(kicad_pcb
	(version 20260206)
	(generator "pcbnew")
	(generator_version "10.0")
	(general
		(thickness 1.6)
		(legacy_teardrops no)
	)
	(paper "A4")
	(layers
		(0 "F.Cu" signal "TOP")
		(4 "In1.Cu" signal "L2GND")
		(6 "In2.Cu" signal "L3")
		(8 "In3.Cu" signal "L4GND")
		(10 "In4.Cu" signal "L5")
		(12 "In5.Cu" signal "L6VCC")
		(14 "In6.Cu" signal "L7VCC")
		(16 "In7.Cu" signal "L8")
		(18 "In8.Cu" signal "L9GND")
		(20 "In9.Cu" signal "L10")
		(22 "In10.Cu" signal "L11GND")
		(2 "B.Cu" signal "BOTTOM")
		(9 "F.Adhes" user "F.Adhesive")
		(11 "B.Adhes" user "B.Adhesive")
		(13 "F.Paste" user "Package Geometry/Pastemask Top")
		(15 "B.Paste" user "Package Geometry/Pastemask Bottom")
		(5 "F.SilkS" user "Ref Des/Silkscreen Top")
		(7 "B.SilkS" user "Ref Des/Silkscreen Bottom")
		(1 "F.Mask" user "Board Geometry/Soldermask Top")
		(3 "B.Mask" user "Board Geometry/Soldermask Bottom")
		(17 "Dwgs.User" user "User.Drawings")
		(19 "Cmts.User" user "User.Comments")
		(21 "Eco1.User" user "User.Eco1")
		(23 "Eco2.User" user "User.Eco2")
		(25 "Edge.Cuts" user "Board Geometry/Outline")
		(27 "Margin" user)
		(31 "F.CrtYd" user "Package Geometry/Place Bound Top")
		(29 "B.CrtYd" user "Package Geometry/Place Bound Bottom")
		(35 "F.Fab" user "Ref Des/Assembly Top")
		(33 "B.Fab" user "Ref Des/Assembly Bottom")
	)
	(setup
		(pad_to_mask_clearance 0)
		(allow_soldermask_bridges_in_footprints no)
		(tenting
			(front yes)
			(back yes)
		)
		(covering
			(front no)
			(back no)
		)
		(plugging
			(front no)
			(back no)
		)
		(capping no)
		(filling no)
		(pcbplotparams
			(layerselection 0x00000000_00000000_55555555_5755f5ff)
			(plot_on_all_layers_selection 0x00000000_00000000_00000000_00000000)
			(disableapertmacros no)
			(usegerberextensions no)
			(usegerberattributes yes)
			(usegerberadvancedattributes yes)
			(creategerberjobfile yes)
			(dashed_line_dash_ratio 12)
			(dashed_line_gap_ratio 3)
			(svgprecision 4)
			(plotframeref no)
			(mode 1)
			(useauxorigin no)
			(pdf_front_fp_property_popups yes)
			(pdf_back_fp_property_popups yes)
			(pdf_metadata yes)
			(pdf_single_document no)
			(dxfpolygonmode yes)
			(dxfimperialunits yes)
			(dxfusepcbnewfont yes)
			(psnegative no)
			(psa4output no)
			(plot_black_and_white yes)
			(sketchpadsonfab no)
			(plotpadnumbers no)
			(hidednponfab no)
			(sketchdnponfab yes)
			(crossoutdnponfab yes)
			(subtractmaskfromsilk no)
			(outputformat 1)
			(mirror no)
			(drillshape 1)
			(scaleselection 1)
			(outputdirectory "")
		)
	)
	(footprint ""
		(layer "F.Cu")
		(at 77.815948 -179.683918 -90)
		(property "Reference" "C228"
			(at 0 0 270)
			(layer "F.SilkS")
			(hide yes)
			(effects
				(font
					(size 1.27 1.27)
				)
			)
		)
		(property "Value" "SC4D7U25V5KX-1-GP"
			(at -0.0762 -6.1214 270)
			(unlocked yes)
			(layer "F.Fab")
			(hide yes)
			(effects
				(font
					(size 1.016 1.016)
					(thickness 0.1524)
				)
			)
		)
		(property "Device Type" "C805H58"
			(at -0.0762 -8.1534 270)
			(unlocked yes)
			(layer "F.Fab")
			(hide yes)
			(effects
				(font
					(size 1.016 1.016)
					(thickness 0.1524)
				)
			)
		)
		(duplicate_pad_numbers_are_jumpers no)
		(fp_line
			(start 0.635 0)
			(end -0.635 0)
			(stroke
				(width 0.508)
				(type default)
			)
			(layer "F.SilkS")
		)
		(fp_rect
			(start -0.9652 1.778)
			(end 0.9652 -1.778)
			(stroke
				(width 0)
				(type default)
			)
			(fill no)
			(layer "F.CrtYd")
		)
		(fp_poly
			(pts
				(xy -0.9652 -1.778) (xy 0.9652 -1.778) (xy 0.9652 1.778) (xy -0.9652 1.778)
			)
			(stroke
				(width 0)
				(type default)
			)
			(fill no)
			(layer "F.Fab")
		)
		(pad "1" smd rect
			(at 0 -0.9652 270)
			(size 1.397 1.143)
			(layers "F.Cu" "F.Mask" "F.Paste")
			(net "P12V_HDD14")
		)
		(pad "2" smd rect
			(at 0 0.9652 270)
			(size 1.397 1.143)
			(layers "F.Cu" "F.Mask" "F.Paste")
			(net "GND")
		)
	)
	(footprint ""
		(layer "F.Cu")
		(at 46.412658 -278.089106 90)
		(property "Reference" "R166"
			(at 0 0 90)
			(layer "F.SilkS")
			(hide yes)
			(effects
				(font
					(size 1.27 1.27)
				)
			)
		)
		(property "Value" "4K7R2J-2-GP"
			(at 0.064008 -3.993896 90)
			(unlocked yes)
			(layer "F.Fab")
			(hide yes)
			(effects
				(font
					(size 1.016 1.016)
					(thickness 0.1524)
				)
			)
		)
		(property "Device Type" "R402H16"
			(at 0.064008 -5.517896 90)
			(unlocked yes)
			(layer "F.Fab")
			(hide yes)
			(effects
				(font
					(size 1.016 1.016)
					(thickness 0.1524)
				)
			)
		)
		(duplicate_pad_numbers_are_jumpers no)
		(fp_line
			(start 0.508 -0.9398)
			(end -0.508 -0.9398)
			(stroke
				(width 0.1524)
				(type default)
			)
			(layer "F.SilkS")
		)
		(fp_line
			(start -0.508 -0.9398)
			(end -0.508 0.9398)
			(stroke
				(width 0.1524)
				(type default)
			)
			(layer "F.SilkS")
		)
		(fp_rect
			(start -0.508 0.9398)
			(end 0.508 -0.9398)
			(stroke
				(width 0)
				(type default)
			)
			(fill no)
			(layer "F.CrtYd")
		)
		(fp_rect
			(start -0.508 0.9398)
			(end 0.508 -0.9398)
			(stroke
				(width 0)
				(type default)
			)
			(fill no)
			(layer "F.Fab")
		)
		(pad "1" smd custom
			(at 0 -0.4445 90)
			(size 0.1397 0.1397)
			(layers "F.Cu" "F.Mask" "F.Paste")
			(net "P12V_A")
			(options
				(clearance outline)
				(anchor circle)
			)
			(primitives
				(gr_poly
					(pts
						(arc
							(start -0.1778 -0.2794)
							(mid -0.249642 -0.249642)
							(end -0.2794 -0.1778)
						)
						(arc
							(start -0.2794 0.1778)
							(mid -0.249642 0.249642)
							(end -0.1778 0.2794)
						)
						(arc
							(start 0.1778 0.2794)
							(mid 0.249642 0.249642)
							(end 0.2794 0.1778)
						)
						(arc
							(start 0.2794 -0.1778)
							(mid 0.249642 -0.249642)
							(end 0.1778 -0.2794)
						)
					)
					(width 0)
					(fill yes)
				)
			)
		)
		(pad "2" smd custom
			(at 0 0.4445 90)
			(size 0.1397 0.1397)
			(layers "F.Cu" "F.Mask" "F.Paste")
			(net "SW_HDD_R1")
			(options
				(clearance outline)
				(anchor circle)
			)
			(primitives
				(gr_poly
					(pts
						(arc
							(start -0.1778 -0.2794)
							(mid -0.249642 -0.249642)
							(end -0.2794 -0.1778)
						)
						(arc
							(start -0.2794 0.1778)
							(mid -0.249642 0.249642)
							(end -0.1778 0.2794)
						)
						(arc
							(start 0.1778 0.2794)
							(mid 0.249642 0.249642)
							(end 0.2794 0.1778)
						)
						(arc
							(start 0.2794 -0.1778)
							(mid 0.249642 -0.249642)
							(end 0.1778 -0.2794)
						)
					)
					(width 0)
					(fill yes)
				)
			)
		)
	)
	(footprint ""
		(layer "F.Cu")
		(at 256.47777 -380.367794)
		(property "Reference" "Q228"
			(at 0 0 0)
			(layer "F.SilkS")
			(hide yes)
			(effects
				(font
					(size 1.27 1.27)
				)
			)
		)
		(property "Value" "IRFH8201TRPBF-GP"
			(at -4.2164 -4.3688 0)
			(unlocked yes)
			(layer "F.Fab")
			(hide yes)
			(effects
				(font
					(size 1.016 1.016)
					(thickness 0.1524)
				)
			)
		)
		(property "Device Type" "PPAK-5PH42"
			(at -4.2164 -5.8928 0)
			(unlocked yes)
			(layer "F.Fab")
			(hide yes)
			(effects
				(font
					(size 1.016 1.016)
					(thickness 0.1524)
				)
			)
		)
		(duplicate_pad_numbers_are_jumpers no)
		(fp_line
			(start -3.0353 4.9276)
			(end -3.0353 3.9624)
			(stroke
				(width 0.3302)
				(type default)
			)
			(layer "F.SilkS")
		)
		(fp_line
			(start -2.8956 -2.794)
			(end 2.8956 -2.794)
			(stroke
				(width 0.1524)
				(type default)
			)
			(layer "F.SilkS")
		)
		(fp_line
			(start -2.8956 4.826)
			(end -2.8956 -2.794)
			(stroke
				(width 0.1524)
				(type default)
			)
			(layer "F.SilkS")
		)
		(fp_line
			(start -1.9431 4.9276)
			(end -3.0353 4.9276)
			(stroke
				(width 0.3302)
				(type default)
			)
			(layer "F.SilkS")
		)
		(fp_line
			(start 2.8956 -2.794)
			(end 2.8956 4.826)
			(stroke
				(width 0.1524)
				(type default)
			)
			(layer "F.SilkS")
		)
		(fp_line
			(start 2.8956 4.826)
			(end -2.8956 4.826)
			(stroke
				(width 0.1524)
				(type default)
			)
			(layer "F.SilkS")
		)
		(fp_poly
			(pts
				(xy -2.3622 5.334) (xy -1.4986 5.334) (xy -1.9304 4.9022)
			)
			(stroke
				(width 0)
				(type default)
			)
			(fill yes)
			(layer "F.SilkS")
		)
		(fp_poly
			(pts
				(xy -2.6416 -0.3556) (xy -0.3556 -0.3556) (xy -0.3556 -2.54) (xy -2.6416 -2.54)
			)
			(stroke
				(width 0)
				(type default)
			)
			(fill yes)
			(layer "F.Paste")
		)
		(fp_poly
			(pts
				(xy -2.6416 2.54) (xy -0.3556 2.54) (xy -0.3556 0.3556) (xy -2.6416 0.3556)
			)
			(stroke
				(width 0)
				(type default)
			)
			(fill yes)
			(layer "F.Paste")
		)
		(fp_poly
			(pts
				(xy 0.3556 -0.3556) (xy 2.6416 -0.3556) (xy 2.6416 -2.54) (xy 0.3556 -2.54)
			)
			(stroke
				(width 0)
				(type default)
			)
			(fill yes)
			(layer "F.Paste")
		)
		(fp_poly
			(pts
				(xy 0.3556 2.54) (xy 2.6416 2.54) (xy 2.6416 0.3556) (xy 0.3556 0.3556)
			)
			(stroke
				(width 0)
				(type default)
			)
			(fill yes)
			(layer "F.Paste")
		)
		(fp_rect
			(start -2.5781 3.9878)
			(end 2.5781 -2.1082)
			(stroke
				(width 0)
				(type default)
			)
			(fill no)
			(layer "F.CrtYd")
		)
		(fp_poly
			(pts
				(xy -3.1496 5.08) (xy -3.1496 -3.048) (xy 3.1496 -3.048) (xy 3.1496 3.9751) (xy 2.5781 3.9751) (xy 2.5781 -2.1082)
				(xy -2.5781 -2.1082) (xy -2.5781 3.9878) (xy 3.1496 3.9878) (xy 3.1496 5.08)
			)
			(stroke
				(width 0)
				(type default)
			)
			(fill no)
			(layer "F.CrtYd")
		)
		(fp_rect
			(start -3.1496 5.08)
			(end 3.1496 -3.048)
			(stroke
				(width 0)
				(type default)
			)
			(fill no)
			(layer "F.Fab")
		)
		(pad "1" smd rect
			(at -1.905 3.81)
			(size 0.762 1.524)
			(layers "F.Cu" "F.Mask" "F.Paste")
			(net "P12V_A")
		)
		(pad "2" smd rect
			(at -0.635 3.81)
			(size 0.762 1.524)
			(layers "F.Cu" "F.Mask" "F.Paste")
			(net "P12V_A")
		)
		(pad "3" smd rect
			(at 0.635 3.81)
			(size 0.762 1.524)
			(layers "F.Cu" "F.Mask" "F.Paste")
			(net "P12V_A")
		)
		(pad "4" smd rect
			(at 1.905 3.81)
			(size 0.762 1.524)
			(layers "F.Cu" "F.Mask" "F.Paste")
			(net "MB3_12V_CTRL_GATE3")
		)
		(pad "5" smd rect
			(at 0 0)
			(size 5.2832 5.08)
			(layers "F.Cu" "F.Mask" "F.Paste")
			(net "MB3_P12V_IN_R")
		)
		(pad "6" smd rect
			(at 0.635 -2.032)
			(size 0.0254 0.0254)
			(layers "F.Cu" "F.Mask" "F.Paste")
			(net "MB3_P12V_IN_R")
		)
		(pad "7" smd rect
			(at -0.635 -2.032)
			(size 0.0254 0.0254)
			(layers "F.Cu" "F.Mask" "F.Paste")
			(net "MB3_P12V_IN_R")
		)
		(pad "8" smd rect
			(at -1.905 -2.032)
			(size 0.0254 0.0254)
			(layers "F.Cu" "F.Mask" "F.Paste")
			(net "MB3_P12V_IN_R")
		)
	)
	(footprint ""
		(layer "F.Cu")
		(at 368.8588 -132.1054)
		(property "Reference" "C562"
			(at 0 0 0)
			(layer "F.SilkS")
			(hide yes)
			(effects
				(font
					(size 1.27 1.27)
				)
			)
		)
		(property "Value" "SCD1U25V2KX-2-GP"
			(at 1.1811 -2.7051 0)
			(unlocked yes)
			(layer "F.Fab")
			(hide yes)
			(effects
				(font
					(size 1.016 1.016)
					(thickness 0.1524)
				)
			)
		)
		(property "Device Type" "C402H22"
			(at 1.1811 -4.2291 0)
			(unlocked yes)
			(layer "F.Fab")
			(hide yes)
			(effects
				(font
					(size 1.016 1.016)
					(thickness 0.1524)
				)
			)
		)
		(duplicate_pad_numbers_are_jumpers no)
		(fp_rect
			(start -0.4318 0.9525)
			(end 0.4318 -0.9525)
			(stroke
				(width 0)
				(type default)
			)
			(fill no)
			(layer "F.CrtYd")
		)
		(fp_rect
			(start -0.4318 0.9525)
			(end 0.4318 -0.9525)
			(stroke
				(width 0)
				(type default)
			)
			(fill no)
			(layer "F.Fab")
		)
		(pad "1" smd custom
			(at 0 -0.4445)
			(size 0.1524 0.1524)
			(layers "F.Cu" "F.Mask" "F.Paste")
			(net "MB1_ISET_R")
			(options
				(clearance outline)
				(anchor circle)
			)
			(primitives
				(gr_poly
					(pts
						(arc
							(start 0.3048 -0.2032)
							(mid 0.275042 -0.275042)
							(end 0.2032 -0.3048)
						)
						(arc
							(start -0.2032 -0.3048)
							(mid -0.275042 -0.275042)
							(end -0.3048 -0.2032)
						)
						(arc
							(start -0.3048 0.2032)
							(mid -0.275042 0.275042)
							(end -0.2032 0.3048)
						)
						(arc
							(start 0.2032 0.3048)
							(mid 0.275042 0.275042)
							(end 0.3048 0.2032)
						)
					)
					(width 0)
					(fill yes)
				)
			)
		)
		(pad "2" smd custom
			(at 0 0.4445)
			(size 0.1524 0.1524)
			(layers "F.Cu" "F.Mask" "F.Paste")
			(net "AGND_CURRENT_MONOB")
			(options
				(clearance outline)
				(anchor circle)
			)
			(primitives
				(gr_poly
					(pts
						(arc
							(start 0.3048 -0.2032)
							(mid 0.275042 -0.275042)
							(end 0.2032 -0.3048)
						)
						(arc
							(start -0.2032 -0.3048)
							(mid -0.275042 -0.275042)
							(end -0.3048 -0.2032)
						)
						(arc
							(start -0.3048 0.2032)
							(mid -0.275042 0.275042)
							(end -0.2032 0.3048)
						)
						(arc
							(start 0.2032 0.3048)
							(mid 0.275042 0.275042)
							(end 0.3048 0.2032)
						)
					)
					(width 0)
					(fill yes)
				)
			)
		)
	)
	(footprint ""
		(layer "F.Cu")
		(at 142.818866 -145.372074 180)
		(property "Reference" "C542"
			(at 0 0 180)
			(layer "F.SilkS")
			(hide yes)
			(effects
				(font
					(size 1.27 1.27)
				)
			)
		)
		(property "Value" "SCD01U25V2KX-3GP"
			(at 1.1811 -2.7051 180)
			(unlocked yes)
			(layer "F.Fab")
			(hide yes)
			(effects
				(font
					(size 1.016 1.016)
					(thickness 0.1524)
				)
			)
		)
		(property "Device Type" "C402H22"
			(at 1.1811 -4.2291 180)
			(unlocked yes)
			(layer "F.Fab")
			(hide yes)
			(effects
				(font
					(size 1.016 1.016)
					(thickness 0.1524)
				)
			)
		)
		(duplicate_pad_numbers_are_jumpers no)
		(fp_rect
			(start -0.4318 0.9525)
			(end 0.4318 -0.9525)
			(stroke
				(width 0)
				(type default)
			)
			(fill no)
			(layer "F.CrtYd")
		)
		(fp_rect
			(start -0.4318 0.9525)
			(end 0.4318 -0.9525)
			(stroke
				(width 0)
				(type default)
			)
			(fill no)
			(layer "F.Fab")
		)
		(pad "1" smd custom
			(at 0 -0.4445 180)
			(size 0.1524 0.1524)
			(layers "F.Cu" "F.Mask" "F.Paste")
			(net "MB0_TIME_R")
			(options
				(clearance outline)
				(anchor circle)
			)
			(primitives
				(gr_poly
					(pts
						(arc
							(start 0.3048 -0.2032)
							(mid 0.275042 -0.275042)
							(end 0.2032 -0.3048)
						)
						(arc
							(start -0.2032 -0.3048)
							(mid -0.275042 -0.275042)
							(end -0.3048 -0.2032)
						)
						(arc
							(start -0.3048 0.2032)
							(mid -0.275042 0.275042)
							(end -0.2032 0.3048)
						)
						(arc
							(start 0.2032 0.3048)
							(mid 0.275042 0.275042)
							(end 0.3048 0.2032)
						)
					)
					(width 0)
					(fill yes)
				)
			)
		)
		(pad "2" smd custom
			(at 0 0.4445 180)
			(size 0.1524 0.1524)
			(layers "F.Cu" "F.Mask" "F.Paste")
			(net "AGND_CURRENT_MONOA")
			(options
				(clearance outline)
				(anchor circle)
			)
			(primitives
				(gr_poly
					(pts
						(arc
							(start 0.3048 -0.2032)
							(mid 0.275042 -0.275042)
							(end 0.2032 -0.3048)
						)
						(arc
							(start -0.2032 -0.3048)
							(mid -0.275042 -0.275042)
							(end -0.3048 -0.2032)
						)
						(arc
							(start -0.3048 0.2032)
							(mid -0.275042 0.275042)
							(end -0.2032 0.3048)
						)
						(arc
							(start 0.2032 0.3048)
							(mid 0.275042 0.275042)
							(end 0.3048 0.2032)
						)
					)
					(width 0)
					(fill yes)
				)
			)
		)
	)
	(footprint ""
		(layer "F.Cu")
		(at 336.9056 -45.735494 180)
		(property "Reference" "R834"
			(at 0 0 180)
			(layer "F.SilkS")
			(hide yes)
			(effects
				(font
					(size 1.27 1.27)
				)
			)
		)
		(property "Value" "4K7R2J-2-GP"
			(at 0.064008 -3.993896 180)
			(unlocked yes)
			(layer "F.Fab")
			(hide yes)
			(effects
				(font
					(size 1.016 1.016)
					(thickness 0.1524)
				)
			)
		)
		(property "Device Type" "R402H16"
			(at 0.064008 -5.517896 180)
			(unlocked yes)
			(layer "F.Fab")
			(hide yes)
			(effects
				(font
					(size 1.016 1.016)
					(thickness 0.1524)
				)
			)
		)
		(duplicate_pad_numbers_are_jumpers no)
		(fp_line
			(start 0.508 -0.9398)
			(end -0.508 -0.9398)
			(stroke
				(width 0.1524)
				(type default)
			)
			(layer "F.SilkS")
		)
		(fp_line
			(start -0.508 -0.9398)
			(end -0.508 0.9398)
			(stroke
				(width 0.1524)
				(type default)
			)
			(layer "F.SilkS")
		)
		(fp_rect
			(start -0.508 0.9398)
			(end 0.508 -0.9398)
			(stroke
				(width 0)
				(type default)
			)
			(fill no)
			(layer "F.CrtYd")
		)
		(fp_rect
			(start -0.508 0.9398)
			(end 0.508 -0.9398)
			(stroke
				(width 0)
				(type default)
			)
			(fill no)
			(layer "F.Fab")
		)
		(pad "1" smd custom
			(at 0 -0.4445 180)
			(size 0.1397 0.1397)
			(layers "F.Cu" "F.Mask" "F.Paste")
			(net "P12V_A")
			(options
				(clearance outline)
				(anchor circle)
			)
			(primitives
				(gr_poly
					(pts
						(arc
							(start -0.1778 -0.2794)
							(mid -0.249642 -0.249642)
							(end -0.2794 -0.1778)
						)
						(arc
							(start -0.2794 0.1778)
							(mid -0.249642 0.249642)
							(end -0.1778 0.2794)
						)
						(arc
							(start 0.1778 0.2794)
							(mid 0.249642 0.249642)
							(end 0.2794 0.1778)
						)
						(arc
							(start 0.2794 -0.1778)
							(mid 0.249642 -0.249642)
							(end 0.1778 -0.2794)
						)
					)
					(width 0)
					(fill yes)
				)
			)
		)
		(pad "2" smd custom
			(at 0 0.4445 180)
			(size 0.1397 0.1397)
			(layers "F.Cu" "F.Mask" "F.Paste")
			(net "SW_HDD_R30")
			(options
				(clearance outline)
				(anchor circle)
			)
			(primitives
				(gr_poly
					(pts
						(arc
							(start -0.1778 -0.2794)
							(mid -0.249642 -0.249642)
							(end -0.2794 -0.1778)
						)
						(arc
							(start -0.2794 0.1778)
							(mid -0.249642 0.249642)
							(end -0.1778 0.2794)
						)
						(arc
							(start 0.1778 0.2794)
							(mid 0.249642 0.249642)
							(end 0.2794 0.1778)
						)
						(arc
							(start 0.2794 -0.1778)
							(mid 0.249642 -0.249642)
							(end 0.1778 -0.2794)
						)
					)
					(width 0)
					(fill yes)
				)
			)
		)
	)
	(footprint ""
		(layer "F.Cu")
		(at 300.7614 -68.453)
		(property "Reference" "U50"
			(at 0 0 0)
			(layer "F.SilkS")
			(hide yes)
			(effects
				(font
					(size 1.27 1.27)
				)
			)
		)
		(property "Value" "TXS0102QDCURQ1-GP"
			(at 0 -11.1252 0)
			(unlocked yes)
			(layer "F.Fab")
			(hide yes)
			(effects
				(font
					(size 1.016 1.016)
					(thickness 0.1524)
				)
			)
		)
		(property "Device Type" "SSOIC8-4H36"
			(at 0 -12.6492 0)
			(unlocked yes)
			(layer "F.Fab")
			(hide yes)
			(effects
				(font
					(size 1.016 1.016)
					(thickness 0.1524)
				)
			)
		)
		(duplicate_pad_numbers_are_jumpers no)
		(fp_line
			(start -1.2954 0.4572)
			(end -1.2954 2.159)
			(stroke
				(width 0.4064)
				(type default)
			)
			(layer "F.SilkS")
		)
		(fp_line
			(start -1.2573 -2.1844)
			(end 1.2573 -2.1844)
			(stroke
				(width 0.1524)
				(type default)
			)
			(layer "F.SilkS")
		)
		(fp_line
			(start -1.2573 -0.3556)
			(end -1.2192 -0.3556)
			(stroke
				(width 0.1524)
				(type default)
			)
			(layer "F.SilkS")
		)
		(fp_line
			(start -1.2573 2.1844)
			(end -1.2573 -2.1844)
			(stroke
				(width 0.1524)
				(type default)
			)
			(layer "F.SilkS")
		)
		(fp_line
			(start -1.2192 -0.3556)
			(end -0.9017 -0.0381)
			(stroke
				(width 0.1524)
				(type default)
			)
			(layer "F.SilkS")
		)
		(fp_line
			(start -1.2065 0.2667)
			(end -1.27 0.2667)
			(stroke
				(width 0.1524)
				(type default)
			)
			(layer "F.SilkS")
		)
		(fp_line
			(start -0.9017 -0.0381)
			(end -1.2065 0.2667)
			(stroke
				(width 0.1524)
				(type default)
			)
			(layer "F.SilkS")
		)
		(fp_line
			(start 1.2573 -2.1844)
			(end 1.2573 2.1844)
			(stroke
				(width 0.1524)
				(type default)
			)
			(layer "F.SilkS")
		)
		(fp_line
			(start 1.2573 2.1844)
			(end -1.2573 2.1844)
			(stroke
				(width 0.1524)
				(type default)
			)
			(layer "F.SilkS")
		)
		(fp_poly
			(pts
				(xy -1.5113 2.4384) (xy 1.5113 2.4384) (xy 1.5113 -2.4384) (xy -1.5113 -2.4384)
			)
			(stroke
				(width 0)
				(type default)
			)
			(fill no)
			(layer "F.CrtYd")
		)
		(fp_poly
			(pts
				(xy -1.5113 -2.4384) (xy 1.5113 -2.4384) (xy 1.5113 2.4384) (xy -1.5113 2.4384)
			)
			(stroke
				(width 0)
				(type default)
			)
			(fill no)
			(layer "F.Fab")
		)
		(pad "1" smd rect
			(at -0.75057 1.1684)
			(size 0.3048 1.524)
			(layers "F.Cu" "F.Mask" "F.Paste")
			(net "I2C_BMC_B_COMP_B_SDA")
		)
		(pad "2" smd rect
			(at -0.25019 1.1684)
			(size 0.3048 1.524)
			(layers "F.Cu" "F.Mask" "F.Paste")
			(net "GND")
		)
		(pad "3" smd rect
			(at 0.25019 1.1684)
			(size 0.3048 1.524)
			(layers "F.Cu" "F.Mask" "F.Paste")
			(net "P3V3_STBY_B")
		)
		(pad "4" smd rect
			(at 0.75057 1.1684)
			(size 0.3048 1.524)
			(layers "F.Cu" "F.Mask" "F.Paste")
			(net "I2C_BMC_B_COMP_B_SDA_BUF")
		)
		(pad "5" smd rect
			(at 0.75057 -1.1684)
			(size 0.3048 1.524)
			(layers "F.Cu" "F.Mask" "F.Paste")
			(net "I2C_BMC_B_COMP_B_SCL_BUF")
		)
		(pad "6" smd rect
			(at 0.25019 -1.1684)
			(size 0.3048 1.524)
			(layers "F.Cu" "F.Mask" "F.Paste")
			(net "TXS0102_B_OE")
		)
		(pad "7" smd rect
			(at -0.25019 -1.1684)
			(size 0.3048 1.524)
			(layers "F.Cu" "F.Mask" "F.Paste")
			(net "P3V3_STBY_B")
		)
		(pad "8" smd rect
			(at -0.75057 -1.1684)
			(size 0.3048 1.524)
			(layers "F.Cu" "F.Mask" "F.Paste")
			(net "I2C_BMC_B_COMP_B_SCL")
		)
	)
	(footprint ""
		(layer "F.Cu")
		(at 80.900016 -94.400116)
		(property "Reference" "FLED15"
			(at 0 0 0)
			(layer "F.SilkS")
			(hide yes)
			(effects
				(font
					(size 1.27 1.27)
				)
			)
		)
		(property "Value" "LED-BY-19-GP"
			(at -2.132076 1.414018 0)
			(unlocked yes)
			(layer "F.Fab")
			(hide yes)
			(effects
				(font
					(size 1.016 1.016)
					(thickness 0.1524)
				)
			)
		)
		(property "Device Type" "LED-1615-4PH26"
			(at -2.132076 -0.109982 0)
			(unlocked yes)
			(layer "F.Fab")
			(hide yes)
			(effects
				(font
					(size 1.016 1.016)
					(thickness 0.1524)
				)
			)
		)
		(duplicate_pad_numbers_are_jumpers no)
		(fp_line
			(start -1.2954 0.254)
			(end -1.2954 1.6002)
			(stroke
				(width 0.508)
				(type default)
			)
			(layer "F.SilkS")
		)
		(fp_line
			(start -1.2954 1.6002)
			(end 1.2954 1.6002)
			(stroke
				(width 0.508)
				(type default)
			)
			(layer "F.SilkS")
		)
		(fp_line
			(start -1.1176 -1.4224)
			(end 1.1176 -1.4224)
			(stroke
				(width 0.1524)
				(type default)
			)
			(layer "F.SilkS")
		)
		(fp_line
			(start -1.1176 1.4224)
			(end -1.1176 -1.4224)
			(stroke
				(width 0.1524)
				(type default)
			)
			(layer "F.SilkS")
		)
		(fp_line
			(start 1.1176 -1.4224)
			(end 1.1176 1.4224)
			(stroke
				(width 0.1524)
				(type default)
			)
			(layer "F.SilkS")
		)
		(fp_line
			(start 1.1176 1.4224)
			(end -1.1176 1.4224)
			(stroke
				(width 0.1524)
				(type default)
			)
			(layer "F.SilkS")
		)
		(fp_line
			(start 1.2954 1.6002)
			(end 1.2954 0.254)
			(stroke
				(width 0.508)
				(type default)
			)
			(layer "F.SilkS")
		)
		(fp_rect
			(start -0.7493 0.8001)
			(end 0.7493 -0.8001)
			(stroke
				(width 0)
				(type default)
			)
			(fill no)
			(layer "F.CrtYd")
		)
		(fp_poly
			(pts
				(xy -1.3716 1.6764) (xy -1.3716 -1.6764) (xy 1.3716 -1.6764) (xy 1.3716 0.0635) (xy 0.7493 0.0635)
				(xy 0.7493 -0.8001) (xy -0.7493 -0.8001) (xy -0.7493 0.8001) (xy 0.7493 0.8001) (xy 0.7493 0.0762)
				(xy 1.3716 0.0762) (xy 1.3716 1.6764)
			)
			(stroke
				(width 0)
				(type default)
			)
			(fill no)
			(layer "F.CrtYd")
		)
		(fp_rect
			(start -1.3716 1.6764)
			(end 1.3716 -1.6764)
			(stroke
				(width 0)
				(type default)
			)
			(fill no)
			(layer "F.Fab")
		)
		(pad "1" smd rect
			(at 0.50038 -0.73025)
			(size 0.7112 0.8636)
			(layers "F.Cu" "F.Mask" "F.Paste")
			(net "DRV_ACT_14")
		)
		(pad "2" smd rect
			(at -0.50038 -0.73025)
			(size 0.7112 0.8636)
			(layers "F.Cu" "F.Mask" "F.Paste")
			(net "FLT_HDD14")
		)
		(pad "3" smd rect
			(at 0.50038 0.73025)
			(size 0.7112 0.8636)
			(layers "F.Cu" "F.Mask" "F.Paste")
			(net "DRV_ACT_14_N")
		)
		(pad "4" smd rect
			(at -0.50038 0.73025)
			(size 0.7112 0.8636)
			(layers "F.Cu" "F.Mask" "F.Paste")
			(net "FLT_HDD14_N")
		)
	)
	(footprint ""
		(layer "F.Cu")
		(at 264.254742 -221.666562 90)
		(property "Reference" "R408"
			(at 0 0 90)
			(layer "F.SilkS")
			(hide yes)
			(effects
				(font
					(size 1.27 1.27)
				)
			)
		)
		(property "Value" "0R2J-2-GP"
			(at 0.064008 -3.993896 90)
			(unlocked yes)
			(layer "F.Fab")
			(hide yes)
			(effects
				(font
					(size 1.016 1.016)
					(thickness 0.1524)
				)
			)
		)
		(property "Device Type" "R402H16"
			(at 0.064008 -5.517896 90)
			(unlocked yes)
			(layer "F.Fab")
			(hide yes)
			(effects
				(font
					(size 1.016 1.016)
					(thickness 0.1524)
				)
			)
		)
		(duplicate_pad_numbers_are_jumpers no)
		(fp_line
			(start 0.508 -0.9398)
			(end -0.508 -0.9398)
			(stroke
				(width 0.1524)
				(type default)
			)
			(layer "F.SilkS")
		)
		(fp_line
			(start -0.508 -0.9398)
			(end -0.508 0.9398)
			(stroke
				(width 0.1524)
				(type default)
			)
			(layer "F.SilkS")
		)
		(fp_rect
			(start -0.508 0.9398)
			(end 0.508 -0.9398)
			(stroke
				(width 0)
				(type default)
			)
			(fill no)
			(layer "F.CrtYd")
		)
		(fp_rect
			(start -0.508 0.9398)
			(end 0.508 -0.9398)
			(stroke
				(width 0)
				(type default)
			)
			(fill no)
			(layer "F.Fab")
		)
		(pad "1" smd custom
			(at 0 -0.4445 90)
			(size 0.1397 0.1397)
			(layers "F.Cu" "F.Mask" "F.Paste")
			(net "I2C_DPB_A_SDA_BUF")
			(options
				(clearance outline)
				(anchor circle)
			)
			(primitives
				(gr_poly
					(pts
						(arc
							(start -0.1778 -0.2794)
							(mid -0.249642 -0.249642)
							(end -0.2794 -0.1778)
						)
						(arc
							(start -0.2794 0.1778)
							(mid -0.249642 0.249642)
							(end -0.1778 0.2794)
						)
						(arc
							(start 0.1778 0.2794)
							(mid 0.249642 0.249642)
							(end 0.2794 0.1778)
						)
						(arc
							(start 0.2794 -0.1778)
							(mid 0.249642 -0.249642)
							(end 0.1778 -0.2794)
						)
					)
					(width 0)
					(fill yes)
				)
			)
		)
		(pad "2" smd custom
			(at 0 0.4445 90)
			(size 0.1397 0.1397)
			(layers "F.Cu" "F.Mask" "F.Paste")
			(net "I2C_DPB_A_SDA")
			(options
				(clearance outline)
				(anchor circle)
			)
			(primitives
				(gr_poly
					(pts
						(arc
							(start -0.1778 -0.2794)
							(mid -0.249642 -0.249642)
							(end -0.2794 -0.1778)
						)
						(arc
							(start -0.2794 0.1778)
							(mid -0.249642 0.249642)
							(end -0.1778 0.2794)
						)
						(arc
							(start 0.1778 0.2794)
							(mid 0.249642 0.249642)
							(end 0.2794 0.1778)
						)
						(arc
							(start 0.2794 -0.1778)
							(mid 0.249642 -0.249642)
							(end 0.1778 -0.2794)
						)
					)
					(width 0)
					(fill yes)
				)
			)
		)
	)
	(footprint ""
		(layer "F.Cu")
		(at 471.924126 -53.126894 -90)
		(property "Reference" "C503"
			(at 0 0 270)
			(layer "F.SilkS")
			(hide yes)
			(effects
				(font
					(size 1.27 1.27)
				)
			)
		)
		(property "Value" "SCD033U25V2KX-GP"
			(at 1.1811 -2.7051 270)
			(unlocked yes)
			(layer "F.Fab")
			(hide yes)
			(effects
				(font
					(size 1.016 1.016)
					(thickness 0.1524)
				)
			)
		)
		(property "Device Type" "C402H22"
			(at 1.1811 -4.2291 270)
			(unlocked yes)
			(layer "F.Fab")
			(hide yes)
			(effects
				(font
					(size 1.016 1.016)
					(thickness 0.1524)
				)
			)
		)
		(duplicate_pad_numbers_are_jumpers no)
		(fp_rect
			(start -0.4318 0.9525)
			(end 0.4318 -0.9525)
			(stroke
				(width 0)
				(type default)
			)
			(fill no)
			(layer "F.CrtYd")
		)
		(fp_rect
			(start -0.4318 0.9525)
			(end 0.4318 -0.9525)
			(stroke
				(width 0)
				(type default)
			)
			(fill no)
			(layer "F.Fab")
		)
		(pad "1" smd custom
			(at 0 -0.4445 270)
			(size 0.1524 0.1524)
			(layers "F.Cu" "F.Mask" "F.Paste")
			(net "SW_HDD_P35")
			(options
				(clearance outline)
				(anchor circle)
			)
			(primitives
				(gr_poly
					(pts
						(arc
							(start 0.3048 -0.2032)
							(mid 0.275042 -0.275042)
							(end 0.2032 -0.3048)
						)
						(arc
							(start -0.2032 -0.3048)
							(mid -0.275042 -0.275042)
							(end -0.3048 -0.2032)
						)
						(arc
							(start -0.3048 0.2032)
							(mid -0.275042 0.275042)
							(end -0.2032 0.3048)
						)
						(arc
							(start 0.2032 0.3048)
							(mid 0.275042 0.275042)
							(end 0.3048 0.2032)
						)
					)
					(width 0)
					(fill yes)
				)
			)
		)
		(pad "2" smd custom
			(at 0 0.4445 270)
			(size 0.1524 0.1524)
			(layers "F.Cu" "F.Mask" "F.Paste")
			(net "GND")
			(options
				(clearance outline)
				(anchor circle)
			)
			(primitives
				(gr_poly
					(pts
						(arc
							(start 0.3048 -0.2032)
							(mid 0.275042 -0.275042)
							(end 0.2032 -0.3048)
						)
						(arc
							(start -0.2032 -0.3048)
							(mid -0.275042 -0.275042)
							(end -0.3048 -0.2032)
						)
						(arc
							(start -0.3048 0.2032)
							(mid -0.275042 0.275042)
							(end -0.2032 0.3048)
						)
						(arc
							(start 0.2032 0.3048)
							(mid 0.275042 0.275042)
							(end 0.3048 0.2032)
						)
					)
					(width 0)
					(fill yes)
				)
			)
		)
	)
	(footprint ""
		(layer "F.Cu")
		(at 18.415 -127.254)
		(property "Reference" "R277"
			(at 0 0 0)
			(layer "F.SilkS")
			(hide yes)
			(effects
				(font
					(size 1.27 1.27)
				)
			)
		)
		(property "Value" "91R3F-1-GP"
			(at -0.0254 -2.5146 0)
			(unlocked yes)
			(layer "F.Fab")
			(hide yes)
			(effects
				(font
					(size 1.016 1.016)
					(thickness 0.1524)
				)
			)
		)
		(property "Device Type" "R603H22"
			(at -0.0254 -4.0386 0)
			(unlocked yes)
			(layer "F.Fab")
			(hide yes)
			(effects
				(font
					(size 1.016 1.016)
					(thickness 0.1524)
				)
			)
		)
		(duplicate_pad_numbers_are_jumpers no)
		(fp_line
			(start -0.4826 0)
			(end -0.2032 0)
			(stroke
				(width 0.2032)
				(type default)
			)
			(layer "F.SilkS")
		)
		(fp_line
			(start 0.2032 0)
			(end 0.4826 0)
			(stroke
				(width 0.2032)
				(type default)
			)
			(layer "F.SilkS")
		)
		(fp_rect
			(start -0.5842 1.3335)
			(end 0.5842 -1.3335)
			(stroke
				(width 0)
				(type default)
			)
			(fill no)
			(layer "F.CrtYd")
		)
		(fp_rect
			(start -0.5842 1.3335)
			(end 0.5842 -1.3335)
			(stroke
				(width 0)
				(type default)
			)
			(fill no)
			(layer "F.Fab")
		)
		(pad "1" smd custom
			(at 0 -0.762)
			(size 0.2159 0.2159)
			(layers "F.Cu" "F.Mask" "F.Paste")
			(net "P5V_A_1")
			(options
				(clearance outline)
				(anchor circle)
			)
			(primitives
				(gr_poly
					(pts
						(arc
							(start -0.3302 -0.4318)
							(mid -0.402042 -0.402042)
							(end -0.4318 -0.3302)
						)
						(arc
							(start -0.4318 0.3302)
							(mid -0.402042 0.402042)
							(end -0.3302 0.4318)
						)
						(arc
							(start 0.3302 0.4318)
							(mid 0.402042 0.402042)
							(end 0.4318 0.3302)
						)
						(arc
							(start 0.4318 -0.3302)
							(mid 0.402042 -0.402042)
							(end 0.3302 -0.4318)
						)
					)
					(width 0)
					(fill yes)
				)
			)
		)
		(pad "2" smd custom
			(at 0 0.762)
			(size 0.2159 0.2159)
			(layers "F.Cu" "F.Mask" "F.Paste")
			(net "DRV_ACT_12")
			(options
				(clearance outline)
				(anchor circle)
			)
			(primitives
				(gr_poly
					(pts
						(arc
							(start -0.3302 -0.4318)
							(mid -0.402042 -0.402042)
							(end -0.4318 -0.3302)
						)
						(arc
							(start -0.4318 0.3302)
							(mid -0.402042 0.402042)
							(end -0.3302 0.4318)
						)
						(arc
							(start 0.3302 0.4318)
							(mid 0.402042 0.402042)
							(end 0.4318 0.3302)
						)
						(arc
							(start 0.4318 -0.3302)
							(mid 0.402042 -0.402042)
							(end 0.3302 -0.4318)
						)
					)
					(width 0)
					(fill yes)
				)
			)
		)
	)
	(footprint ""
		(layer "F.Cu")
		(at 427.390052 -163.554918 -90)
		(property "Reference" "R620"
			(at 0 0 270)
			(layer "F.SilkS")
			(hide yes)
			(effects
				(font
					(size 1.27 1.27)
				)
			)
		)
		(property "Value" "4K7R2J-2-GP"
			(at 0.064008 -3.993896 270)
			(unlocked yes)
			(layer "F.Fab")
			(hide yes)
			(effects
				(font
					(size 1.016 1.016)
					(thickness 0.1524)
				)
			)
		)
		(property "Device Type" "R402H16"
			(at 0.064008 -5.517896 270)
			(unlocked yes)
			(layer "F.Fab")
			(hide yes)
			(effects
				(font
					(size 1.016 1.016)
					(thickness 0.1524)
				)
			)
		)
		(duplicate_pad_numbers_are_jumpers no)
		(fp_line
			(start -0.508 -0.9398)
			(end -0.508 0.9398)
			(stroke
				(width 0.1524)
				(type default)
			)
			(layer "F.SilkS")
		)
		(fp_line
			(start 0.508 -0.9398)
			(end -0.508 -0.9398)
			(stroke
				(width 0.1524)
				(type default)
			)
			(layer "F.SilkS")
		)
		(fp_rect
			(start -0.508 0.9398)
			(end 0.508 -0.9398)
			(stroke
				(width 0)
				(type default)
			)
			(fill no)
			(layer "F.CrtYd")
		)
		(fp_rect
			(start -0.508 0.9398)
			(end 0.508 -0.9398)
			(stroke
				(width 0)
				(type default)
			)
			(fill no)
			(layer "F.Fab")
		)
		(pad "1" smd custom
			(at 0 -0.4445 270)
			(size 0.1397 0.1397)
			(layers "F.Cu" "F.Mask" "F.Paste")
			(net "P12V_A")
			(options
				(clearance outline)
				(anchor circle)
			)
			(primitives
				(gr_poly
					(pts
						(arc
							(start -0.1778 -0.2794)
							(mid -0.249642 -0.249642)
							(end -0.2794 -0.1778)
						)
						(arc
							(start -0.2794 0.1778)
							(mid -0.249642 0.249642)
							(end -0.1778 0.2794)
						)
						(arc
							(start 0.1778 0.2794)
							(mid 0.249642 0.249642)
							(end 0.2794 0.1778)
						)
						(arc
							(start 0.2794 -0.1778)
							(mid 0.249642 -0.249642)
							(end 0.1778 -0.2794)
						)
					)
					(width 0)
					(fill yes)
				)
			)
		)
		(pad "2" smd custom
			(at 0 0.4445 270)
			(size 0.1397 0.1397)
			(layers "F.Cu" "F.Mask" "F.Paste")
			(net "SW_HDD_P21")
			(options
				(clearance outline)
				(anchor circle)
			)
			(primitives
				(gr_poly
					(pts
						(arc
							(start -0.1778 -0.2794)
							(mid -0.249642 -0.249642)
							(end -0.2794 -0.1778)
						)
						(arc
							(start -0.2794 0.1778)
							(mid -0.249642 0.249642)
							(end -0.1778 0.2794)
						)
						(arc
							(start 0.1778 0.2794)
							(mid 0.249642 0.249642)
							(end 0.2794 0.1778)
						)
						(arc
							(start 0.2794 -0.1778)
							(mid 0.249642 -0.249642)
							(end 0.1778 -0.2794)
						)
					)
					(width 0)
					(fill yes)
				)
			)
		)
	)
	(footprint ""
		(layer "F.Cu")
		(at 146.755866 -143.848074 -90)
		(property "Reference" "R1058"
			(at 0 0 270)
			(layer "F.SilkS")
			(hide yes)
			(effects
				(font
					(size 1.27 1.27)
				)
			)
		)
		(property "Value" "100KR2F-L1-GP"
			(at 0.064008 -3.993896 270)
			(unlocked yes)
			(layer "F.Fab")
			(hide yes)
			(effects
				(font
					(size 1.016 1.016)
					(thickness 0.1524)
				)
			)
		)
		(property "Device Type" "R402H16"
			(at 0.064008 -5.517896 270)
			(unlocked yes)
			(layer "F.Fab")
			(hide yes)
			(effects
				(font
					(size 1.016 1.016)
					(thickness 0.1524)
				)
			)
		)
		(duplicate_pad_numbers_are_jumpers no)
		(fp_line
			(start -0.508 -0.9398)
			(end -0.508 0.9398)
			(stroke
				(width 0.1524)
				(type default)
			)
			(layer "F.SilkS")
		)
		(fp_line
			(start 0.508 -0.9398)
			(end -0.508 -0.9398)
			(stroke
				(width 0.1524)
				(type default)
			)
			(layer "F.SilkS")
		)
		(fp_rect
			(start -0.508 0.9398)
			(end 0.508 -0.9398)
			(stroke
				(width 0)
				(type default)
			)
			(fill no)
			(layer "F.CrtYd")
		)
		(fp_rect
			(start -0.508 0.9398)
			(end 0.508 -0.9398)
			(stroke
				(width 0)
				(type default)
			)
			(fill no)
			(layer "F.Fab")
		)
		(pad "1" smd custom
			(at 0 -0.4445 270)
			(size 0.1397 0.1397)
			(layers "F.Cu" "F.Mask" "F.Paste")
			(net "MB0_VCAP_R")
			(options
				(clearance outline)
				(anchor circle)
			)
			(primitives
				(gr_poly
					(pts
						(arc
							(start -0.1778 -0.2794)
							(mid -0.249642 -0.249642)
							(end -0.2794 -0.1778)
						)
						(arc
							(start -0.2794 0.1778)
							(mid -0.249642 0.249642)
							(end -0.1778 0.2794)
						)
						(arc
							(start 0.1778 0.2794)
							(mid 0.249642 0.249642)
							(end 0.2794 0.1778)
						)
						(arc
							(start 0.2794 -0.1778)
							(mid 0.249642 -0.249642)
							(end 0.1778 -0.2794)
						)
					)
					(width 0)
					(fill yes)
				)
			)
		)
		(pad "2" smd custom
			(at 0 0.4445 270)
			(size 0.1397 0.1397)
			(layers "F.Cu" "F.Mask" "F.Paste")
			(net "MB0_ISET_R")
			(options
				(clearance outline)
				(anchor circle)
			)
			(primitives
				(gr_poly
					(pts
						(arc
							(start -0.1778 -0.2794)
							(mid -0.249642 -0.249642)
							(end -0.2794 -0.1778)
						)
						(arc
							(start -0.2794 0.1778)
							(mid -0.249642 0.249642)
							(end -0.1778 0.2794)
						)
						(arc
							(start 0.1778 0.2794)
							(mid 0.249642 0.249642)
							(end 0.2794 0.1778)
						)
						(arc
							(start 0.2794 -0.1778)
							(mid 0.249642 -0.249642)
							(end 0.1778 -0.2794)
						)
					)
					(width 0)
					(fill yes)
				)
			)
		)
	)
	(footprint ""
		(layer "F.Cu")
		(at 334.899 -52.872894 -90)
		(property "Reference" "Q180"
			(at 0 0 270)
			(layer "F.SilkS")
			(hide yes)
			(effects
				(font
					(size 1.27 1.27)
				)
			)
		)
		(property "Value" "AO4406AL-GP"
			(at -3.707384 -1.5367 270)
			(unlocked yes)
			(layer "F.Fab")
			(hide yes)
			(effects
				(font
					(size 1.016 1.016)
					(thickness 0.1524)
				)
			)
		)
		(property "Device Type" "SOIC8H69"
			(at -3.707384 -3.0607 270)
			(unlocked yes)
			(layer "F.Fab")
			(hide yes)
			(effects
				(font
					(size 1.016 1.016)
					(thickness 0.1524)
				)
			)
		)
		(duplicate_pad_numbers_are_jumpers no)
		(fp_line
			(start -2.6289 3.4417)
			(end -2.6289 1.4732)
			(stroke
				(width 0.381)
				(type default)
			)
			(layer "F.SilkS")
		)
		(fp_line
			(start -2.7432 1.4224)
			(end -2.6416 1.4224)
			(stroke
				(width 0.1524)
				(type default)
			)
			(layer "F.SilkS")
		)
		(fp_line
			(start -2.7432 1.4224)
			(end 2.1336 1.4224)
			(stroke
				(width 0.1524)
				(type default)
			)
			(layer "F.SilkS")
		)
		(fp_line
			(start 2.1336 1.4224)
			(end 2.1336 -1.4224)
			(stroke
				(width 0.1524)
				(type default)
			)
			(layer "F.SilkS")
		)
		(fp_line
			(start -2.1844 -0.0508)
			(end -2.7178 0.508)
			(stroke
				(width 0.1524)
				(type default)
			)
			(layer "F.SilkS")
		)
		(fp_line
			(start -2.7178 -0.508)
			(end -2.1844 -0.0508)
			(stroke
				(width 0.1524)
				(type default)
			)
			(layer "F.SilkS")
		)
		(fp_line
			(start -2.7432 -1.4224)
			(end -2.7432 1.4224)
			(stroke
				(width 0.1524)
				(type default)
			)
			(layer "F.SilkS")
		)
		(fp_line
			(start 2.1336 -1.4224)
			(end -2.7432 -1.4224)
			(stroke
				(width 0.1524)
				(type default)
			)
			(layer "F.SilkS")
		)
		(fp_poly
			(pts
				(xy -2.2098 -1.4224) (xy -2.2098 1.4224) (xy 2.2098 1.4224) (xy 2.2098 -1.4224)
			)
			(stroke
				(width 0)
				(type default)
			)
			(fill yes)
			(layer "F.SilkS")
		)
		(fp_rect
			(start -2.450084 2.999994)
			(end 2.450084 -2.999994)
			(stroke
				(width 0)
				(type default)
			)
			(fill no)
			(layer "F.CrtYd")
		)
		(fp_poly
			(pts
				(xy -2.8194 3.6322) (xy -2.8194 -3.6322) (xy 2.8194 -3.6322) (xy 2.8194 1.18364) (xy 2.450084 1.18364)
				(xy 2.450084 -2.999994) (xy -2.450084 -2.999994) (xy -2.450084 2.999994) (xy 2.450084 2.999994)
				(xy 2.450084 1.18618) (xy 2.8194 1.18618) (xy 2.8194 3.6322)
			)
			(stroke
				(width 0)
				(type default)
			)
			(fill no)
			(layer "F.CrtYd")
		)
		(fp_rect
			(start -2.8194 3.6322)
			(end 2.8194 -3.6322)
			(stroke
				(width 0)
				(type default)
			)
			(fill no)
			(layer "F.Fab")
		)
		(pad "1" smd rect
			(at -1.905 2.54 270)
			(size 0.635 1.651)
			(layers "F.Cu" "F.Mask" "F.Paste")
			(net "P5V_HDD30")
		)
		(pad "2" smd rect
			(at -0.635 2.54 270)
			(size 0.635 1.651)
			(layers "F.Cu" "F.Mask" "F.Paste")
			(net "P5V_HDD30")
		)
		(pad "3" smd rect
			(at 0.635 2.54 270)
			(size 0.635 1.651)
			(layers "F.Cu" "F.Mask" "F.Paste")
			(net "P5V_HDD30")
		)
		(pad "4" smd rect
			(at 1.905 2.54 270)
			(size 0.635 1.651)
			(layers "F.Cu" "F.Mask" "F.Paste")
			(net "SW_HDD_P30")
		)
		(pad "5" smd rect
			(at 1.905 -2.54 270)
			(size 0.635 1.651)
			(layers "F.Cu" "F.Mask" "F.Paste")
			(net "P5V_A_4")
		)
		(pad "6" smd rect
			(at 0.635 -2.54 270)
			(size 0.635 1.651)
			(layers "F.Cu" "F.Mask" "F.Paste")
			(net "P5V_A_4")
		)
		(pad "7" smd rect
			(at -0.635 -2.54 270)
			(size 0.635 1.651)
			(layers "F.Cu" "F.Mask" "F.Paste")
			(net "P5V_A_4")
		)
		(pad "8" smd rect
			(at -1.905 -2.54 270)
			(size 0.635 1.651)
			(layers "F.Cu" "F.Mask" "F.Paste")
			(net "P5V_A_4")
		)
	)
	(footprint ""
		(layer "F.Cu")
		(at 398.81175 -45.735494 180)
		(property "Reference" "R883"
			(at 0 0 180)
			(layer "F.SilkS")
			(hide yes)
			(effects
				(font
					(size 1.27 1.27)
				)
			)
		)
		(property "Value" "0R2J-2-GP"
			(at 0.064008 -3.993896 180)
			(unlocked yes)
			(layer "F.Fab")
			(hide yes)
			(effects
				(font
					(size 1.016 1.016)
					(thickness 0.1524)
				)
			)
		)
		(property "Device Type" "R402H16"
			(at 0.064008 -5.517896 180)
			(unlocked yes)
			(layer "F.Fab")
			(hide yes)
			(effects
				(font
					(size 1.016 1.016)
					(thickness 0.1524)
				)
			)
		)
		(duplicate_pad_numbers_are_jumpers no)
		(fp_line
			(start 0.508 -0.9398)
			(end -0.508 -0.9398)
			(stroke
				(width 0.1524)
				(type default)
			)
			(layer "F.SilkS")
		)
		(fp_line
			(start -0.508 -0.9398)
			(end -0.508 0.9398)
			(stroke
				(width 0.1524)
				(type default)
			)
			(layer "F.SilkS")
		)
		(fp_rect
			(start -0.508 0.9398)
			(end 0.508 -0.9398)
			(stroke
				(width 0)
				(type default)
			)
			(fill no)
			(layer "F.CrtYd")
		)
		(fp_rect
			(start -0.508 0.9398)
			(end 0.508 -0.9398)
			(stroke
				(width 0)
				(type default)
			)
			(fill no)
			(layer "F.Fab")
		)
		(pad "1" smd custom
			(at 0 -0.4445 180)
			(size 0.1397 0.1397)
			(layers "F.Cu" "F.Mask" "F.Paste")
			(net "SW_HDD_G32")
			(options
				(clearance outline)
				(anchor circle)
			)
			(primitives
				(gr_poly
					(pts
						(arc
							(start -0.1778 -0.2794)
							(mid -0.249642 -0.249642)
							(end -0.2794 -0.1778)
						)
						(arc
							(start -0.2794 0.1778)
							(mid -0.249642 0.249642)
							(end -0.1778 0.2794)
						)
						(arc
							(start 0.1778 0.2794)
							(mid 0.249642 0.249642)
							(end 0.2794 0.1778)
						)
						(arc
							(start 0.2794 -0.1778)
							(mid 0.249642 -0.249642)
							(end 0.1778 -0.2794)
						)
					)
					(width 0)
					(fill yes)
				)
			)
		)
		(pad "2" smd custom
			(at 0 0.4445 180)
			(size 0.1397 0.1397)
			(layers "F.Cu" "F.Mask" "F.Paste")
			(net "SW_HDD_R32")
			(options
				(clearance outline)
				(anchor circle)
			)
			(primitives
				(gr_poly
					(pts
						(arc
							(start -0.1778 -0.2794)
							(mid -0.249642 -0.249642)
							(end -0.2794 -0.1778)
						)
						(arc
							(start -0.2794 0.1778)
							(mid -0.249642 0.249642)
							(end -0.1778 0.2794)
						)
						(arc
							(start 0.1778 0.2794)
							(mid 0.249642 0.249642)
							(end 0.2794 0.1778)
						)
						(arc
							(start 0.2794 -0.1778)
							(mid 0.249642 -0.249642)
							(end 0.1778 -0.2794)
						)
					)
					(width 0)
					(fill yes)
				)
			)
		)
	)
	(footprint ""
		(layer "F.Cu")
		(at 172.517308 -27.99334 90)
		(property "Reference" "U30"
			(at 0 0 90)
			(layer "F.SilkS")
			(hide yes)
			(effects
				(font
					(size 1.27 1.27)
				)
			)
		)
		(property "Value" "SNLVC1G126DCKR-GP"
			(at -2.3368 -8.6868 90)
			(unlocked yes)
			(layer "F.Fab")
			(hide yes)
			(effects
				(font
					(size 1.016 1.016)
					(thickness 0.1524)
				)
			)
		)
		(property "Device Type" "SC70-5H44"
			(at -2.3114 -10.414 90)
			(unlocked yes)
			(layer "F.Fab")
			(hide yes)
			(effects
				(font
					(size 1.016 1.016)
					(thickness 0.1524)
				)
			)
		)
		(duplicate_pad_numbers_are_jumpers no)
		(fp_line
			(start 1.3843 -1.8034)
			(end 1.3843 -1.1176)
			(stroke
				(width 0.3302)
				(type default)
			)
			(layer "F.SilkS")
		)
		(fp_line
			(start 0.6604 -1.8034)
			(end 1.3843 -1.8034)
			(stroke
				(width 0.3302)
				(type default)
			)
			(layer "F.SilkS")
		)
		(fp_line
			(start 1.27 -1.7018)
			(end 1.27 1.7018)
			(stroke
				(width 0.1524)
				(type default)
			)
			(layer "F.SilkS")
		)
		(fp_line
			(start -1.27 -1.7018)
			(end 1.27 -1.7018)
			(stroke
				(width 0.1524)
				(type default)
			)
			(layer "F.SilkS")
		)
		(fp_line
			(start 1.27 1.7018)
			(end -1.27 1.7018)
			(stroke
				(width 0.1524)
				(type default)
			)
			(layer "F.SilkS")
		)
		(fp_line
			(start -1.27 1.7018)
			(end -1.27 -1.7018)
			(stroke
				(width 0.1524)
				(type default)
			)
			(layer "F.SilkS")
		)
		(fp_rect
			(start -1.524 1.9558)
			(end 1.524 -1.9558)
			(stroke
				(width 0)
				(type default)
			)
			(fill no)
			(layer "F.CrtYd")
		)
		(fp_poly
			(pts
				(xy -1.524 -1.9558) (xy 1.524 -1.9558) (xy 1.524 1.9558) (xy -1.524 1.9558)
			)
			(stroke
				(width 0)
				(type default)
			)
			(fill no)
			(layer "F.Fab")
		)
		(pad "1" smd rect
			(at 0.65024 -0.8255 90)
			(size 0.4064 1.2192)
			(layers "F.Cu" "F.Mask" "F.Paste")
			(net "P3V3_STBY_A")
		)
		(pad "2" smd rect
			(at 0 -0.8255 90)
			(size 0.4064 1.2192)
			(layers "F.Cu" "F.Mask" "F.Paste")
			(net "SYS_A_RESET_N")
		)
		(pad "3" smd rect
			(at -0.65024 -0.8255 90)
			(size 0.4064 1.2192)
			(layers "F.Cu" "F.Mask" "F.Paste")
			(net "GND")
		)
		(pad "4" smd rect
			(at -0.65024 0.8255 90)
			(size 0.4064 1.2192)
			(layers "F.Cu" "F.Mask" "F.Paste")
			(net "SYS_A_RESET_BUFFER_N")
		)
		(pad "5" smd rect
			(at 0.65024 0.8255 90)
			(size 0.4064 1.2192)
			(layers "F.Cu" "F.Mask" "F.Paste")
			(net "P3V3_STBY_A")
		)
	)
	(footprint ""
		(layer "F.Cu")
		(at 20.430998 -62.778894 -90)
		(property "Reference" "C352"
			(at 0 0 270)
			(layer "F.SilkS")
			(hide yes)
			(effects
				(font
					(size 1.27 1.27)
				)
			)
		)
		(property "Value" "SC1U16V3KX-5GP"
			(at 0 -2.8194 270)
			(unlocked yes)
			(layer "F.Fab")
			(hide yes)
			(effects
				(font
					(size 1.016 1.016)
					(thickness 0.1524)
				)
			)
		)
		(property "Device Type" "C603H36"
			(at 0 -4.3434 270)
			(unlocked yes)
			(layer "F.Fab")
			(hide yes)
			(effects
				(font
					(size 1.016 1.016)
					(thickness 0.1524)
				)
			)
		)
		(duplicate_pad_numbers_are_jumpers no)
		(fp_line
			(start 0.508 0)
			(end -0.508 0)
			(stroke
				(width 0.2032)
				(type default)
			)
			(layer "F.SilkS")
		)
		(fp_rect
			(start -0.5842 1.3335)
			(end 0.5842 -1.3335)
			(stroke
				(width 0)
				(type default)
			)
			(fill no)
			(layer "F.CrtYd")
		)
		(fp_rect
			(start -0.5842 1.3335)
			(end 0.5842 -1.3335)
			(stroke
				(width 0)
				(type default)
			)
			(fill no)
			(layer "F.Fab")
		)
		(pad "1" smd custom
			(at 0 -0.762 270)
			(size 0.2159 0.2159)
			(layers "F.Cu" "F.Mask" "F.Paste")
			(net "P5V_HDD24")
			(options
				(clearance outline)
				(anchor circle)
			)
			(primitives
				(gr_poly
					(pts
						(arc
							(start -0.3302 -0.4318)
							(mid -0.402042 -0.402042)
							(end -0.4318 -0.3302)
						)
						(arc
							(start -0.4318 0.3302)
							(mid -0.402042 0.402042)
							(end -0.3302 0.4318)
						)
						(arc
							(start 0.3302 0.4318)
							(mid 0.402042 0.402042)
							(end 0.4318 0.3302)
						)
						(arc
							(start 0.4318 -0.3302)
							(mid 0.402042 -0.402042)
							(end 0.3302 -0.4318)
						)
					)
					(width 0)
					(fill yes)
				)
			)
		)
		(pad "2" smd custom
			(at 0 0.762 270)
			(size 0.2159 0.2159)
			(layers "F.Cu" "F.Mask" "F.Paste")
			(net "GND")
			(options
				(clearance outline)
				(anchor circle)
			)
			(primitives
				(gr_poly
					(pts
						(arc
							(start -0.3302 -0.4318)
							(mid -0.402042 -0.402042)
							(end -0.4318 -0.3302)
						)
						(arc
							(start -0.4318 0.3302)
							(mid -0.402042 0.402042)
							(end -0.3302 0.4318)
						)
						(arc
							(start 0.3302 0.4318)
							(mid 0.402042 0.402042)
							(end 0.4318 0.3302)
						)
						(arc
							(start 0.4318 -0.3302)
							(mid 0.402042 -0.402042)
							(end 0.3302 -0.4318)
						)
					)
					(width 0)
					(fill yes)
				)
			)
		)
	)
	(footprint ""
		(layer "F.Cu")
		(at 246.507 -231.14 180)
		(property "Reference" "R86"
			(at 0 0 180)
			(layer "F.SilkS")
			(hide yes)
			(effects
				(font
					(size 1.27 1.27)
				)
			)
		)
		(property "Value" "4K7R2F-GP"
			(at 0.064008 -3.993896 180)
			(unlocked yes)
			(layer "F.Fab")
			(hide yes)
			(effects
				(font
					(size 1.016 1.016)
					(thickness 0.1524)
				)
			)
		)
		(property "Device Type" "R402H16"
			(at 0.064008 -5.517896 180)
			(unlocked yes)
			(layer "F.Fab")
			(hide yes)
			(effects
				(font
					(size 1.016 1.016)
					(thickness 0.1524)
				)
			)
		)
		(duplicate_pad_numbers_are_jumpers no)
		(fp_line
			(start 0.508 -0.9398)
			(end -0.508 -0.9398)
			(stroke
				(width 0.1524)
				(type default)
			)
			(layer "F.SilkS")
		)
		(fp_line
			(start -0.508 -0.9398)
			(end -0.508 0.9398)
			(stroke
				(width 0.1524)
				(type default)
			)
			(layer "F.SilkS")
		)
		(fp_rect
			(start -0.508 0.9398)
			(end 0.508 -0.9398)
			(stroke
				(width 0)
				(type default)
			)
			(fill no)
			(layer "F.CrtYd")
		)
		(fp_rect
			(start -0.508 0.9398)
			(end 0.508 -0.9398)
			(stroke
				(width 0)
				(type default)
			)
			(fill no)
			(layer "F.Fab")
		)
		(pad "1" smd custom
			(at 0 -0.4445 180)
			(size 0.1397 0.1397)
			(layers "F.Cu" "F.Mask" "F.Paste")
			(net "P3V3_STBY_A")
			(options
				(clearance outline)
				(anchor circle)
			)
			(primitives
				(gr_poly
					(pts
						(arc
							(start -0.1778 -0.2794)
							(mid -0.249642 -0.249642)
							(end -0.2794 -0.1778)
						)
						(arc
							(start -0.2794 0.1778)
							(mid -0.249642 0.249642)
							(end -0.1778 0.2794)
						)
						(arc
							(start 0.1778 0.2794)
							(mid 0.249642 0.249642)
							(end 0.2794 0.1778)
						)
						(arc
							(start 0.2794 -0.1778)
							(mid 0.249642 -0.249642)
							(end 0.1778 -0.2794)
						)
					)
					(width 0)
					(fill yes)
				)
			)
		)
		(pad "2" smd custom
			(at 0 0.4445 180)
			(size 0.1397 0.1397)
			(layers "F.Cu" "F.Mask" "F.Paste")
			(net "IO_EXP2_A2")
			(options
				(clearance outline)
				(anchor circle)
			)
			(primitives
				(gr_poly
					(pts
						(arc
							(start -0.1778 -0.2794)
							(mid -0.249642 -0.249642)
							(end -0.2794 -0.1778)
						)
						(arc
							(start -0.2794 0.1778)
							(mid -0.249642 0.249642)
							(end -0.1778 0.2794)
						)
						(arc
							(start 0.1778 0.2794)
							(mid 0.249642 0.249642)
							(end 0.2794 0.1778)
						)
						(arc
							(start 0.2794 -0.1778)
							(mid 0.249642 -0.249642)
							(end 0.1778 -0.2794)
						)
					)
					(width 0)
					(fill yes)
				)
			)
		)
	)
	(footprint ""
		(layer "F.Cu")
		(at 378.249942 -324.39991)
		(property "Reference" "RLED33"
			(at 0 0 0)
			(layer "F.SilkS")
			(hide yes)
			(effects
				(font
					(size 1.27 1.27)
				)
			)
		)
		(property "Value" "LED-BY-19-GP"
			(at -2.132076 1.414018 0)
			(unlocked yes)
			(layer "F.Fab")
			(hide yes)
			(effects
				(font
					(size 1.016 1.016)
					(thickness 0.1524)
				)
			)
		)
		(property "Device Type" "LED-1615-4PH26"
			(at -2.132076 -0.109982 0)
			(unlocked yes)
			(layer "F.Fab")
			(hide yes)
			(effects
				(font
					(size 1.016 1.016)
					(thickness 0.1524)
				)
			)
		)
		(duplicate_pad_numbers_are_jumpers no)
		(fp_line
			(start -1.2954 0.254)
			(end -1.2954 1.6002)
			(stroke
				(width 0.508)
				(type default)
			)
			(layer "F.SilkS")
		)
		(fp_line
			(start -1.2954 1.6002)
			(end 1.2954 1.6002)
			(stroke
				(width 0.508)
				(type default)
			)
			(layer "F.SilkS")
		)
		(fp_line
			(start -1.1176 -1.4224)
			(end 1.1176 -1.4224)
			(stroke
				(width 0.1524)
				(type default)
			)
			(layer "F.SilkS")
		)
		(fp_line
			(start -1.1176 1.4224)
			(end -1.1176 -1.4224)
			(stroke
				(width 0.1524)
				(type default)
			)
			(layer "F.SilkS")
		)
		(fp_line
			(start 1.1176 -1.4224)
			(end 1.1176 1.4224)
			(stroke
				(width 0.1524)
				(type default)
			)
			(layer "F.SilkS")
		)
		(fp_line
			(start 1.1176 1.4224)
			(end -1.1176 1.4224)
			(stroke
				(width 0.1524)
				(type default)
			)
			(layer "F.SilkS")
		)
		(fp_line
			(start 1.2954 1.6002)
			(end 1.2954 0.254)
			(stroke
				(width 0.508)
				(type default)
			)
			(layer "F.SilkS")
		)
		(fp_rect
			(start -0.7493 0.8001)
			(end 0.7493 -0.8001)
			(stroke
				(width 0)
				(type default)
			)
			(fill no)
			(layer "F.CrtYd")
		)
		(fp_poly
			(pts
				(xy -1.3716 1.6764) (xy -1.3716 -1.6764) (xy 1.3716 -1.6764) (xy 1.3716 0.0635) (xy 0.7493 0.0635)
				(xy 0.7493 -0.8001) (xy -0.7493 -0.8001) (xy -0.7493 0.8001) (xy 0.7493 0.8001) (xy 0.7493 0.0762)
				(xy 1.3716 0.0762) (xy 1.3716 1.6764)
			)
			(stroke
				(width 0)
				(type default)
			)
			(fill no)
			(layer "F.CrtYd")
		)
		(fp_rect
			(start -1.3716 1.6764)
			(end 1.3716 -1.6764)
			(stroke
				(width 0)
				(type default)
			)
			(fill no)
			(layer "F.Fab")
		)
		(pad "1" smd rect
			(at 0.50038 -0.73025)
			(size 0.7112 0.8636)
			(layers "F.Cu" "F.Mask" "F.Paste")
			(net "DRV_ACT_32")
		)
		(pad "2" smd rect
			(at -0.50038 -0.73025)
			(size 0.7112 0.8636)
			(layers "F.Cu" "F.Mask" "F.Paste")
			(net "FLT_HDD32")
		)
		(pad "3" smd rect
			(at 0.50038 0.73025)
			(size 0.7112 0.8636)
			(layers "F.Cu" "F.Mask" "F.Paste")
			(net "DRV_ACT_32_N")
		)
		(pad "4" smd rect
			(at -0.50038 0.73025)
			(size 0.7112 0.8636)
			(layers "F.Cu" "F.Mask" "F.Paste")
			(net "FLT_HDD32_N")
		)
	)
	(footprint ""
		(layer "F.Cu")
		(at 84.587334 -31.40837 180)
		(property "Reference" "R64"
			(at 0 0 180)
			(layer "F.SilkS")
			(hide yes)
			(effects
				(font
					(size 1.27 1.27)
				)
			)
		)
		(property "Value" "4K7R2F-GP"
			(at 0.064008 -3.993896 180)
			(unlocked yes)
			(layer "F.Fab")
			(hide yes)
			(effects
				(font
					(size 1.016 1.016)
					(thickness 0.1524)
				)
			)
		)
		(property "Device Type" "R402H16"
			(at 0.064008 -5.517896 180)
			(unlocked yes)
			(layer "F.Fab")
			(hide yes)
			(effects
				(font
					(size 1.016 1.016)
					(thickness 0.1524)
				)
			)
		)
		(duplicate_pad_numbers_are_jumpers no)
		(fp_line
			(start 0.508 -0.9398)
			(end -0.508 -0.9398)
			(stroke
				(width 0.1524)
				(type default)
			)
			(layer "F.SilkS")
		)
		(fp_line
			(start -0.508 -0.9398)
			(end -0.508 0.9398)
			(stroke
				(width 0.1524)
				(type default)
			)
			(layer "F.SilkS")
		)
		(fp_rect
			(start -0.508 0.9398)
			(end 0.508 -0.9398)
			(stroke
				(width 0)
				(type default)
			)
			(fill no)
			(layer "F.CrtYd")
		)
		(fp_rect
			(start -0.508 0.9398)
			(end 0.508 -0.9398)
			(stroke
				(width 0)
				(type default)
			)
			(fill no)
			(layer "F.Fab")
		)
		(pad "1" smd custom
			(at 0 -0.4445 180)
			(size 0.1397 0.1397)
			(layers "F.Cu" "F.Mask" "F.Paste")
			(net "IO_EXP10_A0")
			(options
				(clearance outline)
				(anchor circle)
			)
			(primitives
				(gr_poly
					(pts
						(arc
							(start -0.1778 -0.2794)
							(mid -0.249642 -0.249642)
							(end -0.2794 -0.1778)
						)
						(arc
							(start -0.2794 0.1778)
							(mid -0.249642 0.249642)
							(end -0.1778 0.2794)
						)
						(arc
							(start 0.1778 0.2794)
							(mid 0.249642 0.249642)
							(end 0.2794 0.1778)
						)
						(arc
							(start 0.2794 -0.1778)
							(mid 0.249642 -0.249642)
							(end 0.1778 -0.2794)
						)
					)
					(width 0)
					(fill yes)
				)
			)
		)
		(pad "2" smd custom
			(at 0 0.4445 180)
			(size 0.1397 0.1397)
			(layers "F.Cu" "F.Mask" "F.Paste")
			(net "GND")
			(options
				(clearance outline)
				(anchor circle)
			)
			(primitives
				(gr_poly
					(pts
						(arc
							(start -0.1778 -0.2794)
							(mid -0.249642 -0.249642)
							(end -0.2794 -0.1778)
						)
						(arc
							(start -0.2794 0.1778)
							(mid -0.249642 0.249642)
							(end -0.1778 0.2794)
						)
						(arc
							(start 0.1778 0.2794)
							(mid 0.249642 0.249642)
							(end 0.2794 0.1778)
						)
						(arc
							(start 0.2794 -0.1778)
							(mid 0.249642 -0.249642)
							(end 0.1778 -0.2794)
						)
					)
					(width 0)
					(fill yes)
				)
			)
		)
	)
	(footprint ""
		(layer "F.Cu")
		(at 224.155 -387.951472 180)
		(property "Reference" "D41"
			(at 0 0 180)
			(layer "F.SilkS")
			(hide yes)
			(effects
				(font
					(size 1.27 1.27)
				)
			)
		)
		(property "Value" "MMPZ5228BPT-GP"
			(at 0 -6.7818 180)
			(unlocked yes)
			(layer "F.Fab")
			(hide yes)
			(effects
				(font
					(size 1.016 1.016)
					(thickness 0.1524)
				)
			)
		)
		(property "Device Type" "SOD323AKH40"
			(at 0 -8.6868 180)
			(unlocked yes)
			(layer "F.Fab")
			(hide yes)
			(effects
				(font
					(size 1.016 1.016)
					(thickness 0.1524)
				)
			)
		)
		(duplicate_pad_numbers_are_jumpers no)
		(fp_line
			(start 0.889 2.159)
			(end -0.889 2.159)
			(stroke
				(width 0.1524)
				(type default)
			)
			(layer "F.SilkS")
		)
		(fp_line
			(start 0.889 -1.9304)
			(end 0.889 2.159)
			(stroke
				(width 0.1524)
				(type default)
			)
			(layer "F.SilkS")
		)
		(fp_line
			(start 0.762 2.0574)
			(end -0.762 2.0574)
			(stroke
				(width 0.508)
				(type default)
			)
			(layer "F.SilkS")
		)
		(fp_line
			(start -0.889 2.159)
			(end -0.889 -1.9304)
			(stroke
				(width 0.1524)
				(type default)
			)
			(layer "F.SilkS")
		)
		(fp_line
			(start -0.889 -1.9304)
			(end 0.889 -1.9304)
			(stroke
				(width 0.1524)
				(type default)
			)
			(layer "F.SilkS")
		)
		(fp_rect
			(start -1.016 2.3114)
			(end 1.016 -2.0066)
			(stroke
				(width 0)
				(type default)
			)
			(fill no)
			(layer "F.CrtYd")
		)
		(fp_poly
			(pts
				(xy -1.016 -2.0066) (xy 1.016 -2.0066) (xy 1.016 2.3114) (xy -1.016 2.3114)
			)
			(stroke
				(width 0)
				(type default)
			)
			(fill no)
			(layer "F.Fab")
		)
		(pad "A" smd rect
			(at 0 -1.143 180)
			(size 0.5588 1.016)
			(layers "F.Cu" "F.Mask" "F.Paste")
			(net "GND")
		)
		(pad "K" smd rect
			(at 0 1.143 180)
			(size 0.5588 1.016)
			(layers "F.Cu" "F.Mask" "F.Paste")
			(net "VCCP_IN")
		)
	)
	(footprint ""
		(layer "F.Cu")
		(at 127.113284 -274.219416 90)
		(property "Reference" "C78"
			(at 0 0 90)
			(layer "F.SilkS")
			(hide yes)
			(effects
				(font
					(size 1.27 1.27)
				)
			)
		)
		(property "Value" "SCD01U16V1KX-GP"
			(at -2.8321 -1.7399 90)
			(unlocked yes)
			(layer "F.Fab")
			(hide yes)
			(effects
				(font
					(size 1.016 1.016)
					(thickness 0.1524)
				)
			)
		)
		(property "Device Type" "C0201H13"
			(at -2.8321 -3.2639 90)
			(unlocked yes)
			(layer "F.Fab")
			(hide yes)
			(effects
				(font
					(size 1.016 1.016)
					(thickness 0.1524)
				)
			)
		)
		(duplicate_pad_numbers_are_jumpers no)
		(fp_rect
			(start -0.2794 0.6477)
			(end 0.2794 -0.6477)
			(stroke
				(width 0)
				(type default)
			)
			(fill no)
			(layer "F.CrtYd")
		)
		(fp_rect
			(start -0.2794 0.6477)
			(end 0.2794 -0.6477)
			(stroke
				(width 0)
				(type default)
			)
			(fill no)
			(layer "F.Fab")
		)
		(pad "1" smd custom
			(at 0 -0.2794 90)
			(size 0.0762 0.0762)
			(layers "F.Cu" "F.Mask" "F.Paste")
			(net "SAS_HDD_RX_N3")
			(options
				(clearance outline)
				(anchor circle)
			)
			(primitives
				(gr_poly
					(pts
						(arc
							(start 0.1524 -0.127)
							(mid 0.137521 -0.162921)
							(end 0.1016 -0.1778)
						)
						(arc
							(start -0.1016 -0.1778)
							(mid -0.137521 -0.162921)
							(end -0.1524 -0.127)
						)
						(arc
							(start -0.1524 0.127)
							(mid -0.137521 0.162921)
							(end -0.1016 0.1778)
						)
						(arc
							(start 0.1016 0.1778)
							(mid 0.137521 0.162921)
							(end 0.1524 0.127)
						)
					)
					(width 0)
					(fill yes)
				)
			)
		)
		(pad "2" smd custom
			(at 0 0.2794 90)
			(size 0.0762 0.0762)
			(layers "F.Cu" "F.Mask" "F.Paste")
			(net "PHY_SCC_A_TO_DRV_A_3_DN")
			(options
				(clearance outline)
				(anchor circle)
			)
			(primitives
				(gr_poly
					(pts
						(arc
							(start 0.1524 -0.127)
							(mid 0.137521 -0.162921)
							(end 0.1016 -0.1778)
						)
						(arc
							(start -0.1016 -0.1778)
							(mid -0.137521 -0.162921)
							(end -0.1524 -0.127)
						)
						(arc
							(start -0.1524 0.127)
							(mid -0.137521 0.162921)
							(end -0.1016 0.1778)
						)
						(arc
							(start 0.1016 0.1778)
							(mid 0.137521 0.162921)
							(end 0.1524 0.127)
						)
					)
					(width 0)
					(fill yes)
				)
			)
		)
	)
	(footprint ""
		(layer "F.Cu")
		(at 336.931 -275.735542 180)
		(property "Reference" "R282"
			(at 0 0 180)
			(layer "F.SilkS")
			(hide yes)
			(effects
				(font
					(size 1.27 1.27)
				)
			)
		)
		(property "Value" "4K7R2J-2-GP"
			(at 0.064008 -3.993896 180)
			(unlocked yes)
			(layer "F.Fab")
			(hide yes)
			(effects
				(font
					(size 1.016 1.016)
					(thickness 0.1524)
				)
			)
		)
		(property "Device Type" "R402H16"
			(at 0.064008 -5.517896 180)
			(unlocked yes)
			(layer "F.Fab")
			(hide yes)
			(effects
				(font
					(size 1.016 1.016)
					(thickness 0.1524)
				)
			)
		)
		(duplicate_pad_numbers_are_jumpers no)
		(fp_line
			(start 0.508 -0.9398)
			(end -0.508 -0.9398)
			(stroke
				(width 0.1524)
				(type default)
			)
			(layer "F.SilkS")
		)
		(fp_line
			(start -0.508 -0.9398)
			(end -0.508 0.9398)
			(stroke
				(width 0.1524)
				(type default)
			)
			(layer "F.SilkS")
		)
		(fp_rect
			(start -0.508 0.9398)
			(end 0.508 -0.9398)
			(stroke
				(width 0)
				(type default)
			)
			(fill no)
			(layer "F.CrtYd")
		)
		(fp_rect
			(start -0.508 0.9398)
			(end 0.508 -0.9398)
			(stroke
				(width 0)
				(type default)
			)
			(fill no)
			(layer "F.Fab")
		)
		(pad "1" smd custom
			(at 0 -0.4445 180)
			(size 0.1397 0.1397)
			(layers "F.Cu" "F.Mask" "F.Paste")
			(net "P12V_A")
			(options
				(clearance outline)
				(anchor circle)
			)
			(primitives
				(gr_poly
					(pts
						(arc
							(start -0.1778 -0.2794)
							(mid -0.249642 -0.249642)
							(end -0.2794 -0.1778)
						)
						(arc
							(start -0.2794 0.1778)
							(mid -0.249642 0.249642)
							(end -0.1778 0.2794)
						)
						(arc
							(start 0.1778 0.2794)
							(mid 0.249642 0.249642)
							(end 0.2794 0.1778)
						)
						(arc
							(start 0.2794 -0.1778)
							(mid 0.249642 -0.249642)
							(end 0.1778 -0.2794)
						)
					)
					(width 0)
					(fill yes)
				)
			)
		)
		(pad "2" smd custom
			(at 0 0.4445 180)
			(size 0.1397 0.1397)
			(layers "F.Cu" "F.Mask" "F.Paste")
			(net "SW_HDD_R6")
			(options
				(clearance outline)
				(anchor circle)
			)
			(primitives
				(gr_poly
					(pts
						(arc
							(start -0.1778 -0.2794)
							(mid -0.249642 -0.249642)
							(end -0.2794 -0.1778)
						)
						(arc
							(start -0.2794 0.1778)
							(mid -0.249642 0.249642)
							(end -0.1778 0.2794)
						)
						(arc
							(start 0.1778 0.2794)
							(mid 0.249642 0.249642)
							(end 0.2794 0.1778)
						)
						(arc
							(start 0.2794 -0.1778)
							(mid 0.249642 -0.249642)
							(end 0.1778 -0.2794)
						)
					)
					(width 0)
					(fill yes)
				)
			)
		)
	)
	(footprint ""
		(layer "F.Cu")
		(at 178.181 -278.554942 180)
		(property "Reference" "Q31"
			(at 0 0 180)
			(layer "F.SilkS")
			(hide yes)
			(effects
				(font
					(size 1.27 1.27)
				)
			)
		)
		(property "Value" "2N7002KDW-GP"
			(at -2.3622 -8.2042 180)
			(unlocked yes)
			(layer "F.Fab")
			(hide yes)
			(effects
				(font
					(size 1.016 1.016)
					(thickness 0.1524)
				)
			)
		)
		(property "Device Type" "SOT-363H44"
			(at -2.3622 -10.1092 180)
			(unlocked yes)
			(layer "F.Fab")
			(hide yes)
			(effects
				(font
					(size 1.016 1.016)
					(thickness 0.1524)
				)
			)
		)
		(duplicate_pad_numbers_are_jumpers no)
		(fp_line
			(start 1.4478 1.7018)
			(end 1.4478 -1.7018)
			(stroke
				(width 0.1524)
				(type default)
			)
			(layer "F.SilkS")
		)
		(fp_line
			(start 1.4478 -1.7018)
			(end -1.4478 -1.7018)
			(stroke
				(width 0.1524)
				(type default)
			)
			(layer "F.SilkS")
		)
		(fp_line
			(start -1.27 1.524)
			(end -1.27 0.6604)
			(stroke
				(width 0.4826)
				(type default)
			)
			(layer "F.SilkS")
		)
		(fp_line
			(start -1.4478 1.7018)
			(end 1.4478 1.7018)
			(stroke
				(width 0.1524)
				(type default)
			)
			(layer "F.SilkS")
		)
		(fp_line
			(start -1.4478 -1.7018)
			(end -1.4478 1.7018)
			(stroke
				(width 0.1524)
				(type default)
			)
			(layer "F.SilkS")
		)
		(fp_poly
			(pts
				(xy -1.524 -1.778) (xy 1.524 -1.778) (xy 1.524 1.778) (xy -1.524 1.778)
			)
			(stroke
				(width 0)
				(type default)
			)
			(fill no)
			(layer "F.CrtYd")
		)
		(fp_poly
			(pts
				(xy -1.524 -1.778) (xy 1.524 -1.778) (xy 1.524 1.778) (xy -1.524 1.778)
			)
			(stroke
				(width 0)
				(type default)
			)
			(fill no)
			(layer "F.Fab")
		)
		(pad "1" smd rect
			(at -0.65024 0.9398 180)
			(size 0.4064 1.016)
			(layers "F.Cu" "F.Mask" "F.Paste")
			(net "GND")
		)
		(pad "2" smd rect
			(at 0 0.9398 180)
			(size 0.4064 1.016)
			(layers "F.Cu" "F.Mask" "F.Paste")
			(net "SW_PWR_R_HDD5")
		)
		(pad "3" smd rect
			(at 0.65024 0.9398 180)
			(size 0.4064 1.016)
			(layers "F.Cu" "F.Mask" "F.Paste")
			(net "SW_HDD_P5")
		)
		(pad "4" smd rect
			(at 0.65024 -0.9398 180)
			(size 0.4064 1.016)
			(layers "F.Cu" "F.Mask" "F.Paste")
			(net "GND")
		)
		(pad "5" smd rect
			(at 0 -0.9398 180)
			(size 0.4064 1.016)
			(layers "F.Cu" "F.Mask" "F.Paste")
			(net "SW_HDD_G5")
		)
		(pad "6" smd rect
			(at -0.65024 -0.9398 180)
			(size 0.4064 1.016)
			(layers "F.Cu" "F.Mask" "F.Paste")
			(net "SW_HDD_R5")
		)
	)
	(footprint ""
		(layer "F.Cu")
		(at 424.469052 -66.842894 180)
		(property "Reference" "C469"
			(at 0 0 180)
			(layer "F.SilkS")
			(hide yes)
			(effects
				(font
					(size 1.27 1.27)
				)
			)
		)
		(property "Value" "SC1U16V3KX-5GP"
			(at 0 -2.8194 180)
			(unlocked yes)
			(layer "F.Fab")
			(hide yes)
			(effects
				(font
					(size 1.016 1.016)
					(thickness 0.1524)
				)
			)
		)
		(property "Device Type" "C603H36"
			(at 0 -4.3434 180)
			(unlocked yes)
			(layer "F.Fab")
			(hide yes)
			(effects
				(font
					(size 1.016 1.016)
					(thickness 0.1524)
				)
			)
		)
		(duplicate_pad_numbers_are_jumpers no)
		(fp_line
			(start 0.508 0)
			(end -0.508 0)
			(stroke
				(width 0.2032)
				(type default)
			)
			(layer "F.SilkS")
		)
		(fp_rect
			(start -0.5842 1.3335)
			(end 0.5842 -1.3335)
			(stroke
				(width 0)
				(type default)
			)
			(fill no)
			(layer "F.CrtYd")
		)
		(fp_rect
			(start -0.5842 1.3335)
			(end 0.5842 -1.3335)
			(stroke
				(width 0)
				(type default)
			)
			(fill no)
			(layer "F.Fab")
		)
		(pad "1" smd custom
			(at 0 -0.762 180)
			(size 0.2159 0.2159)
			(layers "F.Cu" "F.Mask" "F.Paste")
			(net "P5V_HDD33")
			(options
				(clearance outline)
				(anchor circle)
			)
			(primitives
				(gr_poly
					(pts
						(arc
							(start -0.3302 -0.4318)
							(mid -0.402042 -0.402042)
							(end -0.4318 -0.3302)
						)
						(arc
							(start -0.4318 0.3302)
							(mid -0.402042 0.402042)
							(end -0.3302 0.4318)
						)
						(arc
							(start 0.3302 0.4318)
							(mid 0.402042 0.402042)
							(end 0.4318 0.3302)
						)
						(arc
							(start 0.4318 -0.3302)
							(mid 0.402042 -0.402042)
							(end 0.3302 -0.4318)
						)
					)
					(width 0)
					(fill yes)
				)
			)
		)
		(pad "2" smd custom
			(at 0 0.762 180)
			(size 0.2159 0.2159)
			(layers "F.Cu" "F.Mask" "F.Paste")
			(net "GND")
			(options
				(clearance outline)
				(anchor circle)
			)
			(primitives
				(gr_poly
					(pts
						(arc
							(start -0.3302 -0.4318)
							(mid -0.402042 -0.402042)
							(end -0.4318 -0.3302)
						)
						(arc
							(start -0.4318 0.3302)
							(mid -0.402042 0.402042)
							(end -0.3302 0.4318)
						)
						(arc
							(start 0.3302 0.4318)
							(mid 0.402042 0.402042)
							(end 0.4318 0.3302)
						)
						(arc
							(start 0.4318 -0.3302)
							(mid 0.402042 -0.402042)
							(end 0.3302 -0.4318)
						)
					)
					(width 0)
					(fill yes)
				)
			)
		)
	)
	(footprint ""
		(layer "F.Cu")
		(at 325.550022 -172.909992 -90)
		(property "Reference" "HDDSAS18"
			(at 0 0 270)
			(layer "F.SilkS")
			(hide yes)
			(effects
				(font
					(size 1.27 1.27)
				)
			)
		)
		(property "Value" "SKT-SAS15P-14P-45-GP"
			(at -20.7645 -8.9789 270)
			(unlocked yes)
			(layer "F.Fab")
			(hide yes)
			(effects
				(font
					(size 1.016 1.016)
					(thickness 0.1524)
				)
			)
		)
		(property "Device Type" "10120818-001C-TRLF"
			(at -20.7645 -10.5029 270)
			(unlocked yes)
			(layer "F.Fab")
			(hide yes)
			(effects
				(font
					(size 1.016 1.016)
					(thickness 0.1524)
				)
			)
		)
		(duplicate_pad_numbers_are_jumpers no)
		(fp_line
			(start 1.651 4.2926)
			(end 1.651 3.0099)
			(stroke
				(width 0.1524)
				(type default)
			)
			(layer "F.SilkS")
		)
		(fp_line
			(start 8.509 4.2926)
			(end 1.651 4.2926)
			(stroke
				(width 0.1524)
				(type default)
			)
			(layer "F.SilkS")
		)
		(fp_line
			(start -23.4188 3.0099)
			(end -23.4188 -3.2512)
			(stroke
				(width 0.1524)
				(type default)
			)
			(layer "F.SilkS")
		)
		(fp_line
			(start 1.651 3.0099)
			(end -23.4188 3.0099)
			(stroke
				(width 0.1524)
				(type default)
			)
			(layer "F.SilkS")
		)
		(fp_line
			(start 8.509 3.0099)
			(end 8.509 4.2926)
			(stroke
				(width 0.1524)
				(type default)
			)
			(layer "F.SilkS")
		)
		(fp_line
			(start 23.4188 3.0099)
			(end 8.509 3.0099)
			(stroke
				(width 0.1524)
				(type default)
			)
			(layer "F.SilkS")
		)
		(fp_line
			(start -23.4188 -3.2512)
			(end 23.4188 -3.2512)
			(stroke
				(width 0.1524)
				(type default)
			)
			(layer "F.SilkS")
		)
		(fp_line
			(start 23.4188 -3.2512)
			(end 23.4188 3.0099)
			(stroke
				(width 0.1524)
				(type default)
			)
			(layer "F.SilkS")
		)
		(fp_line
			(start 15.5067 -3.3401)
			(end 16.2687 -3.3401)
			(stroke
				(width 0.3302)
				(type default)
			)
			(layer "F.SilkS")
		)
		(fp_poly
			(pts
				(xy 15.868904 -3.230372) (xy 16.503904 -3.865372) (xy 15.233904 -3.865372)
			)
			(stroke
				(width 0)
				(type default)
			)
			(fill yes)
			(layer "F.SilkS")
		)
		(fp_poly
			(pts
				(xy -22.8727 -2.7559) (xy 22.8727 -2.7559) (xy 22.8727 2.7559) (xy 8.255 2.7559) (xy 8.255 3.5179)
				(xy 1.905 3.5179) (xy 1.905 2.7559) (xy -22.8727 2.7559)
			)
			(stroke
				(width 0)
				(type default)
			)
			(fill no)
			(layer "F.CrtYd")
		)
		(fp_poly
			(pts
				(xy 1.397 4.5466) (xy 1.397 3.2639) (xy -23.6728 3.2639) (xy -23.6728 -3.5052) (xy 23.6728 -3.5052)
				(xy 23.6728 -0.00635) (xy 22.8727 -0.00635) (xy 22.8727 -2.7559) (xy -22.8727 -2.7559) (xy -22.8727 2.7559)
				(xy 1.905 2.7559) (xy 1.905 3.5179) (xy 8.255 3.5179) (xy 8.255 2.7559) (xy 22.8727 2.7559) (xy 22.8727 0.00635)
				(xy 23.6728 0.00635) (xy 23.6728 3.2639) (xy 8.763 3.2639) (xy 8.763 4.5466)
			)
			(stroke
				(width 0)
				(type default)
			)
			(fill no)
			(layer "F.CrtYd")
		)
		(fp_poly
			(pts
				(xy 1.397 4.5466) (xy 1.397 3.2639) (xy -23.6728 3.2639) (xy -23.6728 -3.5052) (xy 23.6728 -3.5052)
				(xy 23.6728 3.2639) (xy 8.763 3.2639) (xy 8.763 4.5466)
			)
			(stroke
				(width 0)
				(type default)
			)
			(fill no)
			(layer "F.Fab")
		)
		(pad "" np_thru_hole circle
			(at -18.874994 0 270)
			(size 0.254 0.254)
			(drill 1.3462)
			(layers "*.Cu" "*.Mask")
			(clearance 0.9017)
			(thermal_gap 0.9017)
		)
		(pad "" np_thru_hole circle
			(at 18.874994 0 270)
			(size 0.254 0.254)
			(drill 0.9398)
			(layers "*.Cu" "*.Mask")
			(clearance 0.6985)
			(thermal_gap 0.6985)
		)
		(pad "G1" smd rect
			(at 21.874988 0 270)
			(size 2.5908 2.5908)
			(layers "F.Cu" "F.Mask" "F.Paste")
			(net "GND")
		)
		(pad "G2" smd rect
			(at -21.874988 0 270)
			(size 2.5908 2.5908)
			(layers "F.Cu" "F.Mask" "F.Paste")
			(net "GND")
		)
		(pad "P1" smd rect
			(at 1.905 -1.82499 270)
			(size 0.6096 2.3622)
			(layers "F.Cu" "F.Mask" "F.Paste")
			(net "Net_2126")
		)
		(pad "P2" smd rect
			(at 0.635 -1.82499 270)
			(size 0.6096 2.3622)
			(layers "F.Cu" "F.Mask" "F.Paste")
			(net "Net_2127")
		)
		(pad "P3" smd rect
			(at -0.635 -1.82499 270)
			(size 0.6096 2.3622)
			(layers "F.Cu" "F.Mask" "F.Paste")
			(net "Net_2128")
		)
		(pad "P4" smd rect
			(at -1.905 -1.82499 270)
			(size 0.6096 2.3622)
			(layers "F.Cu" "F.Mask" "F.Paste")
			(net "GND")
		)
		(pad "P5" smd rect
			(at -3.175 -1.82499 270)
			(size 0.6096 2.3622)
			(layers "F.Cu" "F.Mask" "F.Paste")
			(net "HDD_PRSNT_18")
		)
		(pad "P6" smd rect
			(at -4.445 -1.82499 270)
			(size 0.6096 2.3622)
			(layers "F.Cu" "F.Mask" "F.Paste")
			(net "GND")
		)
		(pad "P7" smd rect
			(at -5.715 -1.82499 270)
			(size 0.6096 2.3622)
			(layers "F.Cu" "F.Mask" "F.Paste")
			(net "5V_PRE_18")
		)
		(pad "P8" smd rect
			(at -6.985 -1.82499 270)
			(size 0.6096 2.3622)
			(layers "F.Cu" "F.Mask" "F.Paste")
			(net "P5V_HDD18")
		)
		(pad "P9" smd rect
			(at -8.255 -1.82499 270)
			(size 0.6096 2.3622)
			(layers "F.Cu" "F.Mask" "F.Paste")
			(net "P5V_HDD18")
		)
		(pad "P10" smd rect
			(at -9.525 -1.82499 270)
			(size 0.6096 2.3622)
			(layers "F.Cu" "F.Mask" "F.Paste")
			(net "GND")
		)
		(pad "P11" smd rect
			(at -10.795 -1.82499 270)
			(size 0.6096 2.3622)
			(layers "F.Cu" "F.Mask" "F.Paste")
			(net "ACT_HDD_18")
		)
		(pad "P12" smd rect
			(at -12.065 -1.82499 270)
			(size 0.6096 2.3622)
			(layers "F.Cu" "F.Mask" "F.Paste")
			(net "GND")
		)
		(pad "P13" smd rect
			(at -13.335 -1.82499 270)
			(size 0.6096 2.3622)
			(layers "F.Cu" "F.Mask" "F.Paste")
			(net "12V_PRE_18")
		)
		(pad "P14" smd rect
			(at -14.605 -1.82499 270)
			(size 0.6096 2.3622)
			(layers "F.Cu" "F.Mask" "F.Paste")
			(net "P12V_HDD18")
		)
		(pad "P15" smd rect
			(at -15.875 -1.82499 270)
			(size 0.6096 2.3622)
			(layers "F.Cu" "F.Mask" "F.Paste")
			(net "P12V_HDD18")
		)
		(pad "S1" smd rect
			(at 15.875 -1.82499 270)
			(size 0.6096 2.3622)
			(layers "F.Cu" "F.Mask" "F.Paste")
			(net "GND")
		)
		(pad "S2" smd rect
			(at 14.605 -1.82499 270)
			(size 0.6096 2.3622)
			(layers "F.Cu" "F.Mask" "F.Paste")
			(net "SAS_HDD_RX_P18")
		)
		(pad "S3" smd rect
			(at 13.335 -1.82499 270)
			(size 0.6096 2.3622)
			(layers "F.Cu" "F.Mask" "F.Paste")
			(net "SAS_HDD_RX_N18")
		)
		(pad "S4" smd rect
			(at 12.065 -1.82499 270)
			(size 0.6096 2.3622)
			(layers "F.Cu" "F.Mask" "F.Paste")
			(net "GND")
		)
		(pad "S5" smd rect
			(at 10.795 -1.82499 270)
			(size 0.6096 2.3622)
			(layers "F.Cu" "F.Mask" "F.Paste")
			(net "PHY_DRV_A_TO_SCC_A_18_DN")
		)
		(pad "S6" smd rect
			(at 9.525 -1.82499 270)
			(size 0.6096 2.3622)
			(layers "F.Cu" "F.Mask" "F.Paste")
			(net "PHY_DRV_A_TO_SCC_A_18_DP")
		)
		(pad "S7" smd rect
			(at 8.255 -1.82499 270)
			(size 0.6096 2.3622)
			(layers "F.Cu" "F.Mask" "F.Paste")
			(net "GND")
		)
		(pad "S8" smd rect
			(at 7.480046 2.845054 270)
			(size 0.508 2.3622)
			(layers "F.Cu" "F.Mask" "F.Paste")
			(net "GND")
		)
		(pad "S9" smd rect
			(at 6.679946 2.845054 270)
			(size 0.508 2.3622)
			(layers "F.Cu" "F.Mask" "F.Paste")
			(net "Net_455")
		)
		(pad "S10" smd rect
			(at 5.8801 2.845054 270)
			(size 0.508 2.3622)
			(layers "F.Cu" "F.Mask" "F.Paste")
			(net "Net_347")
		)
		(pad "S11" smd rect
			(at 5.08 2.845054 270)
			(size 0.508 2.3622)
			(layers "F.Cu" "F.Mask" "F.Paste")
			(net "GND")
		)
		(pad "S12" smd rect
			(at 4.2799 2.845054 270)
			(size 0.508 2.3622)
			(layers "F.Cu" "F.Mask" "F.Paste")
			(net "Net_383")
		)
		(pad "S13" smd rect
			(at 3.480054 2.845054 270)
			(size 0.508 2.3622)
			(layers "F.Cu" "F.Mask" "F.Paste")
			(net "Net_419")
		)
		(pad "S14" smd rect
			(at 2.679954 2.845054 270)
			(size 0.508 2.3622)
			(layers "F.Cu" "F.Mask" "F.Paste")
			(net "GND")
		)
		(zone
			(layer "F.Cu")
			(hatch none 0.5)
			(connect_pads
				(clearance 0)
			)
			(min_thickness 0.25)
			(keepout
				(tracks not_allowed)
				(vias allowed)
				(pads allowed)
				(copperpour not_allowed)
				(footprints allowed)
			)
			(placement
				(enabled no)
				(sheetname "")
			)
			(fill
				(thermal_gap 0.5)
				(thermal_bridge_width 0.5)
				(island_removal_mode 0)
			)
			(polygon
				(pts
					(xy 329.207622 -189.648592) (xy 322.133722 -189.648592) (xy 322.133722 -196.582792) (xy 323.238622 -196.582792)
					(xy 323.238622 -192.467992) (xy 327.861422 -192.467992) (xy 327.861422 -196.582792) (xy 329.207622 -196.582792)
				)
			)
		)
		(zone
			(layer "F.Cu")
			(hatch none 0.5)
			(connect_pads
				(clearance 0)
			)
			(min_thickness 0.25)
			(keepout
				(tracks allowed)
				(vias not_allowed)
				(pads allowed)
				(copperpour not_allowed)
				(footprints allowed)
			)
			(placement
				(enabled no)
				(sheetname "")
			)
			(fill
				(thermal_gap 0.5)
				(thermal_bridge_width 0.5)
				(island_removal_mode 0)
			)
			(polygon
				(pts
					(xy 329.207622 -189.648592) (xy 322.133722 -189.648592) (xy 322.133722 -196.582792) (xy 323.238622 -196.582792)
					(xy 323.238622 -192.467992) (xy 327.861422 -192.467992) (xy 327.861422 -196.582792) (xy 329.207622 -196.582792)
				)
			)
		)
		(zone
			(layer "F.Cu")
			(hatch none 0.5)
			(connect_pads
				(clearance 0)
			)
			(min_thickness 0.25)
			(keepout
				(tracks not_allowed)
				(vias allowed)
				(pads allowed)
				(copperpour not_allowed)
				(footprints allowed)
			)
			(placement
				(enabled no)
				(sheetname "")
			)
			(fill
				(thermal_gap 0.5)
				(thermal_bridge_width 0.5)
				(island_removal_mode 0)
			)
			(polygon
				(pts
					(xy 329.207622 -156.171392) (xy 322.133722 -156.171392) (xy 322.133722 -149.237192) (xy 323.238622 -149.237192)
					(xy 323.238622 -153.351992) (xy 327.861422 -153.351992) (xy 327.861422 -149.237192) (xy 329.207622 -149.237192)
				)
			)
		)
		(zone
			(layer "F.Cu")
			(hatch none 0.5)
			(connect_pads
				(clearance 0)
			)
			(min_thickness 0.25)
			(keepout
				(tracks allowed)
				(vias not_allowed)
				(pads allowed)
				(copperpour not_allowed)
				(footprints allowed)
			)
			(placement
				(enabled no)
				(sheetname "")
			)
			(fill
				(thermal_gap 0.5)
				(thermal_bridge_width 0.5)
				(island_removal_mode 0)
			)
			(polygon
				(pts
					(xy 329.207622 -156.171392) (xy 322.133722 -156.171392) (xy 322.133722 -149.237192) (xy 323.238622 -149.237192)
					(xy 323.238622 -153.351992) (xy 327.861422 -153.351992) (xy 327.861422 -149.237192) (xy 329.207622 -149.237192)
				)
			)
		)
		(zone
			(layers "F.Cu" "B.Cu" "In1.Cu" "In2.Cu" "In3.Cu" "In4.Cu" "In5.Cu" "In6.Cu"
				"In7.Cu" "In8.Cu" "In9.Cu" "In10.Cu"
			)
			(hatch none 0.5)
			(connect_pads
				(clearance 0)
			)
			(min_thickness 0.25)
			(keepout
				(tracks not_allowed)
				(vias allowed)
				(pads allowed)
				(copperpour not_allowed)
				(footprints allowed)
			)
			(placement
				(enabled no)
				(sheetname "")
			)
			(fill
				(thermal_gap 0.5)
				(thermal_bridge_width 0.5)
				(island_removal_mode 0)
			)
			(polygon
				(pts
					(arc
						(start 326.324722 -154.034998)
						(mid 324.775322 -154.034998)
						(end 326.324722 -154.034998)
					)
				)
			)
		)
		(zone
			(layers "F.Cu" "B.Cu" "In1.Cu" "In2.Cu" "In3.Cu" "In4.Cu" "In5.Cu" "In6.Cu"
				"In7.Cu" "In8.Cu" "In9.Cu" "In10.Cu"
			)
			(hatch none 0.5)
			(connect_pads
				(clearance 0)
			)
			(min_thickness 0.25)
			(keepout
				(tracks not_allowed)
				(vias allowed)
				(pads allowed)
				(copperpour not_allowed)
				(footprints allowed)
			)
			(placement
				(enabled no)
				(sheetname "")
			)
			(fill
				(thermal_gap 0.5)
				(thermal_bridge_width 0.5)
				(island_removal_mode 0)
			)
			(polygon
				(pts
					(arc
						(start 326.527922 -191.784986)
						(mid 324.572122 -191.784986)
						(end 326.527922 -191.784986)
					)
				)
			)
		)
	)
	(footprint ""
		(layer "F.Cu")
		(at 268.232382 19.366738 90)
		(property "Reference" "C89"
			(at 0 0 90)
			(layer "F.SilkS")
			(hide yes)
			(effects
				(font
					(size 1.27 1.27)
				)
			)
		)
		(property "Value" "SCD1U16V2KX-3GP"
			(at 1.1811 -2.7051 90)
			(unlocked yes)
			(layer "F.Fab")
			(hide yes)
			(effects
				(font
					(size 1.016 1.016)
					(thickness 0.1524)
				)
			)
		)
		(property "Device Type" "C402H22"
			(at 1.1811 -4.2291 90)
			(unlocked yes)
			(layer "F.Fab")
			(hide yes)
			(effects
				(font
					(size 1.016 1.016)
					(thickness 0.1524)
				)
			)
		)
		(duplicate_pad_numbers_are_jumpers no)
		(fp_rect
			(start -0.4318 0.9525)
			(end 0.4318 -0.9525)
			(stroke
				(width 0)
				(type default)
			)
			(fill no)
			(layer "F.CrtYd")
		)
		(fp_rect
			(start -0.4318 0.9525)
			(end 0.4318 -0.9525)
			(stroke
				(width 0)
				(type default)
			)
			(fill no)
			(layer "F.Fab")
		)
		(pad "1" smd custom
			(at 0 -0.4445 90)
			(size 0.1524 0.1524)
			(layers "F.Cu" "F.Mask" "F.Paste")
			(net "P5V_USB_B")
			(options
				(clearance outline)
				(anchor circle)
			)
			(primitives
				(gr_poly
					(pts
						(arc
							(start 0.3048 -0.2032)
							(mid 0.275042 -0.275042)
							(end 0.2032 -0.3048)
						)
						(arc
							(start -0.2032 -0.3048)
							(mid -0.275042 -0.275042)
							(end -0.3048 -0.2032)
						)
						(arc
							(start -0.3048 0.2032)
							(mid -0.275042 0.275042)
							(end -0.2032 0.3048)
						)
						(arc
							(start 0.2032 0.3048)
							(mid 0.275042 0.275042)
							(end 0.3048 0.2032)
						)
					)
					(width 0)
					(fill yes)
				)
			)
		)
		(pad "2" smd custom
			(at 0 0.4445 90)
			(size 0.1524 0.1524)
			(layers "F.Cu" "F.Mask" "F.Paste")
			(net "GND")
			(options
				(clearance outline)
				(anchor circle)
			)
			(primitives
				(gr_poly
					(pts
						(arc
							(start 0.3048 -0.2032)
							(mid 0.275042 -0.275042)
							(end 0.2032 -0.3048)
						)
						(arc
							(start -0.2032 -0.3048)
							(mid -0.275042 -0.275042)
							(end -0.3048 -0.2032)
						)
						(arc
							(start -0.3048 0.2032)
							(mid -0.275042 0.275042)
							(end -0.2032 0.3048)
						)
						(arc
							(start 0.2032 0.3048)
							(mid 0.275042 0.275042)
							(end 0.3048 0.2032)
						)
					)
					(width 0)
					(fill yes)
				)
			)
		)
	)
	(footprint ""
		(layer "F.Cu")
		(at 109.467396 -45.633894 90)
		(property "Reference" "R765"
			(at 0 0 90)
			(layer "F.SilkS")
			(hide yes)
			(effects
				(font
					(size 1.27 1.27)
				)
			)
		)
		(property "Value" "4K7R2J-2-GP"
			(at 0.064008 -3.993896 90)
			(unlocked yes)
			(layer "F.Fab")
			(hide yes)
			(effects
				(font
					(size 1.016 1.016)
					(thickness 0.1524)
				)
			)
		)
		(property "Device Type" "R402H16"
			(at 0.064008 -5.517896 90)
			(unlocked yes)
			(layer "F.Fab")
			(hide yes)
			(effects
				(font
					(size 1.016 1.016)
					(thickness 0.1524)
				)
			)
		)
		(duplicate_pad_numbers_are_jumpers no)
		(fp_line
			(start 0.508 -0.9398)
			(end -0.508 -0.9398)
			(stroke
				(width 0.1524)
				(type default)
			)
			(layer "F.SilkS")
		)
		(fp_line
			(start -0.508 -0.9398)
			(end -0.508 0.9398)
			(stroke
				(width 0.1524)
				(type default)
			)
			(layer "F.SilkS")
		)
		(fp_rect
			(start -0.508 0.9398)
			(end 0.508 -0.9398)
			(stroke
				(width 0)
				(type default)
			)
			(fill no)
			(layer "F.CrtYd")
		)
		(fp_rect
			(start -0.508 0.9398)
			(end 0.508 -0.9398)
			(stroke
				(width 0)
				(type default)
			)
			(fill no)
			(layer "F.Fab")
		)
		(pad "1" smd custom
			(at 0 -0.4445 90)
			(size 0.1397 0.1397)
			(layers "F.Cu" "F.Mask" "F.Paste")
			(net "P12V_A")
			(options
				(clearance outline)
				(anchor circle)
			)
			(primitives
				(gr_poly
					(pts
						(arc
							(start -0.1778 -0.2794)
							(mid -0.249642 -0.249642)
							(end -0.2794 -0.1778)
						)
						(arc
							(start -0.2794 0.1778)
							(mid -0.249642 0.249642)
							(end -0.1778 0.2794)
						)
						(arc
							(start 0.1778 0.2794)
							(mid 0.249642 0.249642)
							(end 0.2794 0.1778)
						)
						(arc
							(start 0.2794 -0.1778)
							(mid 0.249642 -0.249642)
							(end 0.1778 -0.2794)
						)
					)
					(width 0)
					(fill yes)
				)
			)
		)
		(pad "2" smd custom
			(at 0 0.4445 90)
			(size 0.1397 0.1397)
			(layers "F.Cu" "F.Mask" "F.Paste")
			(net "SW_HDD_R27")
			(options
				(clearance outline)
				(anchor circle)
			)
			(primitives
				(gr_poly
					(pts
						(arc
							(start -0.1778 -0.2794)
							(mid -0.249642 -0.249642)
							(end -0.2794 -0.1778)
						)
						(arc
							(start -0.2794 0.1778)
							(mid -0.249642 0.249642)
							(end -0.1778 0.2794)
						)
						(arc
							(start 0.1778 0.2794)
							(mid 0.249642 0.249642)
							(end 0.2794 0.1778)
						)
						(arc
							(start 0.2794 -0.1778)
							(mid 0.249642 -0.249642)
							(end 0.1778 -0.2794)
						)
					)
					(width 0)
					(fill yes)
				)
			)
		)
	)
	(footprint ""
		(layer "F.Cu")
		(at 457.6699 -291.127942 -90)
		(property "Reference" "R359"
			(at 0 0 270)
			(layer "F.SilkS")
			(hide yes)
			(effects
				(font
					(size 1.27 1.27)
				)
			)
		)
		(property "Value" "2R6F-GP"
			(at -0.0508 -4.8514 270)
			(unlocked yes)
			(layer "F.Fab")
			(hide yes)
			(effects
				(font
					(size 1.016 1.016)
					(thickness 0.1524)
				)
			)
		)
		(property "Device Type" "R1206H26"
			(at 0 -6.3754 270)
			(unlocked yes)
			(layer "F.Fab")
			(hide yes)
			(effects
				(font
					(size 1.016 1.016)
					(thickness 0.1524)
				)
			)
		)
		(duplicate_pad_numbers_are_jumpers no)
		(fp_line
			(start -1.016 2.2352)
			(end -1.016 -2.2352)
			(stroke
				(width 0.1524)
				(type default)
			)
			(layer "F.SilkS")
		)
		(fp_line
			(start 1.016 2.2352)
			(end -1.016 2.2352)
			(stroke
				(width 0.1524)
				(type default)
			)
			(layer "F.SilkS")
		)
		(fp_line
			(start -1.016 -2.2352)
			(end 1.016 -2.2352)
			(stroke
				(width 0.1524)
				(type default)
			)
			(layer "F.SilkS")
		)
		(fp_line
			(start 1.016 -2.2352)
			(end 1.016 2.2352)
			(stroke
				(width 0.1524)
				(type default)
			)
			(layer "F.SilkS")
		)
		(fp_rect
			(start -1.0922 2.3114)
			(end 1.0922 -2.3114)
			(stroke
				(width 0)
				(type default)
			)
			(fill no)
			(layer "F.CrtYd")
		)
		(fp_poly
			(pts
				(xy -1.0922 -2.3114) (xy 1.0922 -2.3114) (xy 1.0922 2.3114) (xy -1.0922 2.3114)
			)
			(stroke
				(width 0)
				(type default)
			)
			(fill no)
			(layer "F.Fab")
		)
		(pad "1" smd rect
			(at 0 -1.397 270)
			(size 1.651 1.27)
			(layers "F.Cu" "F.Mask" "F.Paste")
			(net "P5V_HDD10")
		)
		(pad "2" smd rect
			(at 0 1.397 270)
			(size 1.651 1.27)
			(layers "F.Cu" "F.Mask" "F.Paste")
			(net "5V_PRE_10")
		)
	)
	(footprint ""
		(layer "F.Cu")
		(at 440.738514 -290.951412 90)
		(property "Reference" "R595"
			(at 0 0 90)
			(layer "F.SilkS")
			(hide yes)
			(effects
				(font
					(size 1.27 1.27)
				)
			)
		)
		(property "Value" "4K7R2J-2-GP"
			(at 0.064008 -3.993896 90)
			(unlocked yes)
			(layer "F.Fab")
			(hide yes)
			(effects
				(font
					(size 1.016 1.016)
					(thickness 0.1524)
				)
			)
		)
		(property "Device Type" "R402H16"
			(at 0.064008 -5.517896 90)
			(unlocked yes)
			(layer "F.Fab")
			(hide yes)
			(effects
				(font
					(size 1.016 1.016)
					(thickness 0.1524)
				)
			)
		)
		(duplicate_pad_numbers_are_jumpers no)
		(fp_line
			(start 0.508 -0.9398)
			(end -0.508 -0.9398)
			(stroke
				(width 0.1524)
				(type default)
			)
			(layer "F.SilkS")
		)
		(fp_line
			(start -0.508 -0.9398)
			(end -0.508 0.9398)
			(stroke
				(width 0.1524)
				(type default)
			)
			(layer "F.SilkS")
		)
		(fp_rect
			(start -0.508 0.9398)
			(end 0.508 -0.9398)
			(stroke
				(width 0)
				(type default)
			)
			(fill no)
			(layer "F.CrtYd")
		)
		(fp_rect
			(start -0.508 0.9398)
			(end 0.508 -0.9398)
			(stroke
				(width 0)
				(type default)
			)
			(fill no)
			(layer "F.Fab")
		)
		(pad "1" smd custom
			(at 0 -0.4445 90)
			(size 0.1397 0.1397)
			(layers "F.Cu" "F.Mask" "F.Paste")
			(net "DRIVE_B_34_FLT_LED")
			(options
				(clearance outline)
				(anchor circle)
			)
			(primitives
				(gr_poly
					(pts
						(arc
							(start -0.1778 -0.2794)
							(mid -0.249642 -0.249642)
							(end -0.2794 -0.1778)
						)
						(arc
							(start -0.2794 0.1778)
							(mid -0.249642 0.249642)
							(end -0.1778 0.2794)
						)
						(arc
							(start 0.1778 0.2794)
							(mid 0.249642 0.249642)
							(end 0.2794 0.1778)
						)
						(arc
							(start 0.2794 -0.1778)
							(mid 0.249642 -0.249642)
							(end 0.1778 -0.2794)
						)
					)
					(width 0)
					(fill yes)
				)
			)
		)
		(pad "2" smd custom
			(at 0 0.4445 90)
			(size 0.1397 0.1397)
			(layers "F.Cu" "F.Mask" "F.Paste")
			(net "GND")
			(options
				(clearance outline)
				(anchor circle)
			)
			(primitives
				(gr_poly
					(pts
						(arc
							(start -0.1778 -0.2794)
							(mid -0.249642 -0.249642)
							(end -0.2794 -0.1778)
						)
						(arc
							(start -0.2794 0.1778)
							(mid -0.249642 0.249642)
							(end -0.1778 0.2794)
						)
						(arc
							(start 0.1778 0.2794)
							(mid 0.249642 0.249642)
							(end 0.2794 0.1778)
						)
						(arc
							(start 0.2794 -0.1778)
							(mid 0.249642 -0.249642)
							(end 0.1778 -0.2794)
						)
					)
					(width 0)
					(fill yes)
				)
			)
		)
	)
	(footprint ""
		(layer "F.Cu")
		(at 32.463486 -43.660568 90)
		(property "Reference" "C351"
			(at 0 0 90)
			(layer "F.SilkS")
			(hide yes)
			(effects
				(font
					(size 1.27 1.27)
				)
			)
		)
		(property "Value" "SCD01U16V1KX-GP"
			(at -2.8321 -1.7399 90)
			(unlocked yes)
			(layer "F.Fab")
			(hide yes)
			(effects
				(font
					(size 1.016 1.016)
					(thickness 0.1524)
				)
			)
		)
		(property "Device Type" "C0201H13"
			(at -2.8321 -3.2639 90)
			(unlocked yes)
			(layer "F.Fab")
			(hide yes)
			(effects
				(font
					(size 1.016 1.016)
					(thickness 0.1524)
				)
			)
		)
		(duplicate_pad_numbers_are_jumpers no)
		(fp_rect
			(start -0.2794 0.6477)
			(end 0.2794 -0.6477)
			(stroke
				(width 0)
				(type default)
			)
			(fill no)
			(layer "F.CrtYd")
		)
		(fp_rect
			(start -0.2794 0.6477)
			(end 0.2794 -0.6477)
			(stroke
				(width 0)
				(type default)
			)
			(fill no)
			(layer "F.Fab")
		)
		(pad "1" smd custom
			(at 0 -0.2794 90)
			(size 0.0762 0.0762)
			(layers "F.Cu" "F.Mask" "F.Paste")
			(net "SAS_HDD_RX_P24")
			(options
				(clearance outline)
				(anchor circle)
			)
			(primitives
				(gr_poly
					(pts
						(arc
							(start 0.1524 -0.127)
							(mid 0.137521 -0.162921)
							(end 0.1016 -0.1778)
						)
						(arc
							(start -0.1016 -0.1778)
							(mid -0.137521 -0.162921)
							(end -0.1524 -0.127)
						)
						(arc
							(start -0.1524 0.127)
							(mid -0.137521 0.162921)
							(end -0.1016 0.1778)
						)
						(arc
							(start 0.1016 0.1778)
							(mid 0.137521 0.162921)
							(end 0.1524 0.127)
						)
					)
					(width 0)
					(fill yes)
				)
			)
		)
		(pad "2" smd custom
			(at 0 0.2794 90)
			(size 0.0762 0.0762)
			(layers "F.Cu" "F.Mask" "F.Paste")
			(net "PHY_SCC_A_TO_DRV_A_24_DP")
			(options
				(clearance outline)
				(anchor circle)
			)
			(primitives
				(gr_poly
					(pts
						(arc
							(start 0.1524 -0.127)
							(mid 0.137521 -0.162921)
							(end 0.1016 -0.1778)
						)
						(arc
							(start -0.1016 -0.1778)
							(mid -0.137521 -0.162921)
							(end -0.1524 -0.127)
						)
						(arc
							(start -0.1524 0.127)
							(mid -0.137521 0.162921)
							(end -0.1016 0.1778)
						)
						(arc
							(start 0.1016 0.1778)
							(mid 0.137521 0.162921)
							(end 0.1524 0.127)
						)
					)
					(width 0)
					(fill yes)
				)
			)
		)
	)
	(footprint ""
		(layer "F.Cu")
		(at 308.748938 -64.77381)
		(property "Reference" "R362"
			(at 0 0 0)
			(layer "F.SilkS")
			(hide yes)
			(effects
				(font
					(size 1.27 1.27)
				)
			)
		)
		(property "Value" "4K7R2F-GP"
			(at 0.064008 -3.993896 0)
			(unlocked yes)
			(layer "F.Fab")
			(hide yes)
			(effects
				(font
					(size 1.016 1.016)
					(thickness 0.1524)
				)
			)
		)
		(property "Device Type" "R402H16"
			(at 0.064008 -5.517896 0)
			(unlocked yes)
			(layer "F.Fab")
			(hide yes)
			(effects
				(font
					(size 1.016 1.016)
					(thickness 0.1524)
				)
			)
		)
		(duplicate_pad_numbers_are_jumpers no)
		(fp_line
			(start -0.508 -0.9398)
			(end -0.508 0.9398)
			(stroke
				(width 0.1524)
				(type default)
			)
			(layer "F.SilkS")
		)
		(fp_line
			(start 0.508 -0.9398)
			(end -0.508 -0.9398)
			(stroke
				(width 0.1524)
				(type default)
			)
			(layer "F.SilkS")
		)
		(fp_rect
			(start -0.508 0.9398)
			(end 0.508 -0.9398)
			(stroke
				(width 0)
				(type default)
			)
			(fill no)
			(layer "F.CrtYd")
		)
		(fp_rect
			(start -0.508 0.9398)
			(end 0.508 -0.9398)
			(stroke
				(width 0)
				(type default)
			)
			(fill no)
			(layer "F.Fab")
		)
		(pad "1" smd custom
			(at 0 -0.4445)
			(size 0.1397 0.1397)
			(layers "F.Cu" "F.Mask" "F.Paste")
			(net "COMP_B_FAST_THROTTLE_N")
			(options
				(clearance outline)
				(anchor circle)
			)
			(primitives
				(gr_poly
					(pts
						(arc
							(start -0.1778 -0.2794)
							(mid -0.249642 -0.249642)
							(end -0.2794 -0.1778)
						)
						(arc
							(start -0.2794 0.1778)
							(mid -0.249642 0.249642)
							(end -0.1778 0.2794)
						)
						(arc
							(start 0.1778 0.2794)
							(mid 0.249642 0.249642)
							(end 0.2794 0.1778)
						)
						(arc
							(start 0.2794 -0.1778)
							(mid 0.249642 -0.249642)
							(end 0.1778 -0.2794)
						)
					)
					(width 0)
					(fill yes)
				)
			)
		)
		(pad "2" smd custom
			(at 0 0.4445)
			(size 0.1397 0.1397)
			(layers "F.Cu" "F.Mask" "F.Paste")
			(net "P3V3_STBY_B")
			(options
				(clearance outline)
				(anchor circle)
			)
			(primitives
				(gr_poly
					(pts
						(arc
							(start -0.1778 -0.2794)
							(mid -0.249642 -0.249642)
							(end -0.2794 -0.1778)
						)
						(arc
							(start -0.2794 0.1778)
							(mid -0.249642 0.249642)
							(end -0.1778 0.2794)
						)
						(arc
							(start 0.1778 0.2794)
							(mid 0.249642 0.249642)
							(end 0.2794 0.1778)
						)
						(arc
							(start 0.2794 -0.1778)
							(mid 0.249642 -0.249642)
							(end 0.1778 -0.2794)
						)
					)
					(width 0)
					(fill yes)
				)
			)
		)
	)
	(footprint ""
		(layer "F.Cu")
		(at 98.897948 -176.127918 90)
		(property "Reference" "C226"
			(at 0 0 90)
			(layer "F.SilkS")
			(hide yes)
			(effects
				(font
					(size 1.27 1.27)
				)
			)
		)
		(property "Value" "SCD01U50V2KX-1GP"
			(at 1.1811 -2.7051 90)
			(unlocked yes)
			(layer "F.Fab")
			(hide yes)
			(effects
				(font
					(size 1.016 1.016)
					(thickness 0.1524)
				)
			)
		)
		(property "Device Type" "C402H22"
			(at 1.1811 -4.2291 90)
			(unlocked yes)
			(layer "F.Fab")
			(hide yes)
			(effects
				(font
					(size 1.016 1.016)
					(thickness 0.1524)
				)
			)
		)
		(duplicate_pad_numbers_are_jumpers no)
		(fp_rect
			(start -0.4318 0.9525)
			(end 0.4318 -0.9525)
			(stroke
				(width 0)
				(type default)
			)
			(fill no)
			(layer "F.CrtYd")
		)
		(fp_rect
			(start -0.4318 0.9525)
			(end 0.4318 -0.9525)
			(stroke
				(width 0)
				(type default)
			)
			(fill no)
			(layer "F.Fab")
		)
		(pad "1" smd custom
			(at 0 -0.4445 90)
			(size 0.1524 0.1524)
			(layers "F.Cu" "F.Mask" "F.Paste")
			(net "HDD_PRSNT_14")
			(options
				(clearance outline)
				(anchor circle)
			)
			(primitives
				(gr_poly
					(pts
						(arc
							(start 0.3048 -0.2032)
							(mid 0.275042 -0.275042)
							(end 0.2032 -0.3048)
						)
						(arc
							(start -0.2032 -0.3048)
							(mid -0.275042 -0.275042)
							(end -0.3048 -0.2032)
						)
						(arc
							(start -0.3048 0.2032)
							(mid -0.275042 0.275042)
							(end -0.2032 0.3048)
						)
						(arc
							(start 0.2032 0.3048)
							(mid 0.275042 0.275042)
							(end 0.3048 0.2032)
						)
					)
					(width 0)
					(fill yes)
				)
			)
		)
		(pad "2" smd custom
			(at 0 0.4445 90)
			(size 0.1524 0.1524)
			(layers "F.Cu" "F.Mask" "F.Paste")
			(net "GND")
			(options
				(clearance outline)
				(anchor circle)
			)
			(primitives
				(gr_poly
					(pts
						(arc
							(start 0.3048 -0.2032)
							(mid 0.275042 -0.275042)
							(end 0.2032 -0.3048)
						)
						(arc
							(start -0.2032 -0.3048)
							(mid -0.275042 -0.275042)
							(end -0.3048 -0.2032)
						)
						(arc
							(start -0.3048 0.2032)
							(mid -0.275042 0.275042)
							(end -0.2032 0.3048)
						)
						(arc
							(start 0.2032 0.3048)
							(mid 0.275042 0.275042)
							(end 0.3048 0.2032)
						)
					)
					(width 0)
					(fill yes)
				)
			)
		)
	)
	(footprint ""
		(layer "F.Cu")
		(at 285.5214 -284.5308 180)
		(property "Reference" "R124"
			(at 0 0 180)
			(layer "F.SilkS")
			(hide yes)
			(effects
				(font
					(size 1.27 1.27)
				)
			)
		)
		(property "Value" "4K7R2F-GP"
			(at 0.064008 -3.993896 180)
			(unlocked yes)
			(layer "F.Fab")
			(hide yes)
			(effects
				(font
					(size 1.016 1.016)
					(thickness 0.1524)
				)
			)
		)
		(property "Device Type" "R402H16"
			(at 0.064008 -5.517896 180)
			(unlocked yes)
			(layer "F.Fab")
			(hide yes)
			(effects
				(font
					(size 1.016 1.016)
					(thickness 0.1524)
				)
			)
		)
		(duplicate_pad_numbers_are_jumpers no)
		(fp_line
			(start 0.508 -0.9398)
			(end -0.508 -0.9398)
			(stroke
				(width 0.1524)
				(type default)
			)
			(layer "F.SilkS")
		)
		(fp_line
			(start -0.508 -0.9398)
			(end -0.508 0.9398)
			(stroke
				(width 0.1524)
				(type default)
			)
			(layer "F.SilkS")
		)
		(fp_rect
			(start -0.508 0.9398)
			(end 0.508 -0.9398)
			(stroke
				(width 0)
				(type default)
			)
			(fill no)
			(layer "F.CrtYd")
		)
		(fp_rect
			(start -0.508 0.9398)
			(end 0.508 -0.9398)
			(stroke
				(width 0)
				(type default)
			)
			(fill no)
			(layer "F.Fab")
		)
		(pad "1" smd custom
			(at 0 -0.4445 180)
			(size 0.1397 0.1397)
			(layers "F.Cu" "F.Mask" "F.Paste")
			(net "IO_EXP2_HDD_FAULT_A0")
			(options
				(clearance outline)
				(anchor circle)
			)
			(primitives
				(gr_poly
					(pts
						(arc
							(start -0.1778 -0.2794)
							(mid -0.249642 -0.249642)
							(end -0.2794 -0.1778)
						)
						(arc
							(start -0.2794 0.1778)
							(mid -0.249642 0.249642)
							(end -0.1778 0.2794)
						)
						(arc
							(start 0.1778 0.2794)
							(mid 0.249642 0.249642)
							(end 0.2794 0.1778)
						)
						(arc
							(start 0.2794 -0.1778)
							(mid 0.249642 -0.249642)
							(end 0.1778 -0.2794)
						)
					)
					(width 0)
					(fill yes)
				)
			)
		)
		(pad "2" smd custom
			(at 0 0.4445 180)
			(size 0.1397 0.1397)
			(layers "F.Cu" "F.Mask" "F.Paste")
			(net "GND")
			(options
				(clearance outline)
				(anchor circle)
			)
			(primitives
				(gr_poly
					(pts
						(arc
							(start -0.1778 -0.2794)
							(mid -0.249642 -0.249642)
							(end -0.2794 -0.1778)
						)
						(arc
							(start -0.2794 0.1778)
							(mid -0.249642 0.249642)
							(end -0.1778 0.2794)
						)
						(arc
							(start 0.1778 0.2794)
							(mid 0.249642 0.249642)
							(end 0.2794 0.1778)
						)
						(arc
							(start 0.2794 -0.1778)
							(mid 0.249642 -0.249642)
							(end 0.1778 -0.2794)
						)
					)
					(width 0)
					(fill yes)
				)
			)
		)
	)
	(footprint ""
		(layer "F.Cu")
		(at 338.709 -172.851318 90)
		(property "Reference" "C283"
			(at 0 0 90)
			(layer "F.SilkS")
			(hide yes)
			(effects
				(font
					(size 1.27 1.27)
				)
			)
		)
		(property "Value" "SCD033U25V2KX-GP"
			(at 1.1811 -2.7051 90)
			(unlocked yes)
			(layer "F.Fab")
			(hide yes)
			(effects
				(font
					(size 1.016 1.016)
					(thickness 0.1524)
				)
			)
		)
		(property "Device Type" "C402H22"
			(at 1.1811 -4.2291 90)
			(unlocked yes)
			(layer "F.Fab")
			(hide yes)
			(effects
				(font
					(size 1.016 1.016)
					(thickness 0.1524)
				)
			)
		)
		(duplicate_pad_numbers_are_jumpers no)
		(fp_rect
			(start -0.4318 0.9525)
			(end 0.4318 -0.9525)
			(stroke
				(width 0)
				(type default)
			)
			(fill no)
			(layer "F.CrtYd")
		)
		(fp_rect
			(start -0.4318 0.9525)
			(end 0.4318 -0.9525)
			(stroke
				(width 0)
				(type default)
			)
			(fill no)
			(layer "F.Fab")
		)
		(pad "1" smd custom
			(at 0 -0.4445 90)
			(size 0.1524 0.1524)
			(layers "F.Cu" "F.Mask" "F.Paste")
			(net "P12V_A")
			(options
				(clearance outline)
				(anchor circle)
			)
			(primitives
				(gr_poly
					(pts
						(arc
							(start 0.3048 -0.2032)
							(mid 0.275042 -0.275042)
							(end 0.2032 -0.3048)
						)
						(arc
							(start -0.2032 -0.3048)
							(mid -0.275042 -0.275042)
							(end -0.3048 -0.2032)
						)
						(arc
							(start -0.3048 0.2032)
							(mid -0.275042 0.275042)
							(end -0.2032 0.3048)
						)
						(arc
							(start 0.2032 0.3048)
							(mid 0.275042 0.275042)
							(end 0.3048 0.2032)
						)
					)
					(width 0)
					(fill yes)
				)
			)
		)
		(pad "2" smd custom
			(at 0 0.4445 90)
			(size 0.1524 0.1524)
			(layers "F.Cu" "F.Mask" "F.Paste")
			(net "SW_HDD_N18")
			(options
				(clearance outline)
				(anchor circle)
			)
			(primitives
				(gr_poly
					(pts
						(arc
							(start 0.3048 -0.2032)
							(mid 0.275042 -0.275042)
							(end 0.2032 -0.3048)
						)
						(arc
							(start -0.2032 -0.3048)
							(mid -0.275042 -0.275042)
							(end -0.3048 -0.2032)
						)
						(arc
							(start -0.3048 0.2032)
							(mid -0.275042 0.275042)
							(end -0.2032 0.3048)
						)
						(arc
							(start 0.2032 0.3048)
							(mid 0.275042 0.275042)
							(end 0.3048 0.2032)
						)
					)
					(width 0)
					(fill yes)
				)
			)
		)
	)
	(footprint ""
		(layer "F.Cu")
		(at 428.26686 -299.435266 -90)
		(property "Reference" "R340"
			(at 0 0 270)
			(layer "F.SilkS")
			(hide yes)
			(effects
				(font
					(size 1.27 1.27)
				)
			)
		)
		(property "Value" "2R6F-GP"
			(at -0.0508 -4.8514 270)
			(unlocked yes)
			(layer "F.Fab")
			(hide yes)
			(effects
				(font
					(size 1.016 1.016)
					(thickness 0.1524)
				)
			)
		)
		(property "Device Type" "R1206H26"
			(at 0 -6.3754 270)
			(unlocked yes)
			(layer "F.Fab")
			(hide yes)
			(effects
				(font
					(size 1.016 1.016)
					(thickness 0.1524)
				)
			)
		)
		(duplicate_pad_numbers_are_jumpers no)
		(fp_line
			(start -1.016 2.2352)
			(end -1.016 -2.2352)
			(stroke
				(width 0.1524)
				(type default)
			)
			(layer "F.SilkS")
		)
		(fp_line
			(start 1.016 2.2352)
			(end -1.016 2.2352)
			(stroke
				(width 0.1524)
				(type default)
			)
			(layer "F.SilkS")
		)
		(fp_line
			(start -1.016 -2.2352)
			(end 1.016 -2.2352)
			(stroke
				(width 0.1524)
				(type default)
			)
			(layer "F.SilkS")
		)
		(fp_line
			(start 1.016 -2.2352)
			(end 1.016 2.2352)
			(stroke
				(width 0.1524)
				(type default)
			)
			(layer "F.SilkS")
		)
		(fp_rect
			(start -1.0922 2.3114)
			(end 1.0922 -2.3114)
			(stroke
				(width 0)
				(type default)
			)
			(fill no)
			(layer "F.CrtYd")
		)
		(fp_poly
			(pts
				(xy -1.0922 -2.3114) (xy 1.0922 -2.3114) (xy 1.0922 2.3114) (xy -1.0922 2.3114)
			)
			(stroke
				(width 0)
				(type default)
			)
			(fill no)
			(layer "F.Fab")
		)
		(pad "1" smd rect
			(at 0 -1.397 270)
			(size 1.651 1.27)
			(layers "F.Cu" "F.Mask" "F.Paste")
			(net "P12V_HDD9")
		)
		(pad "2" smd rect
			(at 0 1.397 270)
			(size 1.651 1.27)
			(layers "F.Cu" "F.Mask" "F.Paste")
			(net "12V_PRE_9")
		)
	)
	(footprint ""
		(layer "F.Cu")
		(at 241.775488 -346.354908)
		(property "Reference" "R182"
			(at 0 0 0)
			(layer "F.SilkS")
			(hide yes)
			(effects
				(font
					(size 1.27 1.27)
				)
			)
		)
		(property "Value" "16K2R2F-GP"
			(at 0.064008 -3.993896 0)
			(unlocked yes)
			(layer "F.Fab")
			(hide yes)
			(effects
				(font
					(size 1.016 1.016)
					(thickness 0.1524)
				)
			)
		)
		(property "Device Type" "R402H16"
			(at 0.064008 -5.517896 0)
			(unlocked yes)
			(layer "F.Fab")
			(hide yes)
			(effects
				(font
					(size 1.016 1.016)
					(thickness 0.1524)
				)
			)
		)
		(duplicate_pad_numbers_are_jumpers no)
		(fp_line
			(start -0.508 -0.9398)
			(end -0.508 0.9398)
			(stroke
				(width 0.1524)
				(type default)
			)
			(layer "F.SilkS")
		)
		(fp_line
			(start 0.508 -0.9398)
			(end -0.508 -0.9398)
			(stroke
				(width 0.1524)
				(type default)
			)
			(layer "F.SilkS")
		)
		(fp_rect
			(start -0.508 0.9398)
			(end 0.508 -0.9398)
			(stroke
				(width 0)
				(type default)
			)
			(fill no)
			(layer "F.CrtYd")
		)
		(fp_rect
			(start -0.508 0.9398)
			(end 0.508 -0.9398)
			(stroke
				(width 0)
				(type default)
			)
			(fill no)
			(layer "F.Fab")
		)
		(pad "1" smd custom
			(at 0 -0.4445)
			(size 0.1397 0.1397)
			(layers "F.Cu" "F.Mask" "F.Paste")
			(net "P5V_A_3")
			(options
				(clearance outline)
				(anchor circle)
			)
			(primitives
				(gr_poly
					(pts
						(arc
							(start -0.1778 -0.2794)
							(mid -0.249642 -0.249642)
							(end -0.2794 -0.1778)
						)
						(arc
							(start -0.2794 0.1778)
							(mid -0.249642 0.249642)
							(end -0.1778 0.2794)
						)
						(arc
							(start 0.1778 0.2794)
							(mid 0.249642 0.249642)
							(end 0.2794 0.1778)
						)
						(arc
							(start 0.2794 -0.1778)
							(mid 0.249642 -0.249642)
							(end 0.1778 -0.2794)
						)
					)
					(width 0)
					(fill yes)
				)
			)
		)
		(pad "2" smd custom
			(at 0 0.4445)
			(size 0.1397 0.1397)
			(layers "F.Cu" "F.Mask" "F.Paste")
			(net "P5V_A_3_SENSE")
			(options
				(clearance outline)
				(anchor circle)
			)
			(primitives
				(gr_poly
					(pts
						(arc
							(start -0.1778 -0.2794)
							(mid -0.249642 -0.249642)
							(end -0.2794 -0.1778)
						)
						(arc
							(start -0.2794 0.1778)
							(mid -0.249642 0.249642)
							(end -0.1778 0.2794)
						)
						(arc
							(start 0.1778 0.2794)
							(mid 0.249642 0.249642)
							(end 0.2794 0.1778)
						)
						(arc
							(start 0.2794 -0.1778)
							(mid 0.249642 -0.249642)
							(end 0.1778 -0.2794)
						)
					)
					(width 0)
					(fill yes)
				)
			)
		)
	)
	(footprint ""
		(layer "F.Cu")
		(at 261.112 -272.288 180)
		(property "Reference" "R102"
			(at 0 0 180)
			(layer "F.SilkS")
			(hide yes)
			(effects
				(font
					(size 1.27 1.27)
				)
			)
		)
		(property "Value" "4K7R2F-GP"
			(at 0.064008 -3.993896 180)
			(unlocked yes)
			(layer "F.Fab")
			(hide yes)
			(effects
				(font
					(size 1.016 1.016)
					(thickness 0.1524)
				)
			)
		)
		(property "Device Type" "R402H16"
			(at 0.064008 -5.517896 180)
			(unlocked yes)
			(layer "F.Fab")
			(hide yes)
			(effects
				(font
					(size 1.016 1.016)
					(thickness 0.1524)
				)
			)
		)
		(duplicate_pad_numbers_are_jumpers no)
		(fp_line
			(start 0.508 -0.9398)
			(end -0.508 -0.9398)
			(stroke
				(width 0.1524)
				(type default)
			)
			(layer "F.SilkS")
		)
		(fp_line
			(start -0.508 -0.9398)
			(end -0.508 0.9398)
			(stroke
				(width 0.1524)
				(type default)
			)
			(layer "F.SilkS")
		)
		(fp_rect
			(start -0.508 0.9398)
			(end 0.508 -0.9398)
			(stroke
				(width 0)
				(type default)
			)
			(fill no)
			(layer "F.CrtYd")
		)
		(fp_rect
			(start -0.508 0.9398)
			(end 0.508 -0.9398)
			(stroke
				(width 0)
				(type default)
			)
			(fill no)
			(layer "F.Fab")
		)
		(pad "1" smd custom
			(at 0 -0.4445 180)
			(size 0.1397 0.1397)
			(layers "F.Cu" "F.Mask" "F.Paste")
			(net "P3V3_STBY_A")
			(options
				(clearance outline)
				(anchor circle)
			)
			(primitives
				(gr_poly
					(pts
						(arc
							(start -0.1778 -0.2794)
							(mid -0.249642 -0.249642)
							(end -0.2794 -0.1778)
						)
						(arc
							(start -0.2794 0.1778)
							(mid -0.249642 0.249642)
							(end -0.1778 0.2794)
						)
						(arc
							(start 0.1778 0.2794)
							(mid 0.249642 0.249642)
							(end 0.2794 0.1778)
						)
						(arc
							(start 0.2794 -0.1778)
							(mid 0.249642 -0.249642)
							(end 0.1778 -0.2794)
						)
					)
					(width 0)
					(fill yes)
				)
			)
		)
		(pad "2" smd custom
			(at 0 0.4445 180)
			(size 0.1397 0.1397)
			(layers "F.Cu" "F.Mask" "F.Paste")
			(net "IO_EXP0_HDD_FAULT_A1")
			(options
				(clearance outline)
				(anchor circle)
			)
			(primitives
				(gr_poly
					(pts
						(arc
							(start -0.1778 -0.2794)
							(mid -0.249642 -0.249642)
							(end -0.2794 -0.1778)
						)
						(arc
							(start -0.2794 0.1778)
							(mid -0.249642 0.249642)
							(end -0.1778 0.2794)
						)
						(arc
							(start 0.1778 0.2794)
							(mid 0.249642 0.249642)
							(end 0.2794 0.1778)
						)
						(arc
							(start 0.2794 -0.1778)
							(mid 0.249642 -0.249642)
							(end 0.1778 -0.2794)
						)
					)
					(width 0)
					(fill yes)
				)
			)
		)
	)
	(footprint ""
		(layer "F.Cu")
		(at 158.342838 -27.338782 -90)
		(property "Reference" "R11"
			(at 0 0 270)
			(layer "F.SilkS")
			(hide yes)
			(effects
				(font
					(size 1.27 1.27)
				)
			)
		)
		(property "Value" "0R2J-2-GP"
			(at 0.064008 -3.993896 270)
			(unlocked yes)
			(layer "F.Fab")
			(hide yes)
			(effects
				(font
					(size 1.016 1.016)
					(thickness 0.1524)
				)
			)
		)
		(property "Device Type" "R402H16"
			(at 0.064008 -5.517896 270)
			(unlocked yes)
			(layer "F.Fab")
			(hide yes)
			(effects
				(font
					(size 1.016 1.016)
					(thickness 0.1524)
				)
			)
		)
		(duplicate_pad_numbers_are_jumpers no)
		(fp_line
			(start -0.508 -0.9398)
			(end -0.508 0.9398)
			(stroke
				(width 0.1524)
				(type default)
			)
			(layer "F.SilkS")
		)
		(fp_line
			(start 0.508 -0.9398)
			(end -0.508 -0.9398)
			(stroke
				(width 0.1524)
				(type default)
			)
			(layer "F.SilkS")
		)
		(fp_rect
			(start -0.508 0.9398)
			(end 0.508 -0.9398)
			(stroke
				(width 0)
				(type default)
			)
			(fill no)
			(layer "F.CrtYd")
		)
		(fp_rect
			(start -0.508 0.9398)
			(end 0.508 -0.9398)
			(stroke
				(width 0)
				(type default)
			)
			(fill no)
			(layer "F.Fab")
		)
		(pad "1" smd custom
			(at 0 -0.4445 270)
			(size 0.1397 0.1397)
			(layers "F.Cu" "F.Mask" "F.Paste")
			(net "GND")
			(options
				(clearance outline)
				(anchor circle)
			)
			(primitives
				(gr_poly
					(pts
						(arc
							(start -0.1778 -0.2794)
							(mid -0.249642 -0.249642)
							(end -0.2794 -0.1778)
						)
						(arc
							(start -0.2794 0.1778)
							(mid -0.249642 0.249642)
							(end -0.1778 0.2794)
						)
						(arc
							(start 0.1778 0.2794)
							(mid 0.249642 0.249642)
							(end 0.2794 0.1778)
						)
						(arc
							(start 0.2794 -0.1778)
							(mid 0.249642 -0.249642)
							(end 0.1778 -0.2794)
						)
					)
					(width 0)
					(fill yes)
				)
			)
		)
		(pad "2" smd custom
			(at 0 0.4445 270)
			(size 0.1397 0.1397)
			(layers "F.Cu" "F.Mask" "F.Paste")
			(net "IOM_A_MATED_N")
			(options
				(clearance outline)
				(anchor circle)
			)
			(primitives
				(gr_poly
					(pts
						(arc
							(start -0.1778 -0.2794)
							(mid -0.249642 -0.249642)
							(end -0.2794 -0.1778)
						)
						(arc
							(start -0.2794 0.1778)
							(mid -0.249642 0.249642)
							(end -0.1778 0.2794)
						)
						(arc
							(start 0.1778 0.2794)
							(mid 0.249642 0.249642)
							(end 0.2794 0.1778)
						)
						(arc
							(start 0.2794 -0.1778)
							(mid 0.249642 -0.249642)
							(end 0.1778 -0.2794)
						)
					)
					(width 0)
					(fill yes)
				)
			)
		)
	)
	(footprint ""
		(layer "F.Cu")
		(at 86.121748 -276.040342 -90)
		(property "Reference" "R184"
			(at 0 0 270)
			(layer "F.SilkS")
			(hide yes)
			(effects
				(font
					(size 1.27 1.27)
				)
			)
		)
		(property "Value" "1KR2F-3-GP"
			(at 0.064008 -3.993896 270)
			(unlocked yes)
			(layer "F.Fab")
			(hide yes)
			(effects
				(font
					(size 1.016 1.016)
					(thickness 0.1524)
				)
			)
		)
		(property "Device Type" "R402H16"
			(at 0.064008 -5.517896 270)
			(unlocked yes)
			(layer "F.Fab")
			(hide yes)
			(effects
				(font
					(size 1.016 1.016)
					(thickness 0.1524)
				)
			)
		)
		(duplicate_pad_numbers_are_jumpers no)
		(fp_line
			(start -0.508 -0.9398)
			(end -0.508 0.9398)
			(stroke
				(width 0.1524)
				(type default)
			)
			(layer "F.SilkS")
		)
		(fp_line
			(start 0.508 -0.9398)
			(end -0.508 -0.9398)
			(stroke
				(width 0.1524)
				(type default)
			)
			(layer "F.SilkS")
		)
		(fp_rect
			(start -0.508 0.9398)
			(end 0.508 -0.9398)
			(stroke
				(width 0)
				(type default)
			)
			(fill no)
			(layer "F.CrtYd")
		)
		(fp_rect
			(start -0.508 0.9398)
			(end 0.508 -0.9398)
			(stroke
				(width 0)
				(type default)
			)
			(fill no)
			(layer "F.Fab")
		)
		(pad "1" smd custom
			(at 0 -0.4445 270)
			(size 0.1397 0.1397)
			(layers "F.Cu" "F.Mask" "F.Paste")
			(net "P3V3_STBY_A")
			(options
				(clearance outline)
				(anchor circle)
			)
			(primitives
				(gr_poly
					(pts
						(arc
							(start -0.1778 -0.2794)
							(mid -0.249642 -0.249642)
							(end -0.2794 -0.1778)
						)
						(arc
							(start -0.2794 0.1778)
							(mid -0.249642 0.249642)
							(end -0.1778 0.2794)
						)
						(arc
							(start 0.1778 0.2794)
							(mid 0.249642 0.249642)
							(end 0.2794 0.1778)
						)
						(arc
							(start 0.2794 -0.1778)
							(mid 0.249642 -0.249642)
							(end 0.1778 -0.2794)
						)
					)
					(width 0)
					(fill yes)
				)
			)
		)
		(pad "2" smd custom
			(at 0 0.4445 270)
			(size 0.1397 0.1397)
			(layers "F.Cu" "F.Mask" "F.Paste")
			(net "SW_PWR_R_HDD2")
			(options
				(clearance outline)
				(anchor circle)
			)
			(primitives
				(gr_poly
					(pts
						(arc
							(start -0.1778 -0.2794)
							(mid -0.249642 -0.249642)
							(end -0.2794 -0.1778)
						)
						(arc
							(start -0.2794 0.1778)
							(mid -0.249642 0.249642)
							(end -0.1778 0.2794)
						)
						(arc
							(start 0.1778 0.2794)
							(mid 0.249642 0.249642)
							(end 0.2794 0.1778)
						)
						(arc
							(start 0.2794 -0.1778)
							(mid 0.249642 -0.249642)
							(end 0.1778 -0.2794)
						)
					)
					(width 0)
					(fill yes)
				)
			)
		)
	)
	(footprint ""
		(layer "F.Cu")
		(at 332.105 -160.252918 -90)
		(property "Reference" "Q109"
			(at 0 0 270)
			(layer "F.SilkS")
			(hide yes)
			(effects
				(font
					(size 1.27 1.27)
				)
			)
		)
		(property "Value" "2N7002KDW-GP"
			(at -2.3622 -8.2042 270)
			(unlocked yes)
			(layer "F.Fab")
			(hide yes)
			(effects
				(font
					(size 1.016 1.016)
					(thickness 0.1524)
				)
			)
		)
		(property "Device Type" "SOT-363H44"
			(at -2.3622 -10.1092 270)
			(unlocked yes)
			(layer "F.Fab")
			(hide yes)
			(effects
				(font
					(size 1.016 1.016)
					(thickness 0.1524)
				)
			)
		)
		(duplicate_pad_numbers_are_jumpers no)
		(fp_line
			(start -1.4478 1.7018)
			(end 1.4478 1.7018)
			(stroke
				(width 0.1524)
				(type default)
			)
			(layer "F.SilkS")
		)
		(fp_line
			(start 1.4478 1.7018)
			(end 1.4478 -1.7018)
			(stroke
				(width 0.1524)
				(type default)
			)
			(layer "F.SilkS")
		)
		(fp_line
			(start -1.27 1.524)
			(end -1.27 0.6604)
			(stroke
				(width 0.4826)
				(type default)
			)
			(layer "F.SilkS")
		)
		(fp_line
			(start -1.4478 -1.7018)
			(end -1.4478 1.7018)
			(stroke
				(width 0.1524)
				(type default)
			)
			(layer "F.SilkS")
		)
		(fp_line
			(start 1.4478 -1.7018)
			(end -1.4478 -1.7018)
			(stroke
				(width 0.1524)
				(type default)
			)
			(layer "F.SilkS")
		)
		(fp_poly
			(pts
				(xy -1.524 -1.778) (xy 1.524 -1.778) (xy 1.524 1.778) (xy -1.524 1.778)
			)
			(stroke
				(width 0)
				(type default)
			)
			(fill no)
			(layer "F.CrtYd")
		)
		(fp_poly
			(pts
				(xy -1.524 -1.778) (xy 1.524 -1.778) (xy 1.524 1.778) (xy -1.524 1.778)
			)
			(stroke
				(width 0)
				(type default)
			)
			(fill no)
			(layer "F.Fab")
		)
		(pad "1" smd rect
			(at -0.65024 0.9398 270)
			(size 0.4064 1.016)
			(layers "F.Cu" "F.Mask" "F.Paste")
			(net "GND")
		)
		(pad "2" smd rect
			(at 0 0.9398 270)
			(size 0.4064 1.016)
			(layers "F.Cu" "F.Mask" "F.Paste")
			(net "SW_PWR_R_HDD18")
		)
		(pad "3" smd rect
			(at 0.65024 0.9398 270)
			(size 0.4064 1.016)
			(layers "F.Cu" "F.Mask" "F.Paste")
			(net "SW_HDD_P18")
		)
		(pad "4" smd rect
			(at 0.65024 -0.9398 270)
			(size 0.4064 1.016)
			(layers "F.Cu" "F.Mask" "F.Paste")
			(net "GND")
		)
		(pad "5" smd rect
			(at 0 -0.9398 270)
			(size 0.4064 1.016)
			(layers "F.Cu" "F.Mask" "F.Paste")
			(net "SW_HDD_G18")
		)
		(pad "6" smd rect
			(at -0.65024 -0.9398 270)
			(size 0.4064 1.016)
			(layers "F.Cu" "F.Mask" "F.Paste")
			(net "SW_HDD_R18")
		)
	)
	(footprint ""
		(layer "F.Cu")
		(at 451.749922 -172.909992 -90)
		(property "Reference" "HDDSAS22"
			(at 0 0 270)
			(layer "F.SilkS")
			(hide yes)
			(effects
				(font
					(size 1.27 1.27)
				)
			)
		)
		(property "Value" "SKT-SAS15P-14P-45-GP"
			(at -20.7645 -8.9789 270)
			(unlocked yes)
			(layer "F.Fab")
			(hide yes)
			(effects
				(font
					(size 1.016 1.016)
					(thickness 0.1524)
				)
			)
		)
		(property "Device Type" "10120818-001C-TRLF"
			(at -20.7645 -10.5029 270)
			(unlocked yes)
			(layer "F.Fab")
			(hide yes)
			(effects
				(font
					(size 1.016 1.016)
					(thickness 0.1524)
				)
			)
		)
		(duplicate_pad_numbers_are_jumpers no)
		(fp_line
			(start 1.651 4.2926)
			(end 1.651 3.0099)
			(stroke
				(width 0.1524)
				(type default)
			)
			(layer "F.SilkS")
		)
		(fp_line
			(start 8.509 4.2926)
			(end 1.651 4.2926)
			(stroke
				(width 0.1524)
				(type default)
			)
			(layer "F.SilkS")
		)
		(fp_line
			(start -23.4188 3.0099)
			(end -23.4188 -3.2512)
			(stroke
				(width 0.1524)
				(type default)
			)
			(layer "F.SilkS")
		)
		(fp_line
			(start 1.651 3.0099)
			(end -23.4188 3.0099)
			(stroke
				(width 0.1524)
				(type default)
			)
			(layer "F.SilkS")
		)
		(fp_line
			(start 8.509 3.0099)
			(end 8.509 4.2926)
			(stroke
				(width 0.1524)
				(type default)
			)
			(layer "F.SilkS")
		)
		(fp_line
			(start 23.4188 3.0099)
			(end 8.509 3.0099)
			(stroke
				(width 0.1524)
				(type default)
			)
			(layer "F.SilkS")
		)
		(fp_line
			(start -23.4188 -3.2512)
			(end 23.4188 -3.2512)
			(stroke
				(width 0.1524)
				(type default)
			)
			(layer "F.SilkS")
		)
		(fp_line
			(start 23.4188 -3.2512)
			(end 23.4188 3.0099)
			(stroke
				(width 0.1524)
				(type default)
			)
			(layer "F.SilkS")
		)
		(fp_line
			(start 15.5067 -3.3401)
			(end 16.2687 -3.3401)
			(stroke
				(width 0.3302)
				(type default)
			)
			(layer "F.SilkS")
		)
		(fp_poly
			(pts
				(xy 15.868904 -3.230372) (xy 16.503904 -3.865372) (xy 15.233904 -3.865372)
			)
			(stroke
				(width 0)
				(type default)
			)
			(fill yes)
			(layer "F.SilkS")
		)
		(fp_poly
			(pts
				(xy -22.8727 -2.7559) (xy 22.8727 -2.7559) (xy 22.8727 2.7559) (xy 8.255 2.7559) (xy 8.255 3.5179)
				(xy 1.905 3.5179) (xy 1.905 2.7559) (xy -22.8727 2.7559)
			)
			(stroke
				(width 0)
				(type default)
			)
			(fill no)
			(layer "F.CrtYd")
		)
		(fp_poly
			(pts
				(xy 1.397 4.5466) (xy 1.397 3.2639) (xy -23.6728 3.2639) (xy -23.6728 -3.5052) (xy 23.6728 -3.5052)
				(xy 23.6728 -0.00635) (xy 22.8727 -0.00635) (xy 22.8727 -2.7559) (xy -22.8727 -2.7559) (xy -22.8727 2.7559)
				(xy 1.905 2.7559) (xy 1.905 3.5179) (xy 8.255 3.5179) (xy 8.255 2.7559) (xy 22.8727 2.7559) (xy 22.8727 0.00635)
				(xy 23.6728 0.00635) (xy 23.6728 3.2639) (xy 8.763 3.2639) (xy 8.763 4.5466)
			)
			(stroke
				(width 0)
				(type default)
			)
			(fill no)
			(layer "F.CrtYd")
		)
		(fp_poly
			(pts
				(xy 1.397 4.5466) (xy 1.397 3.2639) (xy -23.6728 3.2639) (xy -23.6728 -3.5052) (xy 23.6728 -3.5052)
				(xy 23.6728 3.2639) (xy 8.763 3.2639) (xy 8.763 4.5466)
			)
			(stroke
				(width 0)
				(type default)
			)
			(fill no)
			(layer "F.Fab")
		)
		(pad "" np_thru_hole circle
			(at -18.874994 0 270)
			(size 0.254 0.254)
			(drill 1.3462)
			(layers "*.Cu" "*.Mask")
			(clearance 0.9017)
			(thermal_gap 0.9017)
		)
		(pad "" np_thru_hole circle
			(at 18.874994 0 270)
			(size 0.254 0.254)
			(drill 0.9398)
			(layers "*.Cu" "*.Mask")
			(clearance 0.6985)
			(thermal_gap 0.6985)
		)
		(pad "G1" smd rect
			(at 21.874988 0 270)
			(size 2.5908 2.5908)
			(layers "F.Cu" "F.Mask" "F.Paste")
			(net "GND")
		)
		(pad "G2" smd rect
			(at -21.874988 0 270)
			(size 2.5908 2.5908)
			(layers "F.Cu" "F.Mask" "F.Paste")
			(net "GND")
		)
		(pad "P1" smd rect
			(at 1.905 -1.82499 270)
			(size 0.6096 2.3622)
			(layers "F.Cu" "F.Mask" "F.Paste")
			(net "Net_2101")
		)
		(pad "P2" smd rect
			(at 0.635 -1.82499 270)
			(size 0.6096 2.3622)
			(layers "F.Cu" "F.Mask" "F.Paste")
			(net "Net_2102")
		)
		(pad "P3" smd rect
			(at -0.635 -1.82499 270)
			(size 0.6096 2.3622)
			(layers "F.Cu" "F.Mask" "F.Paste")
			(net "Net_2103")
		)
		(pad "P4" smd rect
			(at -1.905 -1.82499 270)
			(size 0.6096 2.3622)
			(layers "F.Cu" "F.Mask" "F.Paste")
			(net "GND")
		)
		(pad "P5" smd rect
			(at -3.175 -1.82499 270)
			(size 0.6096 2.3622)
			(layers "F.Cu" "F.Mask" "F.Paste")
			(net "HDD_PRSNT_22")
		)
		(pad "P6" smd rect
			(at -4.445 -1.82499 270)
			(size 0.6096 2.3622)
			(layers "F.Cu" "F.Mask" "F.Paste")
			(net "GND")
		)
		(pad "P7" smd rect
			(at -5.715 -1.82499 270)
			(size 0.6096 2.3622)
			(layers "F.Cu" "F.Mask" "F.Paste")
			(net "5V_PRE_22")
		)
		(pad "P8" smd rect
			(at -6.985 -1.82499 270)
			(size 0.6096 2.3622)
			(layers "F.Cu" "F.Mask" "F.Paste")
			(net "P5V_HDD22")
		)
		(pad "P9" smd rect
			(at -8.255 -1.82499 270)
			(size 0.6096 2.3622)
			(layers "F.Cu" "F.Mask" "F.Paste")
			(net "P5V_HDD22")
		)
		(pad "P10" smd rect
			(at -9.525 -1.82499 270)
			(size 0.6096 2.3622)
			(layers "F.Cu" "F.Mask" "F.Paste")
			(net "GND")
		)
		(pad "P11" smd rect
			(at -10.795 -1.82499 270)
			(size 0.6096 2.3622)
			(layers "F.Cu" "F.Mask" "F.Paste")
			(net "ACT_HDD_22")
		)
		(pad "P12" smd rect
			(at -12.065 -1.82499 270)
			(size 0.6096 2.3622)
			(layers "F.Cu" "F.Mask" "F.Paste")
			(net "GND")
		)
		(pad "P13" smd rect
			(at -13.335 -1.82499 270)
			(size 0.6096 2.3622)
			(layers "F.Cu" "F.Mask" "F.Paste")
			(net "12V_PRE_22")
		)
		(pad "P14" smd rect
			(at -14.605 -1.82499 270)
			(size 0.6096 2.3622)
			(layers "F.Cu" "F.Mask" "F.Paste")
			(net "P12V_HDD22")
		)
		(pad "P15" smd rect
			(at -15.875 -1.82499 270)
			(size 0.6096 2.3622)
			(layers "F.Cu" "F.Mask" "F.Paste")
			(net "P12V_HDD22")
		)
		(pad "S1" smd rect
			(at 15.875 -1.82499 270)
			(size 0.6096 2.3622)
			(layers "F.Cu" "F.Mask" "F.Paste")
			(net "GND")
		)
		(pad "S2" smd rect
			(at 14.605 -1.82499 270)
			(size 0.6096 2.3622)
			(layers "F.Cu" "F.Mask" "F.Paste")
			(net "SAS_HDD_RX_P22")
		)
		(pad "S3" smd rect
			(at 13.335 -1.82499 270)
			(size 0.6096 2.3622)
			(layers "F.Cu" "F.Mask" "F.Paste")
			(net "SAS_HDD_RX_N22")
		)
		(pad "S4" smd rect
			(at 12.065 -1.82499 270)
			(size 0.6096 2.3622)
			(layers "F.Cu" "F.Mask" "F.Paste")
			(net "GND")
		)
		(pad "S5" smd rect
			(at 10.795 -1.82499 270)
			(size 0.6096 2.3622)
			(layers "F.Cu" "F.Mask" "F.Paste")
			(net "PHY_DRV_A_TO_SCC_A_22_DN")
		)
		(pad "S6" smd rect
			(at 9.525 -1.82499 270)
			(size 0.6096 2.3622)
			(layers "F.Cu" "F.Mask" "F.Paste")
			(net "PHY_DRV_A_TO_SCC_A_22_DP")
		)
		(pad "S7" smd rect
			(at 8.255 -1.82499 270)
			(size 0.6096 2.3622)
			(layers "F.Cu" "F.Mask" "F.Paste")
			(net "GND")
		)
		(pad "S8" smd rect
			(at 7.480046 2.845054 270)
			(size 0.508 2.3622)
			(layers "F.Cu" "F.Mask" "F.Paste")
			(net "GND")
		)
		(pad "S9" smd rect
			(at 6.679946 2.845054 270)
			(size 0.508 2.3622)
			(layers "F.Cu" "F.Mask" "F.Paste")
			(net "Net_460")
		)
		(pad "S10" smd rect
			(at 5.8801 2.845054 270)
			(size 0.508 2.3622)
			(layers "F.Cu" "F.Mask" "F.Paste")
			(net "Net_352")
		)
		(pad "S11" smd rect
			(at 5.08 2.845054 270)
			(size 0.508 2.3622)
			(layers "F.Cu" "F.Mask" "F.Paste")
			(net "GND")
		)
		(pad "S12" smd rect
			(at 4.2799 2.845054 270)
			(size 0.508 2.3622)
			(layers "F.Cu" "F.Mask" "F.Paste")
			(net "Net_388")
		)
		(pad "S13" smd rect
			(at 3.480054 2.845054 270)
			(size 0.508 2.3622)
			(layers "F.Cu" "F.Mask" "F.Paste")
			(net "Net_424")
		)
		(pad "S14" smd rect
			(at 2.679954 2.845054 270)
			(size 0.508 2.3622)
			(layers "F.Cu" "F.Mask" "F.Paste")
			(net "GND")
		)
		(zone
			(layer "F.Cu")
			(hatch none 0.5)
			(connect_pads
				(clearance 0)
			)
			(min_thickness 0.25)
			(keepout
				(tracks not_allowed)
				(vias allowed)
				(pads allowed)
				(copperpour not_allowed)
				(footprints allowed)
			)
			(placement
				(enabled no)
				(sheetname "")
			)
			(fill
				(thermal_gap 0.5)
				(thermal_bridge_width 0.5)
				(island_removal_mode 0)
			)
			(polygon
				(pts
					(xy 455.407522 -189.648592) (xy 448.333622 -189.648592) (xy 448.333622 -196.582792) (xy 449.438522 -196.582792)
					(xy 449.438522 -192.467992) (xy 454.061322 -192.467992) (xy 454.061322 -196.582792) (xy 455.407522 -196.582792)
				)
			)
		)
		(zone
			(layer "F.Cu")
			(hatch none 0.5)
			(connect_pads
				(clearance 0)
			)
			(min_thickness 0.25)
			(keepout
				(tracks allowed)
				(vias not_allowed)
				(pads allowed)
				(copperpour not_allowed)
				(footprints allowed)
			)
			(placement
				(enabled no)
				(sheetname "")
			)
			(fill
				(thermal_gap 0.5)
				(thermal_bridge_width 0.5)
				(island_removal_mode 0)
			)
			(polygon
				(pts
					(xy 455.407522 -189.648592) (xy 448.333622 -189.648592) (xy 448.333622 -196.582792) (xy 449.438522 -196.582792)
					(xy 449.438522 -192.467992) (xy 454.061322 -192.467992) (xy 454.061322 -196.582792) (xy 455.407522 -196.582792)
				)
			)
		)
		(zone
			(layer "F.Cu")
			(hatch none 0.5)
			(connect_pads
				(clearance 0)
			)
			(min_thickness 0.25)
			(keepout
				(tracks allowed)
				(vias not_allowed)
				(pads allowed)
				(copperpour not_allowed)
				(footprints allowed)
			)
			(placement
				(enabled no)
				(sheetname "")
			)
			(fill
				(thermal_gap 0.5)
				(thermal_bridge_width 0.5)
				(island_removal_mode 0)
			)
			(polygon
				(pts
					(xy 455.407522 -156.171392) (xy 448.333622 -156.171392) (xy 448.333622 -149.237192) (xy 449.438522 -149.237192)
					(xy 449.438522 -153.351992) (xy 454.061322 -153.351992) (xy 454.061322 -149.237192) (xy 455.407522 -149.237192)
				)
			)
		)
		(zone
			(layer "F.Cu")
			(hatch none 0.5)
			(connect_pads
				(clearance 0)
			)
			(min_thickness 0.25)
			(keepout
				(tracks not_allowed)
				(vias allowed)
				(pads allowed)
				(copperpour not_allowed)
				(footprints allowed)
			)
			(placement
				(enabled no)
				(sheetname "")
			)
			(fill
				(thermal_gap 0.5)
				(thermal_bridge_width 0.5)
				(island_removal_mode 0)
			)
			(polygon
				(pts
					(xy 455.407522 -156.171392) (xy 448.333622 -156.171392) (xy 448.333622 -149.237192) (xy 449.438522 -149.237192)
					(xy 449.438522 -153.351992) (xy 454.061322 -153.351992) (xy 454.061322 -149.237192) (xy 455.407522 -149.237192)
				)
			)
		)
		(zone
			(layers "F.Cu" "B.Cu" "In1.Cu" "In2.Cu" "In3.Cu" "In4.Cu" "In5.Cu" "In6.Cu"
				"In7.Cu" "In8.Cu" "In9.Cu" "In10.Cu"
			)
			(hatch none 0.5)
			(connect_pads
				(clearance 0)
			)
			(min_thickness 0.25)
			(keepout
				(tracks not_allowed)
				(vias allowed)
				(pads allowed)
				(copperpour not_allowed)
				(footprints allowed)
			)
			(placement
				(enabled no)
				(sheetname "")
			)
			(fill
				(thermal_gap 0.5)
				(thermal_bridge_width 0.5)
				(island_removal_mode 0)
			)
			(polygon
				(pts
					(arc
						(start 452.524622 -154.034998)
						(mid 450.975222 -154.034998)
						(end 452.524622 -154.034998)
					)
				)
			)
		)
		(zone
			(layers "F.Cu" "B.Cu" "In1.Cu" "In2.Cu" "In3.Cu" "In4.Cu" "In5.Cu" "In6.Cu"
				"In7.Cu" "In8.Cu" "In9.Cu" "In10.Cu"
			)
			(hatch none 0.5)
			(connect_pads
				(clearance 0)
			)
			(min_thickness 0.25)
			(keepout
				(tracks not_allowed)
				(vias allowed)
				(pads allowed)
				(copperpour not_allowed)
				(footprints allowed)
			)
			(placement
				(enabled no)
				(sheetname "")
			)
			(fill
				(thermal_gap 0.5)
				(thermal_bridge_width 0.5)
				(island_removal_mode 0)
			)
			(polygon
				(pts
					(arc
						(start 452.727822 -191.784986)
						(mid 450.772022 -191.784986)
						(end 452.727822 -191.784986)
					)
				)
			)
		)
	)
	(footprint ""
		(layer "F.Cu")
		(at 255.778 -295.783)
		(property "Reference" "U1"
			(at 0 0 0)
			(layer "F.SilkS")
			(hide yes)
			(effects
				(font
					(size 1.27 1.27)
				)
			)
		)
		(property "Value" "24LC64-I-SN-GP"
			(at -3.707384 -1.5367 0)
			(unlocked yes)
			(layer "F.Fab")
			(hide yes)
			(effects
				(font
					(size 1.016 1.016)
					(thickness 0.1524)
				)
			)
		)
		(property "Device Type" "SOIC8H69"
			(at -3.707384 -3.0607 0)
			(unlocked yes)
			(layer "F.Fab")
			(hide yes)
			(effects
				(font
					(size 1.016 1.016)
					(thickness 0.1524)
				)
			)
		)
		(duplicate_pad_numbers_are_jumpers no)
		(fp_line
			(start -2.7432 -1.4224)
			(end -2.7432 1.4224)
			(stroke
				(width 0.1524)
				(type default)
			)
			(layer "F.SilkS")
		)
		(fp_line
			(start -2.7432 1.4224)
			(end -2.6416 1.4224)
			(stroke
				(width 0.1524)
				(type default)
			)
			(layer "F.SilkS")
		)
		(fp_line
			(start -2.7432 1.4224)
			(end 2.1336 1.4224)
			(stroke
				(width 0.1524)
				(type default)
			)
			(layer "F.SilkS")
		)
		(fp_line
			(start -2.7178 -0.508)
			(end -2.1844 -0.0508)
			(stroke
				(width 0.1524)
				(type default)
			)
			(layer "F.SilkS")
		)
		(fp_line
			(start -2.6289 3.4417)
			(end -2.6289 1.4732)
			(stroke
				(width 0.381)
				(type default)
			)
			(layer "F.SilkS")
		)
		(fp_line
			(start -2.1844 -0.0508)
			(end -2.7178 0.508)
			(stroke
				(width 0.1524)
				(type default)
			)
			(layer "F.SilkS")
		)
		(fp_line
			(start 2.1336 -1.4224)
			(end -2.7432 -1.4224)
			(stroke
				(width 0.1524)
				(type default)
			)
			(layer "F.SilkS")
		)
		(fp_line
			(start 2.1336 1.4224)
			(end 2.1336 -1.4224)
			(stroke
				(width 0.1524)
				(type default)
			)
			(layer "F.SilkS")
		)
		(fp_poly
			(pts
				(xy -2.2098 -1.4224) (xy -2.2098 1.4224) (xy 2.2098 1.4224) (xy 2.2098 -1.4224)
			)
			(stroke
				(width 0)
				(type default)
			)
			(fill yes)
			(layer "F.SilkS")
		)
		(fp_rect
			(start -2.450084 2.999994)
			(end 2.450084 -2.999994)
			(stroke
				(width 0)
				(type default)
			)
			(fill no)
			(layer "F.CrtYd")
		)
		(fp_poly
			(pts
				(xy -2.8194 3.6322) (xy -2.8194 -3.6322) (xy 2.8194 -3.6322) (xy 2.8194 1.18364) (xy 2.450084 1.18364)
				(xy 2.450084 -2.999994) (xy -2.450084 -2.999994) (xy -2.450084 2.999994) (xy 2.450084 2.999994)
				(xy 2.450084 1.18618) (xy 2.8194 1.18618) (xy 2.8194 3.6322)
			)
			(stroke
				(width 0)
				(type default)
			)
			(fill no)
			(layer "F.CrtYd")
		)
		(fp_rect
			(start -2.8194 3.6322)
			(end 2.8194 -3.6322)
			(stroke
				(width 0)
				(type default)
			)
			(fill no)
			(layer "F.Fab")
		)
		(pad "1" smd rect
			(at -1.905 2.54)
			(size 0.635 1.651)
			(layers "F.Cu" "F.Mask" "F.Paste")
			(net "EEPROM_A0")
		)
		(pad "2" smd rect
			(at -0.635 2.54)
			(size 0.635 1.651)
			(layers "F.Cu" "F.Mask" "F.Paste")
			(net "EEPROM_A1")
		)
		(pad "3" smd rect
			(at 0.635 2.54)
			(size 0.635 1.651)
			(layers "F.Cu" "F.Mask" "F.Paste")
			(net "EEPROM_A2")
		)
		(pad "4" smd rect
			(at 1.905 2.54)
			(size 0.635 1.651)
			(layers "F.Cu" "F.Mask" "F.Paste")
			(net "GND")
		)
		(pad "5" smd rect
			(at 1.905 -2.54)
			(size 0.635 1.651)
			(layers "F.Cu" "F.Mask" "F.Paste")
			(net "EEPROM_SDA")
		)
		(pad "6" smd rect
			(at 0.635 -2.54)
			(size 0.635 1.651)
			(layers "F.Cu" "F.Mask" "F.Paste")
			(net "EEPROM_SCL")
		)
		(pad "7" smd rect
			(at -0.635 -2.54)
			(size 0.635 1.651)
			(layers "F.Cu" "F.Mask" "F.Paste")
			(net "EEPROM_WP")
		)
		(pad "8" smd rect
			(at -1.905 -2.54)
			(size 0.635 1.651)
			(layers "F.Cu" "F.Mask" "F.Paste")
			(net "P3V3_STBY_A")
		)
	)
	(footprint ""
		(layer "F.Cu")
		(at 329.819 -181.842918 180)
		(property "Reference" "C274"
			(at 0 0 180)
			(layer "F.SilkS")
			(hide yes)
			(effects
				(font
					(size 1.27 1.27)
				)
			)
		)
		(property "Value" "SC1U16V3KX-5GP"
			(at 0 -2.8194 180)
			(unlocked yes)
			(layer "F.Fab")
			(hide yes)
			(effects
				(font
					(size 1.016 1.016)
					(thickness 0.1524)
				)
			)
		)
		(property "Device Type" "C603H36"
			(at 0 -4.3434 180)
			(unlocked yes)
			(layer "F.Fab")
			(hide yes)
			(effects
				(font
					(size 1.016 1.016)
					(thickness 0.1524)
				)
			)
		)
		(duplicate_pad_numbers_are_jumpers no)
		(fp_line
			(start 0.508 0)
			(end -0.508 0)
			(stroke
				(width 0.2032)
				(type default)
			)
			(layer "F.SilkS")
		)
		(fp_rect
			(start -0.5842 1.3335)
			(end 0.5842 -1.3335)
			(stroke
				(width 0)
				(type default)
			)
			(fill no)
			(layer "F.CrtYd")
		)
		(fp_rect
			(start -0.5842 1.3335)
			(end 0.5842 -1.3335)
			(stroke
				(width 0)
				(type default)
			)
			(fill no)
			(layer "F.Fab")
		)
		(pad "1" smd custom
			(at 0 -0.762 180)
			(size 0.2159 0.2159)
			(layers "F.Cu" "F.Mask" "F.Paste")
			(net "P5V_HDD18")
			(options
				(clearance outline)
				(anchor circle)
			)
			(primitives
				(gr_poly
					(pts
						(arc
							(start -0.3302 -0.4318)
							(mid -0.402042 -0.402042)
							(end -0.4318 -0.3302)
						)
						(arc
							(start -0.4318 0.3302)
							(mid -0.402042 0.402042)
							(end -0.3302 0.4318)
						)
						(arc
							(start 0.3302 0.4318)
							(mid 0.402042 0.402042)
							(end 0.4318 0.3302)
						)
						(arc
							(start 0.4318 -0.3302)
							(mid 0.402042 -0.402042)
							(end 0.3302 -0.4318)
						)
					)
					(width 0)
					(fill yes)
				)
			)
		)
		(pad "2" smd custom
			(at 0 0.762 180)
			(size 0.2159 0.2159)
			(layers "F.Cu" "F.Mask" "F.Paste")
			(net "GND")
			(options
				(clearance outline)
				(anchor circle)
			)
			(primitives
				(gr_poly
					(pts
						(arc
							(start -0.3302 -0.4318)
							(mid -0.402042 -0.402042)
							(end -0.4318 -0.3302)
						)
						(arc
							(start -0.4318 0.3302)
							(mid -0.402042 0.402042)
							(end -0.3302 0.4318)
						)
						(arc
							(start 0.3302 0.4318)
							(mid 0.402042 0.402042)
							(end 0.4318 0.3302)
						)
						(arc
							(start 0.4318 -0.3302)
							(mid 0.402042 -0.402042)
							(end 0.3302 -0.4318)
						)
					)
					(width 0)
					(fill yes)
				)
			)
		)
	)
	(footprint ""
		(layer "F.Cu")
		(at 59.749944 -57.909968 -90)
		(property "Reference" "HDDSAS25"
			(at 0 0 270)
			(layer "F.SilkS")
			(hide yes)
			(effects
				(font
					(size 1.27 1.27)
				)
			)
		)
		(property "Value" "SKT-SAS15P-14P-45-GP"
			(at -20.7645 -8.9789 270)
			(unlocked yes)
			(layer "F.Fab")
			(hide yes)
			(effects
				(font
					(size 1.016 1.016)
					(thickness 0.1524)
				)
			)
		)
		(property "Device Type" "10120818-001C-TRLF"
			(at -20.7645 -10.5029 270)
			(unlocked yes)
			(layer "F.Fab")
			(hide yes)
			(effects
				(font
					(size 1.016 1.016)
					(thickness 0.1524)
				)
			)
		)
		(duplicate_pad_numbers_are_jumpers no)
		(fp_line
			(start 1.651 4.2926)
			(end 1.651 3.0099)
			(stroke
				(width 0.1524)
				(type default)
			)
			(layer "F.SilkS")
		)
		(fp_line
			(start 8.509 4.2926)
			(end 1.651 4.2926)
			(stroke
				(width 0.1524)
				(type default)
			)
			(layer "F.SilkS")
		)
		(fp_line
			(start -23.4188 3.0099)
			(end -23.4188 -3.2512)
			(stroke
				(width 0.1524)
				(type default)
			)
			(layer "F.SilkS")
		)
		(fp_line
			(start 1.651 3.0099)
			(end -23.4188 3.0099)
			(stroke
				(width 0.1524)
				(type default)
			)
			(layer "F.SilkS")
		)
		(fp_line
			(start 8.509 3.0099)
			(end 8.509 4.2926)
			(stroke
				(width 0.1524)
				(type default)
			)
			(layer "F.SilkS")
		)
		(fp_line
			(start 23.4188 3.0099)
			(end 8.509 3.0099)
			(stroke
				(width 0.1524)
				(type default)
			)
			(layer "F.SilkS")
		)
		(fp_line
			(start -23.4188 -3.2512)
			(end 23.4188 -3.2512)
			(stroke
				(width 0.1524)
				(type default)
			)
			(layer "F.SilkS")
		)
		(fp_line
			(start 23.4188 -3.2512)
			(end 23.4188 3.0099)
			(stroke
				(width 0.1524)
				(type default)
			)
			(layer "F.SilkS")
		)
		(fp_line
			(start 15.5067 -3.3401)
			(end 16.2687 -3.3401)
			(stroke
				(width 0.3302)
				(type default)
			)
			(layer "F.SilkS")
		)
		(fp_poly
			(pts
				(xy 15.868904 -3.230372) (xy 16.503904 -3.865372) (xy 15.233904 -3.865372)
			)
			(stroke
				(width 0)
				(type default)
			)
			(fill yes)
			(layer "F.SilkS")
		)
		(fp_poly
			(pts
				(xy -22.8727 -2.7559) (xy 22.8727 -2.7559) (xy 22.8727 2.7559) (xy 8.255 2.7559) (xy 8.255 3.5179)
				(xy 1.905 3.5179) (xy 1.905 2.7559) (xy -22.8727 2.7559)
			)
			(stroke
				(width 0)
				(type default)
			)
			(fill no)
			(layer "F.CrtYd")
		)
		(fp_poly
			(pts
				(xy 1.397 4.5466) (xy 1.397 3.2639) (xy -23.6728 3.2639) (xy -23.6728 -3.5052) (xy 23.6728 -3.5052)
				(xy 23.6728 -0.00635) (xy 22.8727 -0.00635) (xy 22.8727 -2.7559) (xy -22.8727 -2.7559) (xy -22.8727 2.7559)
				(xy 1.905 2.7559) (xy 1.905 3.5179) (xy 8.255 3.5179) (xy 8.255 2.7559) (xy 22.8727 2.7559) (xy 22.8727 0.00635)
				(xy 23.6728 0.00635) (xy 23.6728 3.2639) (xy 8.763 3.2639) (xy 8.763 4.5466)
			)
			(stroke
				(width 0)
				(type default)
			)
			(fill no)
			(layer "F.CrtYd")
		)
		(fp_poly
			(pts
				(xy 1.397 4.5466) (xy 1.397 3.2639) (xy -23.6728 3.2639) (xy -23.6728 -3.5052) (xy 23.6728 -3.5052)
				(xy 23.6728 3.2639) (xy 8.763 3.2639) (xy 8.763 4.5466)
			)
			(stroke
				(width 0)
				(type default)
			)
			(fill no)
			(layer "F.Fab")
		)
		(pad "" np_thru_hole circle
			(at -18.874994 0 270)
			(size 0.254 0.254)
			(drill 1.3462)
			(layers "*.Cu" "*.Mask")
			(clearance 0.9017)
			(thermal_gap 0.9017)
		)
		(pad "" np_thru_hole circle
			(at 18.874994 0 270)
			(size 0.254 0.254)
			(drill 0.9398)
			(layers "*.Cu" "*.Mask")
			(clearance 0.6985)
			(thermal_gap 0.6985)
		)
		(pad "G1" smd rect
			(at 21.874988 0 270)
			(size 2.5908 2.5908)
			(layers "F.Cu" "F.Mask" "F.Paste")
			(net "GND")
		)
		(pad "G2" smd rect
			(at -21.874988 0 270)
			(size 2.5908 2.5908)
			(layers "F.Cu" "F.Mask" "F.Paste")
			(net "GND")
		)
		(pad "P1" smd rect
			(at 1.905 -1.82499 270)
			(size 0.6096 2.3622)
			(layers "F.Cu" "F.Mask" "F.Paste")
			(net "Net_2086")
		)
		(pad "P2" smd rect
			(at 0.635 -1.82499 270)
			(size 0.6096 2.3622)
			(layers "F.Cu" "F.Mask" "F.Paste")
			(net "Net_2087")
		)
		(pad "P3" smd rect
			(at -0.635 -1.82499 270)
			(size 0.6096 2.3622)
			(layers "F.Cu" "F.Mask" "F.Paste")
			(net "Net_2088")
		)
		(pad "P4" smd rect
			(at -1.905 -1.82499 270)
			(size 0.6096 2.3622)
			(layers "F.Cu" "F.Mask" "F.Paste")
			(net "GND")
		)
		(pad "P5" smd rect
			(at -3.175 -1.82499 270)
			(size 0.6096 2.3622)
			(layers "F.Cu" "F.Mask" "F.Paste")
			(net "HDD_PRSNT_25")
		)
		(pad "P6" smd rect
			(at -4.445 -1.82499 270)
			(size 0.6096 2.3622)
			(layers "F.Cu" "F.Mask" "F.Paste")
			(net "GND")
		)
		(pad "P7" smd rect
			(at -5.715 -1.82499 270)
			(size 0.6096 2.3622)
			(layers "F.Cu" "F.Mask" "F.Paste")
			(net "5V_PRE_25")
		)
		(pad "P8" smd rect
			(at -6.985 -1.82499 270)
			(size 0.6096 2.3622)
			(layers "F.Cu" "F.Mask" "F.Paste")
			(net "P5V_HDD25")
		)
		(pad "P9" smd rect
			(at -8.255 -1.82499 270)
			(size 0.6096 2.3622)
			(layers "F.Cu" "F.Mask" "F.Paste")
			(net "P5V_HDD25")
		)
		(pad "P10" smd rect
			(at -9.525 -1.82499 270)
			(size 0.6096 2.3622)
			(layers "F.Cu" "F.Mask" "F.Paste")
			(net "GND")
		)
		(pad "P11" smd rect
			(at -10.795 -1.82499 270)
			(size 0.6096 2.3622)
			(layers "F.Cu" "F.Mask" "F.Paste")
			(net "ACT_HDD_25")
		)
		(pad "P12" smd rect
			(at -12.065 -1.82499 270)
			(size 0.6096 2.3622)
			(layers "F.Cu" "F.Mask" "F.Paste")
			(net "GND")
		)
		(pad "P13" smd rect
			(at -13.335 -1.82499 270)
			(size 0.6096 2.3622)
			(layers "F.Cu" "F.Mask" "F.Paste")
			(net "12V_PRE_25")
		)
		(pad "P14" smd rect
			(at -14.605 -1.82499 270)
			(size 0.6096 2.3622)
			(layers "F.Cu" "F.Mask" "F.Paste")
			(net "P12V_HDD25")
		)
		(pad "P15" smd rect
			(at -15.875 -1.82499 270)
			(size 0.6096 2.3622)
			(layers "F.Cu" "F.Mask" "F.Paste")
			(net "P12V_HDD25")
		)
		(pad "S1" smd rect
			(at 15.875 -1.82499 270)
			(size 0.6096 2.3622)
			(layers "F.Cu" "F.Mask" "F.Paste")
			(net "GND")
		)
		(pad "S2" smd rect
			(at 14.605 -1.82499 270)
			(size 0.6096 2.3622)
			(layers "F.Cu" "F.Mask" "F.Paste")
			(net "SAS_HDD_RX_P25")
		)
		(pad "S3" smd rect
			(at 13.335 -1.82499 270)
			(size 0.6096 2.3622)
			(layers "F.Cu" "F.Mask" "F.Paste")
			(net "SAS_HDD_RX_N25")
		)
		(pad "S4" smd rect
			(at 12.065 -1.82499 270)
			(size 0.6096 2.3622)
			(layers "F.Cu" "F.Mask" "F.Paste")
			(net "GND")
		)
		(pad "S5" smd rect
			(at 10.795 -1.82499 270)
			(size 0.6096 2.3622)
			(layers "F.Cu" "F.Mask" "F.Paste")
			(net "PHY_DRV_A_TO_SCC_A_25_DN")
		)
		(pad "S6" smd rect
			(at 9.525 -1.82499 270)
			(size 0.6096 2.3622)
			(layers "F.Cu" "F.Mask" "F.Paste")
			(net "PHY_DRV_A_TO_SCC_A_25_DP")
		)
		(pad "S7" smd rect
			(at 8.255 -1.82499 270)
			(size 0.6096 2.3622)
			(layers "F.Cu" "F.Mask" "F.Paste")
			(net "GND")
		)
		(pad "S8" smd rect
			(at 7.480046 2.845054 270)
			(size 0.508 2.3622)
			(layers "F.Cu" "F.Mask" "F.Paste")
			(net "GND")
		)
		(pad "S9" smd rect
			(at 6.679946 2.845054 270)
			(size 0.508 2.3622)
			(layers "F.Cu" "F.Mask" "F.Paste")
			(net "Net_463")
		)
		(pad "S10" smd rect
			(at 5.8801 2.845054 270)
			(size 0.508 2.3622)
			(layers "F.Cu" "F.Mask" "F.Paste")
			(net "Net_355")
		)
		(pad "S11" smd rect
			(at 5.08 2.845054 270)
			(size 0.508 2.3622)
			(layers "F.Cu" "F.Mask" "F.Paste")
			(net "GND")
		)
		(pad "S12" smd rect
			(at 4.2799 2.845054 270)
			(size 0.508 2.3622)
			(layers "F.Cu" "F.Mask" "F.Paste")
			(net "Net_391")
		)
		(pad "S13" smd rect
			(at 3.480054 2.845054 270)
			(size 0.508 2.3622)
			(layers "F.Cu" "F.Mask" "F.Paste")
			(net "Net_427")
		)
		(pad "S14" smd rect
			(at 2.679954 2.845054 270)
			(size 0.508 2.3622)
			(layers "F.Cu" "F.Mask" "F.Paste")
			(net "GND")
		)
		(zone
			(layer "F.Cu")
			(hatch none 0.5)
			(connect_pads
				(clearance 0)
			)
			(min_thickness 0.25)
			(keepout
				(tracks allowed)
				(vias not_allowed)
				(pads allowed)
				(copperpour not_allowed)
				(footprints allowed)
			)
			(placement
				(enabled no)
				(sheetname "")
			)
			(fill
				(thermal_gap 0.5)
				(thermal_bridge_width 0.5)
				(island_removal_mode 0)
			)
			(polygon
				(pts
					(xy 63.407544 -74.648568) (xy 56.333644 -74.648568) (xy 56.333644 -81.582768) (xy 57.438544 -81.582768)
					(xy 57.438544 -77.467968) (xy 62.061344 -77.467968) (xy 62.061344 -81.582768) (xy 63.407544 -81.582768)
				)
			)
		)
		(zone
			(layer "F.Cu")
			(hatch none 0.5)
			(connect_pads
				(clearance 0)
			)
			(min_thickness 0.25)
			(keepout
				(tracks not_allowed)
				(vias allowed)
				(pads allowed)
				(copperpour not_allowed)
				(footprints allowed)
			)
			(placement
				(enabled no)
				(sheetname "")
			)
			(fill
				(thermal_gap 0.5)
				(thermal_bridge_width 0.5)
				(island_removal_mode 0)
			)
			(polygon
				(pts
					(xy 63.407544 -74.648568) (xy 56.333644 -74.648568) (xy 56.333644 -81.582768) (xy 57.438544 -81.582768)
					(xy 57.438544 -77.467968) (xy 62.061344 -77.467968) (xy 62.061344 -81.582768) (xy 63.407544 -81.582768)
				)
			)
		)
		(zone
			(layer "F.Cu")
			(hatch none 0.5)
			(connect_pads
				(clearance 0)
			)
			(min_thickness 0.25)
			(keepout
				(tracks allowed)
				(vias not_allowed)
				(pads allowed)
				(copperpour not_allowed)
				(footprints allowed)
			)
			(placement
				(enabled no)
				(sheetname "")
			)
			(fill
				(thermal_gap 0.5)
				(thermal_bridge_width 0.5)
				(island_removal_mode 0)
			)
			(polygon
				(pts
					(xy 63.407544 -41.171368) (xy 56.333644 -41.171368) (xy 56.333644 -34.237168) (xy 57.438544 -34.237168)
					(xy 57.438544 -38.351968) (xy 62.061344 -38.351968) (xy 62.061344 -34.237168) (xy 63.407544 -34.237168)
				)
			)
		)
		(zone
			(layer "F.Cu")
			(hatch none 0.5)
			(connect_pads
				(clearance 0)
			)
			(min_thickness 0.25)
			(keepout
				(tracks not_allowed)
				(vias allowed)
				(pads allowed)
				(copperpour not_allowed)
				(footprints allowed)
			)
			(placement
				(enabled no)
				(sheetname "")
			)
			(fill
				(thermal_gap 0.5)
				(thermal_bridge_width 0.5)
				(island_removal_mode 0)
			)
			(polygon
				(pts
					(xy 63.407544 -41.171368) (xy 56.333644 -41.171368) (xy 56.333644 -34.237168) (xy 57.438544 -34.237168)
					(xy 57.438544 -38.351968) (xy 62.061344 -38.351968) (xy 62.061344 -34.237168) (xy 63.407544 -34.237168)
				)
			)
		)
		(zone
			(layers "F.Cu" "B.Cu" "In1.Cu" "In2.Cu" "In3.Cu" "In4.Cu" "In5.Cu" "In6.Cu"
				"In7.Cu" "In8.Cu" "In9.Cu" "In10.Cu"
			)
			(hatch none 0.5)
			(connect_pads
				(clearance 0)
			)
			(min_thickness 0.25)
			(keepout
				(tracks not_allowed)
				(vias allowed)
				(pads allowed)
				(copperpour not_allowed)
				(footprints allowed)
			)
			(placement
				(enabled no)
				(sheetname "")
			)
			(fill
				(thermal_gap 0.5)
				(thermal_bridge_width 0.5)
				(island_removal_mode 0)
			)
			(polygon
				(pts
					(arc
						(start 60.524644 -39.034974)
						(mid 58.975244 -39.034974)
						(end 60.524644 -39.034974)
					)
				)
			)
		)
		(zone
			(layers "F.Cu" "B.Cu" "In1.Cu" "In2.Cu" "In3.Cu" "In4.Cu" "In5.Cu" "In6.Cu"
				"In7.Cu" "In8.Cu" "In9.Cu" "In10.Cu"
			)
			(hatch none 0.5)
			(connect_pads
				(clearance 0)
			)
			(min_thickness 0.25)
			(keepout
				(tracks not_allowed)
				(vias allowed)
				(pads allowed)
				(copperpour not_allowed)
				(footprints allowed)
			)
			(placement
				(enabled no)
				(sheetname "")
			)
			(fill
				(thermal_gap 0.5)
				(thermal_bridge_width 0.5)
				(island_removal_mode 0)
			)
			(polygon
				(pts
					(arc
						(start 60.727844 -76.784962)
						(mid 58.772044 -76.784962)
						(end 60.727844 -76.784962)
					)
				)
			)
		)
	)
	(footprint ""
		(layer "F.Cu")
		(at 433.359052 -287.851342 90)
		(property "Reference" "C166"
			(at 0 0 90)
			(layer "F.SilkS")
			(hide yes)
			(effects
				(font
					(size 1.27 1.27)
				)
			)
		)
		(property "Value" "SCD033U25V2KX-GP"
			(at 1.1811 -2.7051 90)
			(unlocked yes)
			(layer "F.Fab")
			(hide yes)
			(effects
				(font
					(size 1.016 1.016)
					(thickness 0.1524)
				)
			)
		)
		(property "Device Type" "C402H22"
			(at 1.1811 -4.2291 90)
			(unlocked yes)
			(layer "F.Fab")
			(hide yes)
			(effects
				(font
					(size 1.016 1.016)
					(thickness 0.1524)
				)
			)
		)
		(duplicate_pad_numbers_are_jumpers no)
		(fp_rect
			(start -0.4318 0.9525)
			(end 0.4318 -0.9525)
			(stroke
				(width 0)
				(type default)
			)
			(fill no)
			(layer "F.CrtYd")
		)
		(fp_rect
			(start -0.4318 0.9525)
			(end 0.4318 -0.9525)
			(stroke
				(width 0)
				(type default)
			)
			(fill no)
			(layer "F.Fab")
		)
		(pad "1" smd custom
			(at 0 -0.4445 90)
			(size 0.1524 0.1524)
			(layers "F.Cu" "F.Mask" "F.Paste")
			(net "P12V_A")
			(options
				(clearance outline)
				(anchor circle)
			)
			(primitives
				(gr_poly
					(pts
						(arc
							(start 0.3048 -0.2032)
							(mid 0.275042 -0.275042)
							(end 0.2032 -0.3048)
						)
						(arc
							(start -0.2032 -0.3048)
							(mid -0.275042 -0.275042)
							(end -0.3048 -0.2032)
						)
						(arc
							(start -0.3048 0.2032)
							(mid -0.275042 0.275042)
							(end -0.2032 0.3048)
						)
						(arc
							(start 0.2032 0.3048)
							(mid 0.275042 0.275042)
							(end 0.3048 0.2032)
						)
					)
					(width 0)
					(fill yes)
				)
			)
		)
		(pad "2" smd custom
			(at 0 0.4445 90)
			(size 0.1524 0.1524)
			(layers "F.Cu" "F.Mask" "F.Paste")
			(net "SW_HDD_N9")
			(options
				(clearance outline)
				(anchor circle)
			)
			(primitives
				(gr_poly
					(pts
						(arc
							(start 0.3048 -0.2032)
							(mid 0.275042 -0.275042)
							(end 0.2032 -0.3048)
						)
						(arc
							(start -0.2032 -0.3048)
							(mid -0.275042 -0.275042)
							(end -0.3048 -0.2032)
						)
						(arc
							(start -0.3048 0.2032)
							(mid -0.275042 0.275042)
							(end -0.2032 0.3048)
						)
						(arc
							(start 0.2032 0.3048)
							(mid 0.275042 0.275042)
							(end 0.3048 0.2032)
						)
					)
					(width 0)
					(fill yes)
				)
			)
		)
	)
	(footprint ""
		(layer "F.Cu")
		(at 298.7294 -70.0786)
		(property "Reference" "R626"
			(at 0 0 0)
			(layer "F.SilkS")
			(hide yes)
			(effects
				(font
					(size 1.27 1.27)
				)
			)
		)
		(property "Value" "4K7R2F-GP"
			(at 0.064008 -3.993896 0)
			(unlocked yes)
			(layer "F.Fab")
			(hide yes)
			(effects
				(font
					(size 1.016 1.016)
					(thickness 0.1524)
				)
			)
		)
		(property "Device Type" "R402H16"
			(at 0.064008 -5.517896 0)
			(unlocked yes)
			(layer "F.Fab")
			(hide yes)
			(effects
				(font
					(size 1.016 1.016)
					(thickness 0.1524)
				)
			)
		)
		(duplicate_pad_numbers_are_jumpers no)
		(fp_line
			(start -0.508 -0.9398)
			(end -0.508 0.9398)
			(stroke
				(width 0.1524)
				(type default)
			)
			(layer "F.SilkS")
		)
		(fp_line
			(start 0.508 -0.9398)
			(end -0.508 -0.9398)
			(stroke
				(width 0.1524)
				(type default)
			)
			(layer "F.SilkS")
		)
		(fp_rect
			(start -0.508 0.9398)
			(end 0.508 -0.9398)
			(stroke
				(width 0)
				(type default)
			)
			(fill no)
			(layer "F.CrtYd")
		)
		(fp_rect
			(start -0.508 0.9398)
			(end 0.508 -0.9398)
			(stroke
				(width 0)
				(type default)
			)
			(fill no)
			(layer "F.Fab")
		)
		(pad "1" smd custom
			(at 0 -0.4445)
			(size 0.1397 0.1397)
			(layers "F.Cu" "F.Mask" "F.Paste")
			(net "I2C_BMC_B_COMP_B_SCL")
			(options
				(clearance outline)
				(anchor circle)
			)
			(primitives
				(gr_poly
					(pts
						(arc
							(start -0.1778 -0.2794)
							(mid -0.249642 -0.249642)
							(end -0.2794 -0.1778)
						)
						(arc
							(start -0.2794 0.1778)
							(mid -0.249642 0.249642)
							(end -0.1778 0.2794)
						)
						(arc
							(start 0.1778 0.2794)
							(mid 0.249642 0.249642)
							(end 0.2794 0.1778)
						)
						(arc
							(start 0.2794 -0.1778)
							(mid 0.249642 -0.249642)
							(end 0.1778 -0.2794)
						)
					)
					(width 0)
					(fill yes)
				)
			)
		)
		(pad "2" smd custom
			(at 0 0.4445)
			(size 0.1397 0.1397)
			(layers "F.Cu" "F.Mask" "F.Paste")
			(net "P3V3_STBY_B")
			(options
				(clearance outline)
				(anchor circle)
			)
			(primitives
				(gr_poly
					(pts
						(arc
							(start -0.1778 -0.2794)
							(mid -0.249642 -0.249642)
							(end -0.2794 -0.1778)
						)
						(arc
							(start -0.2794 0.1778)
							(mid -0.249642 0.249642)
							(end -0.1778 0.2794)
						)
						(arc
							(start 0.1778 0.2794)
							(mid 0.249642 0.249642)
							(end 0.2794 0.1778)
						)
						(arc
							(start 0.2794 -0.1778)
							(mid 0.249642 -0.249642)
							(end 0.1778 -0.2794)
						)
					)
					(width 0)
					(fill yes)
				)
			)
		)
	)
	(footprint ""
		(layer "F.Cu")
		(at 257.1496 -14.9606 90)
		(property "Reference" "R1049"
			(at 0 0 90)
			(layer "F.SilkS")
			(hide yes)
			(effects
				(font
					(size 1.27 1.27)
				)
			)
		)
		(property "Value" "100KR2F-L1-GP"
			(at 0.064008 -3.993896 90)
			(unlocked yes)
			(layer "F.Fab")
			(hide yes)
			(effects
				(font
					(size 1.016 1.016)
					(thickness 0.1524)
				)
			)
		)
		(property "Device Type" "R402H16"
			(at 0.064008 -5.517896 90)
			(unlocked yes)
			(layer "F.Fab")
			(hide yes)
			(effects
				(font
					(size 1.016 1.016)
					(thickness 0.1524)
				)
			)
		)
		(duplicate_pad_numbers_are_jumpers no)
		(fp_line
			(start 0.508 -0.9398)
			(end -0.508 -0.9398)
			(stroke
				(width 0.1524)
				(type default)
			)
			(layer "F.SilkS")
		)
		(fp_line
			(start -0.508 -0.9398)
			(end -0.508 0.9398)
			(stroke
				(width 0.1524)
				(type default)
			)
			(layer "F.SilkS")
		)
		(fp_rect
			(start -0.508 0.9398)
			(end 0.508 -0.9398)
			(stroke
				(width 0)
				(type default)
			)
			(fill no)
			(layer "F.CrtYd")
		)
		(fp_rect
			(start -0.508 0.9398)
			(end 0.508 -0.9398)
			(stroke
				(width 0)
				(type default)
			)
			(fill no)
			(layer "F.Fab")
		)
		(pad "1" smd custom
			(at 0 -0.4445 90)
			(size 0.1397 0.1397)
			(layers "F.Cu" "F.Mask" "F.Paste")
			(net "PCIE_COMP_A_RST_5")
			(options
				(clearance outline)
				(anchor circle)
			)
			(primitives
				(gr_poly
					(pts
						(arc
							(start -0.1778 -0.2794)
							(mid -0.249642 -0.249642)
							(end -0.2794 -0.1778)
						)
						(arc
							(start -0.2794 0.1778)
							(mid -0.249642 0.249642)
							(end -0.1778 0.2794)
						)
						(arc
							(start 0.1778 0.2794)
							(mid 0.249642 0.249642)
							(end 0.2794 0.1778)
						)
						(arc
							(start 0.2794 -0.1778)
							(mid 0.249642 -0.249642)
							(end 0.1778 -0.2794)
						)
					)
					(width 0)
					(fill yes)
				)
			)
		)
		(pad "2" smd custom
			(at 0 0.4445 90)
			(size 0.1397 0.1397)
			(layers "F.Cu" "F.Mask" "F.Paste")
			(net "GND")
			(options
				(clearance outline)
				(anchor circle)
			)
			(primitives
				(gr_poly
					(pts
						(arc
							(start -0.1778 -0.2794)
							(mid -0.249642 -0.249642)
							(end -0.2794 -0.1778)
						)
						(arc
							(start -0.2794 0.1778)
							(mid -0.249642 0.249642)
							(end -0.1778 0.2794)
						)
						(arc
							(start 0.1778 0.2794)
							(mid 0.249642 0.249642)
							(end 0.2794 0.1778)
						)
						(arc
							(start 0.2794 -0.1778)
							(mid 0.249642 -0.249642)
							(end 0.1778 -0.2794)
						)
					)
					(width 0)
					(fill yes)
				)
			)
		)
	)
	(footprint ""
		(layer "F.Cu")
		(at 440.180984 -293.841932)
		(property "Reference" "Q298"
			(at 0 0 0)
			(layer "F.SilkS")
			(hide yes)
			(effects
				(font
					(size 1.27 1.27)
				)
			)
		)
		(property "Value" "2N7002K-2-GP"
			(at 0.127 -8.9662 0)
			(unlocked yes)
			(layer "F.Fab")
			(hide yes)
			(effects
				(font
					(size 1.016 1.016)
					(thickness 0.1524)
				)
			)
		)
		(property "Device Type" "SOT23DGS2D4H44"
			(at 0.127 -10.4902 0)
			(unlocked yes)
			(layer "F.Fab")
			(hide yes)
			(effects
				(font
					(size 1.016 1.016)
					(thickness 0.1524)
				)
			)
		)
		(duplicate_pad_numbers_are_jumpers no)
		(fp_line
			(start -1.651 -1.778)
			(end -1.651 1.778)
			(stroke
				(width 0.1524)
				(type default)
			)
			(layer "F.SilkS")
		)
		(fp_line
			(start -1.651 1.778)
			(end 1.651 1.778)
			(stroke
				(width 0.1524)
				(type default)
			)
			(layer "F.SilkS")
		)
		(fp_line
			(start 1.651 -1.778)
			(end -1.651 -1.778)
			(stroke
				(width 0.1524)
				(type default)
			)
			(layer "F.SilkS")
		)
		(fp_line
			(start 1.651 1.778)
			(end 1.651 -1.778)
			(stroke
				(width 0.1524)
				(type default)
			)
			(layer "F.SilkS")
		)
		(fp_poly
			(pts
				(xy -1.778 1.8796) (xy -1.778 -1.8796) (xy 1.778 -1.8796) (xy 1.778 1.8796)
			)
			(stroke
				(width 0)
				(type default)
			)
			(fill no)
			(layer "F.CrtYd")
		)
		(fp_poly
			(pts
				(xy -1.778 1.8796) (xy -1.778 -1.8796) (xy 1.778 -1.8796) (xy 1.778 1.8796)
			)
			(stroke
				(width 0)
				(type default)
			)
			(fill no)
			(layer "F.Fab")
		)
		(pad "D" smd custom
			(at 0 -0.9525)
			(size 0.1905 0.1905)
			(layers "F.Cu" "F.Mask" "F.Paste")
			(net "FLT_HDD34_N")
			(options
				(clearance outline)
				(anchor circle)
			)
			(primitives
				(gr_poly
					(pts
						(arc
							(start -0.1778 0.5715)
							(mid -0.321484 0.511984)
							(end -0.381 0.3683)
						)
						(arc
							(start -0.381 -0.3683)
							(mid -0.321484 -0.511984)
							(end -0.1778 -0.5715)
						)
						(arc
							(start 0.1778 -0.5715)
							(mid 0.321484 -0.511984)
							(end 0.381 -0.3683)
						)
						(arc
							(start 0.381 0.3683)
							(mid 0.321484 0.511984)
							(end 0.1778 0.5715)
						)
					)
					(width 0)
					(fill yes)
				)
			)
		)
		(pad "G" smd custom
			(at -0.98425 0.9525)
			(size 0.1905 0.1905)
			(layers "F.Cu" "F.Mask" "F.Paste")
			(net "DRIVE_B_34_FLT_LED")
			(options
				(clearance outline)
				(anchor circle)
			)
			(primitives
				(gr_poly
					(pts
						(arc
							(start -0.1778 0.5715)
							(mid -0.321484 0.511984)
							(end -0.381 0.3683)
						)
						(arc
							(start -0.381 -0.3683)
							(mid -0.321484 -0.511984)
							(end -0.1778 -0.5715)
						)
						(arc
							(start 0.1778 -0.5715)
							(mid 0.321484 -0.511984)
							(end 0.381 -0.3683)
						)
						(arc
							(start 0.381 0.3683)
							(mid 0.321484 0.511984)
							(end 0.1778 0.5715)
						)
					)
					(width 0)
					(fill yes)
				)
			)
		)
		(pad "S" smd custom
			(at 0.98425 0.9525)
			(size 0.1905 0.1905)
			(layers "F.Cu" "F.Mask" "F.Paste")
			(net "GND")
			(options
				(clearance outline)
				(anchor circle)
			)
			(primitives
				(gr_poly
					(pts
						(arc
							(start -0.1778 0.5715)
							(mid -0.321484 0.511984)
							(end -0.381 0.3683)
						)
						(arc
							(start -0.381 -0.3683)
							(mid -0.321484 -0.511984)
							(end -0.1778 -0.5715)
						)
						(arc
							(start 0.1778 -0.5715)
							(mid 0.321484 -0.511984)
							(end 0.381 -0.3683)
						)
						(arc
							(start 0.381 0.3683)
							(mid 0.321484 0.511984)
							(end 0.1778 0.5715)
						)
					)
					(width 0)
					(fill yes)
				)
			)
		)
	)
	(footprint ""
		(layer "F.Cu")
		(at 281.708352 14.138148 90)
		(property "Reference" "C107"
			(at 0 0 90)
			(layer "F.SilkS")
			(hide yes)
			(effects
				(font
					(size 1.27 1.27)
				)
			)
		)
		(property "Value" "SCD1U16V2KX-3GP"
			(at 1.1811 -2.7051 90)
			(unlocked yes)
			(layer "F.Fab")
			(hide yes)
			(effects
				(font
					(size 1.016 1.016)
					(thickness 0.1524)
				)
			)
		)
		(property "Device Type" "C402H22"
			(at 1.1811 -4.2291 90)
			(unlocked yes)
			(layer "F.Fab")
			(hide yes)
			(effects
				(font
					(size 1.016 1.016)
					(thickness 0.1524)
				)
			)
		)
		(duplicate_pad_numbers_are_jumpers no)
		(fp_rect
			(start -0.4318 0.9525)
			(end 0.4318 -0.9525)
			(stroke
				(width 0)
				(type default)
			)
			(fill no)
			(layer "F.CrtYd")
		)
		(fp_rect
			(start -0.4318 0.9525)
			(end 0.4318 -0.9525)
			(stroke
				(width 0)
				(type default)
			)
			(fill no)
			(layer "F.Fab")
		)
		(pad "1" smd custom
			(at 0 -0.4445 90)
			(size 0.1524 0.1524)
			(layers "F.Cu" "F.Mask" "F.Paste")
			(net "P3V3_BIAS")
			(options
				(clearance outline)
				(anchor circle)
			)
			(primitives
				(gr_poly
					(pts
						(arc
							(start 0.3048 -0.2032)
							(mid 0.275042 -0.275042)
							(end 0.2032 -0.3048)
						)
						(arc
							(start -0.2032 -0.3048)
							(mid -0.275042 -0.275042)
							(end -0.3048 -0.2032)
						)
						(arc
							(start -0.3048 0.2032)
							(mid -0.275042 0.275042)
							(end -0.2032 0.3048)
						)
						(arc
							(start 0.2032 0.3048)
							(mid 0.275042 0.275042)
							(end 0.3048 0.2032)
						)
					)
					(width 0)
					(fill yes)
				)
			)
		)
		(pad "2" smd custom
			(at 0 0.4445 90)
			(size 0.1524 0.1524)
			(layers "F.Cu" "F.Mask" "F.Paste")
			(net "GND")
			(options
				(clearance outline)
				(anchor circle)
			)
			(primitives
				(gr_poly
					(pts
						(arc
							(start 0.3048 -0.2032)
							(mid 0.275042 -0.275042)
							(end 0.2032 -0.3048)
						)
						(arc
							(start -0.2032 -0.3048)
							(mid -0.275042 -0.275042)
							(end -0.3048 -0.2032)
						)
						(arc
							(start -0.3048 0.2032)
							(mid -0.275042 0.275042)
							(end -0.2032 0.3048)
						)
						(arc
							(start 0.2032 0.3048)
							(mid 0.275042 0.275042)
							(end 0.3048 0.2032)
						)
					)
					(width 0)
					(fill yes)
				)
			)
		)
	)
	(footprint ""
		(layer "F.Cu")
		(at 50.152046 -275.633942)
		(property "Reference" "R170"
			(at 0 0 0)
			(layer "F.SilkS")
			(hide yes)
			(effects
				(font
					(size 1.27 1.27)
				)
			)
		)
		(property "Value" "0R2J-2-GP"
			(at 0.064008 -3.993896 0)
			(unlocked yes)
			(layer "F.Fab")
			(hide yes)
			(effects
				(font
					(size 1.016 1.016)
					(thickness 0.1524)
				)
			)
		)
		(property "Device Type" "R402H16"
			(at 0.064008 -5.517896 0)
			(unlocked yes)
			(layer "F.Fab")
			(hide yes)
			(effects
				(font
					(size 1.016 1.016)
					(thickness 0.1524)
				)
			)
		)
		(duplicate_pad_numbers_are_jumpers no)
		(fp_line
			(start -0.508 -0.9398)
			(end -0.508 0.9398)
			(stroke
				(width 0.1524)
				(type default)
			)
			(layer "F.SilkS")
		)
		(fp_line
			(start 0.508 -0.9398)
			(end -0.508 -0.9398)
			(stroke
				(width 0.1524)
				(type default)
			)
			(layer "F.SilkS")
		)
		(fp_rect
			(start -0.508 0.9398)
			(end 0.508 -0.9398)
			(stroke
				(width 0)
				(type default)
			)
			(fill no)
			(layer "F.CrtYd")
		)
		(fp_rect
			(start -0.508 0.9398)
			(end 0.508 -0.9398)
			(stroke
				(width 0)
				(type default)
			)
			(fill no)
			(layer "F.Fab")
		)
		(pad "1" smd custom
			(at 0 -0.4445)
			(size 0.1397 0.1397)
			(layers "F.Cu" "F.Mask" "F.Paste")
			(net "SW_HDD_G1")
			(options
				(clearance outline)
				(anchor circle)
			)
			(primitives
				(gr_poly
					(pts
						(arc
							(start -0.1778 -0.2794)
							(mid -0.249642 -0.249642)
							(end -0.2794 -0.1778)
						)
						(arc
							(start -0.2794 0.1778)
							(mid -0.249642 0.249642)
							(end -0.1778 0.2794)
						)
						(arc
							(start 0.1778 0.2794)
							(mid 0.249642 0.249642)
							(end 0.2794 0.1778)
						)
						(arc
							(start 0.2794 -0.1778)
							(mid 0.249642 -0.249642)
							(end 0.1778 -0.2794)
						)
					)
					(width 0)
					(fill yes)
				)
			)
		)
		(pad "2" smd custom
			(at 0 0.4445)
			(size 0.1397 0.1397)
			(layers "F.Cu" "F.Mask" "F.Paste")
			(net "SW_HDD_R1")
			(options
				(clearance outline)
				(anchor circle)
			)
			(primitives
				(gr_poly
					(pts
						(arc
							(start -0.1778 -0.2794)
							(mid -0.249642 -0.249642)
							(end -0.2794 -0.1778)
						)
						(arc
							(start -0.2794 0.1778)
							(mid -0.249642 0.249642)
							(end -0.1778 0.2794)
						)
						(arc
							(start 0.1778 0.2794)
							(mid 0.249642 0.249642)
							(end 0.2794 0.1778)
						)
						(arc
							(start 0.2794 -0.1778)
							(mid 0.249642 -0.249642)
							(end 0.1778 -0.2794)
						)
					)
					(width 0)
					(fill yes)
				)
			)
		)
	)
	(footprint ""
		(layer "F.Cu")
		(at 483.300024 -287.910016 -90)
		(property "Reference" "HDDSAS11"
			(at 0 0 270)
			(layer "F.SilkS")
			(hide yes)
			(effects
				(font
					(size 1.27 1.27)
				)
			)
		)
		(property "Value" "SKT-SAS15P-14P-45-GP"
			(at -20.7645 -8.9789 270)
			(unlocked yes)
			(layer "F.Fab")
			(hide yes)
			(effects
				(font
					(size 1.016 1.016)
					(thickness 0.1524)
				)
			)
		)
		(property "Device Type" "10120818-001C-TRLF"
			(at -20.7645 -10.5029 270)
			(unlocked yes)
			(layer "F.Fab")
			(hide yes)
			(effects
				(font
					(size 1.016 1.016)
					(thickness 0.1524)
				)
			)
		)
		(duplicate_pad_numbers_are_jumpers no)
		(fp_line
			(start 1.651 4.2926)
			(end 1.651 3.0099)
			(stroke
				(width 0.1524)
				(type default)
			)
			(layer "F.SilkS")
		)
		(fp_line
			(start 8.509 4.2926)
			(end 1.651 4.2926)
			(stroke
				(width 0.1524)
				(type default)
			)
			(layer "F.SilkS")
		)
		(fp_line
			(start -23.4188 3.0099)
			(end -23.4188 -3.2512)
			(stroke
				(width 0.1524)
				(type default)
			)
			(layer "F.SilkS")
		)
		(fp_line
			(start 1.651 3.0099)
			(end -23.4188 3.0099)
			(stroke
				(width 0.1524)
				(type default)
			)
			(layer "F.SilkS")
		)
		(fp_line
			(start 8.509 3.0099)
			(end 8.509 4.2926)
			(stroke
				(width 0.1524)
				(type default)
			)
			(layer "F.SilkS")
		)
		(fp_line
			(start 23.4188 3.0099)
			(end 8.509 3.0099)
			(stroke
				(width 0.1524)
				(type default)
			)
			(layer "F.SilkS")
		)
		(fp_line
			(start -23.4188 -3.2512)
			(end 23.4188 -3.2512)
			(stroke
				(width 0.1524)
				(type default)
			)
			(layer "F.SilkS")
		)
		(fp_line
			(start 23.4188 -3.2512)
			(end 23.4188 3.0099)
			(stroke
				(width 0.1524)
				(type default)
			)
			(layer "F.SilkS")
		)
		(fp_line
			(start 15.5067 -3.3401)
			(end 16.2687 -3.3401)
			(stroke
				(width 0.3302)
				(type default)
			)
			(layer "F.SilkS")
		)
		(fp_poly
			(pts
				(xy 15.868904 -3.230372) (xy 16.503904 -3.865372) (xy 15.233904 -3.865372)
			)
			(stroke
				(width 0)
				(type default)
			)
			(fill yes)
			(layer "F.SilkS")
		)
		(fp_poly
			(pts
				(xy -22.8727 -2.7559) (xy 22.8727 -2.7559) (xy 22.8727 2.7559) (xy 8.255 2.7559) (xy 8.255 3.5179)
				(xy 1.905 3.5179) (xy 1.905 2.7559) (xy -22.8727 2.7559)
			)
			(stroke
				(width 0)
				(type default)
			)
			(fill no)
			(layer "F.CrtYd")
		)
		(fp_poly
			(pts
				(xy 1.397 4.5466) (xy 1.397 3.2639) (xy -23.6728 3.2639) (xy -23.6728 -3.5052) (xy 23.6728 -3.5052)
				(xy 23.6728 -0.00635) (xy 22.8727 -0.00635) (xy 22.8727 -2.7559) (xy -22.8727 -2.7559) (xy -22.8727 2.7559)
				(xy 1.905 2.7559) (xy 1.905 3.5179) (xy 8.255 3.5179) (xy 8.255 2.7559) (xy 22.8727 2.7559) (xy 22.8727 0.00635)
				(xy 23.6728 0.00635) (xy 23.6728 3.2639) (xy 8.763 3.2639) (xy 8.763 4.5466)
			)
			(stroke
				(width 0)
				(type default)
			)
			(fill no)
			(layer "F.CrtYd")
		)
		(fp_poly
			(pts
				(xy 1.397 4.5466) (xy 1.397 3.2639) (xy -23.6728 3.2639) (xy -23.6728 -3.5052) (xy 23.6728 -3.5052)
				(xy 23.6728 3.2639) (xy 8.763 3.2639) (xy 8.763 4.5466)
			)
			(stroke
				(width 0)
				(type default)
			)
			(fill no)
			(layer "F.Fab")
		)
		(pad "" np_thru_hole circle
			(at -18.874994 0 270)
			(size 0.254 0.254)
			(drill 1.3462)
			(layers "*.Cu" "*.Mask")
			(clearance 0.9017)
			(thermal_gap 0.9017)
		)
		(pad "" np_thru_hole circle
			(at 18.874994 0 270)
			(size 0.254 0.254)
			(drill 0.9398)
			(layers "*.Cu" "*.Mask")
			(clearance 0.6985)
			(thermal_gap 0.6985)
		)
		(pad "G1" smd rect
			(at 21.874988 0 270)
			(size 2.5908 2.5908)
			(layers "F.Cu" "F.Mask" "F.Paste")
			(net "GND")
		)
		(pad "G2" smd rect
			(at -21.874988 0 270)
			(size 2.5908 2.5908)
			(layers "F.Cu" "F.Mask" "F.Paste")
			(net "GND")
		)
		(pad "P1" smd rect
			(at 1.905 -1.82499 270)
			(size 0.6096 2.3622)
			(layers "F.Cu" "F.Mask" "F.Paste")
			(net "Net_2161")
		)
		(pad "P2" smd rect
			(at 0.635 -1.82499 270)
			(size 0.6096 2.3622)
			(layers "F.Cu" "F.Mask" "F.Paste")
			(net "Net_2162")
		)
		(pad "P3" smd rect
			(at -0.635 -1.82499 270)
			(size 0.6096 2.3622)
			(layers "F.Cu" "F.Mask" "F.Paste")
			(net "Net_2163")
		)
		(pad "P4" smd rect
			(at -1.905 -1.82499 270)
			(size 0.6096 2.3622)
			(layers "F.Cu" "F.Mask" "F.Paste")
			(net "GND")
		)
		(pad "P5" smd rect
			(at -3.175 -1.82499 270)
			(size 0.6096 2.3622)
			(layers "F.Cu" "F.Mask" "F.Paste")
			(net "HDD_PRSNT_11")
		)
		(pad "P6" smd rect
			(at -4.445 -1.82499 270)
			(size 0.6096 2.3622)
			(layers "F.Cu" "F.Mask" "F.Paste")
			(net "GND")
		)
		(pad "P7" smd rect
			(at -5.715 -1.82499 270)
			(size 0.6096 2.3622)
			(layers "F.Cu" "F.Mask" "F.Paste")
			(net "5V_PRE_11")
		)
		(pad "P8" smd rect
			(at -6.985 -1.82499 270)
			(size 0.6096 2.3622)
			(layers "F.Cu" "F.Mask" "F.Paste")
			(net "P5V_HDD11")
		)
		(pad "P9" smd rect
			(at -8.255 -1.82499 270)
			(size 0.6096 2.3622)
			(layers "F.Cu" "F.Mask" "F.Paste")
			(net "P5V_HDD11")
		)
		(pad "P10" smd rect
			(at -9.525 -1.82499 270)
			(size 0.6096 2.3622)
			(layers "F.Cu" "F.Mask" "F.Paste")
			(net "GND")
		)
		(pad "P11" smd rect
			(at -10.795 -1.82499 270)
			(size 0.6096 2.3622)
			(layers "F.Cu" "F.Mask" "F.Paste")
			(net "ACT_HDD_11")
		)
		(pad "P12" smd rect
			(at -12.065 -1.82499 270)
			(size 0.6096 2.3622)
			(layers "F.Cu" "F.Mask" "F.Paste")
			(net "GND")
		)
		(pad "P13" smd rect
			(at -13.335 -1.82499 270)
			(size 0.6096 2.3622)
			(layers "F.Cu" "F.Mask" "F.Paste")
			(net "12V_PRE_11")
		)
		(pad "P14" smd rect
			(at -14.605 -1.82499 270)
			(size 0.6096 2.3622)
			(layers "F.Cu" "F.Mask" "F.Paste")
			(net "P12V_HDD11")
		)
		(pad "P15" smd rect
			(at -15.875 -1.82499 270)
			(size 0.6096 2.3622)
			(layers "F.Cu" "F.Mask" "F.Paste")
			(net "P12V_HDD11")
		)
		(pad "S1" smd rect
			(at 15.875 -1.82499 270)
			(size 0.6096 2.3622)
			(layers "F.Cu" "F.Mask" "F.Paste")
			(net "GND")
		)
		(pad "S2" smd rect
			(at 14.605 -1.82499 270)
			(size 0.6096 2.3622)
			(layers "F.Cu" "F.Mask" "F.Paste")
			(net "SAS_HDD_RX_P11")
		)
		(pad "S3" smd rect
			(at 13.335 -1.82499 270)
			(size 0.6096 2.3622)
			(layers "F.Cu" "F.Mask" "F.Paste")
			(net "SAS_HDD_RX_N11")
		)
		(pad "S4" smd rect
			(at 12.065 -1.82499 270)
			(size 0.6096 2.3622)
			(layers "F.Cu" "F.Mask" "F.Paste")
			(net "GND")
		)
		(pad "S5" smd rect
			(at 10.795 -1.82499 270)
			(size 0.6096 2.3622)
			(layers "F.Cu" "F.Mask" "F.Paste")
			(net "PHY_DRV_A_TO_SCC_A_11_DN")
		)
		(pad "S6" smd rect
			(at 9.525 -1.82499 270)
			(size 0.6096 2.3622)
			(layers "F.Cu" "F.Mask" "F.Paste")
			(net "PHY_DRV_A_TO_SCC_A_11_DP")
		)
		(pad "S7" smd rect
			(at 8.255 -1.82499 270)
			(size 0.6096 2.3622)
			(layers "F.Cu" "F.Mask" "F.Paste")
			(net "GND")
		)
		(pad "S8" smd rect
			(at 7.480046 2.845054 270)
			(size 0.508 2.3622)
			(layers "F.Cu" "F.Mask" "F.Paste")
			(net "GND")
		)
		(pad "S9" smd rect
			(at 6.679946 2.845054 270)
			(size 0.508 2.3622)
			(layers "F.Cu" "F.Mask" "F.Paste")
			(net "Net_448")
		)
		(pad "S10" smd rect
			(at 5.8801 2.845054 270)
			(size 0.508 2.3622)
			(layers "F.Cu" "F.Mask" "F.Paste")
			(net "Net_340")
		)
		(pad "S11" smd rect
			(at 5.08 2.845054 270)
			(size 0.508 2.3622)
			(layers "F.Cu" "F.Mask" "F.Paste")
			(net "GND")
		)
		(pad "S12" smd rect
			(at 4.2799 2.845054 270)
			(size 0.508 2.3622)
			(layers "F.Cu" "F.Mask" "F.Paste")
			(net "Net_376")
		)
		(pad "S13" smd rect
			(at 3.480054 2.845054 270)
			(size 0.508 2.3622)
			(layers "F.Cu" "F.Mask" "F.Paste")
			(net "Net_412")
		)
		(pad "S14" smd rect
			(at 2.679954 2.845054 270)
			(size 0.508 2.3622)
			(layers "F.Cu" "F.Mask" "F.Paste")
			(net "GND")
		)
		(zone
			(layer "F.Cu")
			(hatch none 0.5)
			(connect_pads
				(clearance 0)
			)
			(min_thickness 0.25)
			(keepout
				(tracks allowed)
				(vias not_allowed)
				(pads allowed)
				(copperpour not_allowed)
				(footprints allowed)
			)
			(placement
				(enabled no)
				(sheetname "")
			)
			(fill
				(thermal_gap 0.5)
				(thermal_bridge_width 0.5)
				(island_removal_mode 0)
			)
			(polygon
				(pts
					(xy 486.957624 -304.648616) (xy 479.883724 -304.648616) (xy 479.883724 -311.582816) (xy 480.988624 -311.582816)
					(xy 480.988624 -307.468016) (xy 485.611424 -307.468016) (xy 485.611424 -311.582816) (xy 486.957624 -311.582816)
				)
			)
		)
		(zone
			(layer "F.Cu")
			(hatch none 0.5)
			(connect_pads
				(clearance 0)
			)
			(min_thickness 0.25)
			(keepout
				(tracks not_allowed)
				(vias allowed)
				(pads allowed)
				(copperpour not_allowed)
				(footprints allowed)
			)
			(placement
				(enabled no)
				(sheetname "")
			)
			(fill
				(thermal_gap 0.5)
				(thermal_bridge_width 0.5)
				(island_removal_mode 0)
			)
			(polygon
				(pts
					(xy 486.957624 -304.648616) (xy 479.883724 -304.648616) (xy 479.883724 -311.582816) (xy 480.988624 -311.582816)
					(xy 480.988624 -307.468016) (xy 485.611424 -307.468016) (xy 485.611424 -311.582816) (xy 486.957624 -311.582816)
				)
			)
		)
		(zone
			(layer "F.Cu")
			(hatch none 0.5)
			(connect_pads
				(clearance 0)
			)
			(min_thickness 0.25)
			(keepout
				(tracks allowed)
				(vias not_allowed)
				(pads allowed)
				(copperpour not_allowed)
				(footprints allowed)
			)
			(placement
				(enabled no)
				(sheetname "")
			)
			(fill
				(thermal_gap 0.5)
				(thermal_bridge_width 0.5)
				(island_removal_mode 0)
			)
			(polygon
				(pts
					(xy 486.957624 -271.171416) (xy 479.883724 -271.171416) (xy 479.883724 -264.237216) (xy 480.988624 -264.237216)
					(xy 480.988624 -268.352016) (xy 485.611424 -268.352016) (xy 485.611424 -264.237216) (xy 486.957624 -264.237216)
				)
			)
		)
		(zone
			(layer "F.Cu")
			(hatch none 0.5)
			(connect_pads
				(clearance 0)
			)
			(min_thickness 0.25)
			(keepout
				(tracks not_allowed)
				(vias allowed)
				(pads allowed)
				(copperpour not_allowed)
				(footprints allowed)
			)
			(placement
				(enabled no)
				(sheetname "")
			)
			(fill
				(thermal_gap 0.5)
				(thermal_bridge_width 0.5)
				(island_removal_mode 0)
			)
			(polygon
				(pts
					(xy 486.957624 -271.171416) (xy 479.883724 -271.171416) (xy 479.883724 -264.237216) (xy 480.988624 -264.237216)
					(xy 480.988624 -268.352016) (xy 485.611424 -268.352016) (xy 485.611424 -264.237216) (xy 486.957624 -264.237216)
				)
			)
		)
		(zone
			(layers "F.Cu" "B.Cu" "In1.Cu" "In2.Cu" "In3.Cu" "In4.Cu" "In5.Cu" "In6.Cu"
				"In7.Cu" "In8.Cu" "In9.Cu" "In10.Cu"
			)
			(hatch none 0.5)
			(connect_pads
				(clearance 0)
			)
			(min_thickness 0.25)
			(keepout
				(tracks not_allowed)
				(vias allowed)
				(pads allowed)
				(copperpour not_allowed)
				(footprints allowed)
			)
			(placement
				(enabled no)
				(sheetname "")
			)
			(fill
				(thermal_gap 0.5)
				(thermal_bridge_width 0.5)
				(island_removal_mode 0)
			)
			(polygon
				(pts
					(arc
						(start 484.074724 -269.035022)
						(mid 482.525324 -269.035022)
						(end 484.074724 -269.035022)
					)
				)
			)
		)
		(zone
			(layers "F.Cu" "B.Cu" "In1.Cu" "In2.Cu" "In3.Cu" "In4.Cu" "In5.Cu" "In6.Cu"
				"In7.Cu" "In8.Cu" "In9.Cu" "In10.Cu"
			)
			(hatch none 0.5)
			(connect_pads
				(clearance 0)
			)
			(min_thickness 0.25)
			(keepout
				(tracks not_allowed)
				(vias allowed)
				(pads allowed)
				(copperpour not_allowed)
				(footprints allowed)
			)
			(placement
				(enabled no)
				(sheetname "")
			)
			(fill
				(thermal_gap 0.5)
				(thermal_bridge_width 0.5)
				(island_removal_mode 0)
			)
			(polygon
				(pts
					(arc
						(start 484.277924 -306.78501)
						(mid 482.322124 -306.78501)
						(end 484.277924 -306.78501)
					)
				)
			)
		)
	)
	(footprint ""
		(layer "F.Cu")
		(at 300.20006 -393.205716)
		(property "Reference" ""
			(at 0 0 0)
			(layer "F.SilkS")
			(hide yes)
			(effects
				(font
					(size 1.27 1.27)
				)
			)
		)
		(property "Value" "*"
			(at -8.398764 -8.057642 0)
			(unlocked yes)
			(layer "F.Fab")
			(hide yes)
			(effects
				(font
					(size 1.016 1.016)
					(thickness 0.1524)
				)
			)
		)
		(duplicate_pad_numbers_are_jumpers no)
		(fp_poly
			(pts
				(arc
					(start 7.3152 0)
					(mid 0 7.3152)
					(end -7.3152 0)
				)
				(arc
					(start -7.3152 -5.9944)
					(mid 0 -13.3096)
					(end 7.3152 -5.9944)
				)
			)
			(stroke
				(width 0)
				(type default)
			)
			(fill no)
			(layer "B.CrtYd")
		)
		(fp_poly
			(pts
				(arc
					(start 7.3152 0)
					(mid 0 7.3152)
					(end -7.3152 0)
				)
				(arc
					(start -7.3152 -5.9944)
					(mid 0 -13.3096)
					(end 7.3152 -5.9944)
				)
			)
			(stroke
				(width 0)
				(type default)
			)
			(fill no)
			(layer "F.CrtYd")
		)
		(fp_poly
			(pts
				(arc
					(start 7.3152 0)
					(mid 0 7.3152)
					(end -7.3152 0)
				)
				(arc
					(start -7.3152 -5.9944)
					(mid 0 -13.3096)
					(end 7.3152 -5.9944)
				)
			)
			(stroke
				(width 0)
				(type default)
			)
			(fill no)
			(layer "B.Fab")
		)
		(fp_poly
			(pts
				(arc
					(start 7.3152 0)
					(mid 0 7.3152)
					(end -7.3152 0)
				)
				(arc
					(start -7.3152 -5.9944)
					(mid 0 -13.3096)
					(end 7.3152 -5.9944)
				)
			)
			(stroke
				(width 0)
				(type default)
			)
			(fill no)
			(layer "F.Fab")
		)
		(pad "1" thru_hole oval
			(at 0 0)
			(size 14.0208 20.0152)
			(drill 0.0254
				(offset 0 -2.9972)
			)
			(layers "*.Cu" "*.Mask")
			(remove_unused_layers no)
			(net "Net_65")
			(clearance -1.002284)
			(thermal_gap 0.1524)
			(padstack
				(mode front_inner_back)
				(layer "Inner"
					(shape custom)
					(size 2.928012 2.928012)
					(options
						(anchor circle)
					)
					(primitives
						(gr_poly
							(pts
								(arc
									(start 4.571746 -2.084324)
									(mid 0.000333 7.430372)
									(end -4.571492 -2.084324)
								)
								(arc
									(start -4.571492 -2.084324)
									(mid -3.570296 -3.611977)
									(end -2.875026 -5.30098)
								)
								(arc
									(start -2.875026 -5.30098)
									(mid 0.000217 -7.43089)
									(end 2.87528 -5.30098)
								)
								(arc
									(start 2.87528 -5.30098)
									(mid 3.570511 -3.611956)
									(end 4.571746 -2.084324)
								)
							)
							(width 0)
							(fill yes)
						)
					)
					(clearance 0.1524)
				)
				(layer "B.Cu"
					(shape oval)
					(size 14.0208 20.0152)
					(offset 0 -2.9972)
					(clearance -1.002284)
				)
			)
		)
		(zone
			(layers "F.Cu" "B.Cu" "In1.Cu" "In2.Cu" "In3.Cu" "In4.Cu" "In5.Cu" "In6.Cu"
				"In7.Cu" "In8.Cu" "In9.Cu" "In10.Cu"
			)
			(hatch none 0.5)
			(connect_pads
				(clearance 0)
			)
			(min_thickness 0.25)
			(keepout
				(tracks not_allowed)
				(vias allowed)
				(pads allowed)
				(copperpour not_allowed)
				(footprints allowed)
			)
			(placement
				(enabled no)
				(sheetname "")
			)
			(fill
				(thermal_gap 0.5)
				(thermal_bridge_width 0.5)
				(island_removal_mode 0)
			)
			(polygon
				(pts
					(arc
						(start 293.18966 -399.200116)
						(mid 300.20006 -406.210516)
						(end 307.21046 -399.200116)
					)
					(arc
						(start 307.21046 -393.205716)
						(mid 300.20006 -386.195316)
						(end 293.18966 -393.205716)
					)
				)
			)
		)
	)
	(footprint ""
		(layer "F.Cu")
		(at 321.279012 -127.360934)
		(property "Reference" "R315"
			(at 0 0 0)
			(layer "F.SilkS")
			(hide yes)
			(effects
				(font
					(size 1.27 1.27)
				)
			)
		)
		(property "Value" "130R3F-GP"
			(at -0.0254 -2.5146 0)
			(unlocked yes)
			(layer "F.Fab")
			(hide yes)
			(effects
				(font
					(size 1.016 1.016)
					(thickness 0.1524)
				)
			)
		)
		(property "Device Type" "R603H22"
			(at -0.0254 -4.0386 0)
			(unlocked yes)
			(layer "F.Fab")
			(hide yes)
			(effects
				(font
					(size 1.016 1.016)
					(thickness 0.1524)
				)
			)
		)
		(duplicate_pad_numbers_are_jumpers no)
		(fp_line
			(start -0.4826 0)
			(end -0.2032 0)
			(stroke
				(width 0.2032)
				(type default)
			)
			(layer "F.SilkS")
		)
		(fp_line
			(start 0.2032 0)
			(end 0.4826 0)
			(stroke
				(width 0.2032)
				(type default)
			)
			(layer "F.SilkS")
		)
		(fp_rect
			(start -0.5842 1.3335)
			(end 0.5842 -1.3335)
			(stroke
				(width 0)
				(type default)
			)
			(fill no)
			(layer "F.CrtYd")
		)
		(fp_rect
			(start -0.5842 1.3335)
			(end 0.5842 -1.3335)
			(stroke
				(width 0)
				(type default)
			)
			(fill no)
			(layer "F.Fab")
		)
		(pad "1" smd custom
			(at 0 -0.762)
			(size 0.2159 0.2159)
			(layers "F.Cu" "F.Mask" "F.Paste")
			(net "P5V_A_3")
			(options
				(clearance outline)
				(anchor circle)
			)
			(primitives
				(gr_poly
					(pts
						(arc
							(start -0.3302 -0.4318)
							(mid -0.402042 -0.402042)
							(end -0.4318 -0.3302)
						)
						(arc
							(start -0.4318 0.3302)
							(mid -0.402042 0.402042)
							(end -0.3302 0.4318)
						)
						(arc
							(start 0.3302 0.4318)
							(mid 0.402042 0.402042)
							(end 0.4318 0.3302)
						)
						(arc
							(start 0.4318 -0.3302)
							(mid 0.402042 -0.402042)
							(end 0.3302 -0.4318)
						)
					)
					(width 0)
					(fill yes)
				)
			)
		)
		(pad "2" smd custom
			(at 0 0.762)
			(size 0.2159 0.2159)
			(layers "F.Cu" "F.Mask" "F.Paste")
			(net "FLT_HDD18")
			(options
				(clearance outline)
				(anchor circle)
			)
			(primitives
				(gr_poly
					(pts
						(arc
							(start -0.3302 -0.4318)
							(mid -0.402042 -0.402042)
							(end -0.4318 -0.3302)
						)
						(arc
							(start -0.4318 0.3302)
							(mid -0.402042 0.402042)
							(end -0.3302 0.4318)
						)
						(arc
							(start 0.3302 0.4318)
							(mid 0.402042 0.402042)
							(end 0.4318 0.3302)
						)
						(arc
							(start 0.4318 -0.3302)
							(mid 0.402042 -0.402042)
							(end 0.3302 -0.4318)
						)
					)
					(width 0)
					(fill yes)
				)
			)
		)
	)
	(footprint ""
		(layer "F.Cu")
		(at 83.530948 -292.778942 -90)
		(property "Reference" "C66"
			(at 0 0 270)
			(layer "F.SilkS")
			(hide yes)
			(effects
				(font
					(size 1.27 1.27)
				)
			)
		)
		(property "Value" "SC1U16V3KX-5GP"
			(at 0 -2.8194 270)
			(unlocked yes)
			(layer "F.Fab")
			(hide yes)
			(effects
				(font
					(size 1.016 1.016)
					(thickness 0.1524)
				)
			)
		)
		(property "Device Type" "C603H36"
			(at 0 -4.3434 270)
			(unlocked yes)
			(layer "F.Fab")
			(hide yes)
			(effects
				(font
					(size 1.016 1.016)
					(thickness 0.1524)
				)
			)
		)
		(duplicate_pad_numbers_are_jumpers no)
		(fp_line
			(start 0.508 0)
			(end -0.508 0)
			(stroke
				(width 0.2032)
				(type default)
			)
			(layer "F.SilkS")
		)
		(fp_rect
			(start -0.5842 1.3335)
			(end 0.5842 -1.3335)
			(stroke
				(width 0)
				(type default)
			)
			(fill no)
			(layer "F.CrtYd")
		)
		(fp_rect
			(start -0.5842 1.3335)
			(end 0.5842 -1.3335)
			(stroke
				(width 0)
				(type default)
			)
			(fill no)
			(layer "F.Fab")
		)
		(pad "1" smd custom
			(at 0 -0.762 270)
			(size 0.2159 0.2159)
			(layers "F.Cu" "F.Mask" "F.Paste")
			(net "P5V_HDD2")
			(options
				(clearance outline)
				(anchor circle)
			)
			(primitives
				(gr_poly
					(pts
						(arc
							(start -0.3302 -0.4318)
							(mid -0.402042 -0.402042)
							(end -0.4318 -0.3302)
						)
						(arc
							(start -0.4318 0.3302)
							(mid -0.402042 0.402042)
							(end -0.3302 0.4318)
						)
						(arc
							(start 0.3302 0.4318)
							(mid 0.402042 0.402042)
							(end 0.4318 0.3302)
						)
						(arc
							(start 0.4318 -0.3302)
							(mid 0.402042 -0.402042)
							(end 0.3302 -0.4318)
						)
					)
					(width 0)
					(fill yes)
				)
			)
		)
		(pad "2" smd custom
			(at 0 0.762 270)
			(size 0.2159 0.2159)
			(layers "F.Cu" "F.Mask" "F.Paste")
			(net "GND")
			(options
				(clearance outline)
				(anchor circle)
			)
			(primitives
				(gr_poly
					(pts
						(arc
							(start -0.3302 -0.4318)
							(mid -0.402042 -0.402042)
							(end -0.4318 -0.3302)
						)
						(arc
							(start -0.4318 0.3302)
							(mid -0.402042 0.402042)
							(end -0.3302 0.4318)
						)
						(arc
							(start 0.3302 0.4318)
							(mid 0.402042 0.402042)
							(end 0.4318 0.3302)
						)
						(arc
							(start 0.4318 -0.3302)
							(mid 0.402042 -0.402042)
							(end 0.3302 -0.4318)
						)
					)
					(width 0)
					(fill yes)
				)
			)
		)
	)
	(footprint ""
		(layer "F.Cu")
		(at 55.282846 -62.270894)
		(property "Reference" "R704"
			(at 0 0 0)
			(layer "F.SilkS")
			(hide yes)
			(effects
				(font
					(size 1.27 1.27)
				)
			)
		)
		(property "Value" "2R6F-GP"
			(at -0.0508 -4.8514 0)
			(unlocked yes)
			(layer "F.Fab")
			(hide yes)
			(effects
				(font
					(size 1.016 1.016)
					(thickness 0.1524)
				)
			)
		)
		(property "Device Type" "R1206H26"
			(at 0 -6.3754 0)
			(unlocked yes)
			(layer "F.Fab")
			(hide yes)
			(effects
				(font
					(size 1.016 1.016)
					(thickness 0.1524)
				)
			)
		)
		(duplicate_pad_numbers_are_jumpers no)
		(fp_line
			(start -1.016 -2.2352)
			(end 1.016 -2.2352)
			(stroke
				(width 0.1524)
				(type default)
			)
			(layer "F.SilkS")
		)
		(fp_line
			(start -1.016 2.2352)
			(end -1.016 -2.2352)
			(stroke
				(width 0.1524)
				(type default)
			)
			(layer "F.SilkS")
		)
		(fp_line
			(start 1.016 -2.2352)
			(end 1.016 2.2352)
			(stroke
				(width 0.1524)
				(type default)
			)
			(layer "F.SilkS")
		)
		(fp_line
			(start 1.016 2.2352)
			(end -1.016 2.2352)
			(stroke
				(width 0.1524)
				(type default)
			)
			(layer "F.SilkS")
		)
		(fp_rect
			(start -1.0922 2.3114)
			(end 1.0922 -2.3114)
			(stroke
				(width 0)
				(type default)
			)
			(fill no)
			(layer "F.CrtYd")
		)
		(fp_poly
			(pts
				(xy -1.0922 -2.3114) (xy 1.0922 -2.3114) (xy 1.0922 2.3114) (xy -1.0922 2.3114)
			)
			(stroke
				(width 0)
				(type default)
			)
			(fill no)
			(layer "F.Fab")
		)
		(pad "1" smd rect
			(at 0 -1.397)
			(size 1.651 1.27)
			(layers "F.Cu" "F.Mask" "F.Paste")
			(net "P5V_HDD25")
		)
		(pad "2" smd rect
			(at 0 1.397)
			(size 1.651 1.27)
			(layers "F.Cu" "F.Mask" "F.Paste")
			(net "5V_PRE_25")
		)
	)
	(footprint ""
		(layer "F.Cu")
		(at 50.050446 -45.633894)
		(property "Reference" "R722"
			(at 0 0 0)
			(layer "F.SilkS")
			(hide yes)
			(effects
				(font
					(size 1.27 1.27)
				)
			)
		)
		(property "Value" "0R2J-2-GP"
			(at 0.064008 -3.993896 0)
			(unlocked yes)
			(layer "F.Fab")
			(hide yes)
			(effects
				(font
					(size 1.016 1.016)
					(thickness 0.1524)
				)
			)
		)
		(property "Device Type" "R402H16"
			(at 0.064008 -5.517896 0)
			(unlocked yes)
			(layer "F.Fab")
			(hide yes)
			(effects
				(font
					(size 1.016 1.016)
					(thickness 0.1524)
				)
			)
		)
		(duplicate_pad_numbers_are_jumpers no)
		(fp_line
			(start -0.508 -0.9398)
			(end -0.508 0.9398)
			(stroke
				(width 0.1524)
				(type default)
			)
			(layer "F.SilkS")
		)
		(fp_line
			(start 0.508 -0.9398)
			(end -0.508 -0.9398)
			(stroke
				(width 0.1524)
				(type default)
			)
			(layer "F.SilkS")
		)
		(fp_rect
			(start -0.508 0.9398)
			(end 0.508 -0.9398)
			(stroke
				(width 0)
				(type default)
			)
			(fill no)
			(layer "F.CrtYd")
		)
		(fp_rect
			(start -0.508 0.9398)
			(end 0.508 -0.9398)
			(stroke
				(width 0)
				(type default)
			)
			(fill no)
			(layer "F.Fab")
		)
		(pad "1" smd custom
			(at 0 -0.4445)
			(size 0.1397 0.1397)
			(layers "F.Cu" "F.Mask" "F.Paste")
			(net "SW_HDD_G25")
			(options
				(clearance outline)
				(anchor circle)
			)
			(primitives
				(gr_poly
					(pts
						(arc
							(start -0.1778 -0.2794)
							(mid -0.249642 -0.249642)
							(end -0.2794 -0.1778)
						)
						(arc
							(start -0.2794 0.1778)
							(mid -0.249642 0.249642)
							(end -0.1778 0.2794)
						)
						(arc
							(start 0.1778 0.2794)
							(mid 0.249642 0.249642)
							(end 0.2794 0.1778)
						)
						(arc
							(start 0.2794 -0.1778)
							(mid 0.249642 -0.249642)
							(end 0.1778 -0.2794)
						)
					)
					(width 0)
					(fill yes)
				)
			)
		)
		(pad "2" smd custom
			(at 0 0.4445)
			(size 0.1397 0.1397)
			(layers "F.Cu" "F.Mask" "F.Paste")
			(net "SW_HDD_R25")
			(options
				(clearance outline)
				(anchor circle)
			)
			(primitives
				(gr_poly
					(pts
						(arc
							(start -0.1778 -0.2794)
							(mid -0.249642 -0.249642)
							(end -0.2794 -0.1778)
						)
						(arc
							(start -0.2794 0.1778)
							(mid -0.249642 0.249642)
							(end -0.1778 0.2794)
						)
						(arc
							(start 0.1778 0.2794)
							(mid 0.249642 0.249642)
							(end 0.2794 0.1778)
						)
						(arc
							(start 0.2794 -0.1778)
							(mid 0.249642 -0.249642)
							(end 0.1778 -0.2794)
						)
					)
					(width 0)
					(fill yes)
				)
			)
		)
	)
	(footprint ""
		(layer "F.Cu")
		(at 20.049998 -291.000942 -90)
		(property "Reference" "C509"
			(at 0 0 270)
			(layer "F.SilkS")
			(hide yes)
			(effects
				(font
					(size 1.27 1.27)
				)
			)
		)
		(property "Value" "SC10U16V6KX-2GP"
			(at -0.0762 -5.1308 270)
			(unlocked yes)
			(layer "F.Fab")
			(hide yes)
			(effects
				(font
					(size 1.016 1.016)
					(thickness 0.1524)
				)
			)
		)
		(property "Device Type" "C1206H71"
			(at -0.127 -6.6548 270)
			(unlocked yes)
			(layer "F.Fab")
			(hide yes)
			(effects
				(font
					(size 1.016 1.016)
					(thickness 0.1524)
				)
			)
		)
		(duplicate_pad_numbers_are_jumpers no)
		(fp_line
			(start -1.016 2.2352)
			(end -1.016 0.8382)
			(stroke
				(width 0.1524)
				(type default)
			)
			(layer "F.SilkS")
		)
		(fp_line
			(start 1.016 2.2352)
			(end -1.016 2.2352)
			(stroke
				(width 0.1524)
				(type default)
			)
			(layer "F.SilkS")
		)
		(fp_line
			(start 1.016 0.8382)
			(end 1.016 2.2352)
			(stroke
				(width 0.1524)
				(type default)
			)
			(layer "F.SilkS")
		)
		(fp_line
			(start -1.016 -0.8382)
			(end -1.016 -2.2352)
			(stroke
				(width 0.1524)
				(type default)
			)
			(layer "F.SilkS")
		)
		(fp_line
			(start -1.016 -2.2352)
			(end 1.016 -2.2352)
			(stroke
				(width 0.1524)
				(type default)
			)
			(layer "F.SilkS")
		)
		(fp_line
			(start 1.016 -2.2352)
			(end 1.016 -0.8382)
			(stroke
				(width 0.1524)
				(type default)
			)
			(layer "F.SilkS")
		)
		(fp_rect
			(start -1.0922 2.3114)
			(end 1.0922 -2.3114)
			(stroke
				(width 0)
				(type default)
			)
			(fill no)
			(layer "F.CrtYd")
		)
		(fp_poly
			(pts
				(xy 1.0922 -2.3114) (xy 1.0922 2.3114) (xy -1.0922 2.3114) (xy -1.0922 -2.3114)
			)
			(stroke
				(width 0)
				(type default)
			)
			(fill no)
			(layer "F.Fab")
		)
		(pad "1" smd rect
			(at 0 -1.397 270)
			(size 1.651 1.27)
			(layers "F.Cu" "F.Mask" "F.Paste")
			(net "P5V_HDD0")
		)
		(pad "2" smd rect
			(at 0 1.397 270)
			(size 1.651 1.27)
			(layers "F.Cu" "F.Mask" "F.Paste")
			(net "GND")
		)
	)
	(footprint ""
		(layer "F.Cu")
		(at 267.197078 -128.448308 90)
		(property "Reference" "TP184"
			(at 0 0 90)
			(layer "F.SilkS")
			(hide yes)
			(effects
				(font
					(size 1.27 1.27)
				)
			)
		)
		(property "Value" "TPAD32-GP"
			(at -0.0508 -1.6764 90)
			(unlocked yes)
			(layer "F.Fab")
			(hide yes)
			(effects
				(font
					(size 1.016 1.016)
					(thickness 0.1524)
				)
			)
		)
		(property "Device Type" "TPAD32"
			(at -0.0508 -3.2004 90)
			(unlocked yes)
			(layer "F.Fab")
			(hide yes)
			(effects
				(font
					(size 1.016 1.016)
					(thickness 0.1524)
				)
			)
		)
		(duplicate_pad_numbers_are_jumpers no)
		(fp_poly
			(pts
				(arc
					(start 0 0.4064)
					(mid 0 -0.4064)
					(end 0 0.4064)
				)
			)
			(stroke
				(width 0)
				(type default)
			)
			(fill no)
			(layer "F.CrtYd")
		)
		(fp_poly
			(pts
				(arc
					(start 0 0.7112)
					(mid 0 -0.7112)
					(end 0 0.7112)
				)
			)
			(stroke
				(width 0)
				(type default)
			)
			(fill no)
			(layer "F.Fab")
		)
		(pad "1" smd circle
			(at 0 0 90)
			(size 0.8128 0.8128)
			(layers "F.Cu" "F.Mask" "F.Paste")
			(net "TP_COMP_B_SATA_P0_TX_DN")
		)
	)
	(footprint ""
		(layer "F.Cu")
		(at 395.20495 -45.252894 -90)
		(property "Reference" "Q193"
			(at 0 0 270)
			(layer "F.SilkS")
			(hide yes)
			(effects
				(font
					(size 1.27 1.27)
				)
			)
		)
		(property "Value" "2N7002KDW-GP"
			(at -2.3622 -8.2042 270)
			(unlocked yes)
			(layer "F.Fab")
			(hide yes)
			(effects
				(font
					(size 1.016 1.016)
					(thickness 0.1524)
				)
			)
		)
		(property "Device Type" "SOT-363H44"
			(at -2.3622 -10.1092 270)
			(unlocked yes)
			(layer "F.Fab")
			(hide yes)
			(effects
				(font
					(size 1.016 1.016)
					(thickness 0.1524)
				)
			)
		)
		(duplicate_pad_numbers_are_jumpers no)
		(fp_line
			(start -1.4478 1.7018)
			(end 1.4478 1.7018)
			(stroke
				(width 0.1524)
				(type default)
			)
			(layer "F.SilkS")
		)
		(fp_line
			(start 1.4478 1.7018)
			(end 1.4478 -1.7018)
			(stroke
				(width 0.1524)
				(type default)
			)
			(layer "F.SilkS")
		)
		(fp_line
			(start -1.27 1.524)
			(end -1.27 0.6604)
			(stroke
				(width 0.4826)
				(type default)
			)
			(layer "F.SilkS")
		)
		(fp_line
			(start -1.4478 -1.7018)
			(end -1.4478 1.7018)
			(stroke
				(width 0.1524)
				(type default)
			)
			(layer "F.SilkS")
		)
		(fp_line
			(start 1.4478 -1.7018)
			(end -1.4478 -1.7018)
			(stroke
				(width 0.1524)
				(type default)
			)
			(layer "F.SilkS")
		)
		(fp_poly
			(pts
				(xy -1.524 -1.778) (xy 1.524 -1.778) (xy 1.524 1.778) (xy -1.524 1.778)
			)
			(stroke
				(width 0)
				(type default)
			)
			(fill no)
			(layer "F.CrtYd")
		)
		(fp_poly
			(pts
				(xy -1.524 -1.778) (xy 1.524 -1.778) (xy 1.524 1.778) (xy -1.524 1.778)
			)
			(stroke
				(width 0)
				(type default)
			)
			(fill no)
			(layer "F.Fab")
		)
		(pad "1" smd rect
			(at -0.65024 0.9398 270)
			(size 0.4064 1.016)
			(layers "F.Cu" "F.Mask" "F.Paste")
			(net "GND")
		)
		(pad "2" smd rect
			(at 0 0.9398 270)
			(size 0.4064 1.016)
			(layers "F.Cu" "F.Mask" "F.Paste")
			(net "SW_PWR_R_HDD32")
		)
		(pad "3" smd rect
			(at 0.65024 0.9398 270)
			(size 0.4064 1.016)
			(layers "F.Cu" "F.Mask" "F.Paste")
			(net "SW_HDD_P32")
		)
		(pad "4" smd rect
			(at 0.65024 -0.9398 270)
			(size 0.4064 1.016)
			(layers "F.Cu" "F.Mask" "F.Paste")
			(net "GND")
		)
		(pad "5" smd rect
			(at 0 -0.9398 270)
			(size 0.4064 1.016)
			(layers "F.Cu" "F.Mask" "F.Paste")
			(net "SW_HDD_G32")
		)
		(pad "6" smd rect
			(at -0.65024 -0.9398 270)
			(size 0.4064 1.016)
			(layers "F.Cu" "F.Mask" "F.Paste")
			(net "SW_HDD_R32")
		)
	)
	(footprint ""
		(layer "F.Cu")
		(at 424.469052 -189.335918 180)
		(property "Reference" "C320"
			(at 0 0 180)
			(layer "F.SilkS")
			(hide yes)
			(effects
				(font
					(size 1.27 1.27)
				)
			)
		)
		(property "Value" "SC1U25V3KX-GP"
			(at 0 -2.8194 180)
			(unlocked yes)
			(layer "F.Fab")
			(hide yes)
			(effects
				(font
					(size 1.016 1.016)
					(thickness 0.1524)
				)
			)
		)
		(property "Device Type" "C603H36"
			(at 0 -4.3434 180)
			(unlocked yes)
			(layer "F.Fab")
			(hide yes)
			(effects
				(font
					(size 1.016 1.016)
					(thickness 0.1524)
				)
			)
		)
		(duplicate_pad_numbers_are_jumpers no)
		(fp_line
			(start 0.508 0)
			(end -0.508 0)
			(stroke
				(width 0.2032)
				(type default)
			)
			(layer "F.SilkS")
		)
		(fp_rect
			(start -0.5842 1.3335)
			(end 0.5842 -1.3335)
			(stroke
				(width 0)
				(type default)
			)
			(fill no)
			(layer "F.CrtYd")
		)
		(fp_rect
			(start -0.5842 1.3335)
			(end 0.5842 -1.3335)
			(stroke
				(width 0)
				(type default)
			)
			(fill no)
			(layer "F.Fab")
		)
		(pad "1" smd custom
			(at 0 -0.762 180)
			(size 0.2159 0.2159)
			(layers "F.Cu" "F.Mask" "F.Paste")
			(net "P12V_HDD21")
			(options
				(clearance outline)
				(anchor circle)
			)
			(primitives
				(gr_poly
					(pts
						(arc
							(start -0.3302 -0.4318)
							(mid -0.402042 -0.402042)
							(end -0.4318 -0.3302)
						)
						(arc
							(start -0.4318 0.3302)
							(mid -0.402042 0.402042)
							(end -0.3302 0.4318)
						)
						(arc
							(start 0.3302 0.4318)
							(mid 0.402042 0.402042)
							(end 0.4318 0.3302)
						)
						(arc
							(start 0.4318 -0.3302)
							(mid 0.402042 -0.402042)
							(end 0.3302 -0.4318)
						)
					)
					(width 0)
					(fill yes)
				)
			)
		)
		(pad "2" smd custom
			(at 0 0.762 180)
			(size 0.2159 0.2159)
			(layers "F.Cu" "F.Mask" "F.Paste")
			(net "GND")
			(options
				(clearance outline)
				(anchor circle)
			)
			(primitives
				(gr_poly
					(pts
						(arc
							(start -0.3302 -0.4318)
							(mid -0.402042 -0.402042)
							(end -0.4318 -0.3302)
						)
						(arc
							(start -0.4318 0.3302)
							(mid -0.402042 0.402042)
							(end -0.3302 0.4318)
						)
						(arc
							(start 0.3302 0.4318)
							(mid 0.402042 0.402042)
							(end 0.4318 0.3302)
						)
						(arc
							(start 0.4318 -0.3302)
							(mid 0.402042 -0.402042)
							(end 0.3302 -0.4318)
						)
					)
					(width 0)
					(fill yes)
				)
			)
		)
	)
	(footprint ""
		(layer "F.Cu")
		(at 220.861636 -346.331794 180)
		(property "Reference" "TP2"
			(at 0 0 180)
			(layer "F.SilkS")
			(hide yes)
			(effects
				(font
					(size 1.27 1.27)
				)
			)
		)
		(property "Value" "TPAD32-GP"
			(at -0.0508 -1.6764 180)
			(unlocked yes)
			(layer "F.Fab")
			(hide yes)
			(effects
				(font
					(size 1.016 1.016)
					(thickness 0.1524)
				)
			)
		)
		(property "Device Type" "TPAD32"
			(at -0.0508 -3.2004 180)
			(unlocked yes)
			(layer "F.Fab")
			(hide yes)
			(effects
				(font
					(size 1.016 1.016)
					(thickness 0.1524)
				)
			)
		)
		(duplicate_pad_numbers_are_jumpers no)
		(fp_poly
			(pts
				(arc
					(start -0.4064 0)
					(mid 0.4064 0)
					(end -0.4064 0)
				)
			)
			(stroke
				(width 0)
				(type default)
			)
			(fill no)
			(layer "F.CrtYd")
		)
		(fp_poly
			(pts
				(arc
					(start -0.7112 0)
					(mid 0.7112 0)
					(end -0.7112 0)
				)
			)
			(stroke
				(width 0)
				(type default)
			)
			(fill no)
			(layer "F.Fab")
		)
		(pad "1" smd circle
			(at 0 0 180)
			(size 0.8128 0.8128)
			(layers "F.Cu" "F.Mask" "F.Paste")
			(net "VOL_SEN_INT_N")
		)
	)
	(footprint ""
		(layer "F.Cu")
		(at 413.318452 -62.143894 90)
		(property "Reference" "R889"
			(at 0 0 90)
			(layer "F.SilkS")
			(hide yes)
			(effects
				(font
					(size 1.27 1.27)
				)
			)
		)
		(property "Value" "10KR2F-2-GP"
			(at 0.064008 -3.993896 90)
			(unlocked yes)
			(layer "F.Fab")
			(hide yes)
			(effects
				(font
					(size 1.016 1.016)
					(thickness 0.1524)
				)
			)
		)
		(property "Device Type" "R402H16"
			(at 0.064008 -5.517896 90)
			(unlocked yes)
			(layer "F.Fab")
			(hide yes)
			(effects
				(font
					(size 1.016 1.016)
					(thickness 0.1524)
				)
			)
		)
		(duplicate_pad_numbers_are_jumpers no)
		(fp_line
			(start 0.508 -0.9398)
			(end -0.508 -0.9398)
			(stroke
				(width 0.1524)
				(type default)
			)
			(layer "F.SilkS")
		)
		(fp_line
			(start -0.508 -0.9398)
			(end -0.508 0.9398)
			(stroke
				(width 0.1524)
				(type default)
			)
			(layer "F.SilkS")
		)
		(fp_rect
			(start -0.508 0.9398)
			(end 0.508 -0.9398)
			(stroke
				(width 0)
				(type default)
			)
			(fill no)
			(layer "F.CrtYd")
		)
		(fp_rect
			(start -0.508 0.9398)
			(end 0.508 -0.9398)
			(stroke
				(width 0)
				(type default)
			)
			(fill no)
			(layer "F.Fab")
		)
		(pad "1" smd custom
			(at 0 -0.4445 90)
			(size 0.1397 0.1397)
			(layers "F.Cu" "F.Mask" "F.Paste")
			(net "P3V3_STBY_A")
			(options
				(clearance outline)
				(anchor circle)
			)
			(primitives
				(gr_poly
					(pts
						(arc
							(start -0.1778 -0.2794)
							(mid -0.249642 -0.249642)
							(end -0.2794 -0.1778)
						)
						(arc
							(start -0.2794 0.1778)
							(mid -0.249642 0.249642)
							(end -0.1778 0.2794)
						)
						(arc
							(start 0.1778 0.2794)
							(mid 0.249642 0.249642)
							(end 0.2794 0.1778)
						)
						(arc
							(start 0.2794 -0.1778)
							(mid 0.249642 -0.249642)
							(end 0.1778 -0.2794)
						)
					)
					(width 0)
					(fill yes)
				)
			)
		)
		(pad "2" smd custom
			(at 0 0.4445 90)
			(size 0.1397 0.1397)
			(layers "F.Cu" "F.Mask" "F.Paste")
			(net "HDD_PRSNT_33")
			(options
				(clearance outline)
				(anchor circle)
			)
			(primitives
				(gr_poly
					(pts
						(arc
							(start -0.1778 -0.2794)
							(mid -0.249642 -0.249642)
							(end -0.2794 -0.1778)
						)
						(arc
							(start -0.2794 0.1778)
							(mid -0.249642 0.249642)
							(end -0.1778 0.2794)
						)
						(arc
							(start 0.1778 0.2794)
							(mid 0.249642 0.249642)
							(end 0.2794 0.1778)
						)
						(arc
							(start 0.2794 -0.1778)
							(mid 0.249642 -0.249642)
							(end 0.1778 -0.2794)
						)
					)
					(width 0)
					(fill yes)
				)
			)
		)
	)
	(footprint ""
		(layer "F.Cu")
		(at 114.216942 -278.822404 90)
		(property "Reference" "D3"
			(at 0 0 90)
			(layer "F.SilkS")
			(hide yes)
			(effects
				(font
					(size 1.27 1.27)
				)
			)
		)
		(property "Value" "RB551V30-GP"
			(at 0 -6.7818 90)
			(unlocked yes)
			(layer "F.Fab")
			(hide yes)
			(effects
				(font
					(size 1.016 1.016)
					(thickness 0.1524)
				)
			)
		)
		(property "Device Type" "SOD323AKH38"
			(at 0 -8.6868 90)
			(unlocked yes)
			(layer "F.Fab")
			(hide yes)
			(effects
				(font
					(size 1.016 1.016)
					(thickness 0.1524)
				)
			)
		)
		(duplicate_pad_numbers_are_jumpers no)
		(fp_line
			(start 0.889 -1.9304)
			(end 0.889 2.159)
			(stroke
				(width 0.1524)
				(type default)
			)
			(layer "F.SilkS")
		)
		(fp_line
			(start -0.889 -1.9304)
			(end 0.889 -1.9304)
			(stroke
				(width 0.1524)
				(type default)
			)
			(layer "F.SilkS")
		)
		(fp_line
			(start 0.762 2.0574)
			(end -0.762 2.0574)
			(stroke
				(width 0.508)
				(type default)
			)
			(layer "F.SilkS")
		)
		(fp_line
			(start 0.889 2.159)
			(end -0.889 2.159)
			(stroke
				(width 0.1524)
				(type default)
			)
			(layer "F.SilkS")
		)
		(fp_line
			(start -0.889 2.159)
			(end -0.889 -1.9304)
			(stroke
				(width 0.1524)
				(type default)
			)
			(layer "F.SilkS")
		)
		(fp_rect
			(start -1.016 2.3114)
			(end 1.016 -2.0066)
			(stroke
				(width 0)
				(type default)
			)
			(fill no)
			(layer "F.CrtYd")
		)
		(fp_poly
			(pts
				(xy -1.016 -2.0066) (xy 1.016 -2.0066) (xy 1.016 2.3114) (xy -1.016 2.3114)
			)
			(stroke
				(width 0)
				(type default)
			)
			(fill no)
			(layer "F.Fab")
		)
		(pad "A" smd rect
			(at 0 -1.143 90)
			(size 0.5588 1.016)
			(layers "F.Cu" "F.Mask" "F.Paste")
			(net "SW_HDD_R3")
		)
		(pad "K" smd rect
			(at 0 1.143 90)
			(size 0.5588 1.016)
			(layers "F.Cu" "F.Mask" "F.Paste")
			(net "SW_HDD_N3")
		)
	)
	(footprint ""
		(layer "F.Cu")
		(at 365.136938 -69.44995 -90)
		(property "Reference" "R844"
			(at 0 0 270)
			(layer "F.SilkS")
			(hide yes)
			(effects
				(font
					(size 1.27 1.27)
				)
			)
		)
		(property "Value" "2R6F-GP"
			(at -0.0508 -4.8514 270)
			(unlocked yes)
			(layer "F.Fab")
			(hide yes)
			(effects
				(font
					(size 1.016 1.016)
					(thickness 0.1524)
				)
			)
		)
		(property "Device Type" "R1206H26"
			(at 0 -6.3754 270)
			(unlocked yes)
			(layer "F.Fab")
			(hide yes)
			(effects
				(font
					(size 1.016 1.016)
					(thickness 0.1524)
				)
			)
		)
		(duplicate_pad_numbers_are_jumpers no)
		(fp_line
			(start -1.016 2.2352)
			(end -1.016 -2.2352)
			(stroke
				(width 0.1524)
				(type default)
			)
			(layer "F.SilkS")
		)
		(fp_line
			(start 1.016 2.2352)
			(end -1.016 2.2352)
			(stroke
				(width 0.1524)
				(type default)
			)
			(layer "F.SilkS")
		)
		(fp_line
			(start -1.016 -2.2352)
			(end 1.016 -2.2352)
			(stroke
				(width 0.1524)
				(type default)
			)
			(layer "F.SilkS")
		)
		(fp_line
			(start 1.016 -2.2352)
			(end 1.016 2.2352)
			(stroke
				(width 0.1524)
				(type default)
			)
			(layer "F.SilkS")
		)
		(fp_rect
			(start -1.0922 2.3114)
			(end 1.0922 -2.3114)
			(stroke
				(width 0)
				(type default)
			)
			(fill no)
			(layer "F.CrtYd")
		)
		(fp_poly
			(pts
				(xy -1.0922 -2.3114) (xy 1.0922 -2.3114) (xy 1.0922 2.3114) (xy -1.0922 2.3114)
			)
			(stroke
				(width 0)
				(type default)
			)
			(fill no)
			(layer "F.Fab")
		)
		(pad "1" smd rect
			(at 0 -1.397 270)
			(size 1.651 1.27)
			(layers "F.Cu" "F.Mask" "F.Paste")
			(net "P12V_HDD31")
		)
		(pad "2" smd rect
			(at 0 1.397 270)
			(size 1.651 1.27)
			(layers "F.Cu" "F.Mask" "F.Paste")
			(net "12V_PRE_31")
		)
	)
	(footprint ""
		(layer "F.Cu")
		(at 438.2389 -162.749992 -90)
		(property "Reference" "VIA24"
			(at 0 0 270)
			(layer "F.SilkS")
			(hide yes)
			(effects
				(font
					(size 1.27 1.27)
				)
			)
		)
		(property "Value" "100OHM-8L-1D6MM-L18L16-GP"
			(at -3.7211 -4.5085 270)
			(unlocked yes)
			(layer "F.Fab")
			(hide yes)
			(effects
				(font
					(size 1.016 1.016)
					(thickness 0.1524)
				)
			)
		)
		(property "Device Type" "VIA-PCIE-4P-394076"
			(at -3.7211 -6.0325 270)
			(unlocked yes)
			(layer "F.Fab")
			(hide yes)
			(effects
				(font
					(size 1.016 1.016)
					(thickness 0.1524)
				)
			)
		)
		(duplicate_pad_numbers_are_jumpers no)
		(fp_rect
			(start -1.9685 0.381)
			(end 1.9685 -0.381)
			(stroke
				(width 0)
				(type default)
			)
			(fill no)
			(layer "F.CrtYd")
		)
		(fp_rect
			(start -1.9685 0.381)
			(end 1.9685 -0.381)
			(stroke
				(width 0)
				(type default)
			)
			(fill no)
			(layer "F.Fab")
		)
		(pad "1" thru_hole circle
			(at -1.5875 0 270)
			(size 0.508 0.508)
			(drill 0.254)
			(layers "*.Cu" "*.Mask")
			(remove_unused_layers no)
			(net "GND")
			(clearance 0.127)
			(thermal_gap 0.127)
		)
		(pad "2" thru_hole circle
			(at -0.5715 0 270)
			(size 0.508 0.508)
			(drill 0.254)
			(layers "*.Cu" "*.Mask")
			(remove_unused_layers no)
			(net "PHY_DRV_A_TO_SCC_A_22_DP")
			(clearance 0.127)
			(thermal_gap 0.127)
		)
		(pad "3" thru_hole circle
			(at 0.5715 0 270)
			(size 0.508 0.508)
			(drill 0.254)
			(layers "*.Cu" "*.Mask")
			(remove_unused_layers no)
			(net "PHY_DRV_A_TO_SCC_A_22_DN")
			(clearance 0.127)
			(thermal_gap 0.127)
		)
		(pad "4" thru_hole circle
			(at 1.5875 0 270)
			(size 0.508 0.508)
			(drill 0.254)
			(layers "*.Cu" "*.Mask")
			(remove_unused_layers no)
			(net "GND")
			(clearance 0.127)
			(thermal_gap 0.127)
		)
	)
	(footprint ""
		(layer "F.Cu")
		(at 260.874002 -217.894662)
		(property "Reference" "C23"
			(at 0 0 0)
			(layer "F.SilkS")
			(hide yes)
			(effects
				(font
					(size 1.27 1.27)
				)
			)
		)
		(property "Value" "SC1U16V3KX-5GP"
			(at 0 -2.8194 0)
			(unlocked yes)
			(layer "F.Fab")
			(hide yes)
			(effects
				(font
					(size 1.016 1.016)
					(thickness 0.1524)
				)
			)
		)
		(property "Device Type" "C603H36"
			(at 0 -4.3434 0)
			(unlocked yes)
			(layer "F.Fab")
			(hide yes)
			(effects
				(font
					(size 1.016 1.016)
					(thickness 0.1524)
				)
			)
		)
		(duplicate_pad_numbers_are_jumpers no)
		(fp_line
			(start 0.508 0)
			(end -0.508 0)
			(stroke
				(width 0.2032)
				(type default)
			)
			(layer "F.SilkS")
		)
		(fp_rect
			(start -0.5842 1.3335)
			(end 0.5842 -1.3335)
			(stroke
				(width 0)
				(type default)
			)
			(fill no)
			(layer "F.CrtYd")
		)
		(fp_rect
			(start -0.5842 1.3335)
			(end 0.5842 -1.3335)
			(stroke
				(width 0)
				(type default)
			)
			(fill no)
			(layer "F.Fab")
		)
		(pad "1" smd custom
			(at 0 -0.762)
			(size 0.2159 0.2159)
			(layers "F.Cu" "F.Mask" "F.Paste")
			(net "P3V3_STBY_A")
			(options
				(clearance outline)
				(anchor circle)
			)
			(primitives
				(gr_poly
					(pts
						(arc
							(start -0.3302 -0.4318)
							(mid -0.402042 -0.402042)
							(end -0.4318 -0.3302)
						)
						(arc
							(start -0.4318 0.3302)
							(mid -0.402042 0.402042)
							(end -0.3302 0.4318)
						)
						(arc
							(start 0.3302 0.4318)
							(mid 0.402042 0.402042)
							(end 0.4318 0.3302)
						)
						(arc
							(start 0.4318 -0.3302)
							(mid 0.402042 -0.402042)
							(end 0.3302 -0.4318)
						)
					)
					(width 0)
					(fill yes)
				)
			)
		)
		(pad "2" smd custom
			(at 0 0.762)
			(size 0.2159 0.2159)
			(layers "F.Cu" "F.Mask" "F.Paste")
			(net "GND")
			(options
				(clearance outline)
				(anchor circle)
			)
			(primitives
				(gr_poly
					(pts
						(arc
							(start -0.3302 -0.4318)
							(mid -0.402042 -0.402042)
							(end -0.4318 -0.3302)
						)
						(arc
							(start -0.4318 0.3302)
							(mid -0.402042 0.402042)
							(end -0.3302 0.4318)
						)
						(arc
							(start 0.3302 0.4318)
							(mid 0.402042 0.402042)
							(end 0.4318 0.3302)
						)
						(arc
							(start 0.4318 -0.3302)
							(mid 0.402042 -0.402042)
							(end 0.3302 -0.4318)
						)
					)
					(width 0)
					(fill yes)
				)
			)
		)
	)
	(footprint ""
		(layer "F.Cu")
		(at 49.349914 -94.400116)
		(property "Reference" "FLED14"
			(at 0 0 0)
			(layer "F.SilkS")
			(hide yes)
			(effects
				(font
					(size 1.27 1.27)
				)
			)
		)
		(property "Value" "LED-BY-19-GP"
			(at -2.132076 1.414018 0)
			(unlocked yes)
			(layer "F.Fab")
			(hide yes)
			(effects
				(font
					(size 1.016 1.016)
					(thickness 0.1524)
				)
			)
		)
		(property "Device Type" "LED-1615-4PH26"
			(at -2.132076 -0.109982 0)
			(unlocked yes)
			(layer "F.Fab")
			(hide yes)
			(effects
				(font
					(size 1.016 1.016)
					(thickness 0.1524)
				)
			)
		)
		(duplicate_pad_numbers_are_jumpers no)
		(fp_line
			(start -1.2954 0.254)
			(end -1.2954 1.6002)
			(stroke
				(width 0.508)
				(type default)
			)
			(layer "F.SilkS")
		)
		(fp_line
			(start -1.2954 1.6002)
			(end 1.2954 1.6002)
			(stroke
				(width 0.508)
				(type default)
			)
			(layer "F.SilkS")
		)
		(fp_line
			(start -1.1176 -1.4224)
			(end 1.1176 -1.4224)
			(stroke
				(width 0.1524)
				(type default)
			)
			(layer "F.SilkS")
		)
		(fp_line
			(start -1.1176 1.4224)
			(end -1.1176 -1.4224)
			(stroke
				(width 0.1524)
				(type default)
			)
			(layer "F.SilkS")
		)
		(fp_line
			(start 1.1176 -1.4224)
			(end 1.1176 1.4224)
			(stroke
				(width 0.1524)
				(type default)
			)
			(layer "F.SilkS")
		)
		(fp_line
			(start 1.1176 1.4224)
			(end -1.1176 1.4224)
			(stroke
				(width 0.1524)
				(type default)
			)
			(layer "F.SilkS")
		)
		(fp_line
			(start 1.2954 1.6002)
			(end 1.2954 0.254)
			(stroke
				(width 0.508)
				(type default)
			)
			(layer "F.SilkS")
		)
		(fp_rect
			(start -0.7493 0.8001)
			(end 0.7493 -0.8001)
			(stroke
				(width 0)
				(type default)
			)
			(fill no)
			(layer "F.CrtYd")
		)
		(fp_poly
			(pts
				(xy -1.3716 1.6764) (xy -1.3716 -1.6764) (xy 1.3716 -1.6764) (xy 1.3716 0.0635) (xy 0.7493 0.0635)
				(xy 0.7493 -0.8001) (xy -0.7493 -0.8001) (xy -0.7493 0.8001) (xy 0.7493 0.8001) (xy 0.7493 0.0762)
				(xy 1.3716 0.0762) (xy 1.3716 1.6764)
			)
			(stroke
				(width 0)
				(type default)
			)
			(fill no)
			(layer "F.CrtYd")
		)
		(fp_rect
			(start -1.3716 1.6764)
			(end 1.3716 -1.6764)
			(stroke
				(width 0)
				(type default)
			)
			(fill no)
			(layer "F.Fab")
		)
		(pad "1" smd rect
			(at 0.50038 -0.73025)
			(size 0.7112 0.8636)
			(layers "F.Cu" "F.Mask" "F.Paste")
			(net "DRV_ACT_13")
		)
		(pad "2" smd rect
			(at -0.50038 -0.73025)
			(size 0.7112 0.8636)
			(layers "F.Cu" "F.Mask" "F.Paste")
			(net "FLT_HDD13")
		)
		(pad "3" smd rect
			(at 0.50038 0.73025)
			(size 0.7112 0.8636)
			(layers "F.Cu" "F.Mask" "F.Paste")
			(net "DRV_ACT_13_N")
		)
		(pad "4" smd rect
			(at -0.50038 0.73025)
			(size 0.7112 0.8636)
			(layers "F.Cu" "F.Mask" "F.Paste")
			(net "FLT_HDD13_N")
		)
	)
	(footprint ""
		(layer "F.Cu")
		(at 431.962052 -162.792918 90)
		(property "Reference" "D21"
			(at 0 0 90)
			(layer "F.SilkS")
			(hide yes)
			(effects
				(font
					(size 1.27 1.27)
				)
			)
		)
		(property "Value" "RB551V30-GP"
			(at 0 -6.7818 90)
			(unlocked yes)
			(layer "F.Fab")
			(hide yes)
			(effects
				(font
					(size 1.016 1.016)
					(thickness 0.1524)
				)
			)
		)
		(property "Device Type" "SOD323AKH38"
			(at 0 -8.6868 90)
			(unlocked yes)
			(layer "F.Fab")
			(hide yes)
			(effects
				(font
					(size 1.016 1.016)
					(thickness 0.1524)
				)
			)
		)
		(duplicate_pad_numbers_are_jumpers no)
		(fp_line
			(start 0.889 -1.9304)
			(end 0.889 2.159)
			(stroke
				(width 0.1524)
				(type default)
			)
			(layer "F.SilkS")
		)
		(fp_line
			(start -0.889 -1.9304)
			(end 0.889 -1.9304)
			(stroke
				(width 0.1524)
				(type default)
			)
			(layer "F.SilkS")
		)
		(fp_line
			(start 0.762 2.0574)
			(end -0.762 2.0574)
			(stroke
				(width 0.508)
				(type default)
			)
			(layer "F.SilkS")
		)
		(fp_line
			(start 0.889 2.159)
			(end -0.889 2.159)
			(stroke
				(width 0.1524)
				(type default)
			)
			(layer "F.SilkS")
		)
		(fp_line
			(start -0.889 2.159)
			(end -0.889 -1.9304)
			(stroke
				(width 0.1524)
				(type default)
			)
			(layer "F.SilkS")
		)
		(fp_rect
			(start -1.016 2.3114)
			(end 1.016 -2.0066)
			(stroke
				(width 0)
				(type default)
			)
			(fill no)
			(layer "F.CrtYd")
		)
		(fp_poly
			(pts
				(xy -1.016 -2.0066) (xy 1.016 -2.0066) (xy 1.016 2.3114) (xy -1.016 2.3114)
			)
			(stroke
				(width 0)
				(type default)
			)
			(fill no)
			(layer "F.Fab")
		)
		(pad "A" smd rect
			(at 0 -1.143 90)
			(size 0.5588 1.016)
			(layers "F.Cu" "F.Mask" "F.Paste")
			(net "SW_HDD_R21")
		)
		(pad "K" smd rect
			(at 0 1.143 90)
			(size 0.5588 1.016)
			(layers "F.Cu" "F.Mask" "F.Paste")
			(net "SW_HDD_N21")
		)
	)
	(footprint ""
		(layer "F.Cu")
		(at 98.643948 -183.747918)
		(property "Reference" "TP72"
			(at 0 0 0)
			(layer "F.SilkS")
			(hide yes)
			(effects
				(font
					(size 1.27 1.27)
				)
			)
		)
		(property "Value" "TPAD32-GP"
			(at -0.0508 -1.6764 0)
			(unlocked yes)
			(layer "F.Fab")
			(hide yes)
			(effects
				(font
					(size 1.016 1.016)
					(thickness 0.1524)
				)
			)
		)
		(property "Device Type" "TPAD32"
			(at -0.0508 -3.2004 0)
			(unlocked yes)
			(layer "F.Fab")
			(hide yes)
			(effects
				(font
					(size 1.016 1.016)
					(thickness 0.1524)
				)
			)
		)
		(duplicate_pad_numbers_are_jumpers no)
		(fp_poly
			(pts
				(arc
					(start 0.4064 0)
					(mid -0.4064 0)
					(end 0.4064 0)
				)
			)
			(stroke
				(width 0)
				(type default)
			)
			(fill no)
			(layer "F.CrtYd")
		)
		(fp_poly
			(pts
				(arc
					(start 0.7112 0)
					(mid -0.7112 0)
					(end 0.7112 0)
				)
			)
			(stroke
				(width 0)
				(type default)
			)
			(fill no)
			(layer "F.Fab")
		)
		(pad "1" smd circle
			(at 0 0)
			(size 0.8128 0.8128)
			(layers "F.Cu" "F.Mask" "F.Paste")
			(net "ACT_HDD_14")
		)
	)
	(footprint ""
		(layer "F.Cu")
		(at 459.731872 -188.999876 180)
		(property "Reference" "C332"
			(at 0 0 180)
			(layer "F.SilkS")
			(hide yes)
			(effects
				(font
					(size 1.27 1.27)
				)
			)
		)
		(property "Value" "SC4D7U25V5KX-1-GP"
			(at -0.0762 -6.1214 180)
			(unlocked yes)
			(layer "F.Fab")
			(hide yes)
			(effects
				(font
					(size 1.016 1.016)
					(thickness 0.1524)
				)
			)
		)
		(property "Device Type" "C805H58"
			(at -0.0762 -8.1534 180)
			(unlocked yes)
			(layer "F.Fab")
			(hide yes)
			(effects
				(font
					(size 1.016 1.016)
					(thickness 0.1524)
				)
			)
		)
		(duplicate_pad_numbers_are_jumpers no)
		(fp_line
			(start 0.635 0)
			(end -0.635 0)
			(stroke
				(width 0.508)
				(type default)
			)
			(layer "F.SilkS")
		)
		(fp_rect
			(start -0.9652 1.778)
			(end 0.9652 -1.778)
			(stroke
				(width 0)
				(type default)
			)
			(fill no)
			(layer "F.CrtYd")
		)
		(fp_poly
			(pts
				(xy -0.9652 -1.778) (xy 0.9652 -1.778) (xy 0.9652 1.778) (xy -0.9652 1.778)
			)
			(stroke
				(width 0)
				(type default)
			)
			(fill no)
			(layer "F.Fab")
		)
		(pad "1" smd rect
			(at 0 -0.9652 180)
			(size 1.397 1.143)
			(layers "F.Cu" "F.Mask" "F.Paste")
			(net "P12V_HDD22")
		)
		(pad "2" smd rect
			(at 0 0.9652 180)
			(size 1.397 1.143)
			(layers "F.Cu" "F.Mask" "F.Paste")
			(net "GND")
		)
	)
	(footprint ""
		(layer "F.Cu")
		(at 446.1891 -43.939968 90)
		(property "Reference" "VIA15"
			(at 0 0 90)
			(layer "F.SilkS")
			(hide yes)
			(effects
				(font
					(size 1.27 1.27)
				)
			)
		)
		(property "Value" "100OHM-8L-1D6MM-L18L16-GP"
			(at -3.7211 -4.5085 90)
			(unlocked yes)
			(layer "F.Fab")
			(hide yes)
			(effects
				(font
					(size 1.016 1.016)
					(thickness 0.1524)
				)
			)
		)
		(property "Device Type" "VIA-PCIE-4P-394076"
			(at -3.7211 -6.0325 90)
			(unlocked yes)
			(layer "F.Fab")
			(hide yes)
			(effects
				(font
					(size 1.016 1.016)
					(thickness 0.1524)
				)
			)
		)
		(duplicate_pad_numbers_are_jumpers no)
		(fp_rect
			(start -1.9685 0.381)
			(end 1.9685 -0.381)
			(stroke
				(width 0)
				(type default)
			)
			(fill no)
			(layer "F.CrtYd")
		)
		(fp_rect
			(start -1.9685 0.381)
			(end 1.9685 -0.381)
			(stroke
				(width 0)
				(type default)
			)
			(fill no)
			(layer "F.Fab")
		)
		(pad "1" thru_hole circle
			(at -1.5875 0 90)
			(size 0.508 0.508)
			(drill 0.254)
			(layers "*.Cu" "*.Mask")
			(remove_unused_layers no)
			(net "GND")
			(clearance 0.127)
			(thermal_gap 0.127)
		)
		(pad "2" thru_hole circle
			(at -0.5715 0 90)
			(size 0.508 0.508)
			(drill 0.254)
			(layers "*.Cu" "*.Mask")
			(remove_unused_layers no)
			(net "PHY_SCC_A_TO_DRV_A_34_DP")
			(clearance 0.127)
			(thermal_gap 0.127)
		)
		(pad "3" thru_hole circle
			(at 0.5715 0 90)
			(size 0.508 0.508)
			(drill 0.254)
			(layers "*.Cu" "*.Mask")
			(remove_unused_layers no)
			(net "PHY_SCC_A_TO_DRV_A_34_DN")
			(clearance 0.127)
			(thermal_gap 0.127)
		)
		(pad "4" thru_hole circle
			(at 1.5875 0 90)
			(size 0.508 0.508)
			(drill 0.254)
			(layers "*.Cu" "*.Mask")
			(remove_unused_layers no)
			(net "GND")
			(clearance 0.127)
			(thermal_gap 0.127)
		)
	)
	(footprint ""
		(layer "F.Cu")
		(at 340.007194 -242.799362 180)
		(property "Reference" "Q270"
			(at 0 0 180)
			(layer "F.SilkS")
			(hide yes)
			(effects
				(font
					(size 1.27 1.27)
				)
			)
		)
		(property "Value" "SSM3K324R-GP"
			(at 0.127 -8.9662 180)
			(unlocked yes)
			(layer "F.Fab")
			(hide yes)
			(effects
				(font
					(size 1.016 1.016)
					(thickness 0.1524)
				)
			)
		)
		(property "Device Type" "SOT23DGS2D4H35"
			(at 0.127 -10.4902 180)
			(unlocked yes)
			(layer "F.Fab")
			(hide yes)
			(effects
				(font
					(size 1.016 1.016)
					(thickness 0.1524)
				)
			)
		)
		(duplicate_pad_numbers_are_jumpers no)
		(fp_line
			(start 1.651 1.778)
			(end 1.651 -1.778)
			(stroke
				(width 0.1524)
				(type default)
			)
			(layer "F.SilkS")
		)
		(fp_line
			(start 1.651 -1.778)
			(end -1.651 -1.778)
			(stroke
				(width 0.1524)
				(type default)
			)
			(layer "F.SilkS")
		)
		(fp_line
			(start -1.651 1.778)
			(end 1.651 1.778)
			(stroke
				(width 0.1524)
				(type default)
			)
			(layer "F.SilkS")
		)
		(fp_line
			(start -1.651 -1.778)
			(end -1.651 1.778)
			(stroke
				(width 0.1524)
				(type default)
			)
			(layer "F.SilkS")
		)
		(fp_poly
			(pts
				(xy -1.778 1.8796) (xy -1.778 -1.8796) (xy 1.778 -1.8796) (xy 1.778 1.8796)
			)
			(stroke
				(width 0)
				(type default)
			)
			(fill no)
			(layer "F.CrtYd")
		)
		(fp_poly
			(pts
				(xy -1.778 1.8796) (xy -1.778 -1.8796) (xy 1.778 -1.8796) (xy 1.778 1.8796)
			)
			(stroke
				(width 0)
				(type default)
			)
			(fill no)
			(layer "F.Fab")
		)
		(pad "D" smd custom
			(at 0 -0.9525 180)
			(size 0.1905 0.1905)
			(layers "F.Cu" "F.Mask" "F.Paste")
			(net "DRV_ACT_7_N")
			(options
				(clearance outline)
				(anchor circle)
			)
			(primitives
				(gr_poly
					(pts
						(arc
							(start -0.1778 0.5715)
							(mid -0.321484 0.511984)
							(end -0.381 0.3683)
						)
						(arc
							(start -0.381 -0.3683)
							(mid -0.321484 -0.511984)
							(end -0.1778 -0.5715)
						)
						(arc
							(start 0.1778 -0.5715)
							(mid 0.321484 -0.511984)
							(end 0.381 -0.3683)
						)
						(arc
							(start 0.381 0.3683)
							(mid 0.321484 0.511984)
							(end 0.1778 0.5715)
						)
					)
					(width 0)
					(fill yes)
				)
			)
		)
		(pad "G" smd custom
			(at -0.98425 0.9525 180)
			(size 0.1905 0.1905)
			(layers "F.Cu" "F.Mask" "F.Paste")
			(net "DRIVE_A_7_ACT")
			(options
				(clearance outline)
				(anchor circle)
			)
			(primitives
				(gr_poly
					(pts
						(arc
							(start -0.1778 0.5715)
							(mid -0.321484 0.511984)
							(end -0.381 0.3683)
						)
						(arc
							(start -0.381 -0.3683)
							(mid -0.321484 -0.511984)
							(end -0.1778 -0.5715)
						)
						(arc
							(start 0.1778 -0.5715)
							(mid 0.321484 -0.511984)
							(end 0.381 -0.3683)
						)
						(arc
							(start 0.381 0.3683)
							(mid 0.321484 0.511984)
							(end 0.1778 0.5715)
						)
					)
					(width 0)
					(fill yes)
				)
			)
		)
		(pad "S" smd custom
			(at 0.98425 0.9525 180)
			(size 0.1905 0.1905)
			(layers "F.Cu" "F.Mask" "F.Paste")
			(net "GND")
			(options
				(clearance outline)
				(anchor circle)
			)
			(primitives
				(gr_poly
					(pts
						(arc
							(start -0.1778 0.5715)
							(mid -0.321484 0.511984)
							(end -0.381 0.3683)
						)
						(arc
							(start -0.381 -0.3683)
							(mid -0.321484 -0.511984)
							(end -0.1778 -0.5715)
						)
						(arc
							(start 0.1778 -0.5715)
							(mid 0.321484 -0.511984)
							(end 0.381 -0.3683)
						)
						(arc
							(start 0.381 0.3683)
							(mid 0.321484 0.511984)
							(end 0.1778 0.5715)
						)
					)
					(width 0)
					(fill yes)
				)
			)
		)
	)
	(footprint ""
		(layer "F.Cu")
		(at 447.455036 -245.302024 -90)
		(property "Reference" "R495"
			(at 0 0 270)
			(layer "F.SilkS")
			(hide yes)
			(effects
				(font
					(size 1.27 1.27)
				)
			)
		)
		(property "Value" "4K7R2J-2-GP"
			(at 0.064008 -3.993896 270)
			(unlocked yes)
			(layer "F.Fab")
			(hide yes)
			(effects
				(font
					(size 1.016 1.016)
					(thickness 0.1524)
				)
			)
		)
		(property "Device Type" "R402H16"
			(at 0.064008 -5.517896 270)
			(unlocked yes)
			(layer "F.Fab")
			(hide yes)
			(effects
				(font
					(size 1.016 1.016)
					(thickness 0.1524)
				)
			)
		)
		(duplicate_pad_numbers_are_jumpers no)
		(fp_line
			(start -0.508 -0.9398)
			(end -0.508 0.9398)
			(stroke
				(width 0.1524)
				(type default)
			)
			(layer "F.SilkS")
		)
		(fp_line
			(start 0.508 -0.9398)
			(end -0.508 -0.9398)
			(stroke
				(width 0.1524)
				(type default)
			)
			(layer "F.SilkS")
		)
		(fp_rect
			(start -0.508 0.9398)
			(end 0.508 -0.9398)
			(stroke
				(width 0)
				(type default)
			)
			(fill no)
			(layer "F.CrtYd")
		)
		(fp_rect
			(start -0.508 0.9398)
			(end 0.508 -0.9398)
			(stroke
				(width 0)
				(type default)
			)
			(fill no)
			(layer "F.Fab")
		)
		(pad "1" smd custom
			(at 0 -0.4445 270)
			(size 0.1397 0.1397)
			(layers "F.Cu" "F.Mask" "F.Paste")
			(net "DRIVE_A_10_FLT_LED")
			(options
				(clearance outline)
				(anchor circle)
			)
			(primitives
				(gr_poly
					(pts
						(arc
							(start -0.1778 -0.2794)
							(mid -0.249642 -0.249642)
							(end -0.2794 -0.1778)
						)
						(arc
							(start -0.2794 0.1778)
							(mid -0.249642 0.249642)
							(end -0.1778 0.2794)
						)
						(arc
							(start 0.1778 0.2794)
							(mid 0.249642 0.249642)
							(end 0.2794 0.1778)
						)
						(arc
							(start 0.2794 -0.1778)
							(mid 0.249642 -0.249642)
							(end 0.1778 -0.2794)
						)
					)
					(width 0)
					(fill yes)
				)
			)
		)
		(pad "2" smd custom
			(at 0 0.4445 270)
			(size 0.1397 0.1397)
			(layers "F.Cu" "F.Mask" "F.Paste")
			(net "GND")
			(options
				(clearance outline)
				(anchor circle)
			)
			(primitives
				(gr_poly
					(pts
						(arc
							(start -0.1778 -0.2794)
							(mid -0.249642 -0.249642)
							(end -0.2794 -0.1778)
						)
						(arc
							(start -0.2794 0.1778)
							(mid -0.249642 0.249642)
							(end -0.1778 0.2794)
						)
						(arc
							(start 0.1778 0.2794)
							(mid 0.249642 0.249642)
							(end 0.2794 0.1778)
						)
						(arc
							(start 0.2794 -0.1778)
							(mid 0.249642 -0.249642)
							(end 0.1778 -0.2794)
						)
					)
					(width 0)
					(fill yes)
				)
			)
		)
	)
	(footprint ""
		(layer "F.Cu")
		(at 378.864876 -242.25377)
		(property "Reference" "R250"
			(at 0 0 0)
			(layer "F.SilkS")
			(hide yes)
			(effects
				(font
					(size 1.27 1.27)
				)
			)
		)
		(property "Value" "91R3F-1-GP"
			(at -0.0254 -2.5146 0)
			(unlocked yes)
			(layer "F.Fab")
			(hide yes)
			(effects
				(font
					(size 1.016 1.016)
					(thickness 0.1524)
				)
			)
		)
		(property "Device Type" "R603H22"
			(at -0.0254 -4.0386 0)
			(unlocked yes)
			(layer "F.Fab")
			(hide yes)
			(effects
				(font
					(size 1.016 1.016)
					(thickness 0.1524)
				)
			)
		)
		(duplicate_pad_numbers_are_jumpers no)
		(fp_line
			(start -0.4826 0)
			(end -0.2032 0)
			(stroke
				(width 0.2032)
				(type default)
			)
			(layer "F.SilkS")
		)
		(fp_line
			(start 0.2032 0)
			(end 0.4826 0)
			(stroke
				(width 0.2032)
				(type default)
			)
			(layer "F.SilkS")
		)
		(fp_rect
			(start -0.5842 1.3335)
			(end 0.5842 -1.3335)
			(stroke
				(width 0)
				(type default)
			)
			(fill no)
			(layer "F.CrtYd")
		)
		(fp_rect
			(start -0.5842 1.3335)
			(end 0.5842 -1.3335)
			(stroke
				(width 0)
				(type default)
			)
			(fill no)
			(layer "F.Fab")
		)
		(pad "1" smd custom
			(at 0 -0.762)
			(size 0.2159 0.2159)
			(layers "F.Cu" "F.Mask" "F.Paste")
			(net "P5V_A_3")
			(options
				(clearance outline)
				(anchor circle)
			)
			(primitives
				(gr_poly
					(pts
						(arc
							(start -0.3302 -0.4318)
							(mid -0.402042 -0.402042)
							(end -0.4318 -0.3302)
						)
						(arc
							(start -0.4318 0.3302)
							(mid -0.402042 0.402042)
							(end -0.3302 0.4318)
						)
						(arc
							(start 0.3302 0.4318)
							(mid 0.402042 0.402042)
							(end 0.4318 0.3302)
						)
						(arc
							(start 0.4318 -0.3302)
							(mid 0.402042 -0.402042)
							(end 0.3302 -0.4318)
						)
					)
					(width 0)
					(fill yes)
				)
			)
		)
		(pad "2" smd custom
			(at 0 0.762)
			(size 0.2159 0.2159)
			(layers "F.Cu" "F.Mask" "F.Paste")
			(net "DRV_ACT_8")
			(options
				(clearance outline)
				(anchor circle)
			)
			(primitives
				(gr_poly
					(pts
						(arc
							(start -0.3302 -0.4318)
							(mid -0.402042 -0.402042)
							(end -0.4318 -0.3302)
						)
						(arc
							(start -0.4318 0.3302)
							(mid -0.402042 0.402042)
							(end -0.3302 0.4318)
						)
						(arc
							(start 0.3302 0.4318)
							(mid 0.402042 0.402042)
							(end 0.4318 0.3302)
						)
						(arc
							(start 0.4318 -0.3302)
							(mid 0.402042 -0.402042)
							(end 0.3302 -0.4318)
						)
					)
					(width 0)
					(fill yes)
				)
			)
		)
	)
	(footprint ""
		(layer "F.Cu")
		(at 154.29484 -143.198596 180)
		(property "Reference" "C552"
			(at 0 0 180)
			(layer "F.SilkS")
			(hide yes)
			(effects
				(font
					(size 1.27 1.27)
				)
			)
		)
		(property "Value" "SC1U16V3KX-5GP"
			(at 0 -2.8194 180)
			(unlocked yes)
			(layer "F.Fab")
			(hide yes)
			(effects
				(font
					(size 1.016 1.016)
					(thickness 0.1524)
				)
			)
		)
		(property "Device Type" "C603H36"
			(at 0 -4.3434 180)
			(unlocked yes)
			(layer "F.Fab")
			(hide yes)
			(effects
				(font
					(size 1.016 1.016)
					(thickness 0.1524)
				)
			)
		)
		(duplicate_pad_numbers_are_jumpers no)
		(fp_line
			(start 0.508 0)
			(end -0.508 0)
			(stroke
				(width 0.2032)
				(type default)
			)
			(layer "F.SilkS")
		)
		(fp_rect
			(start -0.5842 1.3335)
			(end 0.5842 -1.3335)
			(stroke
				(width 0)
				(type default)
			)
			(fill no)
			(layer "F.CrtYd")
		)
		(fp_rect
			(start -0.5842 1.3335)
			(end 0.5842 -1.3335)
			(stroke
				(width 0)
				(type default)
			)
			(fill no)
			(layer "F.Fab")
		)
		(pad "1" smd custom
			(at 0 -0.762 180)
			(size 0.2159 0.2159)
			(layers "F.Cu" "F.Mask" "F.Paste")
			(net "MB0_CM_OV_R")
			(options
				(clearance outline)
				(anchor circle)
			)
			(primitives
				(gr_poly
					(pts
						(arc
							(start -0.3302 -0.4318)
							(mid -0.402042 -0.402042)
							(end -0.4318 -0.3302)
						)
						(arc
							(start -0.4318 0.3302)
							(mid -0.402042 0.402042)
							(end -0.3302 0.4318)
						)
						(arc
							(start 0.3302 0.4318)
							(mid 0.402042 0.402042)
							(end 0.4318 0.3302)
						)
						(arc
							(start 0.4318 -0.3302)
							(mid 0.402042 -0.402042)
							(end 0.3302 -0.4318)
						)
					)
					(width 0)
					(fill yes)
				)
			)
		)
		(pad "2" smd custom
			(at 0 0.762 180)
			(size 0.2159 0.2159)
			(layers "F.Cu" "F.Mask" "F.Paste")
			(net "AGND_CURRENT_MONOA")
			(options
				(clearance outline)
				(anchor circle)
			)
			(primitives
				(gr_poly
					(pts
						(arc
							(start -0.3302 -0.4318)
							(mid -0.402042 -0.402042)
							(end -0.4318 -0.3302)
						)
						(arc
							(start -0.4318 0.3302)
							(mid -0.402042 0.402042)
							(end -0.3302 0.4318)
						)
						(arc
							(start 0.3302 0.4318)
							(mid 0.402042 0.402042)
							(end 0.4318 0.3302)
						)
						(arc
							(start 0.4318 -0.3302)
							(mid 0.402042 -0.402042)
							(end 0.3302 -0.4318)
						)
					)
					(width 0)
					(fill yes)
				)
			)
		)
	)
	(footprint ""
		(layer "F.Cu")
		(at 49.469802 -148.64715 -90)
		(property "Reference" "C620"
			(at 0 0 270)
			(layer "F.SilkS")
			(hide yes)
			(effects
				(font
					(size 1.27 1.27)
				)
			)
		)
		(property "Value" "SC1U16V3KX-5GP"
			(at 0 -2.8194 270)
			(unlocked yes)
			(layer "F.Fab")
			(hide yes)
			(effects
				(font
					(size 1.016 1.016)
					(thickness 0.1524)
				)
			)
		)
		(property "Device Type" "C603H36"
			(at 0 -4.3434 270)
			(unlocked yes)
			(layer "F.Fab")
			(hide yes)
			(effects
				(font
					(size 1.016 1.016)
					(thickness 0.1524)
				)
			)
		)
		(duplicate_pad_numbers_are_jumpers no)
		(fp_line
			(start 0.508 0)
			(end -0.508 0)
			(stroke
				(width 0.2032)
				(type default)
			)
			(layer "F.SilkS")
		)
		(fp_rect
			(start -0.5842 1.3335)
			(end 0.5842 -1.3335)
			(stroke
				(width 0)
				(type default)
			)
			(fill no)
			(layer "F.CrtYd")
		)
		(fp_rect
			(start -0.5842 1.3335)
			(end 0.5842 -1.3335)
			(stroke
				(width 0)
				(type default)
			)
			(fill no)
			(layer "F.Fab")
		)
		(pad "1" smd custom
			(at 0 -0.762 270)
			(size 0.2159 0.2159)
			(layers "F.Cu" "F.Mask" "F.Paste")
			(net "P5V_B_EN_R")
			(options
				(clearance outline)
				(anchor circle)
			)
			(primitives
				(gr_poly
					(pts
						(arc
							(start -0.3302 -0.4318)
							(mid -0.402042 -0.402042)
							(end -0.4318 -0.3302)
						)
						(arc
							(start -0.4318 0.3302)
							(mid -0.402042 0.402042)
							(end -0.3302 0.4318)
						)
						(arc
							(start 0.3302 0.4318)
							(mid 0.402042 0.402042)
							(end 0.4318 0.3302)
						)
						(arc
							(start 0.4318 -0.3302)
							(mid 0.402042 -0.402042)
							(end 0.3302 -0.4318)
						)
					)
					(width 0)
					(fill yes)
				)
			)
		)
		(pad "2" smd custom
			(at 0 0.762 270)
			(size 0.2159 0.2159)
			(layers "F.Cu" "F.Mask" "F.Paste")
			(net "GND")
			(options
				(clearance outline)
				(anchor circle)
			)
			(primitives
				(gr_poly
					(pts
						(arc
							(start -0.3302 -0.4318)
							(mid -0.402042 -0.402042)
							(end -0.4318 -0.3302)
						)
						(arc
							(start -0.4318 0.3302)
							(mid -0.402042 0.402042)
							(end -0.3302 0.4318)
						)
						(arc
							(start 0.3302 0.4318)
							(mid 0.402042 0.402042)
							(end 0.4318 0.3302)
						)
						(arc
							(start 0.4318 -0.3302)
							(mid 0.402042 -0.402042)
							(end 0.3302 -0.4318)
						)
					)
					(width 0)
					(fill yes)
				)
			)
		)
	)
	(footprint ""
		(layer "F.Cu")
		(at 406.14473 -130.408172 -90)
		(property "Reference" "R541"
			(at 0 0 270)
			(layer "F.SilkS")
			(hide yes)
			(effects
				(font
					(size 1.27 1.27)
				)
			)
		)
		(property "Value" "4K7R2J-2-GP"
			(at 0.064008 -3.993896 270)
			(unlocked yes)
			(layer "F.Fab")
			(hide yes)
			(effects
				(font
					(size 1.016 1.016)
					(thickness 0.1524)
				)
			)
		)
		(property "Device Type" "R402H16"
			(at 0.064008 -5.517896 270)
			(unlocked yes)
			(layer "F.Fab")
			(hide yes)
			(effects
				(font
					(size 1.016 1.016)
					(thickness 0.1524)
				)
			)
		)
		(duplicate_pad_numbers_are_jumpers no)
		(fp_line
			(start -0.508 -0.9398)
			(end -0.508 0.9398)
			(stroke
				(width 0.1524)
				(type default)
			)
			(layer "F.SilkS")
		)
		(fp_line
			(start 0.508 -0.9398)
			(end -0.508 -0.9398)
			(stroke
				(width 0.1524)
				(type default)
			)
			(layer "F.SilkS")
		)
		(fp_rect
			(start -0.508 0.9398)
			(end 0.508 -0.9398)
			(stroke
				(width 0)
				(type default)
			)
			(fill no)
			(layer "F.CrtYd")
		)
		(fp_rect
			(start -0.508 0.9398)
			(end 0.508 -0.9398)
			(stroke
				(width 0)
				(type default)
			)
			(fill no)
			(layer "F.Fab")
		)
		(pad "1" smd custom
			(at 0 -0.4445 270)
			(size 0.1397 0.1397)
			(layers "F.Cu" "F.Mask" "F.Paste")
			(net "DRIVE_A_21_FLT_LED")
			(options
				(clearance outline)
				(anchor circle)
			)
			(primitives
				(gr_poly
					(pts
						(arc
							(start -0.1778 -0.2794)
							(mid -0.249642 -0.249642)
							(end -0.2794 -0.1778)
						)
						(arc
							(start -0.2794 0.1778)
							(mid -0.249642 0.249642)
							(end -0.1778 0.2794)
						)
						(arc
							(start 0.1778 0.2794)
							(mid 0.249642 0.249642)
							(end 0.2794 0.1778)
						)
						(arc
							(start 0.2794 -0.1778)
							(mid 0.249642 -0.249642)
							(end 0.1778 -0.2794)
						)
					)
					(width 0)
					(fill yes)
				)
			)
		)
		(pad "2" smd custom
			(at 0 0.4445 270)
			(size 0.1397 0.1397)
			(layers "F.Cu" "F.Mask" "F.Paste")
			(net "GND")
			(options
				(clearance outline)
				(anchor circle)
			)
			(primitives
				(gr_poly
					(pts
						(arc
							(start -0.1778 -0.2794)
							(mid -0.249642 -0.249642)
							(end -0.2794 -0.1778)
						)
						(arc
							(start -0.2794 0.1778)
							(mid -0.249642 0.249642)
							(end -0.1778 0.2794)
						)
						(arc
							(start 0.1778 0.2794)
							(mid 0.249642 0.249642)
							(end 0.2794 0.1778)
						)
						(arc
							(start 0.2794 -0.1778)
							(mid 0.249642 -0.249642)
							(end 0.1778 -0.2794)
						)
					)
					(width 0)
					(fill yes)
				)
			)
		)
	)
	(footprint ""
		(layer "F.Cu")
		(at 264.788142 -212.268562 90)
		(property "Reference" "R404"
			(at 0 0 90)
			(layer "F.SilkS")
			(hide yes)
			(effects
				(font
					(size 1.27 1.27)
				)
			)
		)
		(property "Value" "0R2J-2-GP"
			(at 0.064008 -3.993896 90)
			(unlocked yes)
			(layer "F.Fab")
			(hide yes)
			(effects
				(font
					(size 1.016 1.016)
					(thickness 0.1524)
				)
			)
		)
		(property "Device Type" "R402H16"
			(at 0.064008 -5.517896 90)
			(unlocked yes)
			(layer "F.Fab")
			(hide yes)
			(effects
				(font
					(size 1.016 1.016)
					(thickness 0.1524)
				)
			)
		)
		(duplicate_pad_numbers_are_jumpers no)
		(fp_line
			(start 0.508 -0.9398)
			(end -0.508 -0.9398)
			(stroke
				(width 0.1524)
				(type default)
			)
			(layer "F.SilkS")
		)
		(fp_line
			(start -0.508 -0.9398)
			(end -0.508 0.9398)
			(stroke
				(width 0.1524)
				(type default)
			)
			(layer "F.SilkS")
		)
		(fp_rect
			(start -0.508 0.9398)
			(end 0.508 -0.9398)
			(stroke
				(width 0)
				(type default)
			)
			(fill no)
			(layer "F.CrtYd")
		)
		(fp_rect
			(start -0.508 0.9398)
			(end 0.508 -0.9398)
			(stroke
				(width 0)
				(type default)
			)
			(fill no)
			(layer "F.Fab")
		)
		(pad "1" smd custom
			(at 0 -0.4445 90)
			(size 0.1397 0.1397)
			(layers "F.Cu" "F.Mask" "F.Paste")
			(net "I2C_DPB_A_SCL_BUF")
			(options
				(clearance outline)
				(anchor circle)
			)
			(primitives
				(gr_poly
					(pts
						(arc
							(start -0.1778 -0.2794)
							(mid -0.249642 -0.249642)
							(end -0.2794 -0.1778)
						)
						(arc
							(start -0.2794 0.1778)
							(mid -0.249642 0.249642)
							(end -0.1778 0.2794)
						)
						(arc
							(start 0.1778 0.2794)
							(mid 0.249642 0.249642)
							(end 0.2794 0.1778)
						)
						(arc
							(start 0.2794 -0.1778)
							(mid 0.249642 -0.249642)
							(end 0.1778 -0.2794)
						)
					)
					(width 0)
					(fill yes)
				)
			)
		)
		(pad "2" smd custom
			(at 0 0.4445 90)
			(size 0.1397 0.1397)
			(layers "F.Cu" "F.Mask" "F.Paste")
			(net "I2C_DPB_A_SCL")
			(options
				(clearance outline)
				(anchor circle)
			)
			(primitives
				(gr_poly
					(pts
						(arc
							(start -0.1778 -0.2794)
							(mid -0.249642 -0.249642)
							(end -0.2794 -0.1778)
						)
						(arc
							(start -0.2794 0.1778)
							(mid -0.249642 0.249642)
							(end -0.1778 0.2794)
						)
						(arc
							(start 0.1778 0.2794)
							(mid 0.249642 0.249642)
							(end 0.2794 0.1778)
						)
						(arc
							(start 0.2794 -0.1778)
							(mid 0.249642 -0.249642)
							(end 0.1778 -0.2794)
						)
					)
					(width 0)
					(fill yes)
				)
			)
		)
	)
	(footprint ""
		(layer "F.Cu")
		(at 255.415034 -5.192522 90)
		(property "Reference" "TP212"
			(at 0 0 90)
			(layer "F.SilkS")
			(hide yes)
			(effects
				(font
					(size 1.27 1.27)
				)
			)
		)
		(property "Value" "TPAD32-GP"
			(at -0.0508 -1.6764 90)
			(unlocked yes)
			(layer "F.Fab")
			(hide yes)
			(effects
				(font
					(size 1.016 1.016)
					(thickness 0.1524)
				)
			)
		)
		(property "Device Type" "TPAD32"
			(at -0.0508 -3.2004 90)
			(unlocked yes)
			(layer "F.Fab")
			(hide yes)
			(effects
				(font
					(size 1.016 1.016)
					(thickness 0.1524)
				)
			)
		)
		(duplicate_pad_numbers_are_jumpers no)
		(fp_poly
			(pts
				(arc
					(start 0 0.4064)
					(mid 0 -0.4064)
					(end 0 0.4064)
				)
			)
			(stroke
				(width 0)
				(type default)
			)
			(fill no)
			(layer "F.CrtYd")
		)
		(fp_poly
			(pts
				(arc
					(start 0 0.7112)
					(mid 0 -0.7112)
					(end 0 0.7112)
				)
			)
			(stroke
				(width 0)
				(type default)
			)
			(fill no)
			(layer "F.Fab")
		)
		(pad "1" smd circle
			(at 0 0 90)
			(size 0.8128 0.8128)
			(layers "F.Cu" "F.Mask" "F.Paste")
			(net "TP_COMP_A_NCSI_TXEN")
		)
	)
	(footprint ""
		(layer "F.Cu")
		(at 181.6862 -186.287918)
		(property "Reference" "C266"
			(at 0 0 0)
			(layer "F.SilkS")
			(hide yes)
			(effects
				(font
					(size 1.27 1.27)
				)
			)
		)
		(property "Value" "SC4D7U25V5KX-1-GP"
			(at -0.0762 -6.1214 0)
			(unlocked yes)
			(layer "F.Fab")
			(hide yes)
			(effects
				(font
					(size 1.016 1.016)
					(thickness 0.1524)
				)
			)
		)
		(property "Device Type" "C805H58"
			(at -0.0762 -8.1534 0)
			(unlocked yes)
			(layer "F.Fab")
			(hide yes)
			(effects
				(font
					(size 1.016 1.016)
					(thickness 0.1524)
				)
			)
		)
		(duplicate_pad_numbers_are_jumpers no)
		(fp_line
			(start 0.635 0)
			(end -0.635 0)
			(stroke
				(width 0.508)
				(type default)
			)
			(layer "F.SilkS")
		)
		(fp_rect
			(start -0.9652 1.778)
			(end 0.9652 -1.778)
			(stroke
				(width 0)
				(type default)
			)
			(fill no)
			(layer "F.CrtYd")
		)
		(fp_poly
			(pts
				(xy -0.9652 -1.778) (xy 0.9652 -1.778) (xy 0.9652 1.778) (xy -0.9652 1.778)
			)
			(stroke
				(width 0)
				(type default)
			)
			(fill no)
			(layer "F.Fab")
		)
		(pad "1" smd rect
			(at 0 -0.9652)
			(size 1.397 1.143)
			(layers "F.Cu" "F.Mask" "F.Paste")
			(net "P12V_HDD17")
		)
		(pad "2" smd rect
			(at 0 0.9652)
			(size 1.397 1.143)
			(layers "F.Cu" "F.Mask" "F.Paste")
			(net "GND")
		)
	)
	(footprint ""
		(layer "F.Cu")
		(at 153.232866 -136.863074 -90)
		(property "Reference" "R1081"
			(at 0 0 270)
			(layer "F.SilkS")
			(hide yes)
			(effects
				(font
					(size 1.27 1.27)
				)
			)
		)
		(property "Value" "10R2F-L-GP"
			(at 0.064008 -3.993896 270)
			(unlocked yes)
			(layer "F.Fab")
			(hide yes)
			(effects
				(font
					(size 1.016 1.016)
					(thickness 0.1524)
				)
			)
		)
		(property "Device Type" "R402H14"
			(at 0.064008 -5.517896 270)
			(unlocked yes)
			(layer "F.Fab")
			(hide yes)
			(effects
				(font
					(size 1.016 1.016)
					(thickness 0.1524)
				)
			)
		)
		(duplicate_pad_numbers_are_jumpers no)
		(fp_line
			(start -0.508 -0.9398)
			(end -0.508 0.9398)
			(stroke
				(width 0.1524)
				(type default)
			)
			(layer "F.SilkS")
		)
		(fp_line
			(start 0.508 -0.9398)
			(end -0.508 -0.9398)
			(stroke
				(width 0.1524)
				(type default)
			)
			(layer "F.SilkS")
		)
		(fp_rect
			(start -0.508 0.9398)
			(end 0.508 -0.9398)
			(stroke
				(width 0)
				(type default)
			)
			(fill no)
			(layer "F.CrtYd")
		)
		(fp_rect
			(start -0.508 0.9398)
			(end 0.508 -0.9398)
			(stroke
				(width 0)
				(type default)
			)
			(fill no)
			(layer "F.Fab")
		)
		(pad "1" smd custom
			(at 0 -0.4445 270)
			(size 0.1397 0.1397)
			(layers "F.Cu" "F.Mask" "F.Paste")
			(net "MB0_CM_SENSE_R1_N")
			(options
				(clearance outline)
				(anchor circle)
			)
			(primitives
				(gr_poly
					(pts
						(arc
							(start -0.1778 -0.2794)
							(mid -0.249642 -0.249642)
							(end -0.2794 -0.1778)
						)
						(arc
							(start -0.2794 0.1778)
							(mid -0.249642 0.249642)
							(end -0.1778 0.2794)
						)
						(arc
							(start 0.1778 0.2794)
							(mid 0.249642 0.249642)
							(end 0.2794 0.1778)
						)
						(arc
							(start 0.2794 -0.1778)
							(mid 0.249642 -0.249642)
							(end 0.1778 -0.2794)
						)
					)
					(width 0)
					(fill yes)
				)
			)
		)
		(pad "2" smd custom
			(at 0 0.4445 270)
			(size 0.1397 0.1397)
			(layers "F.Cu" "F.Mask" "F.Paste")
			(net "MB0_HS_SENSE_N")
			(options
				(clearance outline)
				(anchor circle)
			)
			(primitives
				(gr_poly
					(pts
						(arc
							(start -0.1778 -0.2794)
							(mid -0.249642 -0.249642)
							(end -0.2794 -0.1778)
						)
						(arc
							(start -0.2794 0.1778)
							(mid -0.249642 0.249642)
							(end -0.1778 0.2794)
						)
						(arc
							(start 0.1778 0.2794)
							(mid 0.249642 0.249642)
							(end 0.2794 0.1778)
						)
						(arc
							(start 0.2794 -0.1778)
							(mid 0.249642 -0.249642)
							(end 0.1778 -0.2794)
						)
					)
					(width 0)
					(fill yes)
				)
			)
		)
	)
	(footprint ""
		(layer "F.Cu")
		(at 52.559712 -140.90269 -90)
		(property "Reference" "C623"
			(at 0 0 270)
			(layer "F.SilkS")
			(hide yes)
			(effects
				(font
					(size 1.27 1.27)
				)
			)
		)
		(property "Value" "SC2200P50V2KX-2GP"
			(at 1.1811 -2.7051 270)
			(unlocked yes)
			(layer "F.Fab")
			(hide yes)
			(effects
				(font
					(size 1.016 1.016)
					(thickness 0.1524)
				)
			)
		)
		(property "Device Type" "C402H22"
			(at 1.1811 -4.2291 270)
			(unlocked yes)
			(layer "F.Fab")
			(hide yes)
			(effects
				(font
					(size 1.016 1.016)
					(thickness 0.1524)
				)
			)
		)
		(duplicate_pad_numbers_are_jumpers no)
		(fp_rect
			(start -0.4318 0.9525)
			(end 0.4318 -0.9525)
			(stroke
				(width 0)
				(type default)
			)
			(fill no)
			(layer "F.CrtYd")
		)
		(fp_rect
			(start -0.4318 0.9525)
			(end 0.4318 -0.9525)
			(stroke
				(width 0)
				(type default)
			)
			(fill no)
			(layer "F.Fab")
		)
		(pad "1" smd custom
			(at 0 -0.4445 270)
			(size 0.1524 0.1524)
			(layers "F.Cu" "F.Mask" "F.Paste")
			(net "P5V_B_LL")
			(options
				(clearance outline)
				(anchor circle)
			)
			(primitives
				(gr_poly
					(pts
						(arc
							(start 0.3048 -0.2032)
							(mid 0.275042 -0.275042)
							(end 0.2032 -0.3048)
						)
						(arc
							(start -0.2032 -0.3048)
							(mid -0.275042 -0.275042)
							(end -0.3048 -0.2032)
						)
						(arc
							(start -0.3048 0.2032)
							(mid -0.275042 0.275042)
							(end -0.2032 0.3048)
						)
						(arc
							(start 0.2032 0.3048)
							(mid 0.275042 0.275042)
							(end 0.3048 0.2032)
						)
					)
					(width 0)
					(fill yes)
				)
			)
		)
		(pad "2" smd custom
			(at 0 0.4445 270)
			(size 0.1524 0.1524)
			(layers "F.Cu" "F.Mask" "F.Paste")
			(net "P5V_B_SNB")
			(options
				(clearance outline)
				(anchor circle)
			)
			(primitives
				(gr_poly
					(pts
						(arc
							(start 0.3048 -0.2032)
							(mid 0.275042 -0.275042)
							(end 0.2032 -0.3048)
						)
						(arc
							(start -0.2032 -0.3048)
							(mid -0.275042 -0.275042)
							(end -0.3048 -0.2032)
						)
						(arc
							(start -0.3048 0.2032)
							(mid -0.275042 0.275042)
							(end -0.2032 0.3048)
						)
						(arc
							(start 0.2032 0.3048)
							(mid 0.275042 0.275042)
							(end 0.3048 0.2032)
						)
					)
					(width 0)
					(fill yes)
				)
			)
		)
	)
	(footprint ""
		(layer "F.Cu")
		(at 331.4954 -272.585942)
		(property "Reference" "R281"
			(at 0 0 0)
			(layer "F.SilkS")
			(hide yes)
			(effects
				(font
					(size 1.27 1.27)
				)
			)
		)
		(property "Value" "4K7R2J-2-GP"
			(at 0.064008 -3.993896 0)
			(unlocked yes)
			(layer "F.Fab")
			(hide yes)
			(effects
				(font
					(size 1.016 1.016)
					(thickness 0.1524)
				)
			)
		)
		(property "Device Type" "R402H16"
			(at 0.064008 -5.517896 0)
			(unlocked yes)
			(layer "F.Fab")
			(hide yes)
			(effects
				(font
					(size 1.016 1.016)
					(thickness 0.1524)
				)
			)
		)
		(duplicate_pad_numbers_are_jumpers no)
		(fp_line
			(start -0.508 -0.9398)
			(end -0.508 0.9398)
			(stroke
				(width 0.1524)
				(type default)
			)
			(layer "F.SilkS")
		)
		(fp_line
			(start 0.508 -0.9398)
			(end -0.508 -0.9398)
			(stroke
				(width 0.1524)
				(type default)
			)
			(layer "F.SilkS")
		)
		(fp_rect
			(start -0.508 0.9398)
			(end 0.508 -0.9398)
			(stroke
				(width 0)
				(type default)
			)
			(fill no)
			(layer "F.CrtYd")
		)
		(fp_rect
			(start -0.508 0.9398)
			(end 0.508 -0.9398)
			(stroke
				(width 0)
				(type default)
			)
			(fill no)
			(layer "F.Fab")
		)
		(pad "1" smd custom
			(at 0 -0.4445)
			(size 0.1397 0.1397)
			(layers "F.Cu" "F.Mask" "F.Paste")
			(net "SW_PWR_R_HDD6")
			(options
				(clearance outline)
				(anchor circle)
			)
			(primitives
				(gr_poly
					(pts
						(arc
							(start -0.1778 -0.2794)
							(mid -0.249642 -0.249642)
							(end -0.2794 -0.1778)
						)
						(arc
							(start -0.2794 0.1778)
							(mid -0.249642 0.249642)
							(end -0.1778 0.2794)
						)
						(arc
							(start 0.1778 0.2794)
							(mid 0.249642 0.249642)
							(end 0.2794 0.1778)
						)
						(arc
							(start 0.2794 -0.1778)
							(mid 0.249642 -0.249642)
							(end 0.1778 -0.2794)
						)
					)
					(width 0)
					(fill yes)
				)
			)
		)
		(pad "2" smd custom
			(at 0 0.4445)
			(size 0.1397 0.1397)
			(layers "F.Cu" "F.Mask" "F.Paste")
			(net "GND")
			(options
				(clearance outline)
				(anchor circle)
			)
			(primitives
				(gr_poly
					(pts
						(arc
							(start -0.1778 -0.2794)
							(mid -0.249642 -0.249642)
							(end -0.2794 -0.1778)
						)
						(arc
							(start -0.2794 0.1778)
							(mid -0.249642 0.249642)
							(end -0.1778 0.2794)
						)
						(arc
							(start 0.1778 0.2794)
							(mid 0.249642 0.249642)
							(end 0.2794 0.1778)
						)
						(arc
							(start 0.2794 -0.1778)
							(mid 0.249642 -0.249642)
							(end 0.1778 -0.2794)
						)
					)
					(width 0)
					(fill yes)
				)
			)
		)
	)
	(footprint ""
		(layer "F.Cu")
		(at 445.262 -192.024)
		(property "Reference" "TP112"
			(at 0 0 0)
			(layer "F.SilkS")
			(hide yes)
			(effects
				(font
					(size 1.27 1.27)
				)
			)
		)
		(property "Value" "TPAD32-GP"
			(at -0.0508 -1.6764 0)
			(unlocked yes)
			(layer "F.Fab")
			(hide yes)
			(effects
				(font
					(size 1.016 1.016)
					(thickness 0.1524)
				)
			)
		)
		(property "Device Type" "TPAD32"
			(at -0.0508 -3.2004 0)
			(unlocked yes)
			(layer "F.Fab")
			(hide yes)
			(effects
				(font
					(size 1.016 1.016)
					(thickness 0.1524)
				)
			)
		)
		(duplicate_pad_numbers_are_jumpers no)
		(fp_poly
			(pts
				(arc
					(start 0.4064 0)
					(mid -0.4064 0)
					(end 0.4064 0)
				)
			)
			(stroke
				(width 0)
				(type default)
			)
			(fill no)
			(layer "F.CrtYd")
		)
		(fp_poly
			(pts
				(arc
					(start 0.7112 0)
					(mid -0.7112 0)
					(end 0.7112 0)
				)
			)
			(stroke
				(width 0)
				(type default)
			)
			(fill no)
			(layer "F.Fab")
		)
		(pad "1" smd circle
			(at 0 0)
			(size 0.8128 0.8128)
			(layers "F.Cu" "F.Mask" "F.Paste")
			(net "ACT_HDD_22")
		)
	)
	(footprint ""
		(layer "F.Cu")
		(at 46.821852 -130.271012 -90)
		(property "Reference" "R507"
			(at 0 0 270)
			(layer "F.SilkS")
			(hide yes)
			(effects
				(font
					(size 1.27 1.27)
				)
			)
		)
		(property "Value" "4K7R2J-2-GP"
			(at 0.064008 -3.993896 270)
			(unlocked yes)
			(layer "F.Fab")
			(hide yes)
			(effects
				(font
					(size 1.016 1.016)
					(thickness 0.1524)
				)
			)
		)
		(property "Device Type" "R402H16"
			(at 0.064008 -5.517896 270)
			(unlocked yes)
			(layer "F.Fab")
			(hide yes)
			(effects
				(font
					(size 1.016 1.016)
					(thickness 0.1524)
				)
			)
		)
		(duplicate_pad_numbers_are_jumpers no)
		(fp_line
			(start -0.508 -0.9398)
			(end -0.508 0.9398)
			(stroke
				(width 0.1524)
				(type default)
			)
			(layer "F.SilkS")
		)
		(fp_line
			(start 0.508 -0.9398)
			(end -0.508 -0.9398)
			(stroke
				(width 0.1524)
				(type default)
			)
			(layer "F.SilkS")
		)
		(fp_rect
			(start -0.508 0.9398)
			(end 0.508 -0.9398)
			(stroke
				(width 0)
				(type default)
			)
			(fill no)
			(layer "F.CrtYd")
		)
		(fp_rect
			(start -0.508 0.9398)
			(end 0.508 -0.9398)
			(stroke
				(width 0)
				(type default)
			)
			(fill no)
			(layer "F.Fab")
		)
		(pad "1" smd custom
			(at 0 -0.4445 270)
			(size 0.1397 0.1397)
			(layers "F.Cu" "F.Mask" "F.Paste")
			(net "DRIVE_A_13_FLT_LED")
			(options
				(clearance outline)
				(anchor circle)
			)
			(primitives
				(gr_poly
					(pts
						(arc
							(start -0.1778 -0.2794)
							(mid -0.249642 -0.249642)
							(end -0.2794 -0.1778)
						)
						(arc
							(start -0.2794 0.1778)
							(mid -0.249642 0.249642)
							(end -0.1778 0.2794)
						)
						(arc
							(start 0.1778 0.2794)
							(mid 0.249642 0.249642)
							(end 0.2794 0.1778)
						)
						(arc
							(start 0.2794 -0.1778)
							(mid 0.249642 -0.249642)
							(end 0.1778 -0.2794)
						)
					)
					(width 0)
					(fill yes)
				)
			)
		)
		(pad "2" smd custom
			(at 0 0.4445 270)
			(size 0.1397 0.1397)
			(layers "F.Cu" "F.Mask" "F.Paste")
			(net "GND")
			(options
				(clearance outline)
				(anchor circle)
			)
			(primitives
				(gr_poly
					(pts
						(arc
							(start -0.1778 -0.2794)
							(mid -0.249642 -0.249642)
							(end -0.2794 -0.1778)
						)
						(arc
							(start -0.2794 0.1778)
							(mid -0.249642 0.249642)
							(end -0.1778 0.2794)
						)
						(arc
							(start 0.1778 0.2794)
							(mid 0.249642 0.249642)
							(end 0.2794 0.1778)
						)
						(arc
							(start 0.2794 -0.1778)
							(mid 0.249642 -0.249642)
							(end 0.1778 -0.2794)
						)
					)
					(width 0)
					(fill yes)
				)
			)
		)
	)
	(footprint ""
		(layer "F.Cu")
		(at 265.887962 -222.104458)
		(property "Reference" "R401"
			(at 0 0 0)
			(layer "F.SilkS")
			(hide yes)
			(effects
				(font
					(size 1.27 1.27)
				)
			)
		)
		(property "Value" "10KR2F-2-GP"
			(at 0.064008 -3.993896 0)
			(unlocked yes)
			(layer "F.Fab")
			(hide yes)
			(effects
				(font
					(size 1.016 1.016)
					(thickness 0.1524)
				)
			)
		)
		(property "Device Type" "R402H16"
			(at 0.064008 -5.517896 0)
			(unlocked yes)
			(layer "F.Fab")
			(hide yes)
			(effects
				(font
					(size 1.016 1.016)
					(thickness 0.1524)
				)
			)
		)
		(duplicate_pad_numbers_are_jumpers no)
		(fp_line
			(start -0.508 -0.9398)
			(end -0.508 0.9398)
			(stroke
				(width 0.1524)
				(type default)
			)
			(layer "F.SilkS")
		)
		(fp_line
			(start 0.508 -0.9398)
			(end -0.508 -0.9398)
			(stroke
				(width 0.1524)
				(type default)
			)
			(layer "F.SilkS")
		)
		(fp_rect
			(start -0.508 0.9398)
			(end 0.508 -0.9398)
			(stroke
				(width 0)
				(type default)
			)
			(fill no)
			(layer "F.CrtYd")
		)
		(fp_rect
			(start -0.508 0.9398)
			(end 0.508 -0.9398)
			(stroke
				(width 0)
				(type default)
			)
			(fill no)
			(layer "F.Fab")
		)
		(pad "1" smd custom
			(at 0 -0.4445)
			(size 0.1397 0.1397)
			(layers "F.Cu" "F.Mask" "F.Paste")
			(net "P3V3_STBY_A")
			(options
				(clearance outline)
				(anchor circle)
			)
			(primitives
				(gr_poly
					(pts
						(arc
							(start -0.1778 -0.2794)
							(mid -0.249642 -0.249642)
							(end -0.2794 -0.1778)
						)
						(arc
							(start -0.2794 0.1778)
							(mid -0.249642 0.249642)
							(end -0.1778 0.2794)
						)
						(arc
							(start 0.1778 0.2794)
							(mid 0.249642 0.249642)
							(end 0.2794 0.1778)
						)
						(arc
							(start 0.2794 -0.1778)
							(mid 0.249642 -0.249642)
							(end 0.1778 -0.2794)
						)
					)
					(width 0)
					(fill yes)
				)
			)
		)
		(pad "2" smd custom
			(at 0 0.4445)
			(size 0.1397 0.1397)
			(layers "F.Cu" "F.Mask" "F.Paste")
			(net "I2C_DPB_BUFF_READY")
			(options
				(clearance outline)
				(anchor circle)
			)
			(primitives
				(gr_poly
					(pts
						(arc
							(start -0.1778 -0.2794)
							(mid -0.249642 -0.249642)
							(end -0.2794 -0.1778)
						)
						(arc
							(start -0.2794 0.1778)
							(mid -0.249642 0.249642)
							(end -0.1778 0.2794)
						)
						(arc
							(start 0.1778 0.2794)
							(mid 0.249642 0.249642)
							(end 0.2794 0.1778)
						)
						(arc
							(start 0.2794 -0.1778)
							(mid 0.249642 -0.249642)
							(end 0.1778 -0.2794)
						)
					)
					(width 0)
					(fill yes)
				)
			)
		)
	)
	(footprint ""
		(layer "F.Cu")
		(at 456.0189 -304.335942 180)
		(property "Reference" "C177"
			(at 0 0 180)
			(layer "F.SilkS")
			(hide yes)
			(effects
				(font
					(size 1.27 1.27)
				)
			)
		)
		(property "Value" "SC1U25V3KX-GP"
			(at 0 -2.8194 180)
			(unlocked yes)
			(layer "F.Fab")
			(hide yes)
			(effects
				(font
					(size 1.016 1.016)
					(thickness 0.1524)
				)
			)
		)
		(property "Device Type" "C603H36"
			(at 0 -4.3434 180)
			(unlocked yes)
			(layer "F.Fab")
			(hide yes)
			(effects
				(font
					(size 1.016 1.016)
					(thickness 0.1524)
				)
			)
		)
		(duplicate_pad_numbers_are_jumpers no)
		(fp_line
			(start 0.508 0)
			(end -0.508 0)
			(stroke
				(width 0.2032)
				(type default)
			)
			(layer "F.SilkS")
		)
		(fp_rect
			(start -0.5842 1.3335)
			(end 0.5842 -1.3335)
			(stroke
				(width 0)
				(type default)
			)
			(fill no)
			(layer "F.CrtYd")
		)
		(fp_rect
			(start -0.5842 1.3335)
			(end 0.5842 -1.3335)
			(stroke
				(width 0)
				(type default)
			)
			(fill no)
			(layer "F.Fab")
		)
		(pad "1" smd custom
			(at 0 -0.762 180)
			(size 0.2159 0.2159)
			(layers "F.Cu" "F.Mask" "F.Paste")
			(net "P12V_HDD10")
			(options
				(clearance outline)
				(anchor circle)
			)
			(primitives
				(gr_poly
					(pts
						(arc
							(start -0.3302 -0.4318)
							(mid -0.402042 -0.402042)
							(end -0.4318 -0.3302)
						)
						(arc
							(start -0.4318 0.3302)
							(mid -0.402042 0.402042)
							(end -0.3302 0.4318)
						)
						(arc
							(start 0.3302 0.4318)
							(mid 0.402042 0.402042)
							(end 0.4318 0.3302)
						)
						(arc
							(start 0.4318 -0.3302)
							(mid 0.402042 -0.402042)
							(end 0.3302 -0.4318)
						)
					)
					(width 0)
					(fill yes)
				)
			)
		)
		(pad "2" smd custom
			(at 0 0.762 180)
			(size 0.2159 0.2159)
			(layers "F.Cu" "F.Mask" "F.Paste")
			(net "GND")
			(options
				(clearance outline)
				(anchor circle)
			)
			(primitives
				(gr_poly
					(pts
						(arc
							(start -0.3302 -0.4318)
							(mid -0.402042 -0.402042)
							(end -0.4318 -0.3302)
						)
						(arc
							(start -0.4318 0.3302)
							(mid -0.402042 0.402042)
							(end -0.3302 0.4318)
						)
						(arc
							(start 0.3302 0.4318)
							(mid 0.402042 0.402042)
							(end 0.4318 0.3302)
						)
						(arc
							(start 0.4318 -0.3302)
							(mid 0.402042 -0.402042)
							(end 0.3302 -0.4318)
						)
					)
					(width 0)
					(fill yes)
				)
			)
		)
	)
	(footprint ""
		(layer "F.Cu")
		(at 132.752592 -298.796964)
		(property "Reference" "Q291"
			(at 0 0 0)
			(layer "F.SilkS")
			(hide yes)
			(effects
				(font
					(size 1.27 1.27)
				)
			)
		)
		(property "Value" "SSM3K324R-GP"
			(at 0.127 -8.9662 0)
			(unlocked yes)
			(layer "F.Fab")
			(hide yes)
			(effects
				(font
					(size 1.016 1.016)
					(thickness 0.1524)
				)
			)
		)
		(property "Device Type" "SOT23DGS2D4H35"
			(at 0.127 -10.4902 0)
			(unlocked yes)
			(layer "F.Fab")
			(hide yes)
			(effects
				(font
					(size 1.016 1.016)
					(thickness 0.1524)
				)
			)
		)
		(duplicate_pad_numbers_are_jumpers no)
		(fp_line
			(start -1.651 -1.778)
			(end -1.651 1.778)
			(stroke
				(width 0.1524)
				(type default)
			)
			(layer "F.SilkS")
		)
		(fp_line
			(start -1.651 1.778)
			(end 1.651 1.778)
			(stroke
				(width 0.1524)
				(type default)
			)
			(layer "F.SilkS")
		)
		(fp_line
			(start 1.651 -1.778)
			(end -1.651 -1.778)
			(stroke
				(width 0.1524)
				(type default)
			)
			(layer "F.SilkS")
		)
		(fp_line
			(start 1.651 1.778)
			(end 1.651 -1.778)
			(stroke
				(width 0.1524)
				(type default)
			)
			(layer "F.SilkS")
		)
		(fp_poly
			(pts
				(xy -1.778 1.8796) (xy -1.778 -1.8796) (xy 1.778 -1.8796) (xy 1.778 1.8796)
			)
			(stroke
				(width 0)
				(type default)
			)
			(fill no)
			(layer "F.CrtYd")
		)
		(fp_poly
			(pts
				(xy -1.778 1.8796) (xy -1.778 -1.8796) (xy 1.778 -1.8796) (xy 1.778 1.8796)
			)
			(stroke
				(width 0)
				(type default)
			)
			(fill no)
			(layer "F.Fab")
		)
		(pad "D" smd custom
			(at 0 -0.9525)
			(size 0.1905 0.1905)
			(layers "F.Cu" "F.Mask" "F.Paste")
			(net "DRV_ACT_28_N")
			(options
				(clearance outline)
				(anchor circle)
			)
			(primitives
				(gr_poly
					(pts
						(arc
							(start -0.1778 0.5715)
							(mid -0.321484 0.511984)
							(end -0.381 0.3683)
						)
						(arc
							(start -0.381 -0.3683)
							(mid -0.321484 -0.511984)
							(end -0.1778 -0.5715)
						)
						(arc
							(start 0.1778 -0.5715)
							(mid 0.321484 -0.511984)
							(end 0.381 -0.3683)
						)
						(arc
							(start 0.381 0.3683)
							(mid 0.321484 0.511984)
							(end 0.1778 0.5715)
						)
					)
					(width 0)
					(fill yes)
				)
			)
		)
		(pad "G" smd custom
			(at -0.98425 0.9525)
			(size 0.1905 0.1905)
			(layers "F.Cu" "F.Mask" "F.Paste")
			(net "DRIVE_B_28_ACT")
			(options
				(clearance outline)
				(anchor circle)
			)
			(primitives
				(gr_poly
					(pts
						(arc
							(start -0.1778 0.5715)
							(mid -0.321484 0.511984)
							(end -0.381 0.3683)
						)
						(arc
							(start -0.381 -0.3683)
							(mid -0.321484 -0.511984)
							(end -0.1778 -0.5715)
						)
						(arc
							(start 0.1778 -0.5715)
							(mid 0.321484 -0.511984)
							(end 0.381 -0.3683)
						)
						(arc
							(start 0.381 0.3683)
							(mid 0.321484 0.511984)
							(end 0.1778 0.5715)
						)
					)
					(width 0)
					(fill yes)
				)
			)
		)
		(pad "S" smd custom
			(at 0.98425 0.9525)
			(size 0.1905 0.1905)
			(layers "F.Cu" "F.Mask" "F.Paste")
			(net "GND")
			(options
				(clearance outline)
				(anchor circle)
			)
			(primitives
				(gr_poly
					(pts
						(arc
							(start -0.1778 0.5715)
							(mid -0.321484 0.511984)
							(end -0.381 0.3683)
						)
						(arc
							(start -0.381 -0.3683)
							(mid -0.321484 -0.511984)
							(end -0.1778 -0.5715)
						)
						(arc
							(start 0.1778 -0.5715)
							(mid 0.321484 -0.511984)
							(end 0.381 -0.3683)
						)
						(arc
							(start 0.381 0.3683)
							(mid 0.321484 0.511984)
							(end 0.1778 0.5715)
						)
					)
					(width 0)
					(fill yes)
				)
			)
		)
	)
	(footprint ""
		(layer "F.Cu")
		(at 361.369102 -74.335894 180)
		(property "Reference" "C450"
			(at 0 0 180)
			(layer "F.SilkS")
			(hide yes)
			(effects
				(font
					(size 1.27 1.27)
				)
			)
		)
		(property "Value" "SC1U25V3KX-GP"
			(at 0 -2.8194 180)
			(unlocked yes)
			(layer "F.Fab")
			(hide yes)
			(effects
				(font
					(size 1.016 1.016)
					(thickness 0.1524)
				)
			)
		)
		(property "Device Type" "C603H36"
			(at 0 -4.3434 180)
			(unlocked yes)
			(layer "F.Fab")
			(hide yes)
			(effects
				(font
					(size 1.016 1.016)
					(thickness 0.1524)
				)
			)
		)
		(duplicate_pad_numbers_are_jumpers no)
		(fp_line
			(start 0.508 0)
			(end -0.508 0)
			(stroke
				(width 0.2032)
				(type default)
			)
			(layer "F.SilkS")
		)
		(fp_rect
			(start -0.5842 1.3335)
			(end 0.5842 -1.3335)
			(stroke
				(width 0)
				(type default)
			)
			(fill no)
			(layer "F.CrtYd")
		)
		(fp_rect
			(start -0.5842 1.3335)
			(end 0.5842 -1.3335)
			(stroke
				(width 0)
				(type default)
			)
			(fill no)
			(layer "F.Fab")
		)
		(pad "1" smd custom
			(at 0 -0.762 180)
			(size 0.2159 0.2159)
			(layers "F.Cu" "F.Mask" "F.Paste")
			(net "P12V_HDD31")
			(options
				(clearance outline)
				(anchor circle)
			)
			(primitives
				(gr_poly
					(pts
						(arc
							(start -0.3302 -0.4318)
							(mid -0.402042 -0.402042)
							(end -0.4318 -0.3302)
						)
						(arc
							(start -0.4318 0.3302)
							(mid -0.402042 0.402042)
							(end -0.3302 0.4318)
						)
						(arc
							(start 0.3302 0.4318)
							(mid 0.402042 0.402042)
							(end 0.4318 0.3302)
						)
						(arc
							(start 0.4318 -0.3302)
							(mid 0.402042 -0.402042)
							(end 0.3302 -0.4318)
						)
					)
					(width 0)
					(fill yes)
				)
			)
		)
		(pad "2" smd custom
			(at 0 0.762 180)
			(size 0.2159 0.2159)
			(layers "F.Cu" "F.Mask" "F.Paste")
			(net "GND")
			(options
				(clearance outline)
				(anchor circle)
			)
			(primitives
				(gr_poly
					(pts
						(arc
							(start -0.3302 -0.4318)
							(mid -0.402042 -0.402042)
							(end -0.4318 -0.3302)
						)
						(arc
							(start -0.4318 0.3302)
							(mid -0.402042 0.402042)
							(end -0.3302 0.4318)
						)
						(arc
							(start 0.3302 0.4318)
							(mid 0.402042 0.402042)
							(end 0.4318 0.3302)
						)
						(arc
							(start 0.4318 -0.3302)
							(mid 0.402042 -0.402042)
							(end 0.3302 -0.4318)
						)
					)
					(width 0)
					(fill yes)
				)
			)
		)
	)
	(footprint ""
		(layer "F.Cu")
		(at 261.493 -236.855)
		(property "Reference" "U9"
			(at 0 0 0)
			(layer "F.SilkS")
			(hide yes)
			(effects
				(font
					(size 1.27 1.27)
				)
			)
		)
		(property "Value" "PCA9557PWR-1-GP-U"
			(at 0.127 -12.573 0)
			(unlocked yes)
			(layer "F.Fab")
			(hide yes)
			(effects
				(font
					(size 1.016 1.016)
					(thickness 0.1524)
				)
			)
		)
		(property "Device Type" "TSOIC16H48"
			(at 0.1016 -14.5796 0)
			(unlocked yes)
			(layer "F.Fab")
			(hide yes)
			(effects
				(font
					(size 1.016 1.016)
					(thickness 0.1524)
				)
			)
		)
		(duplicate_pad_numbers_are_jumpers no)
		(fp_line
			(start -3.0988 -1.778)
			(end -3.0988 1.778)
			(stroke
				(width 0.1524)
				(type default)
			)
			(layer "F.SilkS")
		)
		(fp_line
			(start -3.0988 -1.778)
			(end 2.3622 -1.778)
			(stroke
				(width 0.1524)
				(type default)
			)
			(layer "F.SilkS")
		)
		(fp_line
			(start -2.921 3.81)
			(end -2.921 1.778)
			(stroke
				(width 0.508)
				(type default)
			)
			(layer "F.SilkS")
		)
		(fp_line
			(start -2.54 0)
			(end -3.0988 -0.5588)
			(stroke
				(width 0.1524)
				(type default)
			)
			(layer "F.SilkS")
		)
		(fp_line
			(start -2.54 0)
			(end -3.0988 0.5588)
			(stroke
				(width 0.1524)
				(type default)
			)
			(layer "F.SilkS")
		)
		(fp_line
			(start 2.3622 -1.778)
			(end 2.3622 1.778)
			(stroke
				(width 0.1524)
				(type default)
			)
			(layer "F.SilkS")
		)
		(fp_line
			(start 2.3622 1.778)
			(end -2.921 1.778)
			(stroke
				(width 0.1524)
				(type default)
			)
			(layer "F.SilkS")
		)
		(fp_poly
			(pts
				(xy -2.4638 -1.778) (xy -2.4638 1.778) (xy 2.3622 1.778) (xy 2.3622 -1.778)
			)
			(stroke
				(width 0)
				(type default)
			)
			(fill yes)
			(layer "F.SilkS")
		)
		(fp_rect
			(start -3.175 4.064)
			(end 3.175 -4.064)
			(stroke
				(width 0)
				(type default)
			)
			(fill no)
			(layer "F.CrtYd")
		)
		(fp_poly
			(pts
				(xy -3.175 -4.064) (xy 3.175 -4.064) (xy 3.175 4.064) (xy -3.175 4.064)
			)
			(stroke
				(width 0)
				(type default)
			)
			(fill no)
			(layer "F.Fab")
		)
		(pad "1" smd rect
			(at -2.27584 2.8194)
			(size 0.3556 1.524)
			(layers "F.Cu" "F.Mask" "F.Paste")
			(net "IO_EXP3_SCL")
		)
		(pad "2" smd rect
			(at -1.6256 2.8194)
			(size 0.3556 1.524)
			(layers "F.Cu" "F.Mask" "F.Paste")
			(net "IO_EXP3_SDA")
		)
		(pad "3" smd rect
			(at -0.97536 2.8194)
			(size 0.3556 1.524)
			(layers "F.Cu" "F.Mask" "F.Paste")
			(net "IO_EXP3_A0")
		)
		(pad "4" smd rect
			(at -0.32512 2.8194)
			(size 0.3556 1.524)
			(layers "F.Cu" "F.Mask" "F.Paste")
			(net "IO_EXP3_A1")
		)
		(pad "5" smd rect
			(at 0.32512 2.8194)
			(size 0.3556 1.524)
			(layers "F.Cu" "F.Mask" "F.Paste")
			(net "IO_EXP3_A2")
		)
		(pad "6" smd rect
			(at 0.97536 2.8194)
			(size 0.3556 1.524)
			(layers "F.Cu" "F.Mask" "F.Paste")
			(net "Net_40")
		)
		(pad "7" smd rect
			(at 1.6256 2.8194)
			(size 0.3556 1.524)
			(layers "F.Cu" "F.Mask" "F.Paste")
			(net "DRIVE_A_32_PWR")
		)
		(pad "8" smd rect
			(at 2.27584 2.8194)
			(size 0.3556 1.524)
			(layers "F.Cu" "F.Mask" "F.Paste")
			(net "GND")
		)
		(pad "9" smd rect
			(at 2.27584 -2.8194)
			(size 0.3556 1.524)
			(layers "F.Cu" "F.Mask" "F.Paste")
			(net "DRIVE_A_33_PWR")
		)
		(pad "10" smd rect
			(at 1.6256 -2.8194)
			(size 0.3556 1.524)
			(layers "F.Cu" "F.Mask" "F.Paste")
			(net "DRIVE_A_34_PWR")
		)
		(pad "11" smd rect
			(at 0.97536 -2.8194)
			(size 0.3556 1.524)
			(layers "F.Cu" "F.Mask" "F.Paste")
			(net "DRIVE_A_35_PWR")
		)
		(pad "12" smd rect
			(at 0.32512 -2.8194)
			(size 0.3556 1.524)
			(layers "F.Cu" "F.Mask" "F.Paste")
			(net "Net_1270")
		)
		(pad "13" smd rect
			(at -0.32512 -2.8194)
			(size 0.3556 1.524)
			(layers "F.Cu" "F.Mask" "F.Paste")
			(net "Net_245")
		)
		(pad "14" smd rect
			(at -0.97536 -2.8194)
			(size 0.3556 1.524)
			(layers "F.Cu" "F.Mask" "F.Paste")
			(net "Net_240")
		)
		(pad "15" smd rect
			(at -1.6256 -2.8194)
			(size 0.3556 1.524)
			(layers "F.Cu" "F.Mask" "F.Paste")
			(net "IO_EXP3_INT_N")
		)
		(pad "16" smd rect
			(at -2.27584 -2.8194)
			(size 0.3556 1.524)
			(layers "F.Cu" "F.Mask" "F.Paste")
			(net "GPIO_VCC_U9")
		)
	)
	(footprint ""
		(layer "F.Cu")
		(at 241.046 -395.9098 180)
		(property "Reference" "R1163"
			(at 0 0 180)
			(layer "F.SilkS")
			(hide yes)
			(effects
				(font
					(size 1.27 1.27)
				)
			)
		)
		(property "Value" "75KR2F-GP"
			(at 0.064008 -3.993896 180)
			(unlocked yes)
			(layer "F.Fab")
			(hide yes)
			(effects
				(font
					(size 1.016 1.016)
					(thickness 0.1524)
				)
			)
		)
		(property "Device Type" "R402H16"
			(at 0.064008 -5.517896 180)
			(unlocked yes)
			(layer "F.Fab")
			(hide yes)
			(effects
				(font
					(size 1.016 1.016)
					(thickness 0.1524)
				)
			)
		)
		(duplicate_pad_numbers_are_jumpers no)
		(fp_line
			(start 0.508 -0.9398)
			(end -0.508 -0.9398)
			(stroke
				(width 0.1524)
				(type default)
			)
			(layer "F.SilkS")
		)
		(fp_line
			(start -0.508 -0.9398)
			(end -0.508 0.9398)
			(stroke
				(width 0.1524)
				(type default)
			)
			(layer "F.SilkS")
		)
		(fp_rect
			(start -0.508 0.9398)
			(end 0.508 -0.9398)
			(stroke
				(width 0)
				(type default)
			)
			(fill no)
			(layer "F.CrtYd")
		)
		(fp_rect
			(start -0.508 0.9398)
			(end 0.508 -0.9398)
			(stroke
				(width 0)
				(type default)
			)
			(fill no)
			(layer "F.Fab")
		)
		(pad "1" smd custom
			(at 0 -0.4445 180)
			(size 0.1397 0.1397)
			(layers "F.Cu" "F.Mask" "F.Paste")
			(net "MB3_ISET_R")
			(options
				(clearance outline)
				(anchor circle)
			)
			(primitives
				(gr_poly
					(pts
						(arc
							(start -0.1778 -0.2794)
							(mid -0.249642 -0.249642)
							(end -0.2794 -0.1778)
						)
						(arc
							(start -0.2794 0.1778)
							(mid -0.249642 0.249642)
							(end -0.1778 0.2794)
						)
						(arc
							(start 0.1778 0.2794)
							(mid 0.249642 0.249642)
							(end 0.2794 0.1778)
						)
						(arc
							(start 0.2794 -0.1778)
							(mid 0.249642 -0.249642)
							(end 0.1778 -0.2794)
						)
					)
					(width 0)
					(fill yes)
				)
			)
		)
		(pad "2" smd custom
			(at 0 0.4445 180)
			(size 0.1397 0.1397)
			(layers "F.Cu" "F.Mask" "F.Paste")
			(net "AGND_CURRENT_DPB")
			(options
				(clearance outline)
				(anchor circle)
			)
			(primitives
				(gr_poly
					(pts
						(arc
							(start -0.1778 -0.2794)
							(mid -0.249642 -0.249642)
							(end -0.2794 -0.1778)
						)
						(arc
							(start -0.2794 0.1778)
							(mid -0.249642 0.249642)
							(end -0.1778 0.2794)
						)
						(arc
							(start 0.1778 0.2794)
							(mid 0.249642 0.249642)
							(end 0.2794 0.1778)
						)
						(arc
							(start 0.2794 -0.1778)
							(mid 0.249642 -0.249642)
							(end 0.1778 -0.2794)
						)
					)
					(width 0)
					(fill yes)
				)
			)
		)
	)
	(footprint ""
		(layer "F.Cu")
		(at 158.708852 -277.750016 -90)
		(property "Reference" "VIA42"
			(at 0 0 270)
			(layer "F.SilkS")
			(hide yes)
			(effects
				(font
					(size 1.27 1.27)
				)
			)
		)
		(property "Value" "100OHM-8L-1D6MM-L18L16-GP"
			(at -3.7211 -4.5085 270)
			(unlocked yes)
			(layer "F.Fab")
			(hide yes)
			(effects
				(font
					(size 1.016 1.016)
					(thickness 0.1524)
				)
			)
		)
		(property "Device Type" "VIA-PCIE-4P-394076"
			(at -3.7211 -6.0325 270)
			(unlocked yes)
			(layer "F.Fab")
			(hide yes)
			(effects
				(font
					(size 1.016 1.016)
					(thickness 0.1524)
				)
			)
		)
		(duplicate_pad_numbers_are_jumpers no)
		(fp_rect
			(start -1.9685 0.381)
			(end 1.9685 -0.381)
			(stroke
				(width 0)
				(type default)
			)
			(fill no)
			(layer "F.CrtYd")
		)
		(fp_rect
			(start -1.9685 0.381)
			(end 1.9685 -0.381)
			(stroke
				(width 0)
				(type default)
			)
			(fill no)
			(layer "F.Fab")
		)
		(pad "1" thru_hole circle
			(at -1.5875 0 270)
			(size 0.508 0.508)
			(drill 0.254)
			(layers "*.Cu" "*.Mask")
			(remove_unused_layers no)
			(net "GND")
			(clearance 0.127)
			(thermal_gap 0.127)
		)
		(pad "2" thru_hole circle
			(at -0.5715 0 270)
			(size 0.508 0.508)
			(drill 0.254)
			(layers "*.Cu" "*.Mask")
			(remove_unused_layers no)
			(net "PHY_DRV_A_TO_SCC_A_4_DP")
			(clearance 0.127)
			(thermal_gap 0.127)
		)
		(pad "3" thru_hole circle
			(at 0.5715 0 270)
			(size 0.508 0.508)
			(drill 0.254)
			(layers "*.Cu" "*.Mask")
			(remove_unused_layers no)
			(net "PHY_DRV_A_TO_SCC_A_4_DN")
			(clearance 0.127)
			(thermal_gap 0.127)
		)
		(pad "4" thru_hole circle
			(at 1.5875 0 270)
			(size 0.508 0.508)
			(drill 0.254)
			(layers "*.Cu" "*.Mask")
			(remove_unused_layers no)
			(net "GND")
			(clearance 0.127)
			(thermal_gap 0.127)
		)
	)
	(footprint ""
		(layer "F.Cu")
		(at 99.278948 -65.064894 90)
		(property "Reference" "R732"
			(at 0 0 90)
			(layer "F.SilkS")
			(hide yes)
			(effects
				(font
					(size 1.27 1.27)
				)
			)
		)
		(property "Value" "220R3F-1-GP"
			(at -0.0254 -2.5146 90)
			(unlocked yes)
			(layer "F.Fab")
			(hide yes)
			(effects
				(font
					(size 1.016 1.016)
					(thickness 0.1524)
				)
			)
		)
		(property "Device Type" "R603H22"
			(at -0.0254 -4.0386 90)
			(unlocked yes)
			(layer "F.Fab")
			(hide yes)
			(effects
				(font
					(size 1.016 1.016)
					(thickness 0.1524)
				)
			)
		)
		(duplicate_pad_numbers_are_jumpers no)
		(fp_line
			(start 0.2032 0)
			(end 0.4826 0)
			(stroke
				(width 0.2032)
				(type default)
			)
			(layer "F.SilkS")
		)
		(fp_line
			(start -0.4826 0)
			(end -0.2032 0)
			(stroke
				(width 0.2032)
				(type default)
			)
			(layer "F.SilkS")
		)
		(fp_rect
			(start -0.5842 1.3335)
			(end 0.5842 -1.3335)
			(stroke
				(width 0)
				(type default)
			)
			(fill no)
			(layer "F.CrtYd")
		)
		(fp_rect
			(start -0.5842 1.3335)
			(end 0.5842 -1.3335)
			(stroke
				(width 0)
				(type default)
			)
			(fill no)
			(layer "F.Fab")
		)
		(pad "1" smd custom
			(at 0 -0.762 90)
			(size 0.2159 0.2159)
			(layers "F.Cu" "F.Mask" "F.Paste")
			(net "HDD_PRSNT_26")
			(options
				(clearance outline)
				(anchor circle)
			)
			(primitives
				(gr_poly
					(pts
						(arc
							(start -0.3302 -0.4318)
							(mid -0.402042 -0.402042)
							(end -0.4318 -0.3302)
						)
						(arc
							(start -0.4318 0.3302)
							(mid -0.402042 0.402042)
							(end -0.3302 0.4318)
						)
						(arc
							(start 0.3302 0.4318)
							(mid 0.402042 0.402042)
							(end 0.4318 0.3302)
						)
						(arc
							(start 0.4318 -0.3302)
							(mid 0.402042 -0.402042)
							(end 0.3302 -0.4318)
						)
					)
					(width 0)
					(fill yes)
				)
			)
		)
		(pad "2" smd custom
			(at 0 0.762 90)
			(size 0.2159 0.2159)
			(layers "F.Cu" "F.Mask" "F.Paste")
			(net "DRIVE_A_26_INS")
			(options
				(clearance outline)
				(anchor circle)
			)
			(primitives
				(gr_poly
					(pts
						(arc
							(start -0.3302 -0.4318)
							(mid -0.402042 -0.402042)
							(end -0.4318 -0.3302)
						)
						(arc
							(start -0.4318 0.3302)
							(mid -0.402042 0.402042)
							(end -0.3302 0.4318)
						)
						(arc
							(start 0.3302 0.4318)
							(mid 0.402042 0.402042)
							(end 0.4318 0.3302)
						)
						(arc
							(start 0.4318 -0.3302)
							(mid 0.402042 -0.402042)
							(end 0.3302 -0.4318)
						)
					)
					(width 0)
					(fill yes)
				)
			)
		)
	)
	(footprint ""
		(layer "F.Cu")
		(at 272.34007 -7.894828 180)
		(property "Reference" "TP191"
			(at 0 0 180)
			(layer "F.SilkS")
			(hide yes)
			(effects
				(font
					(size 1.27 1.27)
				)
			)
		)
		(property "Value" "TPAD32-GP"
			(at -0.0508 -1.6764 180)
			(unlocked yes)
			(layer "F.Fab")
			(hide yes)
			(effects
				(font
					(size 1.016 1.016)
					(thickness 0.1524)
				)
			)
		)
		(property "Device Type" "TPAD32"
			(at -0.0508 -3.2004 180)
			(unlocked yes)
			(layer "F.Fab")
			(hide yes)
			(effects
				(font
					(size 1.016 1.016)
					(thickness 0.1524)
				)
			)
		)
		(duplicate_pad_numbers_are_jumpers no)
		(fp_poly
			(pts
				(arc
					(start -0.4064 0)
					(mid 0.4064 0)
					(end -0.4064 0)
				)
			)
			(stroke
				(width 0)
				(type default)
			)
			(fill no)
			(layer "F.CrtYd")
		)
		(fp_poly
			(pts
				(arc
					(start -0.7112 0)
					(mid 0.7112 0)
					(end -0.7112 0)
				)
			)
			(stroke
				(width 0)
				(type default)
			)
			(fill no)
			(layer "F.Fab")
		)
		(pad "1" smd circle
			(at 0 0 180)
			(size 0.8128 0.8128)
			(layers "F.Cu" "F.Mask" "F.Paste")
			(net "TP_COMP_B_NCSI_RCLK")
		)
	)
	(footprint ""
		(layer "F.Cu")
		(at 149.196298 -161.040318 -90)
		(property "Reference" "R506"
			(at 0 0 270)
			(layer "F.SilkS")
			(hide yes)
			(effects
				(font
					(size 1.27 1.27)
				)
			)
		)
		(property "Value" "1KR2F-3-GP"
			(at 0.064008 -3.993896 270)
			(unlocked yes)
			(layer "F.Fab")
			(hide yes)
			(effects
				(font
					(size 1.016 1.016)
					(thickness 0.1524)
				)
			)
		)
		(property "Device Type" "R402H16"
			(at 0.064008 -5.517896 270)
			(unlocked yes)
			(layer "F.Fab")
			(hide yes)
			(effects
				(font
					(size 1.016 1.016)
					(thickness 0.1524)
				)
			)
		)
		(duplicate_pad_numbers_are_jumpers no)
		(fp_line
			(start -0.508 -0.9398)
			(end -0.508 0.9398)
			(stroke
				(width 0.1524)
				(type default)
			)
			(layer "F.SilkS")
		)
		(fp_line
			(start 0.508 -0.9398)
			(end -0.508 -0.9398)
			(stroke
				(width 0.1524)
				(type default)
			)
			(layer "F.SilkS")
		)
		(fp_rect
			(start -0.508 0.9398)
			(end 0.508 -0.9398)
			(stroke
				(width 0)
				(type default)
			)
			(fill no)
			(layer "F.CrtYd")
		)
		(fp_rect
			(start -0.508 0.9398)
			(end 0.508 -0.9398)
			(stroke
				(width 0)
				(type default)
			)
			(fill no)
			(layer "F.Fab")
		)
		(pad "1" smd custom
			(at 0 -0.4445 270)
			(size 0.1397 0.1397)
			(layers "F.Cu" "F.Mask" "F.Paste")
			(net "P3V3_STBY_A")
			(options
				(clearance outline)
				(anchor circle)
			)
			(primitives
				(gr_poly
					(pts
						(arc
							(start -0.1778 -0.2794)
							(mid -0.249642 -0.249642)
							(end -0.2794 -0.1778)
						)
						(arc
							(start -0.2794 0.1778)
							(mid -0.249642 0.249642)
							(end -0.1778 0.2794)
						)
						(arc
							(start 0.1778 0.2794)
							(mid 0.249642 0.249642)
							(end 0.2794 0.1778)
						)
						(arc
							(start 0.2794 -0.1778)
							(mid 0.249642 -0.249642)
							(end 0.1778 -0.2794)
						)
					)
					(width 0)
					(fill yes)
				)
			)
		)
		(pad "2" smd custom
			(at 0 0.4445 270)
			(size 0.1397 0.1397)
			(layers "F.Cu" "F.Mask" "F.Paste")
			(net "SW_PWR_R_HDD16")
			(options
				(clearance outline)
				(anchor circle)
			)
			(primitives
				(gr_poly
					(pts
						(arc
							(start -0.1778 -0.2794)
							(mid -0.249642 -0.249642)
							(end -0.2794 -0.1778)
						)
						(arc
							(start -0.2794 0.1778)
							(mid -0.249642 0.249642)
							(end -0.1778 0.2794)
						)
						(arc
							(start 0.1778 0.2794)
							(mid 0.249642 0.249642)
							(end 0.2794 0.1778)
						)
						(arc
							(start 0.2794 -0.1778)
							(mid 0.249642 -0.249642)
							(end 0.1778 -0.2794)
						)
					)
					(width 0)
					(fill yes)
				)
			)
		)
	)
	(footprint ""
		(layer "F.Cu")
		(at 399.90395 -177.016918)
		(property "Reference" "Q122"
			(at 0 0 0)
			(layer "F.SilkS")
			(hide yes)
			(effects
				(font
					(size 1.27 1.27)
				)
			)
		)
		(property "Value" "AO4407AL-GP"
			(at -3.707384 -1.5367 0)
			(unlocked yes)
			(layer "F.Fab")
			(hide yes)
			(effects
				(font
					(size 1.016 1.016)
					(thickness 0.1524)
				)
			)
		)
		(property "Device Type" "SOIC8H69"
			(at -3.707384 -3.0607 0)
			(unlocked yes)
			(layer "F.Fab")
			(hide yes)
			(effects
				(font
					(size 1.016 1.016)
					(thickness 0.1524)
				)
			)
		)
		(duplicate_pad_numbers_are_jumpers no)
		(fp_line
			(start -2.7432 -1.4224)
			(end -2.7432 1.4224)
			(stroke
				(width 0.1524)
				(type default)
			)
			(layer "F.SilkS")
		)
		(fp_line
			(start -2.7432 1.4224)
			(end -2.6416 1.4224)
			(stroke
				(width 0.1524)
				(type default)
			)
			(layer "F.SilkS")
		)
		(fp_line
			(start -2.7432 1.4224)
			(end 2.1336 1.4224)
			(stroke
				(width 0.1524)
				(type default)
			)
			(layer "F.SilkS")
		)
		(fp_line
			(start -2.7178 -0.508)
			(end -2.1844 -0.0508)
			(stroke
				(width 0.1524)
				(type default)
			)
			(layer "F.SilkS")
		)
		(fp_line
			(start -2.6289 3.4417)
			(end -2.6289 1.4732)
			(stroke
				(width 0.381)
				(type default)
			)
			(layer "F.SilkS")
		)
		(fp_line
			(start -2.1844 -0.0508)
			(end -2.7178 0.508)
			(stroke
				(width 0.1524)
				(type default)
			)
			(layer "F.SilkS")
		)
		(fp_line
			(start 2.1336 -1.4224)
			(end -2.7432 -1.4224)
			(stroke
				(width 0.1524)
				(type default)
			)
			(layer "F.SilkS")
		)
		(fp_line
			(start 2.1336 1.4224)
			(end 2.1336 -1.4224)
			(stroke
				(width 0.1524)
				(type default)
			)
			(layer "F.SilkS")
		)
		(fp_poly
			(pts
				(xy -2.2098 -1.4224) (xy -2.2098 1.4224) (xy 2.2098 1.4224) (xy 2.2098 -1.4224)
			)
			(stroke
				(width 0)
				(type default)
			)
			(fill yes)
			(layer "F.SilkS")
		)
		(fp_rect
			(start -2.450084 2.999994)
			(end 2.450084 -2.999994)
			(stroke
				(width 0)
				(type default)
			)
			(fill no)
			(layer "F.CrtYd")
		)
		(fp_poly
			(pts
				(xy -2.8194 3.6322) (xy -2.8194 -3.6322) (xy 2.8194 -3.6322) (xy 2.8194 1.18364) (xy 2.450084 1.18364)
				(xy 2.450084 -2.999994) (xy -2.450084 -2.999994) (xy -2.450084 2.999994) (xy 2.450084 2.999994)
				(xy 2.450084 1.18618) (xy 2.8194 1.18618) (xy 2.8194 3.6322)
			)
			(stroke
				(width 0)
				(type default)
			)
			(fill no)
			(layer "F.CrtYd")
		)
		(fp_rect
			(start -2.8194 3.6322)
			(end 2.8194 -3.6322)
			(stroke
				(width 0)
				(type default)
			)
			(fill no)
			(layer "F.Fab")
		)
		(pad "1" smd rect
			(at -1.905 2.54)
			(size 0.635 1.651)
			(layers "F.Cu" "F.Mask" "F.Paste")
			(net "P12V_A")
		)
		(pad "2" smd rect
			(at -0.635 2.54)
			(size 0.635 1.651)
			(layers "F.Cu" "F.Mask" "F.Paste")
			(net "P12V_A")
		)
		(pad "3" smd rect
			(at 0.635 2.54)
			(size 0.635 1.651)
			(layers "F.Cu" "F.Mask" "F.Paste")
			(net "P12V_A")
		)
		(pad "4" smd rect
			(at 1.905 2.54)
			(size 0.635 1.651)
			(layers "F.Cu" "F.Mask" "F.Paste")
			(net "SW_HDD_N20")
		)
		(pad "5" smd rect
			(at 1.905 -2.54)
			(size 0.635 1.651)
			(layers "F.Cu" "F.Mask" "F.Paste")
			(net "P12V_HDD20")
		)
		(pad "6" smd rect
			(at 0.635 -2.54)
			(size 0.635 1.651)
			(layers "F.Cu" "F.Mask" "F.Paste")
			(net "P12V_HDD20")
		)
		(pad "7" smd rect
			(at -0.635 -2.54)
			(size 0.635 1.651)
			(layers "F.Cu" "F.Mask" "F.Paste")
			(net "P12V_HDD20")
		)
		(pad "8" smd rect
			(at -1.905 -2.54)
			(size 0.635 1.651)
			(layers "F.Cu" "F.Mask" "F.Paste")
			(net "P12V_HDD20")
		)
	)
	(footprint ""
		(layer "F.Cu")
		(at 392.91895 -66.842894 180)
		(property "Reference" "C456"
			(at 0 0 180)
			(layer "F.SilkS")
			(hide yes)
			(effects
				(font
					(size 1.27 1.27)
				)
			)
		)
		(property "Value" "SC1U16V3KX-5GP"
			(at 0 -2.8194 180)
			(unlocked yes)
			(layer "F.Fab")
			(hide yes)
			(effects
				(font
					(size 1.016 1.016)
					(thickness 0.1524)
				)
			)
		)
		(property "Device Type" "C603H36"
			(at 0 -4.3434 180)
			(unlocked yes)
			(layer "F.Fab")
			(hide yes)
			(effects
				(font
					(size 1.016 1.016)
					(thickness 0.1524)
				)
			)
		)
		(duplicate_pad_numbers_are_jumpers no)
		(fp_line
			(start 0.508 0)
			(end -0.508 0)
			(stroke
				(width 0.2032)
				(type default)
			)
			(layer "F.SilkS")
		)
		(fp_rect
			(start -0.5842 1.3335)
			(end 0.5842 -1.3335)
			(stroke
				(width 0)
				(type default)
			)
			(fill no)
			(layer "F.CrtYd")
		)
		(fp_rect
			(start -0.5842 1.3335)
			(end 0.5842 -1.3335)
			(stroke
				(width 0)
				(type default)
			)
			(fill no)
			(layer "F.Fab")
		)
		(pad "1" smd custom
			(at 0 -0.762 180)
			(size 0.2159 0.2159)
			(layers "F.Cu" "F.Mask" "F.Paste")
			(net "P5V_HDD32")
			(options
				(clearance outline)
				(anchor circle)
			)
			(primitives
				(gr_poly
					(pts
						(arc
							(start -0.3302 -0.4318)
							(mid -0.402042 -0.402042)
							(end -0.4318 -0.3302)
						)
						(arc
							(start -0.4318 0.3302)
							(mid -0.402042 0.402042)
							(end -0.3302 0.4318)
						)
						(arc
							(start 0.3302 0.4318)
							(mid 0.402042 0.402042)
							(end 0.4318 0.3302)
						)
						(arc
							(start 0.4318 -0.3302)
							(mid 0.402042 -0.402042)
							(end 0.3302 -0.4318)
						)
					)
					(width 0)
					(fill yes)
				)
			)
		)
		(pad "2" smd custom
			(at 0 0.762 180)
			(size 0.2159 0.2159)
			(layers "F.Cu" "F.Mask" "F.Paste")
			(net "GND")
			(options
				(clearance outline)
				(anchor circle)
			)
			(primitives
				(gr_poly
					(pts
						(arc
							(start -0.3302 -0.4318)
							(mid -0.402042 -0.402042)
							(end -0.4318 -0.3302)
						)
						(arc
							(start -0.4318 0.3302)
							(mid -0.402042 0.402042)
							(end -0.3302 0.4318)
						)
						(arc
							(start 0.3302 0.4318)
							(mid 0.402042 0.402042)
							(end 0.4318 0.3302)
						)
						(arc
							(start 0.4318 -0.3302)
							(mid 0.402042 -0.402042)
							(end 0.3302 -0.4318)
						)
					)
					(width 0)
					(fill yes)
				)
			)
		)
	)
	(footprint ""
		(layer "F.Cu")
		(at 132.6769 -188.896244)
		(property "Reference" "Q231"
			(at 0 0 0)
			(layer "F.SilkS")
			(hide yes)
			(effects
				(font
					(size 1.27 1.27)
				)
			)
		)
		(property "Value" "2N7002K-2-GP"
			(at 0.127 -8.9662 0)
			(unlocked yes)
			(layer "F.Fab")
			(hide yes)
			(effects
				(font
					(size 1.016 1.016)
					(thickness 0.1524)
				)
			)
		)
		(property "Device Type" "SOT23DGS2D4H44"
			(at 0.127 -10.4902 0)
			(unlocked yes)
			(layer "F.Fab")
			(hide yes)
			(effects
				(font
					(size 1.016 1.016)
					(thickness 0.1524)
				)
			)
		)
		(duplicate_pad_numbers_are_jumpers no)
		(fp_line
			(start -1.651 -1.778)
			(end -1.651 1.778)
			(stroke
				(width 0.1524)
				(type default)
			)
			(layer "F.SilkS")
		)
		(fp_line
			(start -1.651 1.778)
			(end 1.651 1.778)
			(stroke
				(width 0.1524)
				(type default)
			)
			(layer "F.SilkS")
		)
		(fp_line
			(start 1.651 -1.778)
			(end -1.651 -1.778)
			(stroke
				(width 0.1524)
				(type default)
			)
			(layer "F.SilkS")
		)
		(fp_line
			(start 1.651 1.778)
			(end 1.651 -1.778)
			(stroke
				(width 0.1524)
				(type default)
			)
			(layer "F.SilkS")
		)
		(fp_poly
			(pts
				(xy -1.778 1.8796) (xy -1.778 -1.8796) (xy 1.778 -1.8796) (xy 1.778 1.8796)
			)
			(stroke
				(width 0)
				(type default)
			)
			(fill no)
			(layer "F.CrtYd")
		)
		(fp_poly
			(pts
				(xy -1.778 1.8796) (xy -1.778 -1.8796) (xy 1.778 -1.8796) (xy 1.778 1.8796)
			)
			(stroke
				(width 0)
				(type default)
			)
			(fill no)
			(layer "F.Fab")
		)
		(pad "D" smd custom
			(at 0 -0.9525)
			(size 0.1905 0.1905)
			(layers "F.Cu" "F.Mask" "F.Paste")
			(net "FLT_HDD4_N")
			(options
				(clearance outline)
				(anchor circle)
			)
			(primitives
				(gr_poly
					(pts
						(arc
							(start -0.1778 0.5715)
							(mid -0.321484 0.511984)
							(end -0.381 0.3683)
						)
						(arc
							(start -0.381 -0.3683)
							(mid -0.321484 -0.511984)
							(end -0.1778 -0.5715)
						)
						(arc
							(start 0.1778 -0.5715)
							(mid 0.321484 -0.511984)
							(end 0.381 -0.3683)
						)
						(arc
							(start 0.381 0.3683)
							(mid 0.321484 0.511984)
							(end 0.1778 0.5715)
						)
					)
					(width 0)
					(fill yes)
				)
			)
		)
		(pad "G" smd custom
			(at -0.98425 0.9525)
			(size 0.1905 0.1905)
			(layers "F.Cu" "F.Mask" "F.Paste")
			(net "DRIVE_A_4_FLT_LED")
			(options
				(clearance outline)
				(anchor circle)
			)
			(primitives
				(gr_poly
					(pts
						(arc
							(start -0.1778 0.5715)
							(mid -0.321484 0.511984)
							(end -0.381 0.3683)
						)
						(arc
							(start -0.381 -0.3683)
							(mid -0.321484 -0.511984)
							(end -0.1778 -0.5715)
						)
						(arc
							(start 0.1778 -0.5715)
							(mid 0.321484 -0.511984)
							(end 0.381 -0.3683)
						)
						(arc
							(start 0.381 0.3683)
							(mid 0.321484 0.511984)
							(end 0.1778 0.5715)
						)
					)
					(width 0)
					(fill yes)
				)
			)
		)
		(pad "S" smd custom
			(at 0.98425 0.9525)
			(size 0.1905 0.1905)
			(layers "F.Cu" "F.Mask" "F.Paste")
			(net "GND")
			(options
				(clearance outline)
				(anchor circle)
			)
			(primitives
				(gr_poly
					(pts
						(arc
							(start -0.1778 0.5715)
							(mid -0.321484 0.511984)
							(end -0.381 0.3683)
						)
						(arc
							(start -0.381 -0.3683)
							(mid -0.321484 -0.511984)
							(end -0.1778 -0.5715)
						)
						(arc
							(start 0.1778 -0.5715)
							(mid 0.321484 -0.511984)
							(end 0.381 -0.3683)
						)
						(arc
							(start 0.381 0.3683)
							(mid 0.321484 0.511984)
							(end 0.1778 0.5715)
						)
					)
					(width 0)
					(fill yes)
				)
			)
		)
	)
	(footprint ""
		(layer "F.Cu")
		(at 235.7374 -231.3178)
		(property "Reference" "R71"
			(at 0 0 0)
			(layer "F.SilkS")
			(hide yes)
			(effects
				(font
					(size 1.27 1.27)
				)
			)
		)
		(property "Value" "0R2J-2-GP"
			(at 0.064008 -3.993896 0)
			(unlocked yes)
			(layer "F.Fab")
			(hide yes)
			(effects
				(font
					(size 1.016 1.016)
					(thickness 0.1524)
				)
			)
		)
		(property "Device Type" "R402H16"
			(at 0.064008 -5.517896 0)
			(unlocked yes)
			(layer "F.Fab")
			(hide yes)
			(effects
				(font
					(size 1.016 1.016)
					(thickness 0.1524)
				)
			)
		)
		(duplicate_pad_numbers_are_jumpers no)
		(fp_line
			(start -0.508 -0.9398)
			(end -0.508 0.9398)
			(stroke
				(width 0.1524)
				(type default)
			)
			(layer "F.SilkS")
		)
		(fp_line
			(start 0.508 -0.9398)
			(end -0.508 -0.9398)
			(stroke
				(width 0.1524)
				(type default)
			)
			(layer "F.SilkS")
		)
		(fp_rect
			(start -0.508 0.9398)
			(end 0.508 -0.9398)
			(stroke
				(width 0)
				(type default)
			)
			(fill no)
			(layer "F.CrtYd")
		)
		(fp_rect
			(start -0.508 0.9398)
			(end 0.508 -0.9398)
			(stroke
				(width 0)
				(type default)
			)
			(fill no)
			(layer "F.Fab")
		)
		(pad "1" smd custom
			(at 0 -0.4445)
			(size 0.1397 0.1397)
			(layers "F.Cu" "F.Mask" "F.Paste")
			(net "IO_EXP1_SDA")
			(options
				(clearance outline)
				(anchor circle)
			)
			(primitives
				(gr_poly
					(pts
						(arc
							(start -0.1778 -0.2794)
							(mid -0.249642 -0.249642)
							(end -0.2794 -0.1778)
						)
						(arc
							(start -0.2794 0.1778)
							(mid -0.249642 0.249642)
							(end -0.1778 0.2794)
						)
						(arc
							(start 0.1778 0.2794)
							(mid 0.249642 0.249642)
							(end 0.2794 0.1778)
						)
						(arc
							(start 0.2794 -0.1778)
							(mid 0.249642 -0.249642)
							(end 0.1778 -0.2794)
						)
					)
					(width 0)
					(fill yes)
				)
			)
		)
		(pad "2" smd custom
			(at 0 0.4445)
			(size 0.1397 0.1397)
			(layers "F.Cu" "F.Mask" "F.Paste")
			(net "I2C_DRIVE_A_PWR_SDA")
			(options
				(clearance outline)
				(anchor circle)
			)
			(primitives
				(gr_poly
					(pts
						(arc
							(start -0.1778 -0.2794)
							(mid -0.249642 -0.249642)
							(end -0.2794 -0.1778)
						)
						(arc
							(start -0.2794 0.1778)
							(mid -0.249642 0.249642)
							(end -0.1778 0.2794)
						)
						(arc
							(start 0.1778 0.2794)
							(mid 0.249642 0.249642)
							(end 0.2794 0.1778)
						)
						(arc
							(start 0.2794 -0.1778)
							(mid 0.249642 -0.249642)
							(end 0.1778 -0.2794)
						)
					)
					(width 0)
					(fill yes)
				)
			)
		)
	)
	(footprint ""
		(layer "F.Cu")
		(at 458.5589 -295.826942 180)
		(property "Reference" "C171"
			(at 0 0 180)
			(layer "F.SilkS")
			(hide yes)
			(effects
				(font
					(size 1.27 1.27)
				)
			)
		)
		(property "Value" "SC10U16V6KX-2GP"
			(at -0.0762 -5.1308 180)
			(unlocked yes)
			(layer "F.Fab")
			(hide yes)
			(effects
				(font
					(size 1.016 1.016)
					(thickness 0.1524)
				)
			)
		)
		(property "Device Type" "C1206H71"
			(at -0.127 -6.6548 180)
			(unlocked yes)
			(layer "F.Fab")
			(hide yes)
			(effects
				(font
					(size 1.016 1.016)
					(thickness 0.1524)
				)
			)
		)
		(duplicate_pad_numbers_are_jumpers no)
		(fp_line
			(start 1.016 2.2352)
			(end -1.016 2.2352)
			(stroke
				(width 0.1524)
				(type default)
			)
			(layer "F.SilkS")
		)
		(fp_line
			(start 1.016 0.8382)
			(end 1.016 2.2352)
			(stroke
				(width 0.1524)
				(type default)
			)
			(layer "F.SilkS")
		)
		(fp_line
			(start 1.016 -2.2352)
			(end 1.016 -0.8382)
			(stroke
				(width 0.1524)
				(type default)
			)
			(layer "F.SilkS")
		)
		(fp_line
			(start -1.016 2.2352)
			(end -1.016 0.8382)
			(stroke
				(width 0.1524)
				(type default)
			)
			(layer "F.SilkS")
		)
		(fp_line
			(start -1.016 -0.8382)
			(end -1.016 -2.2352)
			(stroke
				(width 0.1524)
				(type default)
			)
			(layer "F.SilkS")
		)
		(fp_line
			(start -1.016 -2.2352)
			(end 1.016 -2.2352)
			(stroke
				(width 0.1524)
				(type default)
			)
			(layer "F.SilkS")
		)
		(fp_rect
			(start -1.0922 2.3114)
			(end 1.0922 -2.3114)
			(stroke
				(width 0)
				(type default)
			)
			(fill no)
			(layer "F.CrtYd")
		)
		(fp_poly
			(pts
				(xy 1.0922 -2.3114) (xy 1.0922 2.3114) (xy -1.0922 2.3114) (xy -1.0922 -2.3114)
			)
			(stroke
				(width 0)
				(type default)
			)
			(fill no)
			(layer "F.Fab")
		)
		(pad "1" smd rect
			(at 0 -1.397 180)
			(size 1.651 1.27)
			(layers "F.Cu" "F.Mask" "F.Paste")
			(net "P5V_HDD10")
		)
		(pad "2" smd rect
			(at 0 1.397 180)
			(size 1.651 1.27)
			(layers "F.Cu" "F.Mask" "F.Paste")
			(net "GND")
		)
	)
	(footprint ""
		(layer "F.Cu")
		(at 185.950098 -57.909968 -90)
		(property "Reference" "HDDSAS29"
			(at 0 0 270)
			(layer "F.SilkS")
			(hide yes)
			(effects
				(font
					(size 1.27 1.27)
				)
			)
		)
		(property "Value" "SKT-SAS15P-14P-45-GP"
			(at -20.7645 -8.9789 270)
			(unlocked yes)
			(layer "F.Fab")
			(hide yes)
			(effects
				(font
					(size 1.016 1.016)
					(thickness 0.1524)
				)
			)
		)
		(property "Device Type" "10120818-001C-TRLF"
			(at -20.7645 -10.5029 270)
			(unlocked yes)
			(layer "F.Fab")
			(hide yes)
			(effects
				(font
					(size 1.016 1.016)
					(thickness 0.1524)
				)
			)
		)
		(duplicate_pad_numbers_are_jumpers no)
		(fp_line
			(start 1.651 4.2926)
			(end 1.651 3.0099)
			(stroke
				(width 0.1524)
				(type default)
			)
			(layer "F.SilkS")
		)
		(fp_line
			(start 8.509 4.2926)
			(end 1.651 4.2926)
			(stroke
				(width 0.1524)
				(type default)
			)
			(layer "F.SilkS")
		)
		(fp_line
			(start -23.4188 3.0099)
			(end -23.4188 -3.2512)
			(stroke
				(width 0.1524)
				(type default)
			)
			(layer "F.SilkS")
		)
		(fp_line
			(start 1.651 3.0099)
			(end -23.4188 3.0099)
			(stroke
				(width 0.1524)
				(type default)
			)
			(layer "F.SilkS")
		)
		(fp_line
			(start 8.509 3.0099)
			(end 8.509 4.2926)
			(stroke
				(width 0.1524)
				(type default)
			)
			(layer "F.SilkS")
		)
		(fp_line
			(start 23.4188 3.0099)
			(end 8.509 3.0099)
			(stroke
				(width 0.1524)
				(type default)
			)
			(layer "F.SilkS")
		)
		(fp_line
			(start -23.4188 -3.2512)
			(end 23.4188 -3.2512)
			(stroke
				(width 0.1524)
				(type default)
			)
			(layer "F.SilkS")
		)
		(fp_line
			(start 23.4188 -3.2512)
			(end 23.4188 3.0099)
			(stroke
				(width 0.1524)
				(type default)
			)
			(layer "F.SilkS")
		)
		(fp_line
			(start 15.5067 -3.3401)
			(end 16.2687 -3.3401)
			(stroke
				(width 0.3302)
				(type default)
			)
			(layer "F.SilkS")
		)
		(fp_poly
			(pts
				(xy 15.868904 -3.230372) (xy 16.503904 -3.865372) (xy 15.233904 -3.865372)
			)
			(stroke
				(width 0)
				(type default)
			)
			(fill yes)
			(layer "F.SilkS")
		)
		(fp_poly
			(pts
				(xy -22.8727 -2.7559) (xy 22.8727 -2.7559) (xy 22.8727 2.7559) (xy 8.255 2.7559) (xy 8.255 3.5179)
				(xy 1.905 3.5179) (xy 1.905 2.7559) (xy -22.8727 2.7559)
			)
			(stroke
				(width 0)
				(type default)
			)
			(fill no)
			(layer "F.CrtYd")
		)
		(fp_poly
			(pts
				(xy 1.397 4.5466) (xy 1.397 3.2639) (xy -23.6728 3.2639) (xy -23.6728 -3.5052) (xy 23.6728 -3.5052)
				(xy 23.6728 -0.00635) (xy 22.8727 -0.00635) (xy 22.8727 -2.7559) (xy -22.8727 -2.7559) (xy -22.8727 2.7559)
				(xy 1.905 2.7559) (xy 1.905 3.5179) (xy 8.255 3.5179) (xy 8.255 2.7559) (xy 22.8727 2.7559) (xy 22.8727 0.00635)
				(xy 23.6728 0.00635) (xy 23.6728 3.2639) (xy 8.763 3.2639) (xy 8.763 4.5466)
			)
			(stroke
				(width 0)
				(type default)
			)
			(fill no)
			(layer "F.CrtYd")
		)
		(fp_poly
			(pts
				(xy 1.397 4.5466) (xy 1.397 3.2639) (xy -23.6728 3.2639) (xy -23.6728 -3.5052) (xy 23.6728 -3.5052)
				(xy 23.6728 3.2639) (xy 8.763 3.2639) (xy 8.763 4.5466)
			)
			(stroke
				(width 0)
				(type default)
			)
			(fill no)
			(layer "F.Fab")
		)
		(pad "" np_thru_hole circle
			(at -18.874994 0 270)
			(size 0.254 0.254)
			(drill 1.3462)
			(layers "*.Cu" "*.Mask")
			(clearance 0.9017)
			(thermal_gap 0.9017)
		)
		(pad "" np_thru_hole circle
			(at 18.874994 0 270)
			(size 0.254 0.254)
			(drill 0.9398)
			(layers "*.Cu" "*.Mask")
			(clearance 0.6985)
			(thermal_gap 0.6985)
		)
		(pad "G1" smd rect
			(at 21.874988 0 270)
			(size 2.5908 2.5908)
			(layers "F.Cu" "F.Mask" "F.Paste")
			(net "GND")
		)
		(pad "G2" smd rect
			(at -21.874988 0 270)
			(size 2.5908 2.5908)
			(layers "F.Cu" "F.Mask" "F.Paste")
			(net "GND")
		)
		(pad "P1" smd rect
			(at 1.905 -1.82499 270)
			(size 0.6096 2.3622)
			(layers "F.Cu" "F.Mask" "F.Paste")
			(net "Net_2061")
		)
		(pad "P2" smd rect
			(at 0.635 -1.82499 270)
			(size 0.6096 2.3622)
			(layers "F.Cu" "F.Mask" "F.Paste")
			(net "Net_2062")
		)
		(pad "P3" smd rect
			(at -0.635 -1.82499 270)
			(size 0.6096 2.3622)
			(layers "F.Cu" "F.Mask" "F.Paste")
			(net "Net_2063")
		)
		(pad "P4" smd rect
			(at -1.905 -1.82499 270)
			(size 0.6096 2.3622)
			(layers "F.Cu" "F.Mask" "F.Paste")
			(net "GND")
		)
		(pad "P5" smd rect
			(at -3.175 -1.82499 270)
			(size 0.6096 2.3622)
			(layers "F.Cu" "F.Mask" "F.Paste")
			(net "HDD_PRSNT_29")
		)
		(pad "P6" smd rect
			(at -4.445 -1.82499 270)
			(size 0.6096 2.3622)
			(layers "F.Cu" "F.Mask" "F.Paste")
			(net "GND")
		)
		(pad "P7" smd rect
			(at -5.715 -1.82499 270)
			(size 0.6096 2.3622)
			(layers "F.Cu" "F.Mask" "F.Paste")
			(net "5V_PRE_29")
		)
		(pad "P8" smd rect
			(at -6.985 -1.82499 270)
			(size 0.6096 2.3622)
			(layers "F.Cu" "F.Mask" "F.Paste")
			(net "P5V_HDD29")
		)
		(pad "P9" smd rect
			(at -8.255 -1.82499 270)
			(size 0.6096 2.3622)
			(layers "F.Cu" "F.Mask" "F.Paste")
			(net "P5V_HDD29")
		)
		(pad "P10" smd rect
			(at -9.525 -1.82499 270)
			(size 0.6096 2.3622)
			(layers "F.Cu" "F.Mask" "F.Paste")
			(net "GND")
		)
		(pad "P11" smd rect
			(at -10.795 -1.82499 270)
			(size 0.6096 2.3622)
			(layers "F.Cu" "F.Mask" "F.Paste")
			(net "ACT_HDD_29")
		)
		(pad "P12" smd rect
			(at -12.065 -1.82499 270)
			(size 0.6096 2.3622)
			(layers "F.Cu" "F.Mask" "F.Paste")
			(net "GND")
		)
		(pad "P13" smd rect
			(at -13.335 -1.82499 270)
			(size 0.6096 2.3622)
			(layers "F.Cu" "F.Mask" "F.Paste")
			(net "12V_PRE_29")
		)
		(pad "P14" smd rect
			(at -14.605 -1.82499 270)
			(size 0.6096 2.3622)
			(layers "F.Cu" "F.Mask" "F.Paste")
			(net "P12V_HDD29")
		)
		(pad "P15" smd rect
			(at -15.875 -1.82499 270)
			(size 0.6096 2.3622)
			(layers "F.Cu" "F.Mask" "F.Paste")
			(net "P12V_HDD29")
		)
		(pad "S1" smd rect
			(at 15.875 -1.82499 270)
			(size 0.6096 2.3622)
			(layers "F.Cu" "F.Mask" "F.Paste")
			(net "GND")
		)
		(pad "S2" smd rect
			(at 14.605 -1.82499 270)
			(size 0.6096 2.3622)
			(layers "F.Cu" "F.Mask" "F.Paste")
			(net "SAS_HDD_RX_P29")
		)
		(pad "S3" smd rect
			(at 13.335 -1.82499 270)
			(size 0.6096 2.3622)
			(layers "F.Cu" "F.Mask" "F.Paste")
			(net "SAS_HDD_RX_N29")
		)
		(pad "S4" smd rect
			(at 12.065 -1.82499 270)
			(size 0.6096 2.3622)
			(layers "F.Cu" "F.Mask" "F.Paste")
			(net "GND")
		)
		(pad "S5" smd rect
			(at 10.795 -1.82499 270)
			(size 0.6096 2.3622)
			(layers "F.Cu" "F.Mask" "F.Paste")
			(net "PHY_DRV_A_TO_SCC_A_29_DN")
		)
		(pad "S6" smd rect
			(at 9.525 -1.82499 270)
			(size 0.6096 2.3622)
			(layers "F.Cu" "F.Mask" "F.Paste")
			(net "PHY_DRV_A_TO_SCC_A_29_DP")
		)
		(pad "S7" smd rect
			(at 8.255 -1.82499 270)
			(size 0.6096 2.3622)
			(layers "F.Cu" "F.Mask" "F.Paste")
			(net "GND")
		)
		(pad "S8" smd rect
			(at 7.480046 2.845054 270)
			(size 0.508 2.3622)
			(layers "F.Cu" "F.Mask" "F.Paste")
			(net "GND")
		)
		(pad "S9" smd rect
			(at 6.679946 2.845054 270)
			(size 0.508 2.3622)
			(layers "F.Cu" "F.Mask" "F.Paste")
			(net "Net_468")
		)
		(pad "S10" smd rect
			(at 5.8801 2.845054 270)
			(size 0.508 2.3622)
			(layers "F.Cu" "F.Mask" "F.Paste")
			(net "Net_360")
		)
		(pad "S11" smd rect
			(at 5.08 2.845054 270)
			(size 0.508 2.3622)
			(layers "F.Cu" "F.Mask" "F.Paste")
			(net "GND")
		)
		(pad "S12" smd rect
			(at 4.2799 2.845054 270)
			(size 0.508 2.3622)
			(layers "F.Cu" "F.Mask" "F.Paste")
			(net "Net_396")
		)
		(pad "S13" smd rect
			(at 3.480054 2.845054 270)
			(size 0.508 2.3622)
			(layers "F.Cu" "F.Mask" "F.Paste")
			(net "Net_432")
		)
		(pad "S14" smd rect
			(at 2.679954 2.845054 270)
			(size 0.508 2.3622)
			(layers "F.Cu" "F.Mask" "F.Paste")
			(net "GND")
		)
		(zone
			(layer "F.Cu")
			(hatch none 0.5)
			(connect_pads
				(clearance 0)
			)
			(min_thickness 0.25)
			(keepout
				(tracks not_allowed)
				(vias allowed)
				(pads allowed)
				(copperpour not_allowed)
				(footprints allowed)
			)
			(placement
				(enabled no)
				(sheetname "")
			)
			(fill
				(thermal_gap 0.5)
				(thermal_bridge_width 0.5)
				(island_removal_mode 0)
			)
			(polygon
				(pts
					(xy 189.607698 -74.648568) (xy 182.533798 -74.648568) (xy 182.533798 -81.582768) (xy 183.638698 -81.582768)
					(xy 183.638698 -77.467968) (xy 188.261498 -77.467968) (xy 188.261498 -81.582768) (xy 189.607698 -81.582768)
				)
			)
		)
		(zone
			(layer "F.Cu")
			(hatch none 0.5)
			(connect_pads
				(clearance 0)
			)
			(min_thickness 0.25)
			(keepout
				(tracks allowed)
				(vias not_allowed)
				(pads allowed)
				(copperpour not_allowed)
				(footprints allowed)
			)
			(placement
				(enabled no)
				(sheetname "")
			)
			(fill
				(thermal_gap 0.5)
				(thermal_bridge_width 0.5)
				(island_removal_mode 0)
			)
			(polygon
				(pts
					(xy 189.607698 -74.648568) (xy 182.533798 -74.648568) (xy 182.533798 -81.582768) (xy 183.638698 -81.582768)
					(xy 183.638698 -77.467968) (xy 188.261498 -77.467968) (xy 188.261498 -81.582768) (xy 189.607698 -81.582768)
				)
			)
		)
		(zone
			(layer "F.Cu")
			(hatch none 0.5)
			(connect_pads
				(clearance 0)
			)
			(min_thickness 0.25)
			(keepout
				(tracks allowed)
				(vias not_allowed)
				(pads allowed)
				(copperpour not_allowed)
				(footprints allowed)
			)
			(placement
				(enabled no)
				(sheetname "")
			)
			(fill
				(thermal_gap 0.5)
				(thermal_bridge_width 0.5)
				(island_removal_mode 0)
			)
			(polygon
				(pts
					(xy 189.607698 -41.171368) (xy 182.533798 -41.171368) (xy 182.533798 -34.237168) (xy 183.638698 -34.237168)
					(xy 183.638698 -38.351968) (xy 188.261498 -38.351968) (xy 188.261498 -34.237168) (xy 189.607698 -34.237168)
				)
			)
		)
		(zone
			(layer "F.Cu")
			(hatch none 0.5)
			(connect_pads
				(clearance 0)
			)
			(min_thickness 0.25)
			(keepout
				(tracks not_allowed)
				(vias allowed)
				(pads allowed)
				(copperpour not_allowed)
				(footprints allowed)
			)
			(placement
				(enabled no)
				(sheetname "")
			)
			(fill
				(thermal_gap 0.5)
				(thermal_bridge_width 0.5)
				(island_removal_mode 0)
			)
			(polygon
				(pts
					(xy 189.607698 -41.171368) (xy 182.533798 -41.171368) (xy 182.533798 -34.237168) (xy 183.638698 -34.237168)
					(xy 183.638698 -38.351968) (xy 188.261498 -38.351968) (xy 188.261498 -34.237168) (xy 189.607698 -34.237168)
				)
			)
		)
		(zone
			(layers "F.Cu" "B.Cu" "In1.Cu" "In2.Cu" "In3.Cu" "In4.Cu" "In5.Cu" "In6.Cu"
				"In7.Cu" "In8.Cu" "In9.Cu" "In10.Cu"
			)
			(hatch none 0.5)
			(connect_pads
				(clearance 0)
			)
			(min_thickness 0.25)
			(keepout
				(tracks not_allowed)
				(vias allowed)
				(pads allowed)
				(copperpour not_allowed)
				(footprints allowed)
			)
			(placement
				(enabled no)
				(sheetname "")
			)
			(fill
				(thermal_gap 0.5)
				(thermal_bridge_width 0.5)
				(island_removal_mode 0)
			)
			(polygon
				(pts
					(arc
						(start 186.724798 -39.034974)
						(mid 185.175398 -39.034974)
						(end 186.724798 -39.034974)
					)
				)
			)
		)
		(zone
			(layers "F.Cu" "B.Cu" "In1.Cu" "In2.Cu" "In3.Cu" "In4.Cu" "In5.Cu" "In6.Cu"
				"In7.Cu" "In8.Cu" "In9.Cu" "In10.Cu"
			)
			(hatch none 0.5)
			(connect_pads
				(clearance 0)
			)
			(min_thickness 0.25)
			(keepout
				(tracks not_allowed)
				(vias allowed)
				(pads allowed)
				(copperpour not_allowed)
				(footprints allowed)
			)
			(placement
				(enabled no)
				(sheetname "")
			)
			(fill
				(thermal_gap 0.5)
				(thermal_bridge_width 0.5)
				(island_removal_mode 0)
			)
			(polygon
				(pts
					(arc
						(start 186.927998 -76.784962)
						(mid 184.972198 -76.784962)
						(end 186.927998 -76.784962)
					)
				)
			)
		)
	)
	(footprint ""
		(layer "F.Cu")
		(at 267.0048 -144.3482 90)
		(property "Reference" "TP202"
			(at 0 0 90)
			(layer "F.SilkS")
			(hide yes)
			(effects
				(font
					(size 1.27 1.27)
				)
			)
		)
		(property "Value" "TPAD32-GP"
			(at -0.0508 -1.6764 90)
			(unlocked yes)
			(layer "F.Fab")
			(hide yes)
			(effects
				(font
					(size 1.016 1.016)
					(thickness 0.1524)
				)
			)
		)
		(property "Device Type" "TPAD32"
			(at -0.0508 -3.2004 90)
			(unlocked yes)
			(layer "F.Fab")
			(hide yes)
			(effects
				(font
					(size 1.016 1.016)
					(thickness 0.1524)
				)
			)
		)
		(duplicate_pad_numbers_are_jumpers no)
		(fp_poly
			(pts
				(arc
					(start 0 0.4064)
					(mid 0 -0.4064)
					(end 0 0.4064)
				)
			)
			(stroke
				(width 0)
				(type default)
			)
			(fill no)
			(layer "F.CrtYd")
		)
		(fp_poly
			(pts
				(arc
					(start 0 0.7112)
					(mid 0 -0.7112)
					(end 0 0.7112)
				)
			)
			(stroke
				(width 0)
				(type default)
			)
			(fill no)
			(layer "F.Fab")
		)
		(pad "1" smd circle
			(at 0 0 90)
			(size 0.8128 0.8128)
			(layers "F.Cu" "F.Mask" "F.Paste")
			(net "TP_SMB_COMP_B_NIC_SCL")
		)
	)
	(footprint ""
		(layer "F.Cu")
		(at 280.834338 -234.928918)
		(property "Reference" "TC14"
			(at 0 0 0)
			(layer "F.SilkS")
			(hide yes)
			(effects
				(font
					(size 1.27 1.27)
				)
			)
		)
		(property "Value" "SE270U16VM-8-GP"
			(at -4.5974 -2.54 0)
			(unlocked yes)
			(layer "F.Fab")
			(hide yes)
			(effects
				(font
					(size 1.016 1.016)
					(thickness 0.1524)
				)
			)
		)
		(property "Device Type" "SE361416H394"
			(at -4.5974 -4.064 0)
			(unlocked yes)
			(layer "F.Fab")
			(hide yes)
			(effects
				(font
					(size 1.016 1.016)
					(thickness 0.1524)
				)
			)
		)
		(duplicate_pad_numbers_are_jumpers no)
		(fp_line
			(start -3.556 -3.4163)
			(end -2.3622 -4.6101)
			(stroke
				(width 0.1524)
				(type default)
			)
			(layer "F.SilkS")
		)
		(fp_line
			(start -3.556 4.6101)
			(end -3.556 -3.4163)
			(stroke
				(width 0.1524)
				(type default)
			)
			(layer "F.SilkS")
		)
		(fp_line
			(start -2.3622 -4.6101)
			(end 2.3622 -4.6101)
			(stroke
				(width 0.1524)
				(type default)
			)
			(layer "F.SilkS")
		)
		(fp_line
			(start 2.3622 -4.6101)
			(end 3.556 -3.4163)
			(stroke
				(width 0.1524)
				(type default)
			)
			(layer "F.SilkS")
		)
		(fp_line
			(start 3.556 -3.4163)
			(end 3.556 4.6101)
			(stroke
				(width 0.1524)
				(type default)
			)
			(layer "F.SilkS")
		)
		(fp_line
			(start 3.556 4.6101)
			(end -3.556 4.6101)
			(stroke
				(width 0.1524)
				(type default)
			)
			(layer "F.SilkS")
		)
		(fp_rect
			(start -3.302 3.6449)
			(end 3.302 -3.6449)
			(stroke
				(width 0)
				(type default)
			)
			(fill no)
			(layer "F.CrtYd")
		)
		(fp_poly
			(pts
				(xy 3.81 4.6863) (xy 3.81 -3.4925) (xy 3.302 -3.4925) (xy 3.302 3.6449) (xy -3.302 3.6449) (xy -3.302 -3.6449)
				(xy 3.302 -3.6449) (xy 3.302 -3.5052) (xy 3.81 -3.5052) (xy 3.81 -4.6863) (xy -3.81 -4.6863) (xy -3.81 4.6863)
			)
			(stroke
				(width 0)
				(type default)
			)
			(fill no)
			(layer "F.CrtYd")
		)
		(fp_rect
			(start -3.81 4.6863)
			(end 3.81 -4.6863)
			(stroke
				(width 0)
				(type default)
			)
			(fill no)
			(layer "F.Fab")
		)
		(pad "1" smd rect
			(at 0 -2.574036)
			(size 1.4224 3.556)
			(layers "F.Cu" "F.Mask" "F.Paste")
			(net "P12V_A")
		)
		(pad "2" smd rect
			(at 0 2.574036)
			(size 1.4224 3.556)
			(layers "F.Cu" "F.Mask" "F.Paste")
			(net "GND")
		)
	)
	(footprint ""
		(layer "F.Cu")
		(at 318.06515 -245.365016 -90)
		(property "Reference" "R478"
			(at 0 0 270)
			(layer "F.SilkS")
			(hide yes)
			(effects
				(font
					(size 1.27 1.27)
				)
			)
		)
		(property "Value" "4K7R2J-2-GP"
			(at 0.064008 -3.993896 270)
			(unlocked yes)
			(layer "F.Fab")
			(hide yes)
			(effects
				(font
					(size 1.016 1.016)
					(thickness 0.1524)
				)
			)
		)
		(property "Device Type" "R402H16"
			(at 0.064008 -5.517896 270)
			(unlocked yes)
			(layer "F.Fab")
			(hide yes)
			(effects
				(font
					(size 1.016 1.016)
					(thickness 0.1524)
				)
			)
		)
		(duplicate_pad_numbers_are_jumpers no)
		(fp_line
			(start -0.508 -0.9398)
			(end -0.508 0.9398)
			(stroke
				(width 0.1524)
				(type default)
			)
			(layer "F.SilkS")
		)
		(fp_line
			(start 0.508 -0.9398)
			(end -0.508 -0.9398)
			(stroke
				(width 0.1524)
				(type default)
			)
			(layer "F.SilkS")
		)
		(fp_rect
			(start -0.508 0.9398)
			(end 0.508 -0.9398)
			(stroke
				(width 0)
				(type default)
			)
			(fill no)
			(layer "F.CrtYd")
		)
		(fp_rect
			(start -0.508 0.9398)
			(end 0.508 -0.9398)
			(stroke
				(width 0)
				(type default)
			)
			(fill no)
			(layer "F.Fab")
		)
		(pad "1" smd custom
			(at 0 -0.4445 270)
			(size 0.1397 0.1397)
			(layers "F.Cu" "F.Mask" "F.Paste")
			(net "DRIVE_A_6_FLT_LED")
			(options
				(clearance outline)
				(anchor circle)
			)
			(primitives
				(gr_poly
					(pts
						(arc
							(start -0.1778 -0.2794)
							(mid -0.249642 -0.249642)
							(end -0.2794 -0.1778)
						)
						(arc
							(start -0.2794 0.1778)
							(mid -0.249642 0.249642)
							(end -0.1778 0.2794)
						)
						(arc
							(start 0.1778 0.2794)
							(mid 0.249642 0.249642)
							(end 0.2794 0.1778)
						)
						(arc
							(start 0.2794 -0.1778)
							(mid 0.249642 -0.249642)
							(end 0.1778 -0.2794)
						)
					)
					(width 0)
					(fill yes)
				)
			)
		)
		(pad "2" smd custom
			(at 0 0.4445 270)
			(size 0.1397 0.1397)
			(layers "F.Cu" "F.Mask" "F.Paste")
			(net "GND")
			(options
				(clearance outline)
				(anchor circle)
			)
			(primitives
				(gr_poly
					(pts
						(arc
							(start -0.1778 -0.2794)
							(mid -0.249642 -0.249642)
							(end -0.2794 -0.1778)
						)
						(arc
							(start -0.2794 0.1778)
							(mid -0.249642 0.249642)
							(end -0.1778 0.2794)
						)
						(arc
							(start 0.1778 0.2794)
							(mid 0.249642 0.249642)
							(end 0.2794 0.1778)
						)
						(arc
							(start 0.2794 -0.1778)
							(mid 0.249642 -0.249642)
							(end 0.1778 -0.2794)
						)
					)
					(width 0)
					(fill yes)
				)
			)
		)
	)
	(footprint ""
		(layer "F.Cu")
		(at 255.0922 -290.195)
		(property "Reference" "R2"
			(at 0 0 0)
			(layer "F.SilkS")
			(hide yes)
			(effects
				(font
					(size 1.27 1.27)
				)
			)
		)
		(property "Value" "4K7R2F-GP"
			(at 0.064008 -3.993896 0)
			(unlocked yes)
			(layer "F.Fab")
			(hide yes)
			(effects
				(font
					(size 1.016 1.016)
					(thickness 0.1524)
				)
			)
		)
		(property "Device Type" "R402H16"
			(at 0.064008 -5.517896 0)
			(unlocked yes)
			(layer "F.Fab")
			(hide yes)
			(effects
				(font
					(size 1.016 1.016)
					(thickness 0.1524)
				)
			)
		)
		(duplicate_pad_numbers_are_jumpers no)
		(fp_line
			(start -0.508 -0.9398)
			(end -0.508 0.9398)
			(stroke
				(width 0.1524)
				(type default)
			)
			(layer "F.SilkS")
		)
		(fp_line
			(start 0.508 -0.9398)
			(end -0.508 -0.9398)
			(stroke
				(width 0.1524)
				(type default)
			)
			(layer "F.SilkS")
		)
		(fp_rect
			(start -0.508 0.9398)
			(end 0.508 -0.9398)
			(stroke
				(width 0)
				(type default)
			)
			(fill no)
			(layer "F.CrtYd")
		)
		(fp_rect
			(start -0.508 0.9398)
			(end 0.508 -0.9398)
			(stroke
				(width 0)
				(type default)
			)
			(fill no)
			(layer "F.Fab")
		)
		(pad "1" smd custom
			(at 0 -0.4445)
			(size 0.1397 0.1397)
			(layers "F.Cu" "F.Mask" "F.Paste")
			(net "EEPROM_A1")
			(options
				(clearance outline)
				(anchor circle)
			)
			(primitives
				(gr_poly
					(pts
						(arc
							(start -0.1778 -0.2794)
							(mid -0.249642 -0.249642)
							(end -0.2794 -0.1778)
						)
						(arc
							(start -0.2794 0.1778)
							(mid -0.249642 0.249642)
							(end -0.1778 0.2794)
						)
						(arc
							(start 0.1778 0.2794)
							(mid 0.249642 0.249642)
							(end 0.2794 0.1778)
						)
						(arc
							(start 0.2794 -0.1778)
							(mid 0.249642 -0.249642)
							(end 0.1778 -0.2794)
						)
					)
					(width 0)
					(fill yes)
				)
			)
		)
		(pad "2" smd custom
			(at 0 0.4445)
			(size 0.1397 0.1397)
			(layers "F.Cu" "F.Mask" "F.Paste")
			(net "GND")
			(options
				(clearance outline)
				(anchor circle)
			)
			(primitives
				(gr_poly
					(pts
						(arc
							(start -0.1778 -0.2794)
							(mid -0.249642 -0.249642)
							(end -0.2794 -0.1778)
						)
						(arc
							(start -0.2794 0.1778)
							(mid -0.249642 0.249642)
							(end -0.1778 0.2794)
						)
						(arc
							(start 0.1778 0.2794)
							(mid 0.249642 0.249642)
							(end 0.2794 0.1778)
						)
						(arc
							(start 0.2794 -0.1778)
							(mid 0.249642 -0.249642)
							(end 0.1778 -0.2794)
						)
					)
					(width 0)
					(fill yes)
				)
			)
		)
	)
	(footprint ""
		(layer "F.Cu")
		(at 371.62359 -128.24079 180)
		(property "Reference" "R534"
			(at 0 0 180)
			(layer "F.SilkS")
			(hide yes)
			(effects
				(font
					(size 1.27 1.27)
				)
			)
		)
		(property "Value" "4K7R2J-2-GP"
			(at 0.064008 -3.993896 180)
			(unlocked yes)
			(layer "F.Fab")
			(hide yes)
			(effects
				(font
					(size 1.016 1.016)
					(thickness 0.1524)
				)
			)
		)
		(property "Device Type" "R402H16"
			(at 0.064008 -5.517896 180)
			(unlocked yes)
			(layer "F.Fab")
			(hide yes)
			(effects
				(font
					(size 1.016 1.016)
					(thickness 0.1524)
				)
			)
		)
		(duplicate_pad_numbers_are_jumpers no)
		(fp_line
			(start 0.508 -0.9398)
			(end -0.508 -0.9398)
			(stroke
				(width 0.1524)
				(type default)
			)
			(layer "F.SilkS")
		)
		(fp_line
			(start -0.508 -0.9398)
			(end -0.508 0.9398)
			(stroke
				(width 0.1524)
				(type default)
			)
			(layer "F.SilkS")
		)
		(fp_rect
			(start -0.508 0.9398)
			(end 0.508 -0.9398)
			(stroke
				(width 0)
				(type default)
			)
			(fill no)
			(layer "F.CrtYd")
		)
		(fp_rect
			(start -0.508 0.9398)
			(end 0.508 -0.9398)
			(stroke
				(width 0)
				(type default)
			)
			(fill no)
			(layer "F.Fab")
		)
		(pad "1" smd custom
			(at 0 -0.4445 180)
			(size 0.1397 0.1397)
			(layers "F.Cu" "F.Mask" "F.Paste")
			(net "DRIVE_A_20_ACT")
			(options
				(clearance outline)
				(anchor circle)
			)
			(primitives
				(gr_poly
					(pts
						(arc
							(start -0.1778 -0.2794)
							(mid -0.249642 -0.249642)
							(end -0.2794 -0.1778)
						)
						(arc
							(start -0.2794 0.1778)
							(mid -0.249642 0.249642)
							(end -0.1778 0.2794)
						)
						(arc
							(start 0.1778 0.2794)
							(mid 0.249642 0.249642)
							(end 0.2794 0.1778)
						)
						(arc
							(start 0.2794 -0.1778)
							(mid 0.249642 -0.249642)
							(end 0.1778 -0.2794)
						)
					)
					(width 0)
					(fill yes)
				)
			)
		)
		(pad "2" smd custom
			(at 0 0.4445 180)
			(size 0.1397 0.1397)
			(layers "F.Cu" "F.Mask" "F.Paste")
			(net "GND")
			(options
				(clearance outline)
				(anchor circle)
			)
			(primitives
				(gr_poly
					(pts
						(arc
							(start -0.1778 -0.2794)
							(mid -0.249642 -0.249642)
							(end -0.2794 -0.1778)
						)
						(arc
							(start -0.2794 0.1778)
							(mid -0.249642 0.249642)
							(end -0.1778 0.2794)
						)
						(arc
							(start 0.1778 0.2794)
							(mid 0.249642 0.249642)
							(end 0.2794 0.1778)
						)
						(arc
							(start 0.2794 -0.1778)
							(mid 0.249642 -0.249642)
							(end 0.1778 -0.2794)
						)
					)
					(width 0)
					(fill yes)
				)
			)
		)
	)
	(footprint ""
		(layer "F.Cu")
		(at 115.080796 -177.778918 -90)
		(property "Reference" "C235"
			(at 0 0 270)
			(layer "F.SilkS")
			(hide yes)
			(effects
				(font
					(size 1.27 1.27)
				)
			)
		)
		(property "Value" "SC1U16V3KX-5GP"
			(at 0 -2.8194 270)
			(unlocked yes)
			(layer "F.Fab")
			(hide yes)
			(effects
				(font
					(size 1.016 1.016)
					(thickness 0.1524)
				)
			)
		)
		(property "Device Type" "C603H36"
			(at 0 -4.3434 270)
			(unlocked yes)
			(layer "F.Fab")
			(hide yes)
			(effects
				(font
					(size 1.016 1.016)
					(thickness 0.1524)
				)
			)
		)
		(duplicate_pad_numbers_are_jumpers no)
		(fp_line
			(start 0.508 0)
			(end -0.508 0)
			(stroke
				(width 0.2032)
				(type default)
			)
			(layer "F.SilkS")
		)
		(fp_rect
			(start -0.5842 1.3335)
			(end 0.5842 -1.3335)
			(stroke
				(width 0)
				(type default)
			)
			(fill no)
			(layer "F.CrtYd")
		)
		(fp_rect
			(start -0.5842 1.3335)
			(end 0.5842 -1.3335)
			(stroke
				(width 0)
				(type default)
			)
			(fill no)
			(layer "F.Fab")
		)
		(pad "1" smd custom
			(at 0 -0.762 270)
			(size 0.2159 0.2159)
			(layers "F.Cu" "F.Mask" "F.Paste")
			(net "P5V_HDD15")
			(options
				(clearance outline)
				(anchor circle)
			)
			(primitives
				(gr_poly
					(pts
						(arc
							(start -0.3302 -0.4318)
							(mid -0.402042 -0.402042)
							(end -0.4318 -0.3302)
						)
						(arc
							(start -0.4318 0.3302)
							(mid -0.402042 0.402042)
							(end -0.3302 0.4318)
						)
						(arc
							(start 0.3302 0.4318)
							(mid 0.402042 0.402042)
							(end 0.4318 0.3302)
						)
						(arc
							(start 0.4318 -0.3302)
							(mid 0.402042 -0.402042)
							(end 0.3302 -0.4318)
						)
					)
					(width 0)
					(fill yes)
				)
			)
		)
		(pad "2" smd custom
			(at 0 0.762 270)
			(size 0.2159 0.2159)
			(layers "F.Cu" "F.Mask" "F.Paste")
			(net "GND")
			(options
				(clearance outline)
				(anchor circle)
			)
			(primitives
				(gr_poly
					(pts
						(arc
							(start -0.3302 -0.4318)
							(mid -0.402042 -0.402042)
							(end -0.4318 -0.3302)
						)
						(arc
							(start -0.4318 0.3302)
							(mid -0.402042 0.402042)
							(end -0.3302 0.4318)
						)
						(arc
							(start 0.3302 0.4318)
							(mid 0.402042 0.402042)
							(end 0.4318 0.3302)
						)
						(arc
							(start 0.4318 -0.3302)
							(mid 0.402042 -0.402042)
							(end 0.3302 -0.4318)
						)
					)
					(width 0)
					(fill yes)
				)
			)
		)
	)
	(footprint ""
		(layer "F.Cu")
		(at 324.739 -162.749992 -90)
		(property "Reference" "VIA28"
			(at 0 0 270)
			(layer "F.SilkS")
			(hide yes)
			(effects
				(font
					(size 1.27 1.27)
				)
			)
		)
		(property "Value" "100OHM-8L-1D6MM-L18L16-GP"
			(at -3.7211 -4.5085 270)
			(unlocked yes)
			(layer "F.Fab")
			(hide yes)
			(effects
				(font
					(size 1.016 1.016)
					(thickness 0.1524)
				)
			)
		)
		(property "Device Type" "VIA-PCIE-4P-394076"
			(at -3.7211 -6.0325 270)
			(unlocked yes)
			(layer "F.Fab")
			(hide yes)
			(effects
				(font
					(size 1.016 1.016)
					(thickness 0.1524)
				)
			)
		)
		(duplicate_pad_numbers_are_jumpers no)
		(fp_rect
			(start -1.9685 0.381)
			(end 1.9685 -0.381)
			(stroke
				(width 0)
				(type default)
			)
			(fill no)
			(layer "F.CrtYd")
		)
		(fp_rect
			(start -1.9685 0.381)
			(end 1.9685 -0.381)
			(stroke
				(width 0)
				(type default)
			)
			(fill no)
			(layer "F.Fab")
		)
		(pad "1" thru_hole circle
			(at -1.5875 0 270)
			(size 0.508 0.508)
			(drill 0.254)
			(layers "*.Cu" "*.Mask")
			(remove_unused_layers no)
			(net "GND")
			(clearance 0.127)
			(thermal_gap 0.127)
		)
		(pad "2" thru_hole circle
			(at -0.5715 0 270)
			(size 0.508 0.508)
			(drill 0.254)
			(layers "*.Cu" "*.Mask")
			(remove_unused_layers no)
			(net "PHY_DRV_A_TO_SCC_A_18_DP")
			(clearance 0.127)
			(thermal_gap 0.127)
		)
		(pad "3" thru_hole circle
			(at 0.5715 0 270)
			(size 0.508 0.508)
			(drill 0.254)
			(layers "*.Cu" "*.Mask")
			(remove_unused_layers no)
			(net "PHY_DRV_A_TO_SCC_A_18_DN")
			(clearance 0.127)
			(thermal_gap 0.127)
		)
		(pad "4" thru_hole circle
			(at 1.5875 0 270)
			(size 0.508 0.508)
			(drill 0.254)
			(layers "*.Cu" "*.Mask")
			(remove_unused_layers no)
			(net "GND")
			(clearance 0.127)
			(thermal_gap 0.127)
		)
	)
	(footprint ""
		(layer "F.Cu")
		(at 113.556796 -64.683894 90)
		(property "Reference" "R752"
			(at 0 0 90)
			(layer "F.SilkS")
			(hide yes)
			(effects
				(font
					(size 1.27 1.27)
				)
			)
		)
		(property "Value" "2R6F-GP"
			(at -0.0508 -4.8514 90)
			(unlocked yes)
			(layer "F.Fab")
			(hide yes)
			(effects
				(font
					(size 1.016 1.016)
					(thickness 0.1524)
				)
			)
		)
		(property "Device Type" "R1206H26"
			(at 0 -6.3754 90)
			(unlocked yes)
			(layer "F.Fab")
			(hide yes)
			(effects
				(font
					(size 1.016 1.016)
					(thickness 0.1524)
				)
			)
		)
		(duplicate_pad_numbers_are_jumpers no)
		(fp_line
			(start 1.016 -2.2352)
			(end 1.016 2.2352)
			(stroke
				(width 0.1524)
				(type default)
			)
			(layer "F.SilkS")
		)
		(fp_line
			(start -1.016 -2.2352)
			(end 1.016 -2.2352)
			(stroke
				(width 0.1524)
				(type default)
			)
			(layer "F.SilkS")
		)
		(fp_line
			(start 1.016 2.2352)
			(end -1.016 2.2352)
			(stroke
				(width 0.1524)
				(type default)
			)
			(layer "F.SilkS")
		)
		(fp_line
			(start -1.016 2.2352)
			(end -1.016 -2.2352)
			(stroke
				(width 0.1524)
				(type default)
			)
			(layer "F.SilkS")
		)
		(fp_rect
			(start -1.0922 2.3114)
			(end 1.0922 -2.3114)
			(stroke
				(width 0)
				(type default)
			)
			(fill no)
			(layer "F.CrtYd")
		)
		(fp_poly
			(pts
				(xy -1.0922 -2.3114) (xy 1.0922 -2.3114) (xy 1.0922 2.3114) (xy -1.0922 2.3114)
			)
			(stroke
				(width 0)
				(type default)
			)
			(fill no)
			(layer "F.Fab")
		)
		(pad "1" smd rect
			(at 0 -1.397 90)
			(size 1.651 1.27)
			(layers "F.Cu" "F.Mask" "F.Paste")
			(net "P12V_HDD27")
		)
		(pad "2" smd rect
			(at 0 1.397 90)
			(size 1.651 1.27)
			(layers "F.Cu" "F.Mask" "F.Paste")
			(net "12V_PRE_27")
		)
	)
	(footprint ""
		(layer "F.Cu")
		(at 264.301732 18.170144 -90)
		(property "Reference" "R136"
			(at 0 0 270)
			(layer "F.SilkS")
			(hide yes)
			(effects
				(font
					(size 1.27 1.27)
				)
			)
		)
		(property "Value" "4K7R2F-GP"
			(at 0.064008 -3.993896 270)
			(unlocked yes)
			(layer "F.Fab")
			(hide yes)
			(effects
				(font
					(size 1.016 1.016)
					(thickness 0.1524)
				)
			)
		)
		(property "Device Type" "R402H16"
			(at 0.064008 -5.517896 270)
			(unlocked yes)
			(layer "F.Fab")
			(hide yes)
			(effects
				(font
					(size 1.016 1.016)
					(thickness 0.1524)
				)
			)
		)
		(duplicate_pad_numbers_are_jumpers no)
		(fp_line
			(start -0.508 -0.9398)
			(end -0.508 0.9398)
			(stroke
				(width 0.1524)
				(type default)
			)
			(layer "F.SilkS")
		)
		(fp_line
			(start 0.508 -0.9398)
			(end -0.508 -0.9398)
			(stroke
				(width 0.1524)
				(type default)
			)
			(layer "F.SilkS")
		)
		(fp_rect
			(start -0.508 0.9398)
			(end 0.508 -0.9398)
			(stroke
				(width 0)
				(type default)
			)
			(fill no)
			(layer "F.CrtYd")
		)
		(fp_rect
			(start -0.508 0.9398)
			(end 0.508 -0.9398)
			(stroke
				(width 0)
				(type default)
			)
			(fill no)
			(layer "F.Fab")
		)
		(pad "1" smd custom
			(at 0 -0.4445 270)
			(size 0.1397 0.1397)
			(layers "F.Cu" "F.Mask" "F.Paste")
			(net "P5V_A_2")
			(options
				(clearance outline)
				(anchor circle)
			)
			(primitives
				(gr_poly
					(pts
						(arc
							(start -0.1778 -0.2794)
							(mid -0.249642 -0.249642)
							(end -0.2794 -0.1778)
						)
						(arc
							(start -0.2794 0.1778)
							(mid -0.249642 0.249642)
							(end -0.1778 0.2794)
						)
						(arc
							(start 0.1778 0.2794)
							(mid 0.249642 0.249642)
							(end 0.2794 0.1778)
						)
						(arc
							(start 0.2794 -0.1778)
							(mid 0.249642 -0.249642)
							(end 0.1778 -0.2794)
						)
					)
					(width 0)
					(fill yes)
				)
			)
		)
		(pad "2" smd custom
			(at 0 0.4445 270)
			(size 0.1397 0.1397)
			(layers "F.Cu" "F.Mask" "F.Paste")
			(net "USB_OCS_N1")
			(options
				(clearance outline)
				(anchor circle)
			)
			(primitives
				(gr_poly
					(pts
						(arc
							(start -0.1778 -0.2794)
							(mid -0.249642 -0.249642)
							(end -0.2794 -0.1778)
						)
						(arc
							(start -0.2794 0.1778)
							(mid -0.249642 0.249642)
							(end -0.1778 0.2794)
						)
						(arc
							(start 0.1778 0.2794)
							(mid 0.249642 0.249642)
							(end 0.2794 0.1778)
						)
						(arc
							(start 0.2794 -0.1778)
							(mid 0.249642 -0.249642)
							(end 0.1778 -0.2794)
						)
					)
					(width 0)
					(fill yes)
				)
			)
		)
	)
	(footprint ""
		(layer "F.Cu")
		(at 46.392846 -59.857894)
		(property "Reference" "Q152"
			(at 0 0 0)
			(layer "F.SilkS")
			(hide yes)
			(effects
				(font
					(size 1.27 1.27)
				)
			)
		)
		(property "Value" "AO4407AL-GP"
			(at -3.707384 -1.5367 0)
			(unlocked yes)
			(layer "F.Fab")
			(hide yes)
			(effects
				(font
					(size 1.016 1.016)
					(thickness 0.1524)
				)
			)
		)
		(property "Device Type" "SOIC8H69"
			(at -3.707384 -3.0607 0)
			(unlocked yes)
			(layer "F.Fab")
			(hide yes)
			(effects
				(font
					(size 1.016 1.016)
					(thickness 0.1524)
				)
			)
		)
		(duplicate_pad_numbers_are_jumpers no)
		(fp_line
			(start -2.7432 -1.4224)
			(end -2.7432 1.4224)
			(stroke
				(width 0.1524)
				(type default)
			)
			(layer "F.SilkS")
		)
		(fp_line
			(start -2.7432 1.4224)
			(end -2.6416 1.4224)
			(stroke
				(width 0.1524)
				(type default)
			)
			(layer "F.SilkS")
		)
		(fp_line
			(start -2.7432 1.4224)
			(end 2.1336 1.4224)
			(stroke
				(width 0.1524)
				(type default)
			)
			(layer "F.SilkS")
		)
		(fp_line
			(start -2.7178 -0.508)
			(end -2.1844 -0.0508)
			(stroke
				(width 0.1524)
				(type default)
			)
			(layer "F.SilkS")
		)
		(fp_line
			(start -2.6289 3.4417)
			(end -2.6289 1.4732)
			(stroke
				(width 0.381)
				(type default)
			)
			(layer "F.SilkS")
		)
		(fp_line
			(start -2.1844 -0.0508)
			(end -2.7178 0.508)
			(stroke
				(width 0.1524)
				(type default)
			)
			(layer "F.SilkS")
		)
		(fp_line
			(start 2.1336 -1.4224)
			(end -2.7432 -1.4224)
			(stroke
				(width 0.1524)
				(type default)
			)
			(layer "F.SilkS")
		)
		(fp_line
			(start 2.1336 1.4224)
			(end 2.1336 -1.4224)
			(stroke
				(width 0.1524)
				(type default)
			)
			(layer "F.SilkS")
		)
		(fp_poly
			(pts
				(xy -2.2098 -1.4224) (xy -2.2098 1.4224) (xy 2.2098 1.4224) (xy 2.2098 -1.4224)
			)
			(stroke
				(width 0)
				(type default)
			)
			(fill yes)
			(layer "F.SilkS")
		)
		(fp_rect
			(start -2.450084 2.999994)
			(end 2.450084 -2.999994)
			(stroke
				(width 0)
				(type default)
			)
			(fill no)
			(layer "F.CrtYd")
		)
		(fp_poly
			(pts
				(xy -2.8194 3.6322) (xy -2.8194 -3.6322) (xy 2.8194 -3.6322) (xy 2.8194 1.18364) (xy 2.450084 1.18364)
				(xy 2.450084 -2.999994) (xy -2.450084 -2.999994) (xy -2.450084 2.999994) (xy 2.450084 2.999994)
				(xy 2.450084 1.18618) (xy 2.8194 1.18618) (xy 2.8194 3.6322)
			)
			(stroke
				(width 0)
				(type default)
			)
			(fill no)
			(layer "F.CrtYd")
		)
		(fp_rect
			(start -2.8194 3.6322)
			(end 2.8194 -3.6322)
			(stroke
				(width 0)
				(type default)
			)
			(fill no)
			(layer "F.Fab")
		)
		(pad "1" smd rect
			(at -1.905 2.54)
			(size 0.635 1.651)
			(layers "F.Cu" "F.Mask" "F.Paste")
			(net "P12V_A")
		)
		(pad "2" smd rect
			(at -0.635 2.54)
			(size 0.635 1.651)
			(layers "F.Cu" "F.Mask" "F.Paste")
			(net "P12V_A")
		)
		(pad "3" smd rect
			(at 0.635 2.54)
			(size 0.635 1.651)
			(layers "F.Cu" "F.Mask" "F.Paste")
			(net "P12V_A")
		)
		(pad "4" smd rect
			(at 1.905 2.54)
			(size 0.635 1.651)
			(layers "F.Cu" "F.Mask" "F.Paste")
			(net "SW_HDD_N25")
		)
		(pad "5" smd rect
			(at 1.905 -2.54)
			(size 0.635 1.651)
			(layers "F.Cu" "F.Mask" "F.Paste")
			(net "P12V_HDD25")
		)
		(pad "6" smd rect
			(at 0.635 -2.54)
			(size 0.635 1.651)
			(layers "F.Cu" "F.Mask" "F.Paste")
			(net "P12V_HDD25")
		)
		(pad "7" smd rect
			(at -0.635 -2.54)
			(size 0.635 1.651)
			(layers "F.Cu" "F.Mask" "F.Paste")
			(net "P12V_HDD25")
		)
		(pad "8" smd rect
			(at -1.905 -2.54)
			(size 0.635 1.651)
			(layers "F.Cu" "F.Mask" "F.Paste")
			(net "P12V_HDD25")
		)
	)
	(footprint ""
		(layer "F.Cu")
		(at 264.693654 -223.251014)
		(property "Reference" "R601"
			(at 0 0 0)
			(layer "F.SilkS")
			(hide yes)
			(effects
				(font
					(size 1.27 1.27)
				)
			)
		)
		(property "Value" "2K2R2F-GP"
			(at 0.064008 -3.993896 0)
			(unlocked yes)
			(layer "F.Fab")
			(hide yes)
			(effects
				(font
					(size 1.016 1.016)
					(thickness 0.1524)
				)
			)
		)
		(property "Device Type" "R402H16"
			(at 0.064008 -5.517896 0)
			(unlocked yes)
			(layer "F.Fab")
			(hide yes)
			(effects
				(font
					(size 1.016 1.016)
					(thickness 0.1524)
				)
			)
		)
		(duplicate_pad_numbers_are_jumpers no)
		(fp_line
			(start -0.508 -0.9398)
			(end -0.508 0.9398)
			(stroke
				(width 0.1524)
				(type default)
			)
			(layer "F.SilkS")
		)
		(fp_line
			(start 0.508 -0.9398)
			(end -0.508 -0.9398)
			(stroke
				(width 0.1524)
				(type default)
			)
			(layer "F.SilkS")
		)
		(fp_rect
			(start -0.508 0.9398)
			(end 0.508 -0.9398)
			(stroke
				(width 0)
				(type default)
			)
			(fill no)
			(layer "F.CrtYd")
		)
		(fp_rect
			(start -0.508 0.9398)
			(end 0.508 -0.9398)
			(stroke
				(width 0)
				(type default)
			)
			(fill no)
			(layer "F.Fab")
		)
		(pad "1" smd custom
			(at 0 -0.4445)
			(size 0.1397 0.1397)
			(layers "F.Cu" "F.Mask" "F.Paste")
			(net "P3V3_STBY_A")
			(options
				(clearance outline)
				(anchor circle)
			)
			(primitives
				(gr_poly
					(pts
						(arc
							(start -0.1778 -0.2794)
							(mid -0.249642 -0.249642)
							(end -0.2794 -0.1778)
						)
						(arc
							(start -0.2794 0.1778)
							(mid -0.249642 0.249642)
							(end -0.1778 0.2794)
						)
						(arc
							(start 0.1778 0.2794)
							(mid 0.249642 0.249642)
							(end 0.2794 0.1778)
						)
						(arc
							(start 0.2794 -0.1778)
							(mid 0.249642 -0.249642)
							(end 0.1778 -0.2794)
						)
					)
					(width 0)
					(fill yes)
				)
			)
		)
		(pad "2" smd custom
			(at 0 0.4445)
			(size 0.1397 0.1397)
			(layers "F.Cu" "F.Mask" "F.Paste")
			(net "I2C_DPB_A_SDA")
			(options
				(clearance outline)
				(anchor circle)
			)
			(primitives
				(gr_poly
					(pts
						(arc
							(start -0.1778 -0.2794)
							(mid -0.249642 -0.249642)
							(end -0.2794 -0.1778)
						)
						(arc
							(start -0.2794 0.1778)
							(mid -0.249642 0.249642)
							(end -0.1778 0.2794)
						)
						(arc
							(start 0.1778 0.2794)
							(mid 0.249642 0.249642)
							(end 0.2794 0.1778)
						)
						(arc
							(start 0.2794 -0.1778)
							(mid 0.249642 -0.249642)
							(end 0.1778 -0.2794)
						)
					)
					(width 0)
					(fill yes)
				)
			)
		)
	)
	(footprint ""
		(layer "F.Cu")
		(at 237.987586 -346.78366 180)
		(property "Reference" "R165"
			(at 0 0 180)
			(layer "F.SilkS")
			(hide yes)
			(effects
				(font
					(size 1.27 1.27)
				)
			)
		)
		(property "Value" "16K2R2F-GP"
			(at 0.064008 -3.993896 180)
			(unlocked yes)
			(layer "F.Fab")
			(hide yes)
			(effects
				(font
					(size 1.016 1.016)
					(thickness 0.1524)
				)
			)
		)
		(property "Device Type" "R402H16"
			(at 0.064008 -5.517896 180)
			(unlocked yes)
			(layer "F.Fab")
			(hide yes)
			(effects
				(font
					(size 1.016 1.016)
					(thickness 0.1524)
				)
			)
		)
		(duplicate_pad_numbers_are_jumpers no)
		(fp_line
			(start 0.508 -0.9398)
			(end -0.508 -0.9398)
			(stroke
				(width 0.1524)
				(type default)
			)
			(layer "F.SilkS")
		)
		(fp_line
			(start -0.508 -0.9398)
			(end -0.508 0.9398)
			(stroke
				(width 0.1524)
				(type default)
			)
			(layer "F.SilkS")
		)
		(fp_rect
			(start -0.508 0.9398)
			(end 0.508 -0.9398)
			(stroke
				(width 0)
				(type default)
			)
			(fill no)
			(layer "F.CrtYd")
		)
		(fp_rect
			(start -0.508 0.9398)
			(end 0.508 -0.9398)
			(stroke
				(width 0)
				(type default)
			)
			(fill no)
			(layer "F.Fab")
		)
		(pad "1" smd custom
			(at 0 -0.4445 180)
			(size 0.1397 0.1397)
			(layers "F.Cu" "F.Mask" "F.Paste")
			(net "P5V_A_2")
			(options
				(clearance outline)
				(anchor circle)
			)
			(primitives
				(gr_poly
					(pts
						(arc
							(start -0.1778 -0.2794)
							(mid -0.249642 -0.249642)
							(end -0.2794 -0.1778)
						)
						(arc
							(start -0.2794 0.1778)
							(mid -0.249642 0.249642)
							(end -0.1778 0.2794)
						)
						(arc
							(start 0.1778 0.2794)
							(mid 0.249642 0.249642)
							(end 0.2794 0.1778)
						)
						(arc
							(start 0.2794 -0.1778)
							(mid 0.249642 -0.249642)
							(end 0.1778 -0.2794)
						)
					)
					(width 0)
					(fill yes)
				)
			)
		)
		(pad "2" smd custom
			(at 0 0.4445 180)
			(size 0.1397 0.1397)
			(layers "F.Cu" "F.Mask" "F.Paste")
			(net "P5V_A_2_SENSE")
			(options
				(clearance outline)
				(anchor circle)
			)
			(primitives
				(gr_poly
					(pts
						(arc
							(start -0.1778 -0.2794)
							(mid -0.249642 -0.249642)
							(end -0.2794 -0.1778)
						)
						(arc
							(start -0.2794 0.1778)
							(mid -0.249642 0.249642)
							(end -0.1778 0.2794)
						)
						(arc
							(start 0.1778 0.2794)
							(mid 0.249642 0.249642)
							(end 0.2794 0.1778)
						)
						(arc
							(start 0.2794 -0.1778)
							(mid 0.249642 -0.249642)
							(end 0.1778 -0.2794)
						)
					)
					(width 0)
					(fill yes)
				)
			)
		)
	)
	(footprint ""
		(layer "F.Cu")
		(at 277.9268 11.5824)
		(property "Reference" "R1296"
			(at 0 0 0)
			(layer "F.SilkS")
			(hide yes)
			(effects
				(font
					(size 1.27 1.27)
				)
			)
		)
		(property "Value" "3K3R3F-GP"
			(at -0.0254 -2.5146 0)
			(unlocked yes)
			(layer "F.Fab")
			(hide yes)
			(effects
				(font
					(size 1.016 1.016)
					(thickness 0.1524)
				)
			)
		)
		(property "Device Type" "R603H22"
			(at -0.0254 -4.0386 0)
			(unlocked yes)
			(layer "F.Fab")
			(hide yes)
			(effects
				(font
					(size 1.016 1.016)
					(thickness 0.1524)
				)
			)
		)
		(duplicate_pad_numbers_are_jumpers no)
		(fp_line
			(start -0.4826 0)
			(end -0.2032 0)
			(stroke
				(width 0.2032)
				(type default)
			)
			(layer "F.SilkS")
		)
		(fp_line
			(start 0.2032 0)
			(end 0.4826 0)
			(stroke
				(width 0.2032)
				(type default)
			)
			(layer "F.SilkS")
		)
		(fp_rect
			(start -0.5842 1.3335)
			(end 0.5842 -1.3335)
			(stroke
				(width 0)
				(type default)
			)
			(fill no)
			(layer "F.CrtYd")
		)
		(fp_rect
			(start -0.5842 1.3335)
			(end 0.5842 -1.3335)
			(stroke
				(width 0)
				(type default)
			)
			(fill no)
			(layer "F.Fab")
		)
		(pad "1" smd custom
			(at 0 -0.762)
			(size 0.2159 0.2159)
			(layers "F.Cu" "F.Mask" "F.Paste")
			(net "P12V_IN")
			(options
				(clearance outline)
				(anchor circle)
			)
			(primitives
				(gr_poly
					(pts
						(arc
							(start -0.3302 -0.4318)
							(mid -0.402042 -0.402042)
							(end -0.4318 -0.3302)
						)
						(arc
							(start -0.4318 0.3302)
							(mid -0.402042 0.402042)
							(end -0.3302 0.4318)
						)
						(arc
							(start 0.3302 0.4318)
							(mid 0.402042 0.402042)
							(end 0.4318 0.3302)
						)
						(arc
							(start 0.4318 -0.3302)
							(mid 0.402042 -0.402042)
							(end 0.3302 -0.4318)
						)
					)
					(width 0)
					(fill yes)
				)
			)
		)
		(pad "2" smd custom
			(at 0 0.762)
			(size 0.2159 0.2159)
			(layers "F.Cu" "F.Mask" "F.Paste")
			(net "VCCP")
			(options
				(clearance outline)
				(anchor circle)
			)
			(primitives
				(gr_poly
					(pts
						(arc
							(start -0.3302 -0.4318)
							(mid -0.402042 -0.402042)
							(end -0.4318 -0.3302)
						)
						(arc
							(start -0.4318 0.3302)
							(mid -0.402042 0.402042)
							(end -0.3302 0.4318)
						)
						(arc
							(start 0.3302 0.4318)
							(mid 0.402042 0.402042)
							(end 0.4318 0.3302)
						)
						(arc
							(start 0.4318 -0.3302)
							(mid 0.402042 -0.402042)
							(end 0.3302 -0.4318)
						)
					)
					(width 0)
					(fill yes)
				)
			)
		)
	)
	(footprint ""
		(layer "F.Cu")
		(at 259.20192 -230.251)
		(property "Reference" "R93"
			(at 0 0 0)
			(layer "F.SilkS")
			(hide yes)
			(effects
				(font
					(size 1.27 1.27)
				)
			)
		)
		(property "Value" "0R2J-2-GP"
			(at 0.064008 -3.993896 0)
			(unlocked yes)
			(layer "F.Fab")
			(hide yes)
			(effects
				(font
					(size 1.016 1.016)
					(thickness 0.1524)
				)
			)
		)
		(property "Device Type" "R402H16"
			(at 0.064008 -5.517896 0)
			(unlocked yes)
			(layer "F.Fab")
			(hide yes)
			(effects
				(font
					(size 1.016 1.016)
					(thickness 0.1524)
				)
			)
		)
		(duplicate_pad_numbers_are_jumpers no)
		(fp_line
			(start -0.508 -0.9398)
			(end -0.508 0.9398)
			(stroke
				(width 0.1524)
				(type default)
			)
			(layer "F.SilkS")
		)
		(fp_line
			(start 0.508 -0.9398)
			(end -0.508 -0.9398)
			(stroke
				(width 0.1524)
				(type default)
			)
			(layer "F.SilkS")
		)
		(fp_rect
			(start -0.508 0.9398)
			(end 0.508 -0.9398)
			(stroke
				(width 0)
				(type default)
			)
			(fill no)
			(layer "F.CrtYd")
		)
		(fp_rect
			(start -0.508 0.9398)
			(end 0.508 -0.9398)
			(stroke
				(width 0)
				(type default)
			)
			(fill no)
			(layer "F.Fab")
		)
		(pad "1" smd custom
			(at 0 -0.4445)
			(size 0.1397 0.1397)
			(layers "F.Cu" "F.Mask" "F.Paste")
			(net "IO_EXP3_SCL")
			(options
				(clearance outline)
				(anchor circle)
			)
			(primitives
				(gr_poly
					(pts
						(arc
							(start -0.1778 -0.2794)
							(mid -0.249642 -0.249642)
							(end -0.2794 -0.1778)
						)
						(arc
							(start -0.2794 0.1778)
							(mid -0.249642 0.249642)
							(end -0.1778 0.2794)
						)
						(arc
							(start 0.1778 0.2794)
							(mid 0.249642 0.249642)
							(end 0.2794 0.1778)
						)
						(arc
							(start 0.2794 -0.1778)
							(mid 0.249642 -0.249642)
							(end 0.1778 -0.2794)
						)
					)
					(width 0)
					(fill yes)
				)
			)
		)
		(pad "2" smd custom
			(at 0 0.4445)
			(size 0.1397 0.1397)
			(layers "F.Cu" "F.Mask" "F.Paste")
			(net "I2C_DRIVE_A_PWR_SCL")
			(options
				(clearance outline)
				(anchor circle)
			)
			(primitives
				(gr_poly
					(pts
						(arc
							(start -0.1778 -0.2794)
							(mid -0.249642 -0.249642)
							(end -0.2794 -0.1778)
						)
						(arc
							(start -0.2794 0.1778)
							(mid -0.249642 0.249642)
							(end -0.1778 0.2794)
						)
						(arc
							(start 0.1778 0.2794)
							(mid 0.249642 0.249642)
							(end 0.2794 0.1778)
						)
						(arc
							(start 0.2794 -0.1778)
							(mid 0.249642 -0.249642)
							(end 0.1778 -0.2794)
						)
					)
					(width 0)
					(fill yes)
				)
			)
		)
	)
	(footprint ""
		(layer "F.Cu")
		(at 365.0488 -133.6294 -90)
		(property "Reference" "R1090"
			(at 0 0 270)
			(layer "F.SilkS")
			(hide yes)
			(effects
				(font
					(size 1.27 1.27)
				)
			)
		)
		(property "Value" "100KR2F-L1-GP"
			(at 0.064008 -3.993896 270)
			(unlocked yes)
			(layer "F.Fab")
			(hide yes)
			(effects
				(font
					(size 1.016 1.016)
					(thickness 0.1524)
				)
			)
		)
		(property "Device Type" "R402H16"
			(at 0.064008 -5.517896 270)
			(unlocked yes)
			(layer "F.Fab")
			(hide yes)
			(effects
				(font
					(size 1.016 1.016)
					(thickness 0.1524)
				)
			)
		)
		(duplicate_pad_numbers_are_jumpers no)
		(fp_line
			(start -0.508 -0.9398)
			(end -0.508 0.9398)
			(stroke
				(width 0.1524)
				(type default)
			)
			(layer "F.SilkS")
		)
		(fp_line
			(start 0.508 -0.9398)
			(end -0.508 -0.9398)
			(stroke
				(width 0.1524)
				(type default)
			)
			(layer "F.SilkS")
		)
		(fp_rect
			(start -0.508 0.9398)
			(end 0.508 -0.9398)
			(stroke
				(width 0)
				(type default)
			)
			(fill no)
			(layer "F.CrtYd")
		)
		(fp_rect
			(start -0.508 0.9398)
			(end 0.508 -0.9398)
			(stroke
				(width 0)
				(type default)
			)
			(fill no)
			(layer "F.Fab")
		)
		(pad "1" smd custom
			(at 0 -0.4445 270)
			(size 0.1397 0.1397)
			(layers "F.Cu" "F.Mask" "F.Paste")
			(net "MB1_VCAP_R")
			(options
				(clearance outline)
				(anchor circle)
			)
			(primitives
				(gr_poly
					(pts
						(arc
							(start -0.1778 -0.2794)
							(mid -0.249642 -0.249642)
							(end -0.2794 -0.1778)
						)
						(arc
							(start -0.2794 0.1778)
							(mid -0.249642 0.249642)
							(end -0.1778 0.2794)
						)
						(arc
							(start 0.1778 0.2794)
							(mid 0.249642 0.249642)
							(end 0.2794 0.1778)
						)
						(arc
							(start 0.2794 -0.1778)
							(mid 0.249642 -0.249642)
							(end 0.1778 -0.2794)
						)
					)
					(width 0)
					(fill yes)
				)
			)
		)
		(pad "2" smd custom
			(at 0 0.4445 270)
			(size 0.1397 0.1397)
			(layers "F.Cu" "F.Mask" "F.Paste")
			(net "MB1_PSET_R")
			(options
				(clearance outline)
				(anchor circle)
			)
			(primitives
				(gr_poly
					(pts
						(arc
							(start -0.1778 -0.2794)
							(mid -0.249642 -0.249642)
							(end -0.2794 -0.1778)
						)
						(arc
							(start -0.2794 0.1778)
							(mid -0.249642 0.249642)
							(end -0.1778 0.2794)
						)
						(arc
							(start 0.1778 0.2794)
							(mid 0.249642 0.249642)
							(end 0.2794 0.1778)
						)
						(arc
							(start 0.2794 -0.1778)
							(mid 0.249642 -0.249642)
							(end 0.1778 -0.2794)
						)
					)
					(width 0)
					(fill yes)
				)
			)
		)
	)
	(footprint ""
		(layer "F.Cu")
		(at 303.090072 -14.774672 90)
		(property "Reference" "C523"
			(at 0 0 90)
			(layer "F.SilkS")
			(hide yes)
			(effects
				(font
					(size 1.27 1.27)
				)
			)
		)
		(property "Value" "SC2D2U25V5KX-2-GP"
			(at -0.0762 -6.1214 90)
			(unlocked yes)
			(layer "F.Fab")
			(hide yes)
			(effects
				(font
					(size 1.016 1.016)
					(thickness 0.1524)
				)
			)
		)
		(property "Device Type" "C805H54"
			(at -0.0762 -8.1534 90)
			(unlocked yes)
			(layer "F.Fab")
			(hide yes)
			(effects
				(font
					(size 1.016 1.016)
					(thickness 0.1524)
				)
			)
		)
		(duplicate_pad_numbers_are_jumpers no)
		(fp_line
			(start 0.635 0)
			(end -0.635 0)
			(stroke
				(width 0.508)
				(type default)
			)
			(layer "F.SilkS")
		)
		(fp_rect
			(start -0.9652 1.778)
			(end 0.9652 -1.778)
			(stroke
				(width 0)
				(type default)
			)
			(fill no)
			(layer "F.CrtYd")
		)
		(fp_poly
			(pts
				(xy -0.9652 -1.778) (xy 0.9652 -1.778) (xy 0.9652 1.778) (xy -0.9652 1.778)
			)
			(stroke
				(width 0)
				(type default)
			)
			(fill no)
			(layer "F.Fab")
		)
		(pad "1" smd rect
			(at 0 -0.9652 90)
			(size 1.397 1.143)
			(layers "F.Cu" "F.Mask" "F.Paste")
			(net "P12V_B_COMP")
		)
		(pad "2" smd rect
			(at 0 0.9652 90)
			(size 1.397 1.143)
			(layers "F.Cu" "F.Mask" "F.Paste")
			(net "GND")
		)
	)
	(footprint ""
		(layer "F.Cu")
		(at 479.340926 -189.462918 180)
		(property "Reference" "C346"
			(at 0 0 180)
			(layer "F.SilkS")
			(hide yes)
			(effects
				(font
					(size 1.27 1.27)
				)
			)
		)
		(property "Value" "SC1U25V3KX-GP"
			(at 0 -2.8194 180)
			(unlocked yes)
			(layer "F.Fab")
			(hide yes)
			(effects
				(font
					(size 1.016 1.016)
					(thickness 0.1524)
				)
			)
		)
		(property "Device Type" "C603H36"
			(at 0 -4.3434 180)
			(unlocked yes)
			(layer "F.Fab")
			(hide yes)
			(effects
				(font
					(size 1.016 1.016)
					(thickness 0.1524)
				)
			)
		)
		(duplicate_pad_numbers_are_jumpers no)
		(fp_line
			(start 0.508 0)
			(end -0.508 0)
			(stroke
				(width 0.2032)
				(type default)
			)
			(layer "F.SilkS")
		)
		(fp_rect
			(start -0.5842 1.3335)
			(end 0.5842 -1.3335)
			(stroke
				(width 0)
				(type default)
			)
			(fill no)
			(layer "F.CrtYd")
		)
		(fp_rect
			(start -0.5842 1.3335)
			(end 0.5842 -1.3335)
			(stroke
				(width 0)
				(type default)
			)
			(fill no)
			(layer "F.Fab")
		)
		(pad "1" smd custom
			(at 0 -0.762 180)
			(size 0.2159 0.2159)
			(layers "F.Cu" "F.Mask" "F.Paste")
			(net "P12V_HDD23")
			(options
				(clearance outline)
				(anchor circle)
			)
			(primitives
				(gr_poly
					(pts
						(arc
							(start -0.3302 -0.4318)
							(mid -0.402042 -0.402042)
							(end -0.4318 -0.3302)
						)
						(arc
							(start -0.4318 0.3302)
							(mid -0.402042 0.402042)
							(end -0.3302 0.4318)
						)
						(arc
							(start 0.3302 0.4318)
							(mid 0.402042 0.402042)
							(end 0.4318 0.3302)
						)
						(arc
							(start 0.4318 -0.3302)
							(mid 0.402042 -0.402042)
							(end 0.3302 -0.4318)
						)
					)
					(width 0)
					(fill yes)
				)
			)
		)
		(pad "2" smd custom
			(at 0 0.762 180)
			(size 0.2159 0.2159)
			(layers "F.Cu" "F.Mask" "F.Paste")
			(net "GND")
			(options
				(clearance outline)
				(anchor circle)
			)
			(primitives
				(gr_poly
					(pts
						(arc
							(start -0.3302 -0.4318)
							(mid -0.402042 -0.402042)
							(end -0.4318 -0.3302)
						)
						(arc
							(start -0.4318 0.3302)
							(mid -0.402042 0.402042)
							(end -0.3302 0.4318)
						)
						(arc
							(start 0.3302 0.4318)
							(mid 0.402042 0.402042)
							(end 0.4318 0.3302)
						)
						(arc
							(start 0.4318 -0.3302)
							(mid 0.402042 -0.402042)
							(end 0.3302 -0.4318)
						)
					)
					(width 0)
					(fill yes)
				)
			)
		)
	)
	(footprint ""
		(layer "F.Cu")
		(at 3.849878 -5.499862)
		(property "Reference" ""
			(at 0 0 0)
			(layer "F.SilkS")
			(hide yes)
			(effects
				(font
					(size 1.27 1.27)
				)
			)
		)
		(property "Value" "*"
			(at -4.729734 -0.095504 0)
			(unlocked yes)
			(layer "F.Fab")
			(hide yes)
			(effects
				(font
					(size 1.016 1.016)
					(thickness 0.1524)
				)
			)
		)
		(duplicate_pad_numbers_are_jumpers no)
		(fp_poly
			(pts
				(arc
					(start 4.064 0)
					(mid -4.064 0)
					(end 4.064 0)
				)
			)
			(stroke
				(width 0)
				(type default)
			)
			(fill no)
			(layer "B.CrtYd")
		)
		(fp_poly
			(pts
				(arc
					(start 4.064 0)
					(mid -4.064 0)
					(end 4.064 0)
				)
			)
			(stroke
				(width 0)
				(type default)
			)
			(fill no)
			(layer "F.CrtYd")
		)
		(fp_poly
			(pts
				(arc
					(start 4.064 0)
					(mid -4.064 0)
					(end 4.064 0)
				)
			)
			(stroke
				(width 0)
				(type default)
			)
			(fill no)
			(layer "B.Fab")
		)
		(fp_poly
			(pts
				(arc
					(start 4.064 0)
					(mid -4.064 0)
					(end 4.064 0)
				)
			)
			(stroke
				(width 0)
				(type default)
			)
			(fill no)
			(layer "F.Fab")
		)
		(pad "1" thru_hole circle
			(at 0 0)
			(size 7.5184 7.5184)
			(drill 4.2164)
			(layers "*.Cu" "*.Mask")
			(remove_unused_layers no)
			(net "Net_25")
			(clearance -1.143)
			(thermal_gap 0.3048)
			(padstack
				(mode front_inner_back)
				(layer "Inner"
					(shape circle)
					(size 4.6228 4.6228)
					(clearance 0.3048)
				)
				(layer "B.Cu"
					(shape circle)
					(size 7.5184 7.5184)
					(clearance -1.143)
				)
			)
		)
	)
	(footprint ""
		(layer "F.Cu")
		(at 178.435 -55.285894 180)
		(property "Reference" "Q174"
			(at 0 0 180)
			(layer "F.SilkS")
			(hide yes)
			(effects
				(font
					(size 1.27 1.27)
				)
			)
		)
		(property "Value" "AO4406AL-GP"
			(at -3.707384 -1.5367 180)
			(unlocked yes)
			(layer "F.Fab")
			(hide yes)
			(effects
				(font
					(size 1.016 1.016)
					(thickness 0.1524)
				)
			)
		)
		(property "Device Type" "SOIC8H69"
			(at -3.707384 -3.0607 180)
			(unlocked yes)
			(layer "F.Fab")
			(hide yes)
			(effects
				(font
					(size 1.016 1.016)
					(thickness 0.1524)
				)
			)
		)
		(duplicate_pad_numbers_are_jumpers no)
		(fp_line
			(start 2.1336 1.4224)
			(end 2.1336 -1.4224)
			(stroke
				(width 0.1524)
				(type default)
			)
			(layer "F.SilkS")
		)
		(fp_line
			(start 2.1336 -1.4224)
			(end -2.7432 -1.4224)
			(stroke
				(width 0.1524)
				(type default)
			)
			(layer "F.SilkS")
		)
		(fp_line
			(start -2.1844 -0.0508)
			(end -2.7178 0.508)
			(stroke
				(width 0.1524)
				(type default)
			)
			(layer "F.SilkS")
		)
		(fp_line
			(start -2.6289 3.4417)
			(end -2.6289 1.4732)
			(stroke
				(width 0.381)
				(type default)
			)
			(layer "F.SilkS")
		)
		(fp_line
			(start -2.7178 -0.508)
			(end -2.1844 -0.0508)
			(stroke
				(width 0.1524)
				(type default)
			)
			(layer "F.SilkS")
		)
		(fp_line
			(start -2.7432 1.4224)
			(end 2.1336 1.4224)
			(stroke
				(width 0.1524)
				(type default)
			)
			(layer "F.SilkS")
		)
		(fp_line
			(start -2.7432 1.4224)
			(end -2.6416 1.4224)
			(stroke
				(width 0.1524)
				(type default)
			)
			(layer "F.SilkS")
		)
		(fp_line
			(start -2.7432 -1.4224)
			(end -2.7432 1.4224)
			(stroke
				(width 0.1524)
				(type default)
			)
			(layer "F.SilkS")
		)
		(fp_poly
			(pts
				(xy -2.2098 -1.4224) (xy -2.2098 1.4224) (xy 2.2098 1.4224) (xy 2.2098 -1.4224)
			)
			(stroke
				(width 0)
				(type default)
			)
			(fill yes)
			(layer "F.SilkS")
		)
		(fp_rect
			(start -2.450084 2.999994)
			(end 2.450084 -2.999994)
			(stroke
				(width 0)
				(type default)
			)
			(fill no)
			(layer "F.CrtYd")
		)
		(fp_poly
			(pts
				(xy -2.8194 3.6322) (xy -2.8194 -3.6322) (xy 2.8194 -3.6322) (xy 2.8194 1.18364) (xy 2.450084 1.18364)
				(xy 2.450084 -2.999994) (xy -2.450084 -2.999994) (xy -2.450084 2.999994) (xy 2.450084 2.999994)
				(xy 2.450084 1.18618) (xy 2.8194 1.18618) (xy 2.8194 3.6322)
			)
			(stroke
				(width 0)
				(type default)
			)
			(fill no)
			(layer "F.CrtYd")
		)
		(fp_rect
			(start -2.8194 3.6322)
			(end 2.8194 -3.6322)
			(stroke
				(width 0)
				(type default)
			)
			(fill no)
			(layer "F.Fab")
		)
		(pad "1" smd rect
			(at -1.905 2.54 180)
			(size 0.635 1.651)
			(layers "F.Cu" "F.Mask" "F.Paste")
			(net "P5V_HDD29")
		)
		(pad "2" smd rect
			(at -0.635 2.54 180)
			(size 0.635 1.651)
			(layers "F.Cu" "F.Mask" "F.Paste")
			(net "P5V_HDD29")
		)
		(pad "3" smd rect
			(at 0.635 2.54 180)
			(size 0.635 1.651)
			(layers "F.Cu" "F.Mask" "F.Paste")
			(net "P5V_HDD29")
		)
		(pad "4" smd rect
			(at 1.905 2.54 180)
			(size 0.635 1.651)
			(layers "F.Cu" "F.Mask" "F.Paste")
			(net "SW_HDD_P29")
		)
		(pad "5" smd rect
			(at 1.905 -2.54 180)
			(size 0.635 1.651)
			(layers "F.Cu" "F.Mask" "F.Paste")
			(net "P5V_A_2")
		)
		(pad "6" smd rect
			(at 0.635 -2.54 180)
			(size 0.635 1.651)
			(layers "F.Cu" "F.Mask" "F.Paste")
			(net "P5V_A_2")
		)
		(pad "7" smd rect
			(at -0.635 -2.54 180)
			(size 0.635 1.651)
			(layers "F.Cu" "F.Mask" "F.Paste")
			(net "P5V_A_2")
		)
		(pad "8" smd rect
			(at -1.905 -2.54 180)
			(size 0.635 1.651)
			(layers "F.Cu" "F.Mask" "F.Paste")
			(net "P5V_A_2")
		)
	)
	(footprint ""
		(layer "F.Cu")
		(at 130.447796 -61.127894 90)
		(property "Reference" "C396"
			(at 0 0 90)
			(layer "F.SilkS")
			(hide yes)
			(effects
				(font
					(size 1.27 1.27)
				)
			)
		)
		(property "Value" "SCD01U50V2KX-1GP"
			(at 1.1811 -2.7051 90)
			(unlocked yes)
			(layer "F.Fab")
			(hide yes)
			(effects
				(font
					(size 1.016 1.016)
					(thickness 0.1524)
				)
			)
		)
		(property "Device Type" "C402H22"
			(at 1.1811 -4.2291 90)
			(unlocked yes)
			(layer "F.Fab")
			(hide yes)
			(effects
				(font
					(size 1.016 1.016)
					(thickness 0.1524)
				)
			)
		)
		(duplicate_pad_numbers_are_jumpers no)
		(fp_rect
			(start -0.4318 0.9525)
			(end 0.4318 -0.9525)
			(stroke
				(width 0)
				(type default)
			)
			(fill no)
			(layer "F.CrtYd")
		)
		(fp_rect
			(start -0.4318 0.9525)
			(end 0.4318 -0.9525)
			(stroke
				(width 0)
				(type default)
			)
			(fill no)
			(layer "F.Fab")
		)
		(pad "1" smd custom
			(at 0 -0.4445 90)
			(size 0.1524 0.1524)
			(layers "F.Cu" "F.Mask" "F.Paste")
			(net "HDD_PRSNT_27")
			(options
				(clearance outline)
				(anchor circle)
			)
			(primitives
				(gr_poly
					(pts
						(arc
							(start 0.3048 -0.2032)
							(mid 0.275042 -0.275042)
							(end 0.2032 -0.3048)
						)
						(arc
							(start -0.2032 -0.3048)
							(mid -0.275042 -0.275042)
							(end -0.3048 -0.2032)
						)
						(arc
							(start -0.3048 0.2032)
							(mid -0.275042 0.275042)
							(end -0.2032 0.3048)
						)
						(arc
							(start 0.2032 0.3048)
							(mid 0.275042 0.275042)
							(end 0.3048 0.2032)
						)
					)
					(width 0)
					(fill yes)
				)
			)
		)
		(pad "2" smd custom
			(at 0 0.4445 90)
			(size 0.1524 0.1524)
			(layers "F.Cu" "F.Mask" "F.Paste")
			(net "GND")
			(options
				(clearance outline)
				(anchor circle)
			)
			(primitives
				(gr_poly
					(pts
						(arc
							(start 0.3048 -0.2032)
							(mid 0.275042 -0.275042)
							(end 0.2032 -0.3048)
						)
						(arc
							(start -0.2032 -0.3048)
							(mid -0.275042 -0.275042)
							(end -0.3048 -0.2032)
						)
						(arc
							(start -0.3048 0.2032)
							(mid -0.275042 0.275042)
							(end -0.2032 0.3048)
						)
						(arc
							(start 0.2032 0.3048)
							(mid 0.275042 0.275042)
							(end 0.3048 0.2032)
						)
					)
					(width 0)
					(fill yes)
				)
			)
		)
	)
	(footprint ""
		(layer "F.Cu")
		(at 101.190044 -303.904396)
		(property "Reference" "Q254"
			(at 0 0 0)
			(layer "F.SilkS")
			(hide yes)
			(effects
				(font
					(size 1.27 1.27)
				)
			)
		)
		(property "Value" "2N7002K-2-GP"
			(at 0.127 -8.9662 0)
			(unlocked yes)
			(layer "F.Fab")
			(hide yes)
			(effects
				(font
					(size 1.016 1.016)
					(thickness 0.1524)
				)
			)
		)
		(property "Device Type" "SOT23DGS2D4H44"
			(at 0.127 -10.4902 0)
			(unlocked yes)
			(layer "F.Fab")
			(hide yes)
			(effects
				(font
					(size 1.016 1.016)
					(thickness 0.1524)
				)
			)
		)
		(duplicate_pad_numbers_are_jumpers no)
		(fp_line
			(start -1.651 -1.778)
			(end -1.651 1.778)
			(stroke
				(width 0.1524)
				(type default)
			)
			(layer "F.SilkS")
		)
		(fp_line
			(start -1.651 1.778)
			(end 1.651 1.778)
			(stroke
				(width 0.1524)
				(type default)
			)
			(layer "F.SilkS")
		)
		(fp_line
			(start 1.651 -1.778)
			(end -1.651 -1.778)
			(stroke
				(width 0.1524)
				(type default)
			)
			(layer "F.SilkS")
		)
		(fp_line
			(start 1.651 1.778)
			(end 1.651 -1.778)
			(stroke
				(width 0.1524)
				(type default)
			)
			(layer "F.SilkS")
		)
		(fp_poly
			(pts
				(xy -1.778 1.8796) (xy -1.778 -1.8796) (xy 1.778 -1.8796) (xy 1.778 1.8796)
			)
			(stroke
				(width 0)
				(type default)
			)
			(fill no)
			(layer "F.CrtYd")
		)
		(fp_poly
			(pts
				(xy -1.778 1.8796) (xy -1.778 -1.8796) (xy 1.778 -1.8796) (xy 1.778 1.8796)
			)
			(stroke
				(width 0)
				(type default)
			)
			(fill no)
			(layer "F.Fab")
		)
		(pad "D" smd custom
			(at 0 -0.9525)
			(size 0.1905 0.1905)
			(layers "F.Cu" "F.Mask" "F.Paste")
			(net "FLT_HDD27_N")
			(options
				(clearance outline)
				(anchor circle)
			)
			(primitives
				(gr_poly
					(pts
						(arc
							(start -0.1778 0.5715)
							(mid -0.321484 0.511984)
							(end -0.381 0.3683)
						)
						(arc
							(start -0.381 -0.3683)
							(mid -0.321484 -0.511984)
							(end -0.1778 -0.5715)
						)
						(arc
							(start 0.1778 -0.5715)
							(mid 0.321484 -0.511984)
							(end 0.381 -0.3683)
						)
						(arc
							(start 0.381 0.3683)
							(mid 0.321484 0.511984)
							(end 0.1778 0.5715)
						)
					)
					(width 0)
					(fill yes)
				)
			)
		)
		(pad "G" smd custom
			(at -0.98425 0.9525)
			(size 0.1905 0.1905)
			(layers "F.Cu" "F.Mask" "F.Paste")
			(net "DRIVE_B_27_FLT_LED")
			(options
				(clearance outline)
				(anchor circle)
			)
			(primitives
				(gr_poly
					(pts
						(arc
							(start -0.1778 0.5715)
							(mid -0.321484 0.511984)
							(end -0.381 0.3683)
						)
						(arc
							(start -0.381 -0.3683)
							(mid -0.321484 -0.511984)
							(end -0.1778 -0.5715)
						)
						(arc
							(start 0.1778 -0.5715)
							(mid 0.321484 -0.511984)
							(end 0.381 -0.3683)
						)
						(arc
							(start 0.381 0.3683)
							(mid 0.321484 0.511984)
							(end 0.1778 0.5715)
						)
					)
					(width 0)
					(fill yes)
				)
			)
		)
		(pad "S" smd custom
			(at 0.98425 0.9525)
			(size 0.1905 0.1905)
			(layers "F.Cu" "F.Mask" "F.Paste")
			(net "GND")
			(options
				(clearance outline)
				(anchor circle)
			)
			(primitives
				(gr_poly
					(pts
						(arc
							(start -0.1778 0.5715)
							(mid -0.321484 0.511984)
							(end -0.381 0.3683)
						)
						(arc
							(start -0.381 -0.3683)
							(mid -0.321484 -0.511984)
							(end -0.1778 -0.5715)
						)
						(arc
							(start 0.1778 -0.5715)
							(mid 0.321484 -0.511984)
							(end 0.381 -0.3683)
						)
						(arc
							(start 0.381 0.3683)
							(mid 0.321484 0.511984)
							(end 0.1778 0.5715)
						)
					)
					(width 0)
					(fill yes)
				)
			)
		)
	)
	(footprint ""
		(layer "F.Cu")
		(at 14.842998 -289.857942)
		(property "Reference" "Q218"
			(at 0 0 0)
			(layer "F.SilkS")
			(hide yes)
			(effects
				(font
					(size 1.27 1.27)
				)
			)
		)
		(property "Value" "AO4407AL-GP"
			(at -3.707384 -1.5367 0)
			(unlocked yes)
			(layer "F.Fab")
			(hide yes)
			(effects
				(font
					(size 1.016 1.016)
					(thickness 0.1524)
				)
			)
		)
		(property "Device Type" "SOIC8H69"
			(at -3.707384 -3.0607 0)
			(unlocked yes)
			(layer "F.Fab")
			(hide yes)
			(effects
				(font
					(size 1.016 1.016)
					(thickness 0.1524)
				)
			)
		)
		(duplicate_pad_numbers_are_jumpers no)
		(fp_line
			(start -2.7432 -1.4224)
			(end -2.7432 1.4224)
			(stroke
				(width 0.1524)
				(type default)
			)
			(layer "F.SilkS")
		)
		(fp_line
			(start -2.7432 1.4224)
			(end -2.6416 1.4224)
			(stroke
				(width 0.1524)
				(type default)
			)
			(layer "F.SilkS")
		)
		(fp_line
			(start -2.7432 1.4224)
			(end 2.1336 1.4224)
			(stroke
				(width 0.1524)
				(type default)
			)
			(layer "F.SilkS")
		)
		(fp_line
			(start -2.7178 -0.508)
			(end -2.1844 -0.0508)
			(stroke
				(width 0.1524)
				(type default)
			)
			(layer "F.SilkS")
		)
		(fp_line
			(start -2.6289 3.4417)
			(end -2.6289 1.4732)
			(stroke
				(width 0.381)
				(type default)
			)
			(layer "F.SilkS")
		)
		(fp_line
			(start -2.1844 -0.0508)
			(end -2.7178 0.508)
			(stroke
				(width 0.1524)
				(type default)
			)
			(layer "F.SilkS")
		)
		(fp_line
			(start 2.1336 -1.4224)
			(end -2.7432 -1.4224)
			(stroke
				(width 0.1524)
				(type default)
			)
			(layer "F.SilkS")
		)
		(fp_line
			(start 2.1336 1.4224)
			(end 2.1336 -1.4224)
			(stroke
				(width 0.1524)
				(type default)
			)
			(layer "F.SilkS")
		)
		(fp_poly
			(pts
				(xy -2.2098 -1.4224) (xy -2.2098 1.4224) (xy 2.2098 1.4224) (xy 2.2098 -1.4224)
			)
			(stroke
				(width 0)
				(type default)
			)
			(fill yes)
			(layer "F.SilkS")
		)
		(fp_rect
			(start -2.450084 2.999994)
			(end 2.450084 -2.999994)
			(stroke
				(width 0)
				(type default)
			)
			(fill no)
			(layer "F.CrtYd")
		)
		(fp_poly
			(pts
				(xy -2.8194 3.6322) (xy -2.8194 -3.6322) (xy 2.8194 -3.6322) (xy 2.8194 1.18364) (xy 2.450084 1.18364)
				(xy 2.450084 -2.999994) (xy -2.450084 -2.999994) (xy -2.450084 2.999994) (xy 2.450084 2.999994)
				(xy 2.450084 1.18618) (xy 2.8194 1.18618) (xy 2.8194 3.6322)
			)
			(stroke
				(width 0)
				(type default)
			)
			(fill no)
			(layer "F.CrtYd")
		)
		(fp_rect
			(start -2.8194 3.6322)
			(end 2.8194 -3.6322)
			(stroke
				(width 0)
				(type default)
			)
			(fill no)
			(layer "F.Fab")
		)
		(pad "1" smd rect
			(at -1.905 2.54)
			(size 0.635 1.651)
			(layers "F.Cu" "F.Mask" "F.Paste")
			(net "P12V_A")
		)
		(pad "2" smd rect
			(at -0.635 2.54)
			(size 0.635 1.651)
			(layers "F.Cu" "F.Mask" "F.Paste")
			(net "P12V_A")
		)
		(pad "3" smd rect
			(at 0.635 2.54)
			(size 0.635 1.651)
			(layers "F.Cu" "F.Mask" "F.Paste")
			(net "P12V_A")
		)
		(pad "4" smd rect
			(at 1.905 2.54)
			(size 0.635 1.651)
			(layers "F.Cu" "F.Mask" "F.Paste")
			(net "SW_HDD_N0")
		)
		(pad "5" smd rect
			(at 1.905 -2.54)
			(size 0.635 1.651)
			(layers "F.Cu" "F.Mask" "F.Paste")
			(net "P12V_HDD0")
		)
		(pad "6" smd rect
			(at 0.635 -2.54)
			(size 0.635 1.651)
			(layers "F.Cu" "F.Mask" "F.Paste")
			(net "P12V_HDD0")
		)
		(pad "7" smd rect
			(at -0.635 -2.54)
			(size 0.635 1.651)
			(layers "F.Cu" "F.Mask" "F.Paste")
			(net "P12V_HDD0")
		)
		(pad "8" smd rect
			(at -1.905 -2.54)
			(size 0.635 1.651)
			(layers "F.Cu" "F.Mask" "F.Paste")
			(net "P12V_HDD0")
		)
	)
	(footprint ""
		(layer "F.Cu")
		(at 367.338102 -272.585942 180)
		(property "Reference" "R302"
			(at 0 0 180)
			(layer "F.SilkS")
			(hide yes)
			(effects
				(font
					(size 1.27 1.27)
				)
			)
		)
		(property "Value" "0R2J-2-GP"
			(at 0.064008 -3.993896 180)
			(unlocked yes)
			(layer "F.Fab")
			(hide yes)
			(effects
				(font
					(size 1.016 1.016)
					(thickness 0.1524)
				)
			)
		)
		(property "Device Type" "R402H16"
			(at 0.064008 -5.517896 180)
			(unlocked yes)
			(layer "F.Fab")
			(hide yes)
			(effects
				(font
					(size 1.016 1.016)
					(thickness 0.1524)
				)
			)
		)
		(duplicate_pad_numbers_are_jumpers no)
		(fp_line
			(start 0.508 -0.9398)
			(end -0.508 -0.9398)
			(stroke
				(width 0.1524)
				(type default)
			)
			(layer "F.SilkS")
		)
		(fp_line
			(start -0.508 -0.9398)
			(end -0.508 0.9398)
			(stroke
				(width 0.1524)
				(type default)
			)
			(layer "F.SilkS")
		)
		(fp_rect
			(start -0.508 0.9398)
			(end 0.508 -0.9398)
			(stroke
				(width 0)
				(type default)
			)
			(fill no)
			(layer "F.CrtYd")
		)
		(fp_rect
			(start -0.508 0.9398)
			(end 0.508 -0.9398)
			(stroke
				(width 0)
				(type default)
			)
			(fill no)
			(layer "F.Fab")
		)
		(pad "1" smd custom
			(at 0 -0.4445 180)
			(size 0.1397 0.1397)
			(layers "F.Cu" "F.Mask" "F.Paste")
			(net "DRIVE_A_7_PWR")
			(options
				(clearance outline)
				(anchor circle)
			)
			(primitives
				(gr_poly
					(pts
						(arc
							(start -0.1778 -0.2794)
							(mid -0.249642 -0.249642)
							(end -0.2794 -0.1778)
						)
						(arc
							(start -0.2794 0.1778)
							(mid -0.249642 0.249642)
							(end -0.1778 0.2794)
						)
						(arc
							(start 0.1778 0.2794)
							(mid 0.249642 0.249642)
							(end 0.2794 0.1778)
						)
						(arc
							(start 0.2794 -0.1778)
							(mid 0.249642 -0.249642)
							(end 0.1778 -0.2794)
						)
					)
					(width 0)
					(fill yes)
				)
			)
		)
		(pad "2" smd custom
			(at 0 0.4445 180)
			(size 0.1397 0.1397)
			(layers "F.Cu" "F.Mask" "F.Paste")
			(net "SW_PWR_R_HDD7")
			(options
				(clearance outline)
				(anchor circle)
			)
			(primitives
				(gr_poly
					(pts
						(arc
							(start -0.1778 -0.2794)
							(mid -0.249642 -0.249642)
							(end -0.2794 -0.1778)
						)
						(arc
							(start -0.2794 0.1778)
							(mid -0.249642 0.249642)
							(end -0.1778 0.2794)
						)
						(arc
							(start 0.1778 0.2794)
							(mid 0.249642 0.249642)
							(end 0.2794 0.1778)
						)
						(arc
							(start 0.2794 -0.1778)
							(mid 0.249642 -0.249642)
							(end 0.1778 -0.2794)
						)
					)
					(width 0)
					(fill yes)
				)
			)
		)
	)
	(footprint ""
		(layer "F.Cu")
		(at 476.672148 -269.348204 180)
		(property "Reference" "R391"
			(at 0 0 180)
			(layer "F.SilkS")
			(hide yes)
			(effects
				(font
					(size 1.27 1.27)
				)
			)
		)
		(property "Value" "1KR2F-3-GP"
			(at 0.064008 -3.993896 180)
			(unlocked yes)
			(layer "F.Fab")
			(hide yes)
			(effects
				(font
					(size 1.016 1.016)
					(thickness 0.1524)
				)
			)
		)
		(property "Device Type" "R402H16"
			(at 0.064008 -5.517896 180)
			(unlocked yes)
			(layer "F.Fab")
			(hide yes)
			(effects
				(font
					(size 1.016 1.016)
					(thickness 0.1524)
				)
			)
		)
		(duplicate_pad_numbers_are_jumpers no)
		(fp_line
			(start 0.508 -0.9398)
			(end -0.508 -0.9398)
			(stroke
				(width 0.1524)
				(type default)
			)
			(layer "F.SilkS")
		)
		(fp_line
			(start -0.508 -0.9398)
			(end -0.508 0.9398)
			(stroke
				(width 0.1524)
				(type default)
			)
			(layer "F.SilkS")
		)
		(fp_rect
			(start -0.508 0.9398)
			(end 0.508 -0.9398)
			(stroke
				(width 0)
				(type default)
			)
			(fill no)
			(layer "F.CrtYd")
		)
		(fp_rect
			(start -0.508 0.9398)
			(end 0.508 -0.9398)
			(stroke
				(width 0)
				(type default)
			)
			(fill no)
			(layer "F.Fab")
		)
		(pad "1" smd custom
			(at 0 -0.4445 180)
			(size 0.1397 0.1397)
			(layers "F.Cu" "F.Mask" "F.Paste")
			(net "P3V3_STBY_A")
			(options
				(clearance outline)
				(anchor circle)
			)
			(primitives
				(gr_poly
					(pts
						(arc
							(start -0.1778 -0.2794)
							(mid -0.249642 -0.249642)
							(end -0.2794 -0.1778)
						)
						(arc
							(start -0.2794 0.1778)
							(mid -0.249642 0.249642)
							(end -0.1778 0.2794)
						)
						(arc
							(start 0.1778 0.2794)
							(mid 0.249642 0.249642)
							(end 0.2794 0.1778)
						)
						(arc
							(start 0.2794 -0.1778)
							(mid 0.249642 -0.249642)
							(end 0.1778 -0.2794)
						)
					)
					(width 0)
					(fill yes)
				)
			)
		)
		(pad "2" smd custom
			(at 0 0.4445 180)
			(size 0.1397 0.1397)
			(layers "F.Cu" "F.Mask" "F.Paste")
			(net "SW_PWR_R_HDD11")
			(options
				(clearance outline)
				(anchor circle)
			)
			(primitives
				(gr_poly
					(pts
						(arc
							(start -0.1778 -0.2794)
							(mid -0.249642 -0.249642)
							(end -0.2794 -0.1778)
						)
						(arc
							(start -0.2794 0.1778)
							(mid -0.249642 0.249642)
							(end -0.1778 0.2794)
						)
						(arc
							(start 0.1778 0.2794)
							(mid 0.249642 0.249642)
							(end 0.2794 0.1778)
						)
						(arc
							(start 0.2794 -0.1778)
							(mid 0.249642 -0.249642)
							(end 0.1778 -0.2794)
						)
					)
					(width 0)
					(fill yes)
				)
			)
		)
	)
	(footprint ""
		(layer "F.Cu")
		(at 267.87475 11.5443 180)
		(property "Reference" "C49"
			(at 0 0 180)
			(layer "F.SilkS")
			(hide yes)
			(effects
				(font
					(size 1.27 1.27)
				)
			)
		)
		(property "Value" "SCD1U16V2KX-3GP"
			(at 1.1811 -2.7051 180)
			(unlocked yes)
			(layer "F.Fab")
			(hide yes)
			(effects
				(font
					(size 1.016 1.016)
					(thickness 0.1524)
				)
			)
		)
		(property "Device Type" "C402H22"
			(at 1.1811 -4.2291 180)
			(unlocked yes)
			(layer "F.Fab")
			(hide yes)
			(effects
				(font
					(size 1.016 1.016)
					(thickness 0.1524)
				)
			)
		)
		(duplicate_pad_numbers_are_jumpers no)
		(fp_rect
			(start -0.4318 0.9525)
			(end 0.4318 -0.9525)
			(stroke
				(width 0)
				(type default)
			)
			(fill no)
			(layer "F.CrtYd")
		)
		(fp_rect
			(start -0.4318 0.9525)
			(end 0.4318 -0.9525)
			(stroke
				(width 0)
				(type default)
			)
			(fill no)
			(layer "F.Fab")
		)
		(pad "1" smd custom
			(at 0 -0.4445 180)
			(size 0.1524 0.1524)
			(layers "F.Cu" "F.Mask" "F.Paste")
			(net "P5V_B")
			(options
				(clearance outline)
				(anchor circle)
			)
			(primitives
				(gr_poly
					(pts
						(arc
							(start 0.3048 -0.2032)
							(mid 0.275042 -0.275042)
							(end 0.2032 -0.3048)
						)
						(arc
							(start -0.2032 -0.3048)
							(mid -0.275042 -0.275042)
							(end -0.3048 -0.2032)
						)
						(arc
							(start -0.3048 0.2032)
							(mid -0.275042 0.275042)
							(end -0.2032 0.3048)
						)
						(arc
							(start 0.2032 0.3048)
							(mid 0.275042 0.275042)
							(end 0.3048 0.2032)
						)
					)
					(width 0)
					(fill yes)
				)
			)
		)
		(pad "2" smd custom
			(at 0 0.4445 180)
			(size 0.1524 0.1524)
			(layers "F.Cu" "F.Mask" "F.Paste")
			(net "GND")
			(options
				(clearance outline)
				(anchor circle)
			)
			(primitives
				(gr_poly
					(pts
						(arc
							(start 0.3048 -0.2032)
							(mid 0.275042 -0.275042)
							(end 0.2032 -0.3048)
						)
						(arc
							(start -0.2032 -0.3048)
							(mid -0.275042 -0.275042)
							(end -0.3048 -0.2032)
						)
						(arc
							(start -0.3048 0.2032)
							(mid -0.275042 0.275042)
							(end -0.2032 0.3048)
						)
						(arc
							(start 0.2032 0.3048)
							(mid 0.275042 0.275042)
							(end 0.3048 0.2032)
						)
					)
					(width 0)
					(fill yes)
				)
			)
		)
	)
	(footprint ""
		(layer "F.Cu")
		(at 272.542 -330.704952 180)
		(property "Reference" "VIA53"
			(at 0 0 180)
			(layer "F.SilkS")
			(hide yes)
			(effects
				(font
					(size 1.27 1.27)
				)
			)
		)
		(property "Value" "100OHM-8L-1D6MM-L18L16-GP"
			(at -3.7211 -4.5085 180)
			(unlocked yes)
			(layer "F.Fab")
			(hide yes)
			(effects
				(font
					(size 1.016 1.016)
					(thickness 0.1524)
				)
			)
		)
		(property "Device Type" "VIA-PCIE-4P-394076"
			(at -3.7211 -6.0325 180)
			(unlocked yes)
			(layer "F.Fab")
			(hide yes)
			(effects
				(font
					(size 1.016 1.016)
					(thickness 0.1524)
				)
			)
		)
		(duplicate_pad_numbers_are_jumpers no)
		(fp_rect
			(start -1.9685 0.381)
			(end 1.9685 -0.381)
			(stroke
				(width 0)
				(type default)
			)
			(fill no)
			(layer "F.CrtYd")
		)
		(fp_rect
			(start -1.9685 0.381)
			(end 1.9685 -0.381)
			(stroke
				(width 0)
				(type default)
			)
			(fill no)
			(layer "F.Fab")
		)
		(pad "1" thru_hole circle
			(at -1.5875 0 180)
			(size 0.508 0.508)
			(drill 0.254)
			(layers "*.Cu" "*.Mask")
			(remove_unused_layers no)
			(net "GND")
			(clearance 0.127)
			(thermal_gap 0.127)
		)
		(pad "2" thru_hole circle
			(at -0.5715 0 180)
			(size 0.508 0.508)
			(drill 0.254)
			(layers "*.Cu" "*.Mask")
			(remove_unused_layers no)
			(net "PHY_SCC_A_TO_DRV_A_16_DP")
			(clearance 0.127)
			(thermal_gap 0.127)
		)
		(pad "3" thru_hole circle
			(at 0.5715 0 180)
			(size 0.508 0.508)
			(drill 0.254)
			(layers "*.Cu" "*.Mask")
			(remove_unused_layers no)
			(net "PHY_SCC_A_TO_DRV_A_16_DN")
			(clearance 0.127)
			(thermal_gap 0.127)
		)
		(pad "4" thru_hole circle
			(at 1.5875 0 180)
			(size 0.508 0.508)
			(drill 0.254)
			(layers "*.Cu" "*.Mask")
			(remove_unused_layers no)
			(net "GND")
			(clearance 0.127)
			(thermal_gap 0.127)
		)
	)
	(footprint ""
		(layer "F.Cu")
		(at 169.200068 -27.487626)
		(property "Reference" "R389"
			(at 0 0 0)
			(layer "F.SilkS")
			(hide yes)
			(effects
				(font
					(size 1.27 1.27)
				)
			)
		)
		(property "Value" "10KR2F-2-GP"
			(at 0.064008 -3.993896 0)
			(unlocked yes)
			(layer "F.Fab")
			(hide yes)
			(effects
				(font
					(size 1.016 1.016)
					(thickness 0.1524)
				)
			)
		)
		(property "Device Type" "R402H16"
			(at 0.064008 -5.517896 0)
			(unlocked yes)
			(layer "F.Fab")
			(hide yes)
			(effects
				(font
					(size 1.016 1.016)
					(thickness 0.1524)
				)
			)
		)
		(duplicate_pad_numbers_are_jumpers no)
		(fp_line
			(start -0.508 -0.9398)
			(end -0.508 0.9398)
			(stroke
				(width 0.1524)
				(type default)
			)
			(layer "F.SilkS")
		)
		(fp_line
			(start 0.508 -0.9398)
			(end -0.508 -0.9398)
			(stroke
				(width 0.1524)
				(type default)
			)
			(layer "F.SilkS")
		)
		(fp_rect
			(start -0.508 0.9398)
			(end 0.508 -0.9398)
			(stroke
				(width 0)
				(type default)
			)
			(fill no)
			(layer "F.CrtYd")
		)
		(fp_rect
			(start -0.508 0.9398)
			(end 0.508 -0.9398)
			(stroke
				(width 0)
				(type default)
			)
			(fill no)
			(layer "F.Fab")
		)
		(pad "1" smd custom
			(at 0 -0.4445)
			(size 0.1397 0.1397)
			(layers "F.Cu" "F.Mask" "F.Paste")
			(net "SYS_A_RESET_N")
			(options
				(clearance outline)
				(anchor circle)
			)
			(primitives
				(gr_poly
					(pts
						(arc
							(start -0.1778 -0.2794)
							(mid -0.249642 -0.249642)
							(end -0.2794 -0.1778)
						)
						(arc
							(start -0.2794 0.1778)
							(mid -0.249642 0.249642)
							(end -0.1778 0.2794)
						)
						(arc
							(start 0.1778 0.2794)
							(mid 0.249642 0.249642)
							(end 0.2794 0.1778)
						)
						(arc
							(start 0.2794 -0.1778)
							(mid 0.249642 -0.249642)
							(end 0.1778 -0.2794)
						)
					)
					(width 0)
					(fill yes)
				)
			)
		)
		(pad "2" smd custom
			(at 0 0.4445)
			(size 0.1397 0.1397)
			(layers "F.Cu" "F.Mask" "F.Paste")
			(net "GND")
			(options
				(clearance outline)
				(anchor circle)
			)
			(primitives
				(gr_poly
					(pts
						(arc
							(start -0.1778 -0.2794)
							(mid -0.249642 -0.249642)
							(end -0.2794 -0.1778)
						)
						(arc
							(start -0.2794 0.1778)
							(mid -0.249642 0.249642)
							(end -0.1778 0.2794)
						)
						(arc
							(start 0.1778 0.2794)
							(mid 0.249642 0.249642)
							(end 0.2794 0.1778)
						)
						(arc
							(start 0.2794 -0.1778)
							(mid 0.249642 -0.249642)
							(end 0.1778 -0.2794)
						)
					)
					(width 0)
					(fill yes)
				)
			)
		)
	)
	(footprint ""
		(layer "F.Cu")
		(at 363.7788 -138.3284 90)
		(property "Reference" "C557"
			(at 0 0 90)
			(layer "F.SilkS")
			(hide yes)
			(effects
				(font
					(size 1.27 1.27)
				)
			)
		)
		(property "Value" "SC1U25V3KX-GP"
			(at 0 -2.8194 90)
			(unlocked yes)
			(layer "F.Fab")
			(hide yes)
			(effects
				(font
					(size 1.016 1.016)
					(thickness 0.1524)
				)
			)
		)
		(property "Device Type" "C603H36"
			(at 0 -4.3434 90)
			(unlocked yes)
			(layer "F.Fab")
			(hide yes)
			(effects
				(font
					(size 1.016 1.016)
					(thickness 0.1524)
				)
			)
		)
		(duplicate_pad_numbers_are_jumpers no)
		(fp_line
			(start 0.508 0)
			(end -0.508 0)
			(stroke
				(width 0.2032)
				(type default)
			)
			(layer "F.SilkS")
		)
		(fp_rect
			(start -0.5842 1.3335)
			(end 0.5842 -1.3335)
			(stroke
				(width 0)
				(type default)
			)
			(fill no)
			(layer "F.CrtYd")
		)
		(fp_rect
			(start -0.5842 1.3335)
			(end 0.5842 -1.3335)
			(stroke
				(width 0)
				(type default)
			)
			(fill no)
			(layer "F.Fab")
		)
		(pad "1" smd custom
			(at 0 -0.762 90)
			(size 0.2159 0.2159)
			(layers "F.Cu" "F.Mask" "F.Paste")
			(net "AGND_CURRENT_MONOB")
			(options
				(clearance outline)
				(anchor circle)
			)
			(primitives
				(gr_poly
					(pts
						(arc
							(start -0.3302 -0.4318)
							(mid -0.402042 -0.402042)
							(end -0.4318 -0.3302)
						)
						(arc
							(start -0.4318 0.3302)
							(mid -0.402042 0.402042)
							(end -0.3302 0.4318)
						)
						(arc
							(start 0.3302 0.4318)
							(mid 0.402042 0.402042)
							(end 0.4318 0.3302)
						)
						(arc
							(start 0.4318 -0.3302)
							(mid 0.402042 -0.402042)
							(end 0.3302 -0.4318)
						)
					)
					(width 0)
					(fill yes)
				)
			)
		)
		(pad "2" smd custom
			(at 0 0.762 90)
			(size 0.2159 0.2159)
			(layers "F.Cu" "F.Mask" "F.Paste")
			(net "MB1_P12V_HS")
			(options
				(clearance outline)
				(anchor circle)
			)
			(primitives
				(gr_poly
					(pts
						(arc
							(start -0.3302 -0.4318)
							(mid -0.402042 -0.402042)
							(end -0.4318 -0.3302)
						)
						(arc
							(start -0.4318 0.3302)
							(mid -0.402042 0.402042)
							(end -0.3302 0.4318)
						)
						(arc
							(start 0.3302 0.4318)
							(mid 0.402042 0.402042)
							(end 0.4318 0.3302)
						)
						(arc
							(start 0.4318 -0.3302)
							(mid 0.402042 -0.402042)
							(end 0.3302 -0.4318)
						)
					)
					(width 0)
					(fill yes)
				)
			)
		)
	)
	(footprint ""
		(layer "F.Cu")
		(at 394.56995 -291.127942 -90)
		(property "Reference" "R313"
			(at 0 0 270)
			(layer "F.SilkS")
			(hide yes)
			(effects
				(font
					(size 1.27 1.27)
				)
			)
		)
		(property "Value" "2R6F-GP"
			(at -0.0508 -4.8514 270)
			(unlocked yes)
			(layer "F.Fab")
			(hide yes)
			(effects
				(font
					(size 1.016 1.016)
					(thickness 0.1524)
				)
			)
		)
		(property "Device Type" "R1206H26"
			(at 0 -6.3754 270)
			(unlocked yes)
			(layer "F.Fab")
			(hide yes)
			(effects
				(font
					(size 1.016 1.016)
					(thickness 0.1524)
				)
			)
		)
		(duplicate_pad_numbers_are_jumpers no)
		(fp_line
			(start -1.016 2.2352)
			(end -1.016 -2.2352)
			(stroke
				(width 0.1524)
				(type default)
			)
			(layer "F.SilkS")
		)
		(fp_line
			(start 1.016 2.2352)
			(end -1.016 2.2352)
			(stroke
				(width 0.1524)
				(type default)
			)
			(layer "F.SilkS")
		)
		(fp_line
			(start -1.016 -2.2352)
			(end 1.016 -2.2352)
			(stroke
				(width 0.1524)
				(type default)
			)
			(layer "F.SilkS")
		)
		(fp_line
			(start 1.016 -2.2352)
			(end 1.016 2.2352)
			(stroke
				(width 0.1524)
				(type default)
			)
			(layer "F.SilkS")
		)
		(fp_rect
			(start -1.0922 2.3114)
			(end 1.0922 -2.3114)
			(stroke
				(width 0)
				(type default)
			)
			(fill no)
			(layer "F.CrtYd")
		)
		(fp_poly
			(pts
				(xy -1.0922 -2.3114) (xy 1.0922 -2.3114) (xy 1.0922 2.3114) (xy -1.0922 2.3114)
			)
			(stroke
				(width 0)
				(type default)
			)
			(fill no)
			(layer "F.Fab")
		)
		(pad "1" smd rect
			(at 0 -1.397 270)
			(size 1.651 1.27)
			(layers "F.Cu" "F.Mask" "F.Paste")
			(net "P5V_HDD8")
		)
		(pad "2" smd rect
			(at 0 1.397 270)
			(size 1.651 1.27)
			(layers "F.Cu" "F.Mask" "F.Paste")
			(net "5V_PRE_8")
		)
	)
	(footprint ""
		(layer "F.Cu")
		(at 127.113284 -158.660592 90)
		(property "Reference" "C234"
			(at 0 0 90)
			(layer "F.SilkS")
			(hide yes)
			(effects
				(font
					(size 1.27 1.27)
				)
			)
		)
		(property "Value" "SCD01U16V1KX-GP"
			(at -2.8321 -1.7399 90)
			(unlocked yes)
			(layer "F.Fab")
			(hide yes)
			(effects
				(font
					(size 1.016 1.016)
					(thickness 0.1524)
				)
			)
		)
		(property "Device Type" "C0201H13"
			(at -2.8321 -3.2639 90)
			(unlocked yes)
			(layer "F.Fab")
			(hide yes)
			(effects
				(font
					(size 1.016 1.016)
					(thickness 0.1524)
				)
			)
		)
		(duplicate_pad_numbers_are_jumpers no)
		(fp_rect
			(start -0.2794 0.6477)
			(end 0.2794 -0.6477)
			(stroke
				(width 0)
				(type default)
			)
			(fill no)
			(layer "F.CrtYd")
		)
		(fp_rect
			(start -0.2794 0.6477)
			(end 0.2794 -0.6477)
			(stroke
				(width 0)
				(type default)
			)
			(fill no)
			(layer "F.Fab")
		)
		(pad "1" smd custom
			(at 0 -0.2794 90)
			(size 0.0762 0.0762)
			(layers "F.Cu" "F.Mask" "F.Paste")
			(net "SAS_HDD_RX_P15")
			(options
				(clearance outline)
				(anchor circle)
			)
			(primitives
				(gr_poly
					(pts
						(arc
							(start 0.1524 -0.127)
							(mid 0.137521 -0.162921)
							(end 0.1016 -0.1778)
						)
						(arc
							(start -0.1016 -0.1778)
							(mid -0.137521 -0.162921)
							(end -0.1524 -0.127)
						)
						(arc
							(start -0.1524 0.127)
							(mid -0.137521 0.162921)
							(end -0.1016 0.1778)
						)
						(arc
							(start 0.1016 0.1778)
							(mid 0.137521 0.162921)
							(end 0.1524 0.127)
						)
					)
					(width 0)
					(fill yes)
				)
			)
		)
		(pad "2" smd custom
			(at 0 0.2794 90)
			(size 0.0762 0.0762)
			(layers "F.Cu" "F.Mask" "F.Paste")
			(net "PHY_SCC_A_TO_DRV_A_15_DP")
			(options
				(clearance outline)
				(anchor circle)
			)
			(primitives
				(gr_poly
					(pts
						(arc
							(start 0.1524 -0.127)
							(mid 0.137521 -0.162921)
							(end 0.1016 -0.1778)
						)
						(arc
							(start -0.1016 -0.1778)
							(mid -0.137521 -0.162921)
							(end -0.1524 -0.127)
						)
						(arc
							(start -0.1524 0.127)
							(mid -0.137521 0.162921)
							(end -0.1016 0.1778)
						)
						(arc
							(start 0.1016 0.1778)
							(mid 0.137521 0.162921)
							(end 0.1524 0.127)
						)
					)
					(width 0)
					(fill yes)
				)
			)
		)
	)
	(footprint ""
		(layer "F.Cu")
		(at 222.6056 -115.5446 -90)
		(property "Reference" "R181"
			(at 0 0 270)
			(layer "F.SilkS")
			(hide yes)
			(effects
				(font
					(size 1.27 1.27)
				)
			)
		)
		(property "Value" "0R2J-2-GP"
			(at 0.064008 -3.993896 270)
			(unlocked yes)
			(layer "F.Fab")
			(hide yes)
			(effects
				(font
					(size 1.016 1.016)
					(thickness 0.1524)
				)
			)
		)
		(property "Device Type" "R402H16"
			(at 0.064008 -5.517896 270)
			(unlocked yes)
			(layer "F.Fab")
			(hide yes)
			(effects
				(font
					(size 1.016 1.016)
					(thickness 0.1524)
				)
			)
		)
		(duplicate_pad_numbers_are_jumpers no)
		(fp_line
			(start -0.508 -0.9398)
			(end -0.508 0.9398)
			(stroke
				(width 0.1524)
				(type default)
			)
			(layer "F.SilkS")
		)
		(fp_line
			(start 0.508 -0.9398)
			(end -0.508 -0.9398)
			(stroke
				(width 0.1524)
				(type default)
			)
			(layer "F.SilkS")
		)
		(fp_rect
			(start -0.508 0.9398)
			(end 0.508 -0.9398)
			(stroke
				(width 0)
				(type default)
			)
			(fill no)
			(layer "F.CrtYd")
		)
		(fp_rect
			(start -0.508 0.9398)
			(end 0.508 -0.9398)
			(stroke
				(width 0)
				(type default)
			)
			(fill no)
			(layer "F.Fab")
		)
		(pad "1" smd custom
			(at 0 -0.4445 270)
			(size 0.1397 0.1397)
			(layers "F.Cu" "F.Mask" "F.Paste")
			(net "SLOT3_SVR_ID0_GPIO2")
			(options
				(clearance outline)
				(anchor circle)
			)
			(primitives
				(gr_poly
					(pts
						(arc
							(start -0.1778 -0.2794)
							(mid -0.249642 -0.249642)
							(end -0.2794 -0.1778)
						)
						(arc
							(start -0.2794 0.1778)
							(mid -0.249642 0.249642)
							(end -0.1778 0.2794)
						)
						(arc
							(start 0.1778 0.2794)
							(mid 0.249642 0.249642)
							(end 0.2794 0.1778)
						)
						(arc
							(start 0.2794 -0.1778)
							(mid 0.249642 -0.249642)
							(end 0.1778 -0.2794)
						)
					)
					(width 0)
					(fill yes)
				)
			)
		)
		(pad "2" smd custom
			(at 0 0.4445 270)
			(size 0.1397 0.1397)
			(layers "F.Cu" "F.Mask" "F.Paste")
			(net "COMP_A_EXP_A_SPARE_0")
			(options
				(clearance outline)
				(anchor circle)
			)
			(primitives
				(gr_poly
					(pts
						(arc
							(start -0.1778 -0.2794)
							(mid -0.249642 -0.249642)
							(end -0.2794 -0.1778)
						)
						(arc
							(start -0.2794 0.1778)
							(mid -0.249642 0.249642)
							(end -0.1778 0.2794)
						)
						(arc
							(start 0.1778 0.2794)
							(mid 0.249642 0.249642)
							(end 0.2794 0.1778)
						)
						(arc
							(start 0.2794 -0.1778)
							(mid 0.249642 -0.249642)
							(end 0.1778 -0.2794)
						)
					)
					(width 0)
					(fill yes)
				)
			)
		)
	)
	(footprint ""
		(layer "F.Cu")
		(at 111.473996 -52.085494 90)
		(property "Reference" "R758"
			(at 0 0 90)
			(layer "F.SilkS")
			(hide yes)
			(effects
				(font
					(size 1.27 1.27)
				)
			)
		)
		(property "Value" "4K7R2J-2-GP"
			(at 0.064008 -3.993896 90)
			(unlocked yes)
			(layer "F.Fab")
			(hide yes)
			(effects
				(font
					(size 1.016 1.016)
					(thickness 0.1524)
				)
			)
		)
		(property "Device Type" "R402H16"
			(at 0.064008 -5.517896 90)
			(unlocked yes)
			(layer "F.Fab")
			(hide yes)
			(effects
				(font
					(size 1.016 1.016)
					(thickness 0.1524)
				)
			)
		)
		(duplicate_pad_numbers_are_jumpers no)
		(fp_line
			(start 0.508 -0.9398)
			(end -0.508 -0.9398)
			(stroke
				(width 0.1524)
				(type default)
			)
			(layer "F.SilkS")
		)
		(fp_line
			(start -0.508 -0.9398)
			(end -0.508 0.9398)
			(stroke
				(width 0.1524)
				(type default)
			)
			(layer "F.SilkS")
		)
		(fp_rect
			(start -0.508 0.9398)
			(end 0.508 -0.9398)
			(stroke
				(width 0)
				(type default)
			)
			(fill no)
			(layer "F.CrtYd")
		)
		(fp_rect
			(start -0.508 0.9398)
			(end 0.508 -0.9398)
			(stroke
				(width 0)
				(type default)
			)
			(fill no)
			(layer "F.Fab")
		)
		(pad "1" smd custom
			(at 0 -0.4445 90)
			(size 0.1397 0.1397)
			(layers "F.Cu" "F.Mask" "F.Paste")
			(net "P12V_A")
			(options
				(clearance outline)
				(anchor circle)
			)
			(primitives
				(gr_poly
					(pts
						(arc
							(start -0.1778 -0.2794)
							(mid -0.249642 -0.249642)
							(end -0.2794 -0.1778)
						)
						(arc
							(start -0.2794 0.1778)
							(mid -0.249642 0.249642)
							(end -0.1778 0.2794)
						)
						(arc
							(start 0.1778 0.2794)
							(mid 0.249642 0.249642)
							(end 0.2794 0.1778)
						)
						(arc
							(start 0.2794 -0.1778)
							(mid 0.249642 -0.249642)
							(end 0.1778 -0.2794)
						)
					)
					(width 0)
					(fill yes)
				)
			)
		)
		(pad "2" smd custom
			(at 0 0.4445 90)
			(size 0.1397 0.1397)
			(layers "F.Cu" "F.Mask" "F.Paste")
			(net "SW_HDD_P27")
			(options
				(clearance outline)
				(anchor circle)
			)
			(primitives
				(gr_poly
					(pts
						(arc
							(start -0.1778 -0.2794)
							(mid -0.249642 -0.249642)
							(end -0.2794 -0.1778)
						)
						(arc
							(start -0.2794 0.1778)
							(mid -0.249642 0.249642)
							(end -0.1778 0.2794)
						)
						(arc
							(start 0.1778 0.2794)
							(mid 0.249642 0.249642)
							(end 0.2794 0.1778)
						)
						(arc
							(start 0.2794 -0.1778)
							(mid 0.249642 -0.249642)
							(end 0.1778 -0.2794)
						)
					)
					(width 0)
					(fill yes)
				)
			)
		)
	)
	(footprint ""
		(layer "F.Cu")
		(at 270.82115 11.6078)
		(property "Reference" "R138"
			(at 0 0 0)
			(layer "F.SilkS")
			(hide yes)
			(effects
				(font
					(size 1.27 1.27)
				)
			)
		)
		(property "Value" "4K7R2F-GP"
			(at 0.064008 -3.993896 0)
			(unlocked yes)
			(layer "F.Fab")
			(hide yes)
			(effects
				(font
					(size 1.016 1.016)
					(thickness 0.1524)
				)
			)
		)
		(property "Device Type" "R402H16"
			(at 0.064008 -5.517896 0)
			(unlocked yes)
			(layer "F.Fab")
			(hide yes)
			(effects
				(font
					(size 1.016 1.016)
					(thickness 0.1524)
				)
			)
		)
		(duplicate_pad_numbers_are_jumpers no)
		(fp_line
			(start -0.508 -0.9398)
			(end -0.508 0.9398)
			(stroke
				(width 0.1524)
				(type default)
			)
			(layer "F.SilkS")
		)
		(fp_line
			(start 0.508 -0.9398)
			(end -0.508 -0.9398)
			(stroke
				(width 0.1524)
				(type default)
			)
			(layer "F.SilkS")
		)
		(fp_rect
			(start -0.508 0.9398)
			(end 0.508 -0.9398)
			(stroke
				(width 0)
				(type default)
			)
			(fill no)
			(layer "F.CrtYd")
		)
		(fp_rect
			(start -0.508 0.9398)
			(end 0.508 -0.9398)
			(stroke
				(width 0)
				(type default)
			)
			(fill no)
			(layer "F.Fab")
		)
		(pad "1" smd custom
			(at 0 -0.4445)
			(size 0.1397 0.1397)
			(layers "F.Cu" "F.Mask" "F.Paste")
			(net "P5V_B")
			(options
				(clearance outline)
				(anchor circle)
			)
			(primitives
				(gr_poly
					(pts
						(arc
							(start -0.1778 -0.2794)
							(mid -0.249642 -0.249642)
							(end -0.2794 -0.1778)
						)
						(arc
							(start -0.2794 0.1778)
							(mid -0.249642 0.249642)
							(end -0.1778 0.2794)
						)
						(arc
							(start 0.1778 0.2794)
							(mid 0.249642 0.249642)
							(end 0.2794 0.1778)
						)
						(arc
							(start 0.2794 -0.1778)
							(mid 0.249642 -0.249642)
							(end 0.1778 -0.2794)
						)
					)
					(width 0)
					(fill yes)
				)
			)
		)
		(pad "2" smd custom
			(at 0 0.4445)
			(size 0.1397 0.1397)
			(layers "F.Cu" "F.Mask" "F.Paste")
			(net "USB_EN_2")
			(options
				(clearance outline)
				(anchor circle)
			)
			(primitives
				(gr_poly
					(pts
						(arc
							(start -0.1778 -0.2794)
							(mid -0.249642 -0.249642)
							(end -0.2794 -0.1778)
						)
						(arc
							(start -0.2794 0.1778)
							(mid -0.249642 0.249642)
							(end -0.1778 0.2794)
						)
						(arc
							(start 0.1778 0.2794)
							(mid 0.249642 0.249642)
							(end 0.2794 0.1778)
						)
						(arc
							(start 0.2794 -0.1778)
							(mid 0.249642 -0.249642)
							(end 0.1778 -0.2794)
						)
					)
					(width 0)
					(fill yes)
				)
			)
		)
	)
	(footprint ""
		(layer "F.Cu")
		(at 270.210534 19.450812 -90)
		(property "Reference" "R140"
			(at 0 0 270)
			(layer "F.SilkS")
			(hide yes)
			(effects
				(font
					(size 1.27 1.27)
				)
			)
		)
		(property "Value" "4K7R2F-GP"
			(at 0.064008 -3.993896 270)
			(unlocked yes)
			(layer "F.Fab")
			(hide yes)
			(effects
				(font
					(size 1.016 1.016)
					(thickness 0.1524)
				)
			)
		)
		(property "Device Type" "R402H16"
			(at 0.064008 -5.517896 270)
			(unlocked yes)
			(layer "F.Fab")
			(hide yes)
			(effects
				(font
					(size 1.016 1.016)
					(thickness 0.1524)
				)
			)
		)
		(duplicate_pad_numbers_are_jumpers no)
		(fp_line
			(start -0.508 -0.9398)
			(end -0.508 0.9398)
			(stroke
				(width 0.1524)
				(type default)
			)
			(layer "F.SilkS")
		)
		(fp_line
			(start 0.508 -0.9398)
			(end -0.508 -0.9398)
			(stroke
				(width 0.1524)
				(type default)
			)
			(layer "F.SilkS")
		)
		(fp_rect
			(start -0.508 0.9398)
			(end 0.508 -0.9398)
			(stroke
				(width 0)
				(type default)
			)
			(fill no)
			(layer "F.CrtYd")
		)
		(fp_rect
			(start -0.508 0.9398)
			(end 0.508 -0.9398)
			(stroke
				(width 0)
				(type default)
			)
			(fill no)
			(layer "F.Fab")
		)
		(pad "1" smd custom
			(at 0 -0.4445 270)
			(size 0.1397 0.1397)
			(layers "F.Cu" "F.Mask" "F.Paste")
			(net "P5V_B")
			(options
				(clearance outline)
				(anchor circle)
			)
			(primitives
				(gr_poly
					(pts
						(arc
							(start -0.1778 -0.2794)
							(mid -0.249642 -0.249642)
							(end -0.2794 -0.1778)
						)
						(arc
							(start -0.2794 0.1778)
							(mid -0.249642 0.249642)
							(end -0.1778 0.2794)
						)
						(arc
							(start 0.1778 0.2794)
							(mid 0.249642 0.249642)
							(end 0.2794 0.1778)
						)
						(arc
							(start 0.2794 -0.1778)
							(mid 0.249642 -0.249642)
							(end 0.1778 -0.2794)
						)
					)
					(width 0)
					(fill yes)
				)
			)
		)
		(pad "2" smd custom
			(at 0 0.4445 270)
			(size 0.1397 0.1397)
			(layers "F.Cu" "F.Mask" "F.Paste")
			(net "USB_OCS_N2")
			(options
				(clearance outline)
				(anchor circle)
			)
			(primitives
				(gr_poly
					(pts
						(arc
							(start -0.1778 -0.2794)
							(mid -0.249642 -0.249642)
							(end -0.2794 -0.1778)
						)
						(arc
							(start -0.2794 0.1778)
							(mid -0.249642 0.249642)
							(end -0.1778 0.2794)
						)
						(arc
							(start 0.1778 0.2794)
							(mid 0.249642 0.249642)
							(end 0.2794 0.1778)
						)
						(arc
							(start 0.2794 -0.1778)
							(mid 0.249642 -0.249642)
							(end 0.1778 -0.2794)
						)
					)
					(width 0)
					(fill yes)
				)
			)
		)
	)
	(footprint ""
		(layer "F.Cu")
		(at 243.6876 -242.6716 180)
		(property "Reference" "R84"
			(at 0 0 180)
			(layer "F.SilkS")
			(hide yes)
			(effects
				(font
					(size 1.27 1.27)
				)
			)
		)
		(property "Value" "4K7R2F-GP"
			(at 0.064008 -3.993896 180)
			(unlocked yes)
			(layer "F.Fab")
			(hide yes)
			(effects
				(font
					(size 1.016 1.016)
					(thickness 0.1524)
				)
			)
		)
		(property "Device Type" "R402H16"
			(at 0.064008 -5.517896 180)
			(unlocked yes)
			(layer "F.Fab")
			(hide yes)
			(effects
				(font
					(size 1.016 1.016)
					(thickness 0.1524)
				)
			)
		)
		(duplicate_pad_numbers_are_jumpers no)
		(fp_line
			(start 0.508 -0.9398)
			(end -0.508 -0.9398)
			(stroke
				(width 0.1524)
				(type default)
			)
			(layer "F.SilkS")
		)
		(fp_line
			(start -0.508 -0.9398)
			(end -0.508 0.9398)
			(stroke
				(width 0.1524)
				(type default)
			)
			(layer "F.SilkS")
		)
		(fp_rect
			(start -0.508 0.9398)
			(end 0.508 -0.9398)
			(stroke
				(width 0)
				(type default)
			)
			(fill no)
			(layer "F.CrtYd")
		)
		(fp_rect
			(start -0.508 0.9398)
			(end 0.508 -0.9398)
			(stroke
				(width 0)
				(type default)
			)
			(fill no)
			(layer "F.Fab")
		)
		(pad "1" smd custom
			(at 0 -0.4445 180)
			(size 0.1397 0.1397)
			(layers "F.Cu" "F.Mask" "F.Paste")
			(net "IO_EXP2_A0")
			(options
				(clearance outline)
				(anchor circle)
			)
			(primitives
				(gr_poly
					(pts
						(arc
							(start -0.1778 -0.2794)
							(mid -0.249642 -0.249642)
							(end -0.2794 -0.1778)
						)
						(arc
							(start -0.2794 0.1778)
							(mid -0.249642 0.249642)
							(end -0.1778 0.2794)
						)
						(arc
							(start 0.1778 0.2794)
							(mid 0.249642 0.249642)
							(end 0.2794 0.1778)
						)
						(arc
							(start 0.2794 -0.1778)
							(mid 0.249642 -0.249642)
							(end 0.1778 -0.2794)
						)
					)
					(width 0)
					(fill yes)
				)
			)
		)
		(pad "2" smd custom
			(at 0 0.4445 180)
			(size 0.1397 0.1397)
			(layers "F.Cu" "F.Mask" "F.Paste")
			(net "GND")
			(options
				(clearance outline)
				(anchor circle)
			)
			(primitives
				(gr_poly
					(pts
						(arc
							(start -0.1778 -0.2794)
							(mid -0.249642 -0.249642)
							(end -0.2794 -0.1778)
						)
						(arc
							(start -0.2794 0.1778)
							(mid -0.249642 0.249642)
							(end -0.1778 0.2794)
						)
						(arc
							(start 0.1778 0.2794)
							(mid 0.249642 0.249642)
							(end 0.2794 0.1778)
						)
						(arc
							(start 0.2794 -0.1778)
							(mid 0.249642 -0.249642)
							(end 0.1778 -0.2794)
						)
					)
					(width 0)
					(fill yes)
				)
			)
		)
	)
	(footprint ""
		(layer "F.Cu")
		(at 266.192254 -110.339886 -90)
		(property "Reference" "R992"
			(at 0 0 270)
			(layer "F.SilkS")
			(hide yes)
			(effects
				(font
					(size 1.27 1.27)
				)
			)
		)
		(property "Value" "100KR2F-L1-GP"
			(at 0.064008 -3.993896 270)
			(unlocked yes)
			(layer "F.Fab")
			(hide yes)
			(effects
				(font
					(size 1.016 1.016)
					(thickness 0.1524)
				)
			)
		)
		(property "Device Type" "R402H16"
			(at 0.064008 -5.517896 270)
			(unlocked yes)
			(layer "F.Fab")
			(hide yes)
			(effects
				(font
					(size 1.016 1.016)
					(thickness 0.1524)
				)
			)
		)
		(duplicate_pad_numbers_are_jumpers no)
		(fp_line
			(start -0.508 -0.9398)
			(end -0.508 0.9398)
			(stroke
				(width 0.1524)
				(type default)
			)
			(layer "F.SilkS")
		)
		(fp_line
			(start 0.508 -0.9398)
			(end -0.508 -0.9398)
			(stroke
				(width 0.1524)
				(type default)
			)
			(layer "F.SilkS")
		)
		(fp_rect
			(start -0.508 0.9398)
			(end 0.508 -0.9398)
			(stroke
				(width 0)
				(type default)
			)
			(fill no)
			(layer "F.CrtYd")
		)
		(fp_rect
			(start -0.508 0.9398)
			(end 0.508 -0.9398)
			(stroke
				(width 0)
				(type default)
			)
			(fill no)
			(layer "F.Fab")
		)
		(pad "1" smd custom
			(at 0 -0.4445 270)
			(size 0.1397 0.1397)
			(layers "F.Cu" "F.Mask" "F.Paste")
			(net "PCIE_COMP_B_TO_SCC_B_RST_0")
			(options
				(clearance outline)
				(anchor circle)
			)
			(primitives
				(gr_poly
					(pts
						(arc
							(start -0.1778 -0.2794)
							(mid -0.249642 -0.249642)
							(end -0.2794 -0.1778)
						)
						(arc
							(start -0.2794 0.1778)
							(mid -0.249642 0.249642)
							(end -0.1778 0.2794)
						)
						(arc
							(start 0.1778 0.2794)
							(mid 0.249642 0.249642)
							(end 0.2794 0.1778)
						)
						(arc
							(start 0.2794 -0.1778)
							(mid 0.249642 -0.249642)
							(end 0.1778 -0.2794)
						)
					)
					(width 0)
					(fill yes)
				)
			)
		)
		(pad "2" smd custom
			(at 0 0.4445 270)
			(size 0.1397 0.1397)
			(layers "F.Cu" "F.Mask" "F.Paste")
			(net "GND")
			(options
				(clearance outline)
				(anchor circle)
			)
			(primitives
				(gr_poly
					(pts
						(arc
							(start -0.1778 -0.2794)
							(mid -0.249642 -0.249642)
							(end -0.2794 -0.1778)
						)
						(arc
							(start -0.2794 0.1778)
							(mid -0.249642 0.249642)
							(end -0.1778 0.2794)
						)
						(arc
							(start 0.1778 0.2794)
							(mid 0.249642 0.249642)
							(end 0.2794 0.1778)
						)
						(arc
							(start 0.2794 -0.1778)
							(mid 0.249642 -0.249642)
							(end 0.1778 -0.2794)
						)
					)
					(width 0)
					(fill yes)
				)
			)
		)
	)
	(footprint ""
		(layer "F.Cu")
		(at 98.897948 -61.127894 90)
		(property "Reference" "C384"
			(at 0 0 90)
			(layer "F.SilkS")
			(hide yes)
			(effects
				(font
					(size 1.27 1.27)
				)
			)
		)
		(property "Value" "SCD01U50V2KX-1GP"
			(at 1.1811 -2.7051 90)
			(unlocked yes)
			(layer "F.Fab")
			(hide yes)
			(effects
				(font
					(size 1.016 1.016)
					(thickness 0.1524)
				)
			)
		)
		(property "Device Type" "C402H22"
			(at 1.1811 -4.2291 90)
			(unlocked yes)
			(layer "F.Fab")
			(hide yes)
			(effects
				(font
					(size 1.016 1.016)
					(thickness 0.1524)
				)
			)
		)
		(duplicate_pad_numbers_are_jumpers no)
		(fp_rect
			(start -0.4318 0.9525)
			(end 0.4318 -0.9525)
			(stroke
				(width 0)
				(type default)
			)
			(fill no)
			(layer "F.CrtYd")
		)
		(fp_rect
			(start -0.4318 0.9525)
			(end 0.4318 -0.9525)
			(stroke
				(width 0)
				(type default)
			)
			(fill no)
			(layer "F.Fab")
		)
		(pad "1" smd custom
			(at 0 -0.4445 90)
			(size 0.1524 0.1524)
			(layers "F.Cu" "F.Mask" "F.Paste")
			(net "HDD_PRSNT_26")
			(options
				(clearance outline)
				(anchor circle)
			)
			(primitives
				(gr_poly
					(pts
						(arc
							(start 0.3048 -0.2032)
							(mid 0.275042 -0.275042)
							(end 0.2032 -0.3048)
						)
						(arc
							(start -0.2032 -0.3048)
							(mid -0.275042 -0.275042)
							(end -0.3048 -0.2032)
						)
						(arc
							(start -0.3048 0.2032)
							(mid -0.275042 0.275042)
							(end -0.2032 0.3048)
						)
						(arc
							(start 0.2032 0.3048)
							(mid 0.275042 0.275042)
							(end 0.3048 0.2032)
						)
					)
					(width 0)
					(fill yes)
				)
			)
		)
		(pad "2" smd custom
			(at 0 0.4445 90)
			(size 0.1524 0.1524)
			(layers "F.Cu" "F.Mask" "F.Paste")
			(net "GND")
			(options
				(clearance outline)
				(anchor circle)
			)
			(primitives
				(gr_poly
					(pts
						(arc
							(start 0.3048 -0.2032)
							(mid 0.275042 -0.275042)
							(end 0.2032 -0.3048)
						)
						(arc
							(start -0.2032 -0.3048)
							(mid -0.275042 -0.275042)
							(end -0.3048 -0.2032)
						)
						(arc
							(start -0.3048 0.2032)
							(mid -0.275042 0.275042)
							(end -0.2032 0.3048)
						)
						(arc
							(start 0.2032 0.3048)
							(mid 0.275042 0.275042)
							(end 0.3048 0.2032)
						)
					)
					(width 0)
					(fill yes)
				)
			)
		)
	)
	(footprint ""
		(layer "F.Cu")
		(at 227.67671 -385.646168)
		(property "Reference" "R1131"
			(at 0 0 0)
			(layer "F.SilkS")
			(hide yes)
			(effects
				(font
					(size 1.27 1.27)
				)
			)
		)
		(property "Value" "3K83R2F-GP"
			(at 0.064008 -3.993896 0)
			(unlocked yes)
			(layer "F.Fab")
			(hide yes)
			(effects
				(font
					(size 1.016 1.016)
					(thickness 0.1524)
				)
			)
		)
		(property "Device Type" "R402H16"
			(at 0.064008 -5.517896 0)
			(unlocked yes)
			(layer "F.Fab")
			(hide yes)
			(effects
				(font
					(size 1.016 1.016)
					(thickness 0.1524)
				)
			)
		)
		(duplicate_pad_numbers_are_jumpers no)
		(fp_line
			(start -0.508 -0.9398)
			(end -0.508 0.9398)
			(stroke
				(width 0.1524)
				(type default)
			)
			(layer "F.SilkS")
		)
		(fp_line
			(start 0.508 -0.9398)
			(end -0.508 -0.9398)
			(stroke
				(width 0.1524)
				(type default)
			)
			(layer "F.SilkS")
		)
		(fp_rect
			(start -0.508 0.9398)
			(end 0.508 -0.9398)
			(stroke
				(width 0)
				(type default)
			)
			(fill no)
			(layer "F.CrtYd")
		)
		(fp_rect
			(start -0.508 0.9398)
			(end 0.508 -0.9398)
			(stroke
				(width 0)
				(type default)
			)
			(fill no)
			(layer "F.Fab")
		)
		(pad "1" smd custom
			(at 0 -0.4445)
			(size 0.1397 0.1397)
			(layers "F.Cu" "F.Mask" "F.Paste")
			(net "DPB_PWR_BTN_BUF_A")
			(options
				(clearance outline)
				(anchor circle)
			)
			(primitives
				(gr_poly
					(pts
						(arc
							(start -0.1778 -0.2794)
							(mid -0.249642 -0.249642)
							(end -0.2794 -0.1778)
						)
						(arc
							(start -0.2794 0.1778)
							(mid -0.249642 0.249642)
							(end -0.1778 0.2794)
						)
						(arc
							(start 0.1778 0.2794)
							(mid 0.249642 0.249642)
							(end 0.2794 0.1778)
						)
						(arc
							(start 0.2794 -0.1778)
							(mid 0.249642 -0.249642)
							(end 0.1778 -0.2794)
						)
					)
					(width 0)
					(fill yes)
				)
			)
		)
		(pad "2" smd custom
			(at 0 0.4445)
			(size 0.1397 0.1397)
			(layers "F.Cu" "F.Mask" "F.Paste")
			(net "GND")
			(options
				(clearance outline)
				(anchor circle)
			)
			(primitives
				(gr_poly
					(pts
						(arc
							(start -0.1778 -0.2794)
							(mid -0.249642 -0.249642)
							(end -0.2794 -0.1778)
						)
						(arc
							(start -0.2794 0.1778)
							(mid -0.249642 0.249642)
							(end -0.1778 0.2794)
						)
						(arc
							(start 0.1778 0.2794)
							(mid 0.249642 0.249642)
							(end 0.2794 0.1778)
						)
						(arc
							(start 0.2794 -0.1778)
							(mid 0.249642 -0.249642)
							(end 0.1778 -0.2794)
						)
					)
					(width 0)
					(fill yes)
				)
			)
		)
	)
	(footprint ""
		(layer "F.Cu")
		(at 449.291202 -257.48615 -90)
		(property "Reference" "R1246"
			(at 0 0 270)
			(layer "F.SilkS")
			(hide yes)
			(effects
				(font
					(size 1.27 1.27)
				)
			)
		)
		(property "Value" "10KR2F-2-GP"
			(at 0.064008 -3.993896 270)
			(unlocked yes)
			(layer "F.Fab")
			(hide yes)
			(effects
				(font
					(size 1.016 1.016)
					(thickness 0.1524)
				)
			)
		)
		(property "Device Type" "R402H16"
			(at 0.064008 -5.517896 270)
			(unlocked yes)
			(layer "F.Fab")
			(hide yes)
			(effects
				(font
					(size 1.016 1.016)
					(thickness 0.1524)
				)
			)
		)
		(duplicate_pad_numbers_are_jumpers no)
		(fp_line
			(start -0.508 -0.9398)
			(end -0.508 0.9398)
			(stroke
				(width 0.1524)
				(type default)
			)
			(layer "F.SilkS")
		)
		(fp_line
			(start 0.508 -0.9398)
			(end -0.508 -0.9398)
			(stroke
				(width 0.1524)
				(type default)
			)
			(layer "F.SilkS")
		)
		(fp_rect
			(start -0.508 0.9398)
			(end 0.508 -0.9398)
			(stroke
				(width 0)
				(type default)
			)
			(fill no)
			(layer "F.CrtYd")
		)
		(fp_rect
			(start -0.508 0.9398)
			(end 0.508 -0.9398)
			(stroke
				(width 0)
				(type default)
			)
			(fill no)
			(layer "F.Fab")
		)
		(pad "1" smd custom
			(at 0 -0.4445 270)
			(size 0.1397 0.1397)
			(layers "F.Cu" "F.Mask" "F.Paste")
			(net "P5V_C_EN_R")
			(options
				(clearance outline)
				(anchor circle)
			)
			(primitives
				(gr_poly
					(pts
						(arc
							(start -0.1778 -0.2794)
							(mid -0.249642 -0.249642)
							(end -0.2794 -0.1778)
						)
						(arc
							(start -0.2794 0.1778)
							(mid -0.249642 0.249642)
							(end -0.1778 0.2794)
						)
						(arc
							(start 0.1778 0.2794)
							(mid 0.249642 0.249642)
							(end 0.2794 0.1778)
						)
						(arc
							(start 0.2794 -0.1778)
							(mid 0.249642 -0.249642)
							(end 0.1778 -0.2794)
						)
					)
					(width 0)
					(fill yes)
				)
			)
		)
		(pad "2" smd custom
			(at 0 0.4445 270)
			(size 0.1397 0.1397)
			(layers "F.Cu" "F.Mask" "F.Paste")
			(net "GND")
			(options
				(clearance outline)
				(anchor circle)
			)
			(primitives
				(gr_poly
					(pts
						(arc
							(start -0.1778 -0.2794)
							(mid -0.249642 -0.249642)
							(end -0.2794 -0.1778)
						)
						(arc
							(start -0.2794 0.1778)
							(mid -0.249642 0.249642)
							(end -0.1778 0.2794)
						)
						(arc
							(start 0.1778 0.2794)
							(mid 0.249642 0.249642)
							(end 0.2794 0.1778)
						)
						(arc
							(start 0.2794 -0.1778)
							(mid 0.249642 -0.249642)
							(end 0.1778 -0.2794)
						)
					)
					(width 0)
					(fill yes)
				)
			)
		)
	)
	(footprint ""
		(layer "F.Cu")
		(at 47.853346 -170.609006 90)
		(property "Reference" "C218"
			(at 0 0 90)
			(layer "F.SilkS")
			(hide yes)
			(effects
				(font
					(size 1.27 1.27)
				)
			)
		)
		(property "Value" "SCD033U25V2KX-GP"
			(at 1.1811 -2.7051 90)
			(unlocked yes)
			(layer "F.Fab")
			(hide yes)
			(effects
				(font
					(size 1.016 1.016)
					(thickness 0.1524)
				)
			)
		)
		(property "Device Type" "C402H22"
			(at 1.1811 -4.2291 90)
			(unlocked yes)
			(layer "F.Fab")
			(hide yes)
			(effects
				(font
					(size 1.016 1.016)
					(thickness 0.1524)
				)
			)
		)
		(duplicate_pad_numbers_are_jumpers no)
		(fp_rect
			(start -0.4318 0.9525)
			(end 0.4318 -0.9525)
			(stroke
				(width 0)
				(type default)
			)
			(fill no)
			(layer "F.CrtYd")
		)
		(fp_rect
			(start -0.4318 0.9525)
			(end 0.4318 -0.9525)
			(stroke
				(width 0)
				(type default)
			)
			(fill no)
			(layer "F.Fab")
		)
		(pad "1" smd custom
			(at 0 -0.4445 90)
			(size 0.1524 0.1524)
			(layers "F.Cu" "F.Mask" "F.Paste")
			(net "P12V_A")
			(options
				(clearance outline)
				(anchor circle)
			)
			(primitives
				(gr_poly
					(pts
						(arc
							(start 0.3048 -0.2032)
							(mid 0.275042 -0.275042)
							(end 0.2032 -0.3048)
						)
						(arc
							(start -0.2032 -0.3048)
							(mid -0.275042 -0.275042)
							(end -0.3048 -0.2032)
						)
						(arc
							(start -0.3048 0.2032)
							(mid -0.275042 0.275042)
							(end -0.2032 0.3048)
						)
						(arc
							(start 0.2032 0.3048)
							(mid 0.275042 0.275042)
							(end 0.3048 0.2032)
						)
					)
					(width 0)
					(fill yes)
				)
			)
		)
		(pad "2" smd custom
			(at 0 0.4445 90)
			(size 0.1524 0.1524)
			(layers "F.Cu" "F.Mask" "F.Paste")
			(net "SW_HDD_N13")
			(options
				(clearance outline)
				(anchor circle)
			)
			(primitives
				(gr_poly
					(pts
						(arc
							(start 0.3048 -0.2032)
							(mid 0.275042 -0.275042)
							(end 0.2032 -0.3048)
						)
						(arc
							(start -0.2032 -0.3048)
							(mid -0.275042 -0.275042)
							(end -0.3048 -0.2032)
						)
						(arc
							(start -0.3048 0.2032)
							(mid -0.275042 0.275042)
							(end -0.2032 0.3048)
						)
						(arc
							(start 0.2032 0.3048)
							(mid 0.275042 0.275042)
							(end 0.3048 0.2032)
						)
					)
					(width 0)
					(fill yes)
				)
			)
		)
	)
	(footprint ""
		(layer "F.Cu")
		(at 127.113284 -273.660616 90)
		(property "Reference" "C77"
			(at 0 0 90)
			(layer "F.SilkS")
			(hide yes)
			(effects
				(font
					(size 1.27 1.27)
				)
			)
		)
		(property "Value" "SCD01U16V1KX-GP"
			(at -2.8321 -1.7399 90)
			(unlocked yes)
			(layer "F.Fab")
			(hide yes)
			(effects
				(font
					(size 1.016 1.016)
					(thickness 0.1524)
				)
			)
		)
		(property "Device Type" "C0201H13"
			(at -2.8321 -3.2639 90)
			(unlocked yes)
			(layer "F.Fab")
			(hide yes)
			(effects
				(font
					(size 1.016 1.016)
					(thickness 0.1524)
				)
			)
		)
		(duplicate_pad_numbers_are_jumpers no)
		(fp_rect
			(start -0.2794 0.6477)
			(end 0.2794 -0.6477)
			(stroke
				(width 0)
				(type default)
			)
			(fill no)
			(layer "F.CrtYd")
		)
		(fp_rect
			(start -0.2794 0.6477)
			(end 0.2794 -0.6477)
			(stroke
				(width 0)
				(type default)
			)
			(fill no)
			(layer "F.Fab")
		)
		(pad "1" smd custom
			(at 0 -0.2794 90)
			(size 0.0762 0.0762)
			(layers "F.Cu" "F.Mask" "F.Paste")
			(net "SAS_HDD_RX_P3")
			(options
				(clearance outline)
				(anchor circle)
			)
			(primitives
				(gr_poly
					(pts
						(arc
							(start 0.1524 -0.127)
							(mid 0.137521 -0.162921)
							(end 0.1016 -0.1778)
						)
						(arc
							(start -0.1016 -0.1778)
							(mid -0.137521 -0.162921)
							(end -0.1524 -0.127)
						)
						(arc
							(start -0.1524 0.127)
							(mid -0.137521 0.162921)
							(end -0.1016 0.1778)
						)
						(arc
							(start 0.1016 0.1778)
							(mid 0.137521 0.162921)
							(end 0.1524 0.127)
						)
					)
					(width 0)
					(fill yes)
				)
			)
		)
		(pad "2" smd custom
			(at 0 0.2794 90)
			(size 0.0762 0.0762)
			(layers "F.Cu" "F.Mask" "F.Paste")
			(net "PHY_SCC_A_TO_DRV_A_3_DP")
			(options
				(clearance outline)
				(anchor circle)
			)
			(primitives
				(gr_poly
					(pts
						(arc
							(start 0.1524 -0.127)
							(mid 0.137521 -0.162921)
							(end 0.1016 -0.1778)
						)
						(arc
							(start -0.1016 -0.1778)
							(mid -0.137521 -0.162921)
							(end -0.1524 -0.127)
						)
						(arc
							(start -0.1524 0.127)
							(mid -0.137521 0.162921)
							(end -0.1016 0.1778)
						)
						(arc
							(start 0.1016 0.1778)
							(mid 0.137521 0.162921)
							(end 0.1524 0.127)
						)
					)
					(width 0)
					(fill yes)
				)
			)
		)
	)
	(footprint ""
		(layer "F.Cu")
		(at 426.120052 -73.954894 180)
		(property "Reference" "C473"
			(at 0 0 180)
			(layer "F.SilkS")
			(hide yes)
			(effects
				(font
					(size 1.27 1.27)
				)
			)
		)
		(property "Value" "SC4D7U25V5KX-1-GP"
			(at -0.0762 -6.1214 180)
			(unlocked yes)
			(layer "F.Fab")
			(hide yes)
			(effects
				(font
					(size 1.016 1.016)
					(thickness 0.1524)
				)
			)
		)
		(property "Device Type" "C805H58"
			(at -0.0762 -8.1534 180)
			(unlocked yes)
			(layer "F.Fab")
			(hide yes)
			(effects
				(font
					(size 1.016 1.016)
					(thickness 0.1524)
				)
			)
		)
		(duplicate_pad_numbers_are_jumpers no)
		(fp_line
			(start 0.635 0)
			(end -0.635 0)
			(stroke
				(width 0.508)
				(type default)
			)
			(layer "F.SilkS")
		)
		(fp_rect
			(start -0.9652 1.778)
			(end 0.9652 -1.778)
			(stroke
				(width 0)
				(type default)
			)
			(fill no)
			(layer "F.CrtYd")
		)
		(fp_poly
			(pts
				(xy -0.9652 -1.778) (xy 0.9652 -1.778) (xy 0.9652 1.778) (xy -0.9652 1.778)
			)
			(stroke
				(width 0)
				(type default)
			)
			(fill no)
			(layer "F.Fab")
		)
		(pad "1" smd rect
			(at 0 -0.9652 180)
			(size 1.397 1.143)
			(layers "F.Cu" "F.Mask" "F.Paste")
			(net "P12V_HDD33")
		)
		(pad "2" smd rect
			(at 0 0.9652 180)
			(size 1.397 1.143)
			(layers "F.Cu" "F.Mask" "F.Paste")
			(net "GND")
		)
	)
	(footprint ""
		(layer "F.Cu")
		(at 243.078 -231.14 180)
		(property "Reference" "R85"
			(at 0 0 180)
			(layer "F.SilkS")
			(hide yes)
			(effects
				(font
					(size 1.27 1.27)
				)
			)
		)
		(property "Value" "4K7R2F-GP"
			(at 0.064008 -3.993896 180)
			(unlocked yes)
			(layer "F.Fab")
			(hide yes)
			(effects
				(font
					(size 1.016 1.016)
					(thickness 0.1524)
				)
			)
		)
		(property "Device Type" "R402H16"
			(at 0.064008 -5.517896 180)
			(unlocked yes)
			(layer "F.Fab")
			(hide yes)
			(effects
				(font
					(size 1.016 1.016)
					(thickness 0.1524)
				)
			)
		)
		(duplicate_pad_numbers_are_jumpers no)
		(fp_line
			(start 0.508 -0.9398)
			(end -0.508 -0.9398)
			(stroke
				(width 0.1524)
				(type default)
			)
			(layer "F.SilkS")
		)
		(fp_line
			(start -0.508 -0.9398)
			(end -0.508 0.9398)
			(stroke
				(width 0.1524)
				(type default)
			)
			(layer "F.SilkS")
		)
		(fp_rect
			(start -0.508 0.9398)
			(end 0.508 -0.9398)
			(stroke
				(width 0)
				(type default)
			)
			(fill no)
			(layer "F.CrtYd")
		)
		(fp_rect
			(start -0.508 0.9398)
			(end 0.508 -0.9398)
			(stroke
				(width 0)
				(type default)
			)
			(fill no)
			(layer "F.Fab")
		)
		(pad "1" smd custom
			(at 0 -0.4445 180)
			(size 0.1397 0.1397)
			(layers "F.Cu" "F.Mask" "F.Paste")
			(net "P3V3_STBY_A")
			(options
				(clearance outline)
				(anchor circle)
			)
			(primitives
				(gr_poly
					(pts
						(arc
							(start -0.1778 -0.2794)
							(mid -0.249642 -0.249642)
							(end -0.2794 -0.1778)
						)
						(arc
							(start -0.2794 0.1778)
							(mid -0.249642 0.249642)
							(end -0.1778 0.2794)
						)
						(arc
							(start 0.1778 0.2794)
							(mid 0.249642 0.249642)
							(end 0.2794 0.1778)
						)
						(arc
							(start 0.2794 -0.1778)
							(mid 0.249642 -0.249642)
							(end 0.1778 -0.2794)
						)
					)
					(width 0)
					(fill yes)
				)
			)
		)
		(pad "2" smd custom
			(at 0 0.4445 180)
			(size 0.1397 0.1397)
			(layers "F.Cu" "F.Mask" "F.Paste")
			(net "IO_EXP2_A1")
			(options
				(clearance outline)
				(anchor circle)
			)
			(primitives
				(gr_poly
					(pts
						(arc
							(start -0.1778 -0.2794)
							(mid -0.249642 -0.249642)
							(end -0.2794 -0.1778)
						)
						(arc
							(start -0.2794 0.1778)
							(mid -0.249642 0.249642)
							(end -0.1778 0.2794)
						)
						(arc
							(start 0.1778 0.2794)
							(mid 0.249642 0.249642)
							(end 0.2794 0.1778)
						)
						(arc
							(start 0.2794 -0.1778)
							(mid 0.249642 -0.249642)
							(end 0.1778 -0.2794)
						)
					)
					(width 0)
					(fill yes)
				)
			)
		)
	)
	(footprint ""
		(layer "F.Cu")
		(at 193.2686 -298.704)
		(property "Reference" "TP27"
			(at 0 0 0)
			(layer "F.SilkS")
			(hide yes)
			(effects
				(font
					(size 1.27 1.27)
				)
			)
		)
		(property "Value" "TPAD32-GP"
			(at -0.0508 -1.6764 0)
			(unlocked yes)
			(layer "F.Fab")
			(hide yes)
			(effects
				(font
					(size 1.016 1.016)
					(thickness 0.1524)
				)
			)
		)
		(property "Device Type" "TPAD32"
			(at -0.0508 -3.2004 0)
			(unlocked yes)
			(layer "F.Fab")
			(hide yes)
			(effects
				(font
					(size 1.016 1.016)
					(thickness 0.1524)
				)
			)
		)
		(duplicate_pad_numbers_are_jumpers no)
		(fp_poly
			(pts
				(arc
					(start 0.4064 0)
					(mid -0.4064 0)
					(end 0.4064 0)
				)
			)
			(stroke
				(width 0)
				(type default)
			)
			(fill no)
			(layer "F.CrtYd")
		)
		(fp_poly
			(pts
				(arc
					(start 0.7112 0)
					(mid -0.7112 0)
					(end 0.7112 0)
				)
			)
			(stroke
				(width 0)
				(type default)
			)
			(fill no)
			(layer "F.Fab")
		)
		(pad "1" smd circle
			(at 0 0)
			(size 0.8128 0.8128)
			(layers "F.Cu" "F.Mask" "F.Paste")
			(net "ACT_HDD_5")
		)
	)
	(footprint ""
		(layer "F.Cu")
		(at 158.708852 -47.749968 -90)
		(property "Reference" "VIA64"
			(at 0 0 270)
			(layer "F.SilkS")
			(hide yes)
			(effects
				(font
					(size 1.27 1.27)
				)
			)
		)
		(property "Value" "100OHM-8L-1D6MM-L18L16-GP"
			(at -3.7211 -4.5085 270)
			(unlocked yes)
			(layer "F.Fab")
			(hide yes)
			(effects
				(font
					(size 1.016 1.016)
					(thickness 0.1524)
				)
			)
		)
		(property "Device Type" "VIA-PCIE-4P-394076"
			(at -3.7211 -6.0325 270)
			(unlocked yes)
			(layer "F.Fab")
			(hide yes)
			(effects
				(font
					(size 1.016 1.016)
					(thickness 0.1524)
				)
			)
		)
		(duplicate_pad_numbers_are_jumpers no)
		(fp_rect
			(start -1.9685 0.381)
			(end 1.9685 -0.381)
			(stroke
				(width 0)
				(type default)
			)
			(fill no)
			(layer "F.CrtYd")
		)
		(fp_rect
			(start -1.9685 0.381)
			(end 1.9685 -0.381)
			(stroke
				(width 0)
				(type default)
			)
			(fill no)
			(layer "F.Fab")
		)
		(pad "1" thru_hole circle
			(at -1.5875 0 270)
			(size 0.508 0.508)
			(drill 0.254)
			(layers "*.Cu" "*.Mask")
			(remove_unused_layers no)
			(net "GND")
			(clearance 0.127)
			(thermal_gap 0.127)
		)
		(pad "2" thru_hole circle
			(at -0.5715 0 270)
			(size 0.508 0.508)
			(drill 0.254)
			(layers "*.Cu" "*.Mask")
			(remove_unused_layers no)
			(net "PHY_DRV_A_TO_SCC_A_28_DP")
			(clearance 0.127)
			(thermal_gap 0.127)
		)
		(pad "3" thru_hole circle
			(at 0.5715 0 270)
			(size 0.508 0.508)
			(drill 0.254)
			(layers "*.Cu" "*.Mask")
			(remove_unused_layers no)
			(net "PHY_DRV_A_TO_SCC_A_28_DN")
			(clearance 0.127)
			(thermal_gap 0.127)
		)
		(pad "4" thru_hole circle
			(at 1.5875 0 270)
			(size 0.508 0.508)
			(drill 0.254)
			(layers "*.Cu" "*.Mask")
			(remove_unused_layers no)
			(net "GND")
			(clearance 0.127)
			(thermal_gap 0.127)
		)
	)
	(footprint ""
		(layer "F.Cu")
		(at 143.049498 -167.060118 90)
		(property "Reference" "R505"
			(at 0 0 90)
			(layer "F.SilkS")
			(hide yes)
			(effects
				(font
					(size 1.27 1.27)
				)
			)
		)
		(property "Value" "4K7R2J-2-GP"
			(at 0.064008 -3.993896 90)
			(unlocked yes)
			(layer "F.Fab")
			(hide yes)
			(effects
				(font
					(size 1.016 1.016)
					(thickness 0.1524)
				)
			)
		)
		(property "Device Type" "R402H16"
			(at 0.064008 -5.517896 90)
			(unlocked yes)
			(layer "F.Fab")
			(hide yes)
			(effects
				(font
					(size 1.016 1.016)
					(thickness 0.1524)
				)
			)
		)
		(duplicate_pad_numbers_are_jumpers no)
		(fp_line
			(start 0.508 -0.9398)
			(end -0.508 -0.9398)
			(stroke
				(width 0.1524)
				(type default)
			)
			(layer "F.SilkS")
		)
		(fp_line
			(start -0.508 -0.9398)
			(end -0.508 0.9398)
			(stroke
				(width 0.1524)
				(type default)
			)
			(layer "F.SilkS")
		)
		(fp_rect
			(start -0.508 0.9398)
			(end 0.508 -0.9398)
			(stroke
				(width 0)
				(type default)
			)
			(fill no)
			(layer "F.CrtYd")
		)
		(fp_rect
			(start -0.508 0.9398)
			(end 0.508 -0.9398)
			(stroke
				(width 0)
				(type default)
			)
			(fill no)
			(layer "F.Fab")
		)
		(pad "1" smd custom
			(at 0 -0.4445 90)
			(size 0.1397 0.1397)
			(layers "F.Cu" "F.Mask" "F.Paste")
			(net "P12V_A")
			(options
				(clearance outline)
				(anchor circle)
			)
			(primitives
				(gr_poly
					(pts
						(arc
							(start -0.1778 -0.2794)
							(mid -0.249642 -0.249642)
							(end -0.2794 -0.1778)
						)
						(arc
							(start -0.2794 0.1778)
							(mid -0.249642 0.249642)
							(end -0.1778 0.2794)
						)
						(arc
							(start 0.1778 0.2794)
							(mid 0.249642 0.249642)
							(end 0.2794 0.1778)
						)
						(arc
							(start 0.2794 -0.1778)
							(mid 0.249642 -0.249642)
							(end 0.1778 -0.2794)
						)
					)
					(width 0)
					(fill yes)
				)
			)
		)
		(pad "2" smd custom
			(at 0 0.4445 90)
			(size 0.1397 0.1397)
			(layers "F.Cu" "F.Mask" "F.Paste")
			(net "SW_HDD_P16")
			(options
				(clearance outline)
				(anchor circle)
			)
			(primitives
				(gr_poly
					(pts
						(arc
							(start -0.1778 -0.2794)
							(mid -0.249642 -0.249642)
							(end -0.2794 -0.1778)
						)
						(arc
							(start -0.2794 0.1778)
							(mid -0.249642 0.249642)
							(end -0.1778 0.2794)
						)
						(arc
							(start 0.1778 0.2794)
							(mid 0.249642 0.249642)
							(end 0.2794 0.1778)
						)
						(arc
							(start 0.2794 -0.1778)
							(mid 0.249642 -0.249642)
							(end 0.1778 -0.2794)
						)
					)
					(width 0)
					(fill yes)
				)
			)
		)
	)
	(footprint ""
		(layer "F.Cu")
		(at 332.74 -49.596294 90)
		(property "Reference" "C438"
			(at 0 0 90)
			(layer "F.SilkS")
			(hide yes)
			(effects
				(font
					(size 1.27 1.27)
				)
			)
		)
		(property "Value" "SCD033U25V2KX-GP"
			(at 1.1811 -2.7051 90)
			(unlocked yes)
			(layer "F.Fab")
			(hide yes)
			(effects
				(font
					(size 1.016 1.016)
					(thickness 0.1524)
				)
			)
		)
		(property "Device Type" "C402H22"
			(at 1.1811 -4.2291 90)
			(unlocked yes)
			(layer "F.Fab")
			(hide yes)
			(effects
				(font
					(size 1.016 1.016)
					(thickness 0.1524)
				)
			)
		)
		(duplicate_pad_numbers_are_jumpers no)
		(fp_rect
			(start -0.4318 0.9525)
			(end 0.4318 -0.9525)
			(stroke
				(width 0)
				(type default)
			)
			(fill no)
			(layer "F.CrtYd")
		)
		(fp_rect
			(start -0.4318 0.9525)
			(end 0.4318 -0.9525)
			(stroke
				(width 0)
				(type default)
			)
			(fill no)
			(layer "F.Fab")
		)
		(pad "1" smd custom
			(at 0 -0.4445 90)
			(size 0.1524 0.1524)
			(layers "F.Cu" "F.Mask" "F.Paste")
			(net "SW_HDD_P30")
			(options
				(clearance outline)
				(anchor circle)
			)
			(primitives
				(gr_poly
					(pts
						(arc
							(start 0.3048 -0.2032)
							(mid 0.275042 -0.275042)
							(end 0.2032 -0.3048)
						)
						(arc
							(start -0.2032 -0.3048)
							(mid -0.275042 -0.275042)
							(end -0.3048 -0.2032)
						)
						(arc
							(start -0.3048 0.2032)
							(mid -0.275042 0.275042)
							(end -0.2032 0.3048)
						)
						(arc
							(start 0.2032 0.3048)
							(mid 0.275042 0.275042)
							(end 0.3048 0.2032)
						)
					)
					(width 0)
					(fill yes)
				)
			)
		)
		(pad "2" smd custom
			(at 0 0.4445 90)
			(size 0.1524 0.1524)
			(layers "F.Cu" "F.Mask" "F.Paste")
			(net "GND")
			(options
				(clearance outline)
				(anchor circle)
			)
			(primitives
				(gr_poly
					(pts
						(arc
							(start 0.3048 -0.2032)
							(mid 0.275042 -0.275042)
							(end 0.2032 -0.3048)
						)
						(arc
							(start -0.2032 -0.3048)
							(mid -0.275042 -0.275042)
							(end -0.3048 -0.2032)
						)
						(arc
							(start -0.3048 0.2032)
							(mid -0.275042 0.275042)
							(end -0.2032 0.3048)
						)
						(arc
							(start 0.2032 0.3048)
							(mid 0.275042 0.275042)
							(end 0.3048 0.2032)
						)
					)
					(width 0)
					(fill yes)
				)
			)
		)
	)
	(footprint ""
		(layer "F.Cu")
		(at 396.34795 -272.585942 180)
		(property "Reference" "R322"
			(at 0 0 180)
			(layer "F.SilkS")
			(hide yes)
			(effects
				(font
					(size 1.27 1.27)
				)
			)
		)
		(property "Value" "1KR2F-3-GP"
			(at 0.064008 -3.993896 180)
			(unlocked yes)
			(layer "F.Fab")
			(hide yes)
			(effects
				(font
					(size 1.016 1.016)
					(thickness 0.1524)
				)
			)
		)
		(property "Device Type" "R402H16"
			(at 0.064008 -5.517896 180)
			(unlocked yes)
			(layer "F.Fab")
			(hide yes)
			(effects
				(font
					(size 1.016 1.016)
					(thickness 0.1524)
				)
			)
		)
		(duplicate_pad_numbers_are_jumpers no)
		(fp_line
			(start 0.508 -0.9398)
			(end -0.508 -0.9398)
			(stroke
				(width 0.1524)
				(type default)
			)
			(layer "F.SilkS")
		)
		(fp_line
			(start -0.508 -0.9398)
			(end -0.508 0.9398)
			(stroke
				(width 0.1524)
				(type default)
			)
			(layer "F.SilkS")
		)
		(fp_rect
			(start -0.508 0.9398)
			(end 0.508 -0.9398)
			(stroke
				(width 0)
				(type default)
			)
			(fill no)
			(layer "F.CrtYd")
		)
		(fp_rect
			(start -0.508 0.9398)
			(end 0.508 -0.9398)
			(stroke
				(width 0)
				(type default)
			)
			(fill no)
			(layer "F.Fab")
		)
		(pad "1" smd custom
			(at 0 -0.4445 180)
			(size 0.1397 0.1397)
			(layers "F.Cu" "F.Mask" "F.Paste")
			(net "P3V3_STBY_A")
			(options
				(clearance outline)
				(anchor circle)
			)
			(primitives
				(gr_poly
					(pts
						(arc
							(start -0.1778 -0.2794)
							(mid -0.249642 -0.249642)
							(end -0.2794 -0.1778)
						)
						(arc
							(start -0.2794 0.1778)
							(mid -0.249642 0.249642)
							(end -0.1778 0.2794)
						)
						(arc
							(start 0.1778 0.2794)
							(mid 0.249642 0.249642)
							(end 0.2794 0.1778)
						)
						(arc
							(start 0.2794 -0.1778)
							(mid 0.249642 -0.249642)
							(end 0.1778 -0.2794)
						)
					)
					(width 0)
					(fill yes)
				)
			)
		)
		(pad "2" smd custom
			(at 0 0.4445 180)
			(size 0.1397 0.1397)
			(layers "F.Cu" "F.Mask" "F.Paste")
			(net "SW_PWR_R_HDD8")
			(options
				(clearance outline)
				(anchor circle)
			)
			(primitives
				(gr_poly
					(pts
						(arc
							(start -0.1778 -0.2794)
							(mid -0.249642 -0.249642)
							(end -0.2794 -0.1778)
						)
						(arc
							(start -0.2794 0.1778)
							(mid -0.249642 0.249642)
							(end -0.1778 0.2794)
						)
						(arc
							(start 0.1778 0.2794)
							(mid 0.249642 0.249642)
							(end 0.2794 0.1778)
						)
						(arc
							(start 0.2794 -0.1778)
							(mid 0.249642 -0.249642)
							(end 0.1778 -0.2794)
						)
					)
					(width 0)
					(fill yes)
				)
			)
		)
	)
	(footprint ""
		(layer "F.Cu")
		(at 457.3905 -272.535142)
		(property "Reference" "R373"
			(at 0 0 0)
			(layer "F.SilkS")
			(hide yes)
			(effects
				(font
					(size 1.27 1.27)
				)
			)
		)
		(property "Value" "4K7R2J-2-GP"
			(at 0.064008 -3.993896 0)
			(unlocked yes)
			(layer "F.Fab")
			(hide yes)
			(effects
				(font
					(size 1.016 1.016)
					(thickness 0.1524)
				)
			)
		)
		(property "Device Type" "R402H16"
			(at 0.064008 -5.517896 0)
			(unlocked yes)
			(layer "F.Fab")
			(hide yes)
			(effects
				(font
					(size 1.016 1.016)
					(thickness 0.1524)
				)
			)
		)
		(duplicate_pad_numbers_are_jumpers no)
		(fp_line
			(start -0.508 -0.9398)
			(end -0.508 0.9398)
			(stroke
				(width 0.1524)
				(type default)
			)
			(layer "F.SilkS")
		)
		(fp_line
			(start 0.508 -0.9398)
			(end -0.508 -0.9398)
			(stroke
				(width 0.1524)
				(type default)
			)
			(layer "F.SilkS")
		)
		(fp_rect
			(start -0.508 0.9398)
			(end 0.508 -0.9398)
			(stroke
				(width 0)
				(type default)
			)
			(fill no)
			(layer "F.CrtYd")
		)
		(fp_rect
			(start -0.508 0.9398)
			(end 0.508 -0.9398)
			(stroke
				(width 0)
				(type default)
			)
			(fill no)
			(layer "F.Fab")
		)
		(pad "1" smd custom
			(at 0 -0.4445)
			(size 0.1397 0.1397)
			(layers "F.Cu" "F.Mask" "F.Paste")
			(net "SW_PWR_R_HDD10")
			(options
				(clearance outline)
				(anchor circle)
			)
			(primitives
				(gr_poly
					(pts
						(arc
							(start -0.1778 -0.2794)
							(mid -0.249642 -0.249642)
							(end -0.2794 -0.1778)
						)
						(arc
							(start -0.2794 0.1778)
							(mid -0.249642 0.249642)
							(end -0.1778 0.2794)
						)
						(arc
							(start 0.1778 0.2794)
							(mid 0.249642 0.249642)
							(end 0.2794 0.1778)
						)
						(arc
							(start 0.2794 -0.1778)
							(mid 0.249642 -0.249642)
							(end 0.1778 -0.2794)
						)
					)
					(width 0)
					(fill yes)
				)
			)
		)
		(pad "2" smd custom
			(at 0 0.4445)
			(size 0.1397 0.1397)
			(layers "F.Cu" "F.Mask" "F.Paste")
			(net "GND")
			(options
				(clearance outline)
				(anchor circle)
			)
			(primitives
				(gr_poly
					(pts
						(arc
							(start -0.1778 -0.2794)
							(mid -0.249642 -0.249642)
							(end -0.2794 -0.1778)
						)
						(arc
							(start -0.2794 0.1778)
							(mid -0.249642 0.249642)
							(end -0.1778 0.2794)
						)
						(arc
							(start 0.1778 0.2794)
							(mid 0.249642 0.249642)
							(end 0.2794 0.1778)
						)
						(arc
							(start 0.2794 -0.1778)
							(mid 0.249642 -0.249642)
							(end 0.1778 -0.2794)
						)
					)
					(width 0)
					(fill yes)
				)
			)
		)
	)
	(footprint ""
		(layer "F.Cu")
		(at 191.135 -290.068)
		(property "Reference" "C111"
			(at 0 0 0)
			(layer "F.SilkS")
			(hide yes)
			(effects
				(font
					(size 1.27 1.27)
				)
			)
		)
		(property "Value" "SCD01U50V2KX-1GP"
			(at 1.1811 -2.7051 0)
			(unlocked yes)
			(layer "F.Fab")
			(hide yes)
			(effects
				(font
					(size 1.016 1.016)
					(thickness 0.1524)
				)
			)
		)
		(property "Device Type" "C402H22"
			(at 1.1811 -4.2291 0)
			(unlocked yes)
			(layer "F.Fab")
			(hide yes)
			(effects
				(font
					(size 1.016 1.016)
					(thickness 0.1524)
				)
			)
		)
		(duplicate_pad_numbers_are_jumpers no)
		(fp_rect
			(start -0.4318 0.9525)
			(end 0.4318 -0.9525)
			(stroke
				(width 0)
				(type default)
			)
			(fill no)
			(layer "F.CrtYd")
		)
		(fp_rect
			(start -0.4318 0.9525)
			(end 0.4318 -0.9525)
			(stroke
				(width 0)
				(type default)
			)
			(fill no)
			(layer "F.Fab")
		)
		(pad "1" smd custom
			(at 0 -0.4445)
			(size 0.1524 0.1524)
			(layers "F.Cu" "F.Mask" "F.Paste")
			(net "HDD_PRSNT_5")
			(options
				(clearance outline)
				(anchor circle)
			)
			(primitives
				(gr_poly
					(pts
						(arc
							(start 0.3048 -0.2032)
							(mid 0.275042 -0.275042)
							(end 0.2032 -0.3048)
						)
						(arc
							(start -0.2032 -0.3048)
							(mid -0.275042 -0.275042)
							(end -0.3048 -0.2032)
						)
						(arc
							(start -0.3048 0.2032)
							(mid -0.275042 0.275042)
							(end -0.2032 0.3048)
						)
						(arc
							(start 0.2032 0.3048)
							(mid 0.275042 0.275042)
							(end 0.3048 0.2032)
						)
					)
					(width 0)
					(fill yes)
				)
			)
		)
		(pad "2" smd custom
			(at 0 0.4445)
			(size 0.1524 0.1524)
			(layers "F.Cu" "F.Mask" "F.Paste")
			(net "GND")
			(options
				(clearance outline)
				(anchor circle)
			)
			(primitives
				(gr_poly
					(pts
						(arc
							(start 0.3048 -0.2032)
							(mid 0.275042 -0.275042)
							(end 0.2032 -0.3048)
						)
						(arc
							(start -0.2032 -0.3048)
							(mid -0.275042 -0.275042)
							(end -0.3048 -0.2032)
						)
						(arc
							(start -0.3048 0.2032)
							(mid -0.275042 0.275042)
							(end -0.2032 0.3048)
						)
						(arc
							(start 0.2032 0.3048)
							(mid 0.275042 0.275042)
							(end 0.3048 0.2032)
						)
					)
					(width 0)
					(fill yes)
				)
			)
		)
	)
	(footprint ""
		(layer "F.Cu")
		(at 77.942948 -59.857894)
		(property "Reference" "Q158"
			(at 0 0 0)
			(layer "F.SilkS")
			(hide yes)
			(effects
				(font
					(size 1.27 1.27)
				)
			)
		)
		(property "Value" "AO4407AL-GP"
			(at -3.707384 -1.5367 0)
			(unlocked yes)
			(layer "F.Fab")
			(hide yes)
			(effects
				(font
					(size 1.016 1.016)
					(thickness 0.1524)
				)
			)
		)
		(property "Device Type" "SOIC8H69"
			(at -3.707384 -3.0607 0)
			(unlocked yes)
			(layer "F.Fab")
			(hide yes)
			(effects
				(font
					(size 1.016 1.016)
					(thickness 0.1524)
				)
			)
		)
		(duplicate_pad_numbers_are_jumpers no)
		(fp_line
			(start -2.7432 -1.4224)
			(end -2.7432 1.4224)
			(stroke
				(width 0.1524)
				(type default)
			)
			(layer "F.SilkS")
		)
		(fp_line
			(start -2.7432 1.4224)
			(end -2.6416 1.4224)
			(stroke
				(width 0.1524)
				(type default)
			)
			(layer "F.SilkS")
		)
		(fp_line
			(start -2.7432 1.4224)
			(end 2.1336 1.4224)
			(stroke
				(width 0.1524)
				(type default)
			)
			(layer "F.SilkS")
		)
		(fp_line
			(start -2.7178 -0.508)
			(end -2.1844 -0.0508)
			(stroke
				(width 0.1524)
				(type default)
			)
			(layer "F.SilkS")
		)
		(fp_line
			(start -2.6289 3.4417)
			(end -2.6289 1.4732)
			(stroke
				(width 0.381)
				(type default)
			)
			(layer "F.SilkS")
		)
		(fp_line
			(start -2.1844 -0.0508)
			(end -2.7178 0.508)
			(stroke
				(width 0.1524)
				(type default)
			)
			(layer "F.SilkS")
		)
		(fp_line
			(start 2.1336 -1.4224)
			(end -2.7432 -1.4224)
			(stroke
				(width 0.1524)
				(type default)
			)
			(layer "F.SilkS")
		)
		(fp_line
			(start 2.1336 1.4224)
			(end 2.1336 -1.4224)
			(stroke
				(width 0.1524)
				(type default)
			)
			(layer "F.SilkS")
		)
		(fp_poly
			(pts
				(xy -2.2098 -1.4224) (xy -2.2098 1.4224) (xy 2.2098 1.4224) (xy 2.2098 -1.4224)
			)
			(stroke
				(width 0)
				(type default)
			)
			(fill yes)
			(layer "F.SilkS")
		)
		(fp_rect
			(start -2.450084 2.999994)
			(end 2.450084 -2.999994)
			(stroke
				(width 0)
				(type default)
			)
			(fill no)
			(layer "F.CrtYd")
		)
		(fp_poly
			(pts
				(xy -2.8194 3.6322) (xy -2.8194 -3.6322) (xy 2.8194 -3.6322) (xy 2.8194 1.18364) (xy 2.450084 1.18364)
				(xy 2.450084 -2.999994) (xy -2.450084 -2.999994) (xy -2.450084 2.999994) (xy 2.450084 2.999994)
				(xy 2.450084 1.18618) (xy 2.8194 1.18618) (xy 2.8194 3.6322)
			)
			(stroke
				(width 0)
				(type default)
			)
			(fill no)
			(layer "F.CrtYd")
		)
		(fp_rect
			(start -2.8194 3.6322)
			(end 2.8194 -3.6322)
			(stroke
				(width 0)
				(type default)
			)
			(fill no)
			(layer "F.Fab")
		)
		(pad "1" smd rect
			(at -1.905 2.54)
			(size 0.635 1.651)
			(layers "F.Cu" "F.Mask" "F.Paste")
			(net "P12V_A")
		)
		(pad "2" smd rect
			(at -0.635 2.54)
			(size 0.635 1.651)
			(layers "F.Cu" "F.Mask" "F.Paste")
			(net "P12V_A")
		)
		(pad "3" smd rect
			(at 0.635 2.54)
			(size 0.635 1.651)
			(layers "F.Cu" "F.Mask" "F.Paste")
			(net "P12V_A")
		)
		(pad "4" smd rect
			(at 1.905 2.54)
			(size 0.635 1.651)
			(layers "F.Cu" "F.Mask" "F.Paste")
			(net "SW_HDD_N26")
		)
		(pad "5" smd rect
			(at 1.905 -2.54)
			(size 0.635 1.651)
			(layers "F.Cu" "F.Mask" "F.Paste")
			(net "P12V_HDD26")
		)
		(pad "6" smd rect
			(at 0.635 -2.54)
			(size 0.635 1.651)
			(layers "F.Cu" "F.Mask" "F.Paste")
			(net "P12V_HDD26")
		)
		(pad "7" smd rect
			(at -0.635 -2.54)
			(size 0.635 1.651)
			(layers "F.Cu" "F.Mask" "F.Paste")
			(net "P12V_HDD26")
		)
		(pad "8" smd rect
			(at -1.905 -2.54)
			(size 0.635 1.651)
			(layers "F.Cu" "F.Mask" "F.Paste")
			(net "P12V_HDD26")
		)
	)
	(footprint ""
		(layer "F.Cu")
		(at 452.635112 -248.59869 -90)
		(property "Reference" "C640"
			(at 0 0 270)
			(layer "F.SilkS")
			(hide yes)
			(effects
				(font
					(size 1.27 1.27)
				)
			)
		)
		(property "Value" "SC2200P50V2KX-2GP"
			(at 1.1811 -2.7051 270)
			(unlocked yes)
			(layer "F.Fab")
			(hide yes)
			(effects
				(font
					(size 1.016 1.016)
					(thickness 0.1524)
				)
			)
		)
		(property "Device Type" "C402H22"
			(at 1.1811 -4.2291 270)
			(unlocked yes)
			(layer "F.Fab")
			(hide yes)
			(effects
				(font
					(size 1.016 1.016)
					(thickness 0.1524)
				)
			)
		)
		(duplicate_pad_numbers_are_jumpers no)
		(fp_rect
			(start -0.4318 0.9525)
			(end 0.4318 -0.9525)
			(stroke
				(width 0)
				(type default)
			)
			(fill no)
			(layer "F.CrtYd")
		)
		(fp_rect
			(start -0.4318 0.9525)
			(end 0.4318 -0.9525)
			(stroke
				(width 0)
				(type default)
			)
			(fill no)
			(layer "F.Fab")
		)
		(pad "1" smd custom
			(at 0 -0.4445 270)
			(size 0.1524 0.1524)
			(layers "F.Cu" "F.Mask" "F.Paste")
			(net "P5V_C_LL")
			(options
				(clearance outline)
				(anchor circle)
			)
			(primitives
				(gr_poly
					(pts
						(arc
							(start 0.3048 -0.2032)
							(mid 0.275042 -0.275042)
							(end 0.2032 -0.3048)
						)
						(arc
							(start -0.2032 -0.3048)
							(mid -0.275042 -0.275042)
							(end -0.3048 -0.2032)
						)
						(arc
							(start -0.3048 0.2032)
							(mid -0.275042 0.275042)
							(end -0.2032 0.3048)
						)
						(arc
							(start 0.2032 0.3048)
							(mid 0.275042 0.275042)
							(end 0.3048 0.2032)
						)
					)
					(width 0)
					(fill yes)
				)
			)
		)
		(pad "2" smd custom
			(at 0 0.4445 270)
			(size 0.1524 0.1524)
			(layers "F.Cu" "F.Mask" "F.Paste")
			(net "P5V_C_SNB")
			(options
				(clearance outline)
				(anchor circle)
			)
			(primitives
				(gr_poly
					(pts
						(arc
							(start 0.3048 -0.2032)
							(mid 0.275042 -0.275042)
							(end 0.2032 -0.3048)
						)
						(arc
							(start -0.2032 -0.3048)
							(mid -0.275042 -0.275042)
							(end -0.3048 -0.2032)
						)
						(arc
							(start -0.3048 0.2032)
							(mid -0.275042 0.275042)
							(end -0.2032 0.3048)
						)
						(arc
							(start 0.2032 0.3048)
							(mid 0.275042 0.275042)
							(end 0.3048 0.2032)
						)
					)
					(width 0)
					(fill yes)
				)
			)
		)
	)
	(footprint ""
		(layer "F.Cu")
		(at 363.655102 -45.252894 -90)
		(property "Reference" "Q187"
			(at 0 0 270)
			(layer "F.SilkS")
			(hide yes)
			(effects
				(font
					(size 1.27 1.27)
				)
			)
		)
		(property "Value" "2N7002KDW-GP"
			(at -2.3622 -8.2042 270)
			(unlocked yes)
			(layer "F.Fab")
			(hide yes)
			(effects
				(font
					(size 1.016 1.016)
					(thickness 0.1524)
				)
			)
		)
		(property "Device Type" "SOT-363H44"
			(at -2.3622 -10.1092 270)
			(unlocked yes)
			(layer "F.Fab")
			(hide yes)
			(effects
				(font
					(size 1.016 1.016)
					(thickness 0.1524)
				)
			)
		)
		(duplicate_pad_numbers_are_jumpers no)
		(fp_line
			(start -1.4478 1.7018)
			(end 1.4478 1.7018)
			(stroke
				(width 0.1524)
				(type default)
			)
			(layer "F.SilkS")
		)
		(fp_line
			(start 1.4478 1.7018)
			(end 1.4478 -1.7018)
			(stroke
				(width 0.1524)
				(type default)
			)
			(layer "F.SilkS")
		)
		(fp_line
			(start -1.27 1.524)
			(end -1.27 0.6604)
			(stroke
				(width 0.4826)
				(type default)
			)
			(layer "F.SilkS")
		)
		(fp_line
			(start -1.4478 -1.7018)
			(end -1.4478 1.7018)
			(stroke
				(width 0.1524)
				(type default)
			)
			(layer "F.SilkS")
		)
		(fp_line
			(start 1.4478 -1.7018)
			(end -1.4478 -1.7018)
			(stroke
				(width 0.1524)
				(type default)
			)
			(layer "F.SilkS")
		)
		(fp_poly
			(pts
				(xy -1.524 -1.778) (xy 1.524 -1.778) (xy 1.524 1.778) (xy -1.524 1.778)
			)
			(stroke
				(width 0)
				(type default)
			)
			(fill no)
			(layer "F.CrtYd")
		)
		(fp_poly
			(pts
				(xy -1.524 -1.778) (xy 1.524 -1.778) (xy 1.524 1.778) (xy -1.524 1.778)
			)
			(stroke
				(width 0)
				(type default)
			)
			(fill no)
			(layer "F.Fab")
		)
		(pad "1" smd rect
			(at -0.65024 0.9398 270)
			(size 0.4064 1.016)
			(layers "F.Cu" "F.Mask" "F.Paste")
			(net "GND")
		)
		(pad "2" smd rect
			(at 0 0.9398 270)
			(size 0.4064 1.016)
			(layers "F.Cu" "F.Mask" "F.Paste")
			(net "SW_PWR_R_HDD31")
		)
		(pad "3" smd rect
			(at 0.65024 0.9398 270)
			(size 0.4064 1.016)
			(layers "F.Cu" "F.Mask" "F.Paste")
			(net "SW_HDD_P31")
		)
		(pad "4" smd rect
			(at 0.65024 -0.9398 270)
			(size 0.4064 1.016)
			(layers "F.Cu" "F.Mask" "F.Paste")
			(net "GND")
		)
		(pad "5" smd rect
			(at 0 -0.9398 270)
			(size 0.4064 1.016)
			(layers "F.Cu" "F.Mask" "F.Paste")
			(net "SW_HDD_G31")
		)
		(pad "6" smd rect
			(at -0.65024 -0.9398 270)
			(size 0.4064 1.016)
			(layers "F.Cu" "F.Mask" "F.Paste")
			(net "SW_HDD_R31")
		)
	)
	(footprint ""
		(layer "F.Cu")
		(at 237.962694 -244.146578)
		(property "Reference" "R76"
			(at 0 0 0)
			(layer "F.SilkS")
			(hide yes)
			(effects
				(font
					(size 1.27 1.27)
				)
			)
		)
		(property "Value" "4K7R2F-GP"
			(at 0.064008 -3.993896 0)
			(unlocked yes)
			(layer "F.Fab")
			(hide yes)
			(effects
				(font
					(size 1.016 1.016)
					(thickness 0.1524)
				)
			)
		)
		(property "Device Type" "R402H16"
			(at 0.064008 -5.517896 0)
			(unlocked yes)
			(layer "F.Fab")
			(hide yes)
			(effects
				(font
					(size 1.016 1.016)
					(thickness 0.1524)
				)
			)
		)
		(duplicate_pad_numbers_are_jumpers no)
		(fp_line
			(start -0.508 -0.9398)
			(end -0.508 0.9398)
			(stroke
				(width 0.1524)
				(type default)
			)
			(layer "F.SilkS")
		)
		(fp_line
			(start 0.508 -0.9398)
			(end -0.508 -0.9398)
			(stroke
				(width 0.1524)
				(type default)
			)
			(layer "F.SilkS")
		)
		(fp_rect
			(start -0.508 0.9398)
			(end 0.508 -0.9398)
			(stroke
				(width 0)
				(type default)
			)
			(fill no)
			(layer "F.CrtYd")
		)
		(fp_rect
			(start -0.508 0.9398)
			(end 0.508 -0.9398)
			(stroke
				(width 0)
				(type default)
			)
			(fill no)
			(layer "F.Fab")
		)
		(pad "1" smd custom
			(at 0 -0.4445)
			(size 0.1397 0.1397)
			(layers "F.Cu" "F.Mask" "F.Paste")
			(net "P3V3_STBY_A")
			(options
				(clearance outline)
				(anchor circle)
			)
			(primitives
				(gr_poly
					(pts
						(arc
							(start -0.1778 -0.2794)
							(mid -0.249642 -0.249642)
							(end -0.2794 -0.1778)
						)
						(arc
							(start -0.2794 0.1778)
							(mid -0.249642 0.249642)
							(end -0.1778 0.2794)
						)
						(arc
							(start 0.1778 0.2794)
							(mid 0.249642 0.249642)
							(end 0.2794 0.1778)
						)
						(arc
							(start 0.2794 -0.1778)
							(mid 0.249642 -0.249642)
							(end 0.1778 -0.2794)
						)
					)
					(width 0)
					(fill yes)
				)
			)
		)
		(pad "2" smd custom
			(at 0 0.4445)
			(size 0.1397 0.1397)
			(layers "F.Cu" "F.Mask" "F.Paste")
			(net "IO_EXP1_INT_N")
			(options
				(clearance outline)
				(anchor circle)
			)
			(primitives
				(gr_poly
					(pts
						(arc
							(start -0.1778 -0.2794)
							(mid -0.249642 -0.249642)
							(end -0.2794 -0.1778)
						)
						(arc
							(start -0.2794 0.1778)
							(mid -0.249642 0.249642)
							(end -0.1778 0.2794)
						)
						(arc
							(start 0.1778 0.2794)
							(mid 0.249642 0.249642)
							(end 0.2794 0.1778)
						)
						(arc
							(start 0.2794 -0.1778)
							(mid 0.249642 -0.249642)
							(end 0.1778 -0.2794)
						)
					)
					(width 0)
					(fill yes)
				)
			)
		)
	)
	(footprint ""
		(layer "F.Cu")
		(at 350.1136 -298.704)
		(property "Reference" "TP37"
			(at 0 0 0)
			(layer "F.SilkS")
			(hide yes)
			(effects
				(font
					(size 1.27 1.27)
				)
			)
		)
		(property "Value" "TPAD32-GP"
			(at -0.0508 -1.6764 0)
			(unlocked yes)
			(layer "F.Fab")
			(hide yes)
			(effects
				(font
					(size 1.016 1.016)
					(thickness 0.1524)
				)
			)
		)
		(property "Device Type" "TPAD32"
			(at -0.0508 -3.2004 0)
			(unlocked yes)
			(layer "F.Fab")
			(hide yes)
			(effects
				(font
					(size 1.016 1.016)
					(thickness 0.1524)
				)
			)
		)
		(duplicate_pad_numbers_are_jumpers no)
		(fp_poly
			(pts
				(arc
					(start 0.4064 0)
					(mid -0.4064 0)
					(end 0.4064 0)
				)
			)
			(stroke
				(width 0)
				(type default)
			)
			(fill no)
			(layer "F.CrtYd")
		)
		(fp_poly
			(pts
				(arc
					(start 0.7112 0)
					(mid -0.7112 0)
					(end 0.7112 0)
				)
			)
			(stroke
				(width 0)
				(type default)
			)
			(fill no)
			(layer "F.Fab")
		)
		(pad "1" smd circle
			(at 0 0)
			(size 0.8128 0.8128)
			(layers "F.Cu" "F.Mask" "F.Paste")
			(net "ACT_HDD_7")
		)
	)
	(footprint ""
		(layer "F.Cu")
		(at 55.486046 -301.287942)
		(property "Reference" "C58"
			(at 0 0 0)
			(layer "F.SilkS")
			(hide yes)
			(effects
				(font
					(size 1.27 1.27)
				)
			)
		)
		(property "Value" "SC4D7U25V5KX-1-GP"
			(at -0.0762 -6.1214 0)
			(unlocked yes)
			(layer "F.Fab")
			(hide yes)
			(effects
				(font
					(size 1.016 1.016)
					(thickness 0.1524)
				)
			)
		)
		(property "Device Type" "C805H58"
			(at -0.0762 -8.1534 0)
			(unlocked yes)
			(layer "F.Fab")
			(hide yes)
			(effects
				(font
					(size 1.016 1.016)
					(thickness 0.1524)
				)
			)
		)
		(duplicate_pad_numbers_are_jumpers no)
		(fp_line
			(start 0.635 0)
			(end -0.635 0)
			(stroke
				(width 0.508)
				(type default)
			)
			(layer "F.SilkS")
		)
		(fp_rect
			(start -0.9652 1.778)
			(end 0.9652 -1.778)
			(stroke
				(width 0)
				(type default)
			)
			(fill no)
			(layer "F.CrtYd")
		)
		(fp_poly
			(pts
				(xy -0.9652 -1.778) (xy 0.9652 -1.778) (xy 0.9652 1.778) (xy -0.9652 1.778)
			)
			(stroke
				(width 0)
				(type default)
			)
			(fill no)
			(layer "F.Fab")
		)
		(pad "1" smd rect
			(at 0 -0.9652)
			(size 1.397 1.143)
			(layers "F.Cu" "F.Mask" "F.Paste")
			(net "P12V_HDD1")
		)
		(pad "2" smd rect
			(at 0 0.9652)
			(size 1.397 1.143)
			(layers "F.Cu" "F.Mask" "F.Paste")
			(net "GND")
		)
	)
	(footprint ""
		(layer "F.Cu")
		(at 329.819 -189.335918 180)
		(property "Reference" "C281"
			(at 0 0 180)
			(layer "F.SilkS")
			(hide yes)
			(effects
				(font
					(size 1.27 1.27)
				)
			)
		)
		(property "Value" "SC1U25V3KX-GP"
			(at 0 -2.8194 180)
			(unlocked yes)
			(layer "F.Fab")
			(hide yes)
			(effects
				(font
					(size 1.016 1.016)
					(thickness 0.1524)
				)
			)
		)
		(property "Device Type" "C603H36"
			(at 0 -4.3434 180)
			(unlocked yes)
			(layer "F.Fab")
			(hide yes)
			(effects
				(font
					(size 1.016 1.016)
					(thickness 0.1524)
				)
			)
		)
		(duplicate_pad_numbers_are_jumpers no)
		(fp_line
			(start 0.508 0)
			(end -0.508 0)
			(stroke
				(width 0.2032)
				(type default)
			)
			(layer "F.SilkS")
		)
		(fp_rect
			(start -0.5842 1.3335)
			(end 0.5842 -1.3335)
			(stroke
				(width 0)
				(type default)
			)
			(fill no)
			(layer "F.CrtYd")
		)
		(fp_rect
			(start -0.5842 1.3335)
			(end 0.5842 -1.3335)
			(stroke
				(width 0)
				(type default)
			)
			(fill no)
			(layer "F.Fab")
		)
		(pad "1" smd custom
			(at 0 -0.762 180)
			(size 0.2159 0.2159)
			(layers "F.Cu" "F.Mask" "F.Paste")
			(net "P12V_HDD18")
			(options
				(clearance outline)
				(anchor circle)
			)
			(primitives
				(gr_poly
					(pts
						(arc
							(start -0.3302 -0.4318)
							(mid -0.402042 -0.402042)
							(end -0.4318 -0.3302)
						)
						(arc
							(start -0.4318 0.3302)
							(mid -0.402042 0.402042)
							(end -0.3302 0.4318)
						)
						(arc
							(start 0.3302 0.4318)
							(mid 0.402042 0.402042)
							(end 0.4318 0.3302)
						)
						(arc
							(start 0.4318 -0.3302)
							(mid 0.402042 -0.402042)
							(end 0.3302 -0.4318)
						)
					)
					(width 0)
					(fill yes)
				)
			)
		)
		(pad "2" smd custom
			(at 0 0.762 180)
			(size 0.2159 0.2159)
			(layers "F.Cu" "F.Mask" "F.Paste")
			(net "GND")
			(options
				(clearance outline)
				(anchor circle)
			)
			(primitives
				(gr_poly
					(pts
						(arc
							(start -0.3302 -0.4318)
							(mid -0.402042 -0.402042)
							(end -0.4318 -0.3302)
						)
						(arc
							(start -0.4318 0.3302)
							(mid -0.402042 0.402042)
							(end -0.3302 0.4318)
						)
						(arc
							(start 0.3302 0.4318)
							(mid 0.402042 0.402042)
							(end 0.4318 0.3302)
						)
						(arc
							(start 0.4318 -0.3302)
							(mid 0.402042 -0.402042)
							(end 0.3302 -0.4318)
						)
					)
					(width 0)
					(fill yes)
				)
			)
		)
	)
	(footprint ""
		(layer "F.Cu")
		(at 272.542 -355.905054 180)
		(property "Reference" "VIA37"
			(at 0 0 180)
			(layer "F.SilkS")
			(hide yes)
			(effects
				(font
					(size 1.27 1.27)
				)
			)
		)
		(property "Value" "100OHM-8L-1D6MM-L18L16-GP"
			(at -3.7211 -4.5085 180)
			(unlocked yes)
			(layer "F.Fab")
			(hide yes)
			(effects
				(font
					(size 1.016 1.016)
					(thickness 0.1524)
				)
			)
		)
		(property "Device Type" "VIA-PCIE-4P-394076"
			(at -3.7211 -6.0325 180)
			(unlocked yes)
			(layer "F.Fab")
			(hide yes)
			(effects
				(font
					(size 1.016 1.016)
					(thickness 0.1524)
				)
			)
		)
		(duplicate_pad_numbers_are_jumpers no)
		(fp_rect
			(start -1.9685 0.381)
			(end 1.9685 -0.381)
			(stroke
				(width 0)
				(type default)
			)
			(fill no)
			(layer "F.CrtYd")
		)
		(fp_rect
			(start -1.9685 0.381)
			(end 1.9685 -0.381)
			(stroke
				(width 0)
				(type default)
			)
			(fill no)
			(layer "F.Fab")
		)
		(pad "1" thru_hole circle
			(at -1.5875 0 180)
			(size 0.508 0.508)
			(drill 0.254)
			(layers "*.Cu" "*.Mask")
			(remove_unused_layers no)
			(net "GND")
			(clearance 0.127)
			(thermal_gap 0.127)
		)
		(pad "2" thru_hole circle
			(at -0.5715 0 180)
			(size 0.508 0.508)
			(drill 0.254)
			(layers "*.Cu" "*.Mask")
			(remove_unused_layers no)
			(net "PHY_SCC_A_TO_DRV_A_2_DP")
			(clearance 0.127)
			(thermal_gap 0.127)
		)
		(pad "3" thru_hole circle
			(at 0.5715 0 180)
			(size 0.508 0.508)
			(drill 0.254)
			(layers "*.Cu" "*.Mask")
			(remove_unused_layers no)
			(net "PHY_SCC_A_TO_DRV_A_2_DN")
			(clearance 0.127)
			(thermal_gap 0.127)
		)
		(pad "4" thru_hole circle
			(at 1.5875 0 180)
			(size 0.508 0.508)
			(drill 0.254)
			(layers "*.Cu" "*.Mask")
			(remove_unused_layers no)
			(net "GND")
			(clearance 0.127)
			(thermal_gap 0.127)
		)
	)
	(footprint ""
		(layer "F.Cu")
		(at 17.800066 -94.400116)
		(property "Reference" "FLED13"
			(at 0 0 0)
			(layer "F.SilkS")
			(hide yes)
			(effects
				(font
					(size 1.27 1.27)
				)
			)
		)
		(property "Value" "LED-BY-19-GP"
			(at -2.132076 1.414018 0)
			(unlocked yes)
			(layer "F.Fab")
			(hide yes)
			(effects
				(font
					(size 1.016 1.016)
					(thickness 0.1524)
				)
			)
		)
		(property "Device Type" "LED-1615-4PH26"
			(at -2.132076 -0.109982 0)
			(unlocked yes)
			(layer "F.Fab")
			(hide yes)
			(effects
				(font
					(size 1.016 1.016)
					(thickness 0.1524)
				)
			)
		)
		(duplicate_pad_numbers_are_jumpers no)
		(fp_line
			(start -1.2954 0.254)
			(end -1.2954 1.6002)
			(stroke
				(width 0.508)
				(type default)
			)
			(layer "F.SilkS")
		)
		(fp_line
			(start -1.2954 1.6002)
			(end 1.2954 1.6002)
			(stroke
				(width 0.508)
				(type default)
			)
			(layer "F.SilkS")
		)
		(fp_line
			(start -1.1176 -1.4224)
			(end 1.1176 -1.4224)
			(stroke
				(width 0.1524)
				(type default)
			)
			(layer "F.SilkS")
		)
		(fp_line
			(start -1.1176 1.4224)
			(end -1.1176 -1.4224)
			(stroke
				(width 0.1524)
				(type default)
			)
			(layer "F.SilkS")
		)
		(fp_line
			(start 1.1176 -1.4224)
			(end 1.1176 1.4224)
			(stroke
				(width 0.1524)
				(type default)
			)
			(layer "F.SilkS")
		)
		(fp_line
			(start 1.1176 1.4224)
			(end -1.1176 1.4224)
			(stroke
				(width 0.1524)
				(type default)
			)
			(layer "F.SilkS")
		)
		(fp_line
			(start 1.2954 1.6002)
			(end 1.2954 0.254)
			(stroke
				(width 0.508)
				(type default)
			)
			(layer "F.SilkS")
		)
		(fp_rect
			(start -0.7493 0.8001)
			(end 0.7493 -0.8001)
			(stroke
				(width 0)
				(type default)
			)
			(fill no)
			(layer "F.CrtYd")
		)
		(fp_poly
			(pts
				(xy -1.3716 1.6764) (xy -1.3716 -1.6764) (xy 1.3716 -1.6764) (xy 1.3716 0.0635) (xy 0.7493 0.0635)
				(xy 0.7493 -0.8001) (xy -0.7493 -0.8001) (xy -0.7493 0.8001) (xy 0.7493 0.8001) (xy 0.7493 0.0762)
				(xy 1.3716 0.0762) (xy 1.3716 1.6764)
			)
			(stroke
				(width 0)
				(type default)
			)
			(fill no)
			(layer "F.CrtYd")
		)
		(fp_rect
			(start -1.3716 1.6764)
			(end 1.3716 -1.6764)
			(stroke
				(width 0)
				(type default)
			)
			(fill no)
			(layer "F.Fab")
		)
		(pad "1" smd rect
			(at 0.50038 -0.73025)
			(size 0.7112 0.8636)
			(layers "F.Cu" "F.Mask" "F.Paste")
			(net "DRV_ACT_12")
		)
		(pad "2" smd rect
			(at -0.50038 -0.73025)
			(size 0.7112 0.8636)
			(layers "F.Cu" "F.Mask" "F.Paste")
			(net "FLT_HDD12")
		)
		(pad "3" smd rect
			(at 0.50038 0.73025)
			(size 0.7112 0.8636)
			(layers "F.Cu" "F.Mask" "F.Paste")
			(net "DRV_ACT_12_N")
		)
		(pad "4" smd rect
			(at -0.50038 0.73025)
			(size 0.7112 0.8636)
			(layers "F.Cu" "F.Mask" "F.Paste")
			(net "FLT_HDD12_N")
		)
	)
	(footprint ""
		(layer "F.Cu")
		(at 226.7458 -390.377172)
		(property "Reference" "R1293"
			(at 0 0 0)
			(layer "F.SilkS")
			(hide yes)
			(effects
				(font
					(size 1.27 1.27)
				)
			)
		)
		(property "Value" "3K3R3F-GP"
			(at -0.0254 -2.5146 0)
			(unlocked yes)
			(layer "F.Fab")
			(hide yes)
			(effects
				(font
					(size 1.016 1.016)
					(thickness 0.1524)
				)
			)
		)
		(property "Device Type" "R603H22"
			(at -0.0254 -4.0386 0)
			(unlocked yes)
			(layer "F.Fab")
			(hide yes)
			(effects
				(font
					(size 1.016 1.016)
					(thickness 0.1524)
				)
			)
		)
		(duplicate_pad_numbers_are_jumpers no)
		(fp_line
			(start -0.4826 0)
			(end -0.2032 0)
			(stroke
				(width 0.2032)
				(type default)
			)
			(layer "F.SilkS")
		)
		(fp_line
			(start 0.2032 0)
			(end 0.4826 0)
			(stroke
				(width 0.2032)
				(type default)
			)
			(layer "F.SilkS")
		)
		(fp_rect
			(start -0.5842 1.3335)
			(end 0.5842 -1.3335)
			(stroke
				(width 0)
				(type default)
			)
			(fill no)
			(layer "F.CrtYd")
		)
		(fp_rect
			(start -0.5842 1.3335)
			(end 0.5842 -1.3335)
			(stroke
				(width 0)
				(type default)
			)
			(fill no)
			(layer "F.Fab")
		)
		(pad "1" smd custom
			(at 0 -0.762)
			(size 0.2159 0.2159)
			(layers "F.Cu" "F.Mask" "F.Paste")
			(net "P12V_IN")
			(options
				(clearance outline)
				(anchor circle)
			)
			(primitives
				(gr_poly
					(pts
						(arc
							(start -0.3302 -0.4318)
							(mid -0.402042 -0.402042)
							(end -0.4318 -0.3302)
						)
						(arc
							(start -0.4318 0.3302)
							(mid -0.402042 0.402042)
							(end -0.3302 0.4318)
						)
						(arc
							(start 0.3302 0.4318)
							(mid 0.402042 0.402042)
							(end 0.4318 0.3302)
						)
						(arc
							(start 0.4318 -0.3302)
							(mid 0.402042 -0.402042)
							(end 0.3302 -0.4318)
						)
					)
					(width 0)
					(fill yes)
				)
			)
		)
		(pad "2" smd custom
			(at 0 0.762)
			(size 0.2159 0.2159)
			(layers "F.Cu" "F.Mask" "F.Paste")
			(net "VCCP_IN")
			(options
				(clearance outline)
				(anchor circle)
			)
			(primitives
				(gr_poly
					(pts
						(arc
							(start -0.3302 -0.4318)
							(mid -0.402042 -0.402042)
							(end -0.4318 -0.3302)
						)
						(arc
							(start -0.4318 0.3302)
							(mid -0.402042 0.402042)
							(end -0.3302 0.4318)
						)
						(arc
							(start 0.3302 0.4318)
							(mid 0.402042 0.402042)
							(end 0.4318 0.3302)
						)
						(arc
							(start 0.4318 -0.3302)
							(mid 0.402042 -0.402042)
							(end 0.3302 -0.4318)
						)
					)
					(width 0)
					(fill yes)
				)
			)
		)
	)
	(footprint ""
		(layer "F.Cu")
		(at 111.499396 -168.126918 -90)
		(property "Reference" "C243"
			(at 0 0 270)
			(layer "F.SilkS")
			(hide yes)
			(effects
				(font
					(size 1.27 1.27)
				)
			)
		)
		(property "Value" "SCD033U25V2KX-GP"
			(at 1.1811 -2.7051 270)
			(unlocked yes)
			(layer "F.Fab")
			(hide yes)
			(effects
				(font
					(size 1.016 1.016)
					(thickness 0.1524)
				)
			)
		)
		(property "Device Type" "C402H22"
			(at 1.1811 -4.2291 270)
			(unlocked yes)
			(layer "F.Fab")
			(hide yes)
			(effects
				(font
					(size 1.016 1.016)
					(thickness 0.1524)
				)
			)
		)
		(duplicate_pad_numbers_are_jumpers no)
		(fp_rect
			(start -0.4318 0.9525)
			(end 0.4318 -0.9525)
			(stroke
				(width 0)
				(type default)
			)
			(fill no)
			(layer "F.CrtYd")
		)
		(fp_rect
			(start -0.4318 0.9525)
			(end 0.4318 -0.9525)
			(stroke
				(width 0)
				(type default)
			)
			(fill no)
			(layer "F.Fab")
		)
		(pad "1" smd custom
			(at 0 -0.4445 270)
			(size 0.1524 0.1524)
			(layers "F.Cu" "F.Mask" "F.Paste")
			(net "SW_HDD_P15")
			(options
				(clearance outline)
				(anchor circle)
			)
			(primitives
				(gr_poly
					(pts
						(arc
							(start 0.3048 -0.2032)
							(mid 0.275042 -0.275042)
							(end 0.2032 -0.3048)
						)
						(arc
							(start -0.2032 -0.3048)
							(mid -0.275042 -0.275042)
							(end -0.3048 -0.2032)
						)
						(arc
							(start -0.3048 0.2032)
							(mid -0.275042 0.275042)
							(end -0.2032 0.3048)
						)
						(arc
							(start 0.2032 0.3048)
							(mid 0.275042 0.275042)
							(end 0.3048 0.2032)
						)
					)
					(width 0)
					(fill yes)
				)
			)
		)
		(pad "2" smd custom
			(at 0 0.4445 270)
			(size 0.1524 0.1524)
			(layers "F.Cu" "F.Mask" "F.Paste")
			(net "GND")
			(options
				(clearance outline)
				(anchor circle)
			)
			(primitives
				(gr_poly
					(pts
						(arc
							(start 0.3048 -0.2032)
							(mid 0.275042 -0.275042)
							(end 0.2032 -0.3048)
						)
						(arc
							(start -0.2032 -0.3048)
							(mid -0.275042 -0.275042)
							(end -0.3048 -0.2032)
						)
						(arc
							(start -0.3048 0.2032)
							(mid -0.275042 0.275042)
							(end -0.2032 0.3048)
						)
						(arc
							(start 0.2032 0.3048)
							(mid 0.275042 0.275042)
							(end 0.3048 0.2032)
						)
					)
					(width 0)
					(fill yes)
				)
			)
		)
	)
	(footprint ""
		(layer "F.Cu")
		(at 283.2608 -272.3134 180)
		(property "Reference" "R120"
			(at 0 0 180)
			(layer "F.SilkS")
			(hide yes)
			(effects
				(font
					(size 1.27 1.27)
				)
			)
		)
		(property "Value" "4K7R2F-GP"
			(at 0.064008 -3.993896 180)
			(unlocked yes)
			(layer "F.Fab")
			(hide yes)
			(effects
				(font
					(size 1.016 1.016)
					(thickness 0.1524)
				)
			)
		)
		(property "Device Type" "R402H16"
			(at 0.064008 -5.517896 180)
			(unlocked yes)
			(layer "F.Fab")
			(hide yes)
			(effects
				(font
					(size 1.016 1.016)
					(thickness 0.1524)
				)
			)
		)
		(duplicate_pad_numbers_are_jumpers no)
		(fp_line
			(start 0.508 -0.9398)
			(end -0.508 -0.9398)
			(stroke
				(width 0.1524)
				(type default)
			)
			(layer "F.SilkS")
		)
		(fp_line
			(start -0.508 -0.9398)
			(end -0.508 0.9398)
			(stroke
				(width 0.1524)
				(type default)
			)
			(layer "F.SilkS")
		)
		(fp_rect
			(start -0.508 0.9398)
			(end 0.508 -0.9398)
			(stroke
				(width 0)
				(type default)
			)
			(fill no)
			(layer "F.CrtYd")
		)
		(fp_rect
			(start -0.508 0.9398)
			(end 0.508 -0.9398)
			(stroke
				(width 0)
				(type default)
			)
			(fill no)
			(layer "F.Fab")
		)
		(pad "1" smd custom
			(at 0 -0.4445 180)
			(size 0.1397 0.1397)
			(layers "F.Cu" "F.Mask" "F.Paste")
			(net "P3V3_STBY_A")
			(options
				(clearance outline)
				(anchor circle)
			)
			(primitives
				(gr_poly
					(pts
						(arc
							(start -0.1778 -0.2794)
							(mid -0.249642 -0.249642)
							(end -0.2794 -0.1778)
						)
						(arc
							(start -0.2794 0.1778)
							(mid -0.249642 0.249642)
							(end -0.1778 0.2794)
						)
						(arc
							(start 0.1778 0.2794)
							(mid 0.249642 0.249642)
							(end 0.2794 0.1778)
						)
						(arc
							(start 0.2794 -0.1778)
							(mid 0.249642 -0.249642)
							(end 0.1778 -0.2794)
						)
					)
					(width 0)
					(fill yes)
				)
			)
		)
		(pad "2" smd custom
			(at 0 0.4445 180)
			(size 0.1397 0.1397)
			(layers "F.Cu" "F.Mask" "F.Paste")
			(net "IO_EXP2_HDD_FAULT_A1")
			(options
				(clearance outline)
				(anchor circle)
			)
			(primitives
				(gr_poly
					(pts
						(arc
							(start -0.1778 -0.2794)
							(mid -0.249642 -0.249642)
							(end -0.2794 -0.1778)
						)
						(arc
							(start -0.2794 0.1778)
							(mid -0.249642 0.249642)
							(end -0.1778 0.2794)
						)
						(arc
							(start 0.1778 0.2794)
							(mid 0.249642 0.249642)
							(end 0.2794 0.1778)
						)
						(arc
							(start 0.2794 -0.1778)
							(mid 0.249642 -0.249642)
							(end 0.1778 -0.2794)
						)
					)
					(width 0)
					(fill yes)
				)
			)
		)
	)
	(footprint ""
		(layer "F.Cu")
		(at 111.499396 -167.085518 90)
		(property "Reference" "R482"
			(at 0 0 90)
			(layer "F.SilkS")
			(hide yes)
			(effects
				(font
					(size 1.27 1.27)
				)
			)
		)
		(property "Value" "4K7R2J-2-GP"
			(at 0.064008 -3.993896 90)
			(unlocked yes)
			(layer "F.Fab")
			(hide yes)
			(effects
				(font
					(size 1.016 1.016)
					(thickness 0.1524)
				)
			)
		)
		(property "Device Type" "R402H16"
			(at 0.064008 -5.517896 90)
			(unlocked yes)
			(layer "F.Fab")
			(hide yes)
			(effects
				(font
					(size 1.016 1.016)
					(thickness 0.1524)
				)
			)
		)
		(duplicate_pad_numbers_are_jumpers no)
		(fp_line
			(start 0.508 -0.9398)
			(end -0.508 -0.9398)
			(stroke
				(width 0.1524)
				(type default)
			)
			(layer "F.SilkS")
		)
		(fp_line
			(start -0.508 -0.9398)
			(end -0.508 0.9398)
			(stroke
				(width 0.1524)
				(type default)
			)
			(layer "F.SilkS")
		)
		(fp_rect
			(start -0.508 0.9398)
			(end 0.508 -0.9398)
			(stroke
				(width 0)
				(type default)
			)
			(fill no)
			(layer "F.CrtYd")
		)
		(fp_rect
			(start -0.508 0.9398)
			(end 0.508 -0.9398)
			(stroke
				(width 0)
				(type default)
			)
			(fill no)
			(layer "F.Fab")
		)
		(pad "1" smd custom
			(at 0 -0.4445 90)
			(size 0.1397 0.1397)
			(layers "F.Cu" "F.Mask" "F.Paste")
			(net "P12V_A")
			(options
				(clearance outline)
				(anchor circle)
			)
			(primitives
				(gr_poly
					(pts
						(arc
							(start -0.1778 -0.2794)
							(mid -0.249642 -0.249642)
							(end -0.2794 -0.1778)
						)
						(arc
							(start -0.2794 0.1778)
							(mid -0.249642 0.249642)
							(end -0.1778 0.2794)
						)
						(arc
							(start 0.1778 0.2794)
							(mid 0.249642 0.249642)
							(end 0.2794 0.1778)
						)
						(arc
							(start 0.2794 -0.1778)
							(mid 0.249642 -0.249642)
							(end 0.1778 -0.2794)
						)
					)
					(width 0)
					(fill yes)
				)
			)
		)
		(pad "2" smd custom
			(at 0 0.4445 90)
			(size 0.1397 0.1397)
			(layers "F.Cu" "F.Mask" "F.Paste")
			(net "SW_HDD_P15")
			(options
				(clearance outline)
				(anchor circle)
			)
			(primitives
				(gr_poly
					(pts
						(arc
							(start -0.1778 -0.2794)
							(mid -0.249642 -0.249642)
							(end -0.2794 -0.1778)
						)
						(arc
							(start -0.2794 0.1778)
							(mid -0.249642 0.249642)
							(end -0.1778 0.2794)
						)
						(arc
							(start 0.1778 0.2794)
							(mid 0.249642 0.249642)
							(end 0.2794 0.1778)
						)
						(arc
							(start 0.2794 -0.1778)
							(mid 0.249642 -0.249642)
							(end 0.1778 -0.2794)
						)
					)
					(width 0)
					(fill yes)
				)
			)
		)
	)
	(footprint ""
		(layer "F.Cu")
		(at 427.390052 -278.554942 -90)
		(property "Reference" "R344"
			(at 0 0 270)
			(layer "F.SilkS")
			(hide yes)
			(effects
				(font
					(size 1.27 1.27)
				)
			)
		)
		(property "Value" "4K7R2J-2-GP"
			(at 0.064008 -3.993896 270)
			(unlocked yes)
			(layer "F.Fab")
			(hide yes)
			(effects
				(font
					(size 1.016 1.016)
					(thickness 0.1524)
				)
			)
		)
		(property "Device Type" "R402H16"
			(at 0.064008 -5.517896 270)
			(unlocked yes)
			(layer "F.Fab")
			(hide yes)
			(effects
				(font
					(size 1.016 1.016)
					(thickness 0.1524)
				)
			)
		)
		(duplicate_pad_numbers_are_jumpers no)
		(fp_line
			(start -0.508 -0.9398)
			(end -0.508 0.9398)
			(stroke
				(width 0.1524)
				(type default)
			)
			(layer "F.SilkS")
		)
		(fp_line
			(start 0.508 -0.9398)
			(end -0.508 -0.9398)
			(stroke
				(width 0.1524)
				(type default)
			)
			(layer "F.SilkS")
		)
		(fp_rect
			(start -0.508 0.9398)
			(end 0.508 -0.9398)
			(stroke
				(width 0)
				(type default)
			)
			(fill no)
			(layer "F.CrtYd")
		)
		(fp_rect
			(start -0.508 0.9398)
			(end 0.508 -0.9398)
			(stroke
				(width 0)
				(type default)
			)
			(fill no)
			(layer "F.Fab")
		)
		(pad "1" smd custom
			(at 0 -0.4445 270)
			(size 0.1397 0.1397)
			(layers "F.Cu" "F.Mask" "F.Paste")
			(net "P12V_A")
			(options
				(clearance outline)
				(anchor circle)
			)
			(primitives
				(gr_poly
					(pts
						(arc
							(start -0.1778 -0.2794)
							(mid -0.249642 -0.249642)
							(end -0.2794 -0.1778)
						)
						(arc
							(start -0.2794 0.1778)
							(mid -0.249642 0.249642)
							(end -0.1778 0.2794)
						)
						(arc
							(start 0.1778 0.2794)
							(mid 0.249642 0.249642)
							(end 0.2794 0.1778)
						)
						(arc
							(start 0.2794 -0.1778)
							(mid 0.249642 -0.249642)
							(end 0.1778 -0.2794)
						)
					)
					(width 0)
					(fill yes)
				)
			)
		)
		(pad "2" smd custom
			(at 0 0.4445 270)
			(size 0.1397 0.1397)
			(layers "F.Cu" "F.Mask" "F.Paste")
			(net "SW_HDD_P9")
			(options
				(clearance outline)
				(anchor circle)
			)
			(primitives
				(gr_poly
					(pts
						(arc
							(start -0.1778 -0.2794)
							(mid -0.249642 -0.249642)
							(end -0.2794 -0.1778)
						)
						(arc
							(start -0.2794 0.1778)
							(mid -0.249642 0.249642)
							(end -0.1778 0.2794)
						)
						(arc
							(start 0.1778 0.2794)
							(mid 0.249642 0.249642)
							(end 0.2794 0.1778)
						)
						(arc
							(start 0.2794 -0.1778)
							(mid 0.249642 -0.249642)
							(end 0.1778 -0.2794)
						)
					)
					(width 0)
					(fill yes)
				)
			)
		)
	)
	(footprint ""
		(layer "F.Cu")
		(at 329.819 -296.842942 180)
		(property "Reference" "C118"
			(at 0 0 180)
			(layer "F.SilkS")
			(hide yes)
			(effects
				(font
					(size 1.27 1.27)
				)
			)
		)
		(property "Value" "SC1U16V3KX-5GP"
			(at 0 -2.8194 180)
			(unlocked yes)
			(layer "F.Fab")
			(hide yes)
			(effects
				(font
					(size 1.016 1.016)
					(thickness 0.1524)
				)
			)
		)
		(property "Device Type" "C603H36"
			(at 0 -4.3434 180)
			(unlocked yes)
			(layer "F.Fab")
			(hide yes)
			(effects
				(font
					(size 1.016 1.016)
					(thickness 0.1524)
				)
			)
		)
		(duplicate_pad_numbers_are_jumpers no)
		(fp_line
			(start 0.508 0)
			(end -0.508 0)
			(stroke
				(width 0.2032)
				(type default)
			)
			(layer "F.SilkS")
		)
		(fp_rect
			(start -0.5842 1.3335)
			(end 0.5842 -1.3335)
			(stroke
				(width 0)
				(type default)
			)
			(fill no)
			(layer "F.CrtYd")
		)
		(fp_rect
			(start -0.5842 1.3335)
			(end 0.5842 -1.3335)
			(stroke
				(width 0)
				(type default)
			)
			(fill no)
			(layer "F.Fab")
		)
		(pad "1" smd custom
			(at 0 -0.762 180)
			(size 0.2159 0.2159)
			(layers "F.Cu" "F.Mask" "F.Paste")
			(net "P5V_HDD6")
			(options
				(clearance outline)
				(anchor circle)
			)
			(primitives
				(gr_poly
					(pts
						(arc
							(start -0.3302 -0.4318)
							(mid -0.402042 -0.402042)
							(end -0.4318 -0.3302)
						)
						(arc
							(start -0.4318 0.3302)
							(mid -0.402042 0.402042)
							(end -0.3302 0.4318)
						)
						(arc
							(start 0.3302 0.4318)
							(mid 0.402042 0.402042)
							(end 0.4318 0.3302)
						)
						(arc
							(start 0.4318 -0.3302)
							(mid 0.402042 -0.402042)
							(end 0.3302 -0.4318)
						)
					)
					(width 0)
					(fill yes)
				)
			)
		)
		(pad "2" smd custom
			(at 0 0.762 180)
			(size 0.2159 0.2159)
			(layers "F.Cu" "F.Mask" "F.Paste")
			(net "GND")
			(options
				(clearance outline)
				(anchor circle)
			)
			(primitives
				(gr_poly
					(pts
						(arc
							(start -0.3302 -0.4318)
							(mid -0.402042 -0.402042)
							(end -0.4318 -0.3302)
						)
						(arc
							(start -0.4318 0.3302)
							(mid -0.402042 0.402042)
							(end -0.3302 0.4318)
						)
						(arc
							(start 0.3302 0.4318)
							(mid 0.402042 0.402042)
							(end 0.4318 0.3302)
						)
						(arc
							(start 0.4318 -0.3302)
							(mid 0.402042 -0.402042)
							(end 0.3302 -0.4318)
						)
					)
					(width 0)
					(fill yes)
				)
			)
		)
	)
	(footprint ""
		(layer "F.Cu")
		(at 175.550068 -324.39991)
		(property "Reference" "RLED30"
			(at 0 0 0)
			(layer "F.SilkS")
			(hide yes)
			(effects
				(font
					(size 1.27 1.27)
				)
			)
		)
		(property "Value" "LED-BY-19-GP"
			(at -2.132076 1.414018 0)
			(unlocked yes)
			(layer "F.Fab")
			(hide yes)
			(effects
				(font
					(size 1.016 1.016)
					(thickness 0.1524)
				)
			)
		)
		(property "Device Type" "LED-1615-4PH26"
			(at -2.132076 -0.109982 0)
			(unlocked yes)
			(layer "F.Fab")
			(hide yes)
			(effects
				(font
					(size 1.016 1.016)
					(thickness 0.1524)
				)
			)
		)
		(duplicate_pad_numbers_are_jumpers no)
		(fp_line
			(start -1.2954 0.254)
			(end -1.2954 1.6002)
			(stroke
				(width 0.508)
				(type default)
			)
			(layer "F.SilkS")
		)
		(fp_line
			(start -1.2954 1.6002)
			(end 1.2954 1.6002)
			(stroke
				(width 0.508)
				(type default)
			)
			(layer "F.SilkS")
		)
		(fp_line
			(start -1.1176 -1.4224)
			(end 1.1176 -1.4224)
			(stroke
				(width 0.1524)
				(type default)
			)
			(layer "F.SilkS")
		)
		(fp_line
			(start -1.1176 1.4224)
			(end -1.1176 -1.4224)
			(stroke
				(width 0.1524)
				(type default)
			)
			(layer "F.SilkS")
		)
		(fp_line
			(start 1.1176 -1.4224)
			(end 1.1176 1.4224)
			(stroke
				(width 0.1524)
				(type default)
			)
			(layer "F.SilkS")
		)
		(fp_line
			(start 1.1176 1.4224)
			(end -1.1176 1.4224)
			(stroke
				(width 0.1524)
				(type default)
			)
			(layer "F.SilkS")
		)
		(fp_line
			(start 1.2954 1.6002)
			(end 1.2954 0.254)
			(stroke
				(width 0.508)
				(type default)
			)
			(layer "F.SilkS")
		)
		(fp_rect
			(start -0.7493 0.8001)
			(end 0.7493 -0.8001)
			(stroke
				(width 0)
				(type default)
			)
			(fill no)
			(layer "F.CrtYd")
		)
		(fp_poly
			(pts
				(xy -1.3716 1.6764) (xy -1.3716 -1.6764) (xy 1.3716 -1.6764) (xy 1.3716 0.0635) (xy 0.7493 0.0635)
				(xy 0.7493 -0.8001) (xy -0.7493 -0.8001) (xy -0.7493 0.8001) (xy 0.7493 0.8001) (xy 0.7493 0.0762)
				(xy 1.3716 0.0762) (xy 1.3716 1.6764)
			)
			(stroke
				(width 0)
				(type default)
			)
			(fill no)
			(layer "F.CrtYd")
		)
		(fp_rect
			(start -1.3716 1.6764)
			(end 1.3716 -1.6764)
			(stroke
				(width 0)
				(type default)
			)
			(fill no)
			(layer "F.Fab")
		)
		(pad "1" smd rect
			(at 0.50038 -0.73025)
			(size 0.7112 0.8636)
			(layers "F.Cu" "F.Mask" "F.Paste")
			(net "DRV_ACT_29")
		)
		(pad "2" smd rect
			(at -0.50038 -0.73025)
			(size 0.7112 0.8636)
			(layers "F.Cu" "F.Mask" "F.Paste")
			(net "FLT_HDD29")
		)
		(pad "3" smd rect
			(at 0.50038 0.73025)
			(size 0.7112 0.8636)
			(layers "F.Cu" "F.Mask" "F.Paste")
			(net "DRV_ACT_29_N")
		)
		(pad "4" smd rect
			(at -0.50038 0.73025)
			(size 0.7112 0.8636)
			(layers "F.Cu" "F.Mask" "F.Paste")
			(net "FLT_HDD29_N")
		)
	)
	(footprint ""
		(layer "F.Cu")
		(at 263.238996 -344.049604 -90)
		(property "Reference" "R981"
			(at 0 0 270)
			(layer "F.SilkS")
			(hide yes)
			(effects
				(font
					(size 1.27 1.27)
				)
			)
		)
		(property "Value" "4K7R2F-GP"
			(at 0.064008 -3.993896 270)
			(unlocked yes)
			(layer "F.Fab")
			(hide yes)
			(effects
				(font
					(size 1.016 1.016)
					(thickness 0.1524)
				)
			)
		)
		(property "Device Type" "R402H16"
			(at 0.064008 -5.517896 270)
			(unlocked yes)
			(layer "F.Fab")
			(hide yes)
			(effects
				(font
					(size 1.016 1.016)
					(thickness 0.1524)
				)
			)
		)
		(duplicate_pad_numbers_are_jumpers no)
		(fp_line
			(start -0.508 -0.9398)
			(end -0.508 0.9398)
			(stroke
				(width 0.1524)
				(type default)
			)
			(layer "F.SilkS")
		)
		(fp_line
			(start 0.508 -0.9398)
			(end -0.508 -0.9398)
			(stroke
				(width 0.1524)
				(type default)
			)
			(layer "F.SilkS")
		)
		(fp_rect
			(start -0.508 0.9398)
			(end 0.508 -0.9398)
			(stroke
				(width 0)
				(type default)
			)
			(fill no)
			(layer "F.CrtYd")
		)
		(fp_rect
			(start -0.508 0.9398)
			(end 0.508 -0.9398)
			(stroke
				(width 0)
				(type default)
			)
			(fill no)
			(layer "F.Fab")
		)
		(pad "1" smd custom
			(at 0 -0.4445 270)
			(size 0.1397 0.1397)
			(layers "F.Cu" "F.Mask" "F.Paste")
			(net "SCC_A_SLOT_ID_1")
			(options
				(clearance outline)
				(anchor circle)
			)
			(primitives
				(gr_poly
					(pts
						(arc
							(start -0.1778 -0.2794)
							(mid -0.249642 -0.249642)
							(end -0.2794 -0.1778)
						)
						(arc
							(start -0.2794 0.1778)
							(mid -0.249642 0.249642)
							(end -0.1778 0.2794)
						)
						(arc
							(start 0.1778 0.2794)
							(mid 0.249642 0.249642)
							(end 0.2794 0.1778)
						)
						(arc
							(start 0.2794 -0.1778)
							(mid 0.249642 -0.249642)
							(end 0.1778 -0.2794)
						)
					)
					(width 0)
					(fill yes)
				)
			)
		)
		(pad "2" smd custom
			(at 0 0.4445 270)
			(size 0.1397 0.1397)
			(layers "F.Cu" "F.Mask" "F.Paste")
			(net "GND")
			(options
				(clearance outline)
				(anchor circle)
			)
			(primitives
				(gr_poly
					(pts
						(arc
							(start -0.1778 -0.2794)
							(mid -0.249642 -0.249642)
							(end -0.2794 -0.1778)
						)
						(arc
							(start -0.2794 0.1778)
							(mid -0.249642 0.249642)
							(end -0.1778 0.2794)
						)
						(arc
							(start 0.1778 0.2794)
							(mid 0.249642 0.249642)
							(end 0.2794 0.1778)
						)
						(arc
							(start 0.2794 -0.1778)
							(mid 0.249642 -0.249642)
							(end 0.1778 -0.2794)
						)
					)
					(width 0)
					(fill yes)
				)
			)
		)
	)
	(footprint ""
		(layer "F.Cu")
		(at 314.356496 -130.411728 -90)
		(property "Reference" "R526"
			(at 0 0 270)
			(layer "F.SilkS")
			(hide yes)
			(effects
				(font
					(size 1.27 1.27)
				)
			)
		)
		(property "Value" "4K7R2J-2-GP"
			(at 0.064008 -3.993896 270)
			(unlocked yes)
			(layer "F.Fab")
			(hide yes)
			(effects
				(font
					(size 1.016 1.016)
					(thickness 0.1524)
				)
			)
		)
		(property "Device Type" "R402H16"
			(at 0.064008 -5.517896 270)
			(unlocked yes)
			(layer "F.Fab")
			(hide yes)
			(effects
				(font
					(size 1.016 1.016)
					(thickness 0.1524)
				)
			)
		)
		(duplicate_pad_numbers_are_jumpers no)
		(fp_line
			(start -0.508 -0.9398)
			(end -0.508 0.9398)
			(stroke
				(width 0.1524)
				(type default)
			)
			(layer "F.SilkS")
		)
		(fp_line
			(start 0.508 -0.9398)
			(end -0.508 -0.9398)
			(stroke
				(width 0.1524)
				(type default)
			)
			(layer "F.SilkS")
		)
		(fp_rect
			(start -0.508 0.9398)
			(end 0.508 -0.9398)
			(stroke
				(width 0)
				(type default)
			)
			(fill no)
			(layer "F.CrtYd")
		)
		(fp_rect
			(start -0.508 0.9398)
			(end 0.508 -0.9398)
			(stroke
				(width 0)
				(type default)
			)
			(fill no)
			(layer "F.Fab")
		)
		(pad "1" smd custom
			(at 0 -0.4445 270)
			(size 0.1397 0.1397)
			(layers "F.Cu" "F.Mask" "F.Paste")
			(net "DRIVE_A_18_ACT")
			(options
				(clearance outline)
				(anchor circle)
			)
			(primitives
				(gr_poly
					(pts
						(arc
							(start -0.1778 -0.2794)
							(mid -0.249642 -0.249642)
							(end -0.2794 -0.1778)
						)
						(arc
							(start -0.2794 0.1778)
							(mid -0.249642 0.249642)
							(end -0.1778 0.2794)
						)
						(arc
							(start 0.1778 0.2794)
							(mid 0.249642 0.249642)
							(end 0.2794 0.1778)
						)
						(arc
							(start 0.2794 -0.1778)
							(mid 0.249642 -0.249642)
							(end 0.1778 -0.2794)
						)
					)
					(width 0)
					(fill yes)
				)
			)
		)
		(pad "2" smd custom
			(at 0 0.4445 270)
			(size 0.1397 0.1397)
			(layers "F.Cu" "F.Mask" "F.Paste")
			(net "GND")
			(options
				(clearance outline)
				(anchor circle)
			)
			(primitives
				(gr_poly
					(pts
						(arc
							(start -0.1778 -0.2794)
							(mid -0.249642 -0.249642)
							(end -0.2794 -0.1778)
						)
						(arc
							(start -0.2794 0.1778)
							(mid -0.249642 0.249642)
							(end -0.1778 0.2794)
						)
						(arc
							(start 0.1778 0.2794)
							(mid 0.249642 0.249642)
							(end 0.2794 0.1778)
						)
						(arc
							(start 0.2794 -0.1778)
							(mid 0.249642 -0.249642)
							(end 0.1778 -0.2794)
						)
					)
					(width 0)
					(fill yes)
				)
			)
		)
	)
	(footprint ""
		(layer "F.Cu")
		(at 471.275918 -159.088074 90)
		(property "Reference" "Q139"
			(at 0 0 90)
			(layer "F.SilkS")
			(hide yes)
			(effects
				(font
					(size 1.27 1.27)
				)
			)
		)
		(property "Value" "2N7002KDW-GP"
			(at -2.3622 -8.2042 90)
			(unlocked yes)
			(layer "F.Fab")
			(hide yes)
			(effects
				(font
					(size 1.016 1.016)
					(thickness 0.1524)
				)
			)
		)
		(property "Device Type" "SOT-363H44"
			(at -2.3622 -10.1092 90)
			(unlocked yes)
			(layer "F.Fab")
			(hide yes)
			(effects
				(font
					(size 1.016 1.016)
					(thickness 0.1524)
				)
			)
		)
		(duplicate_pad_numbers_are_jumpers no)
		(fp_line
			(start 1.4478 -1.7018)
			(end -1.4478 -1.7018)
			(stroke
				(width 0.1524)
				(type default)
			)
			(layer "F.SilkS")
		)
		(fp_line
			(start -1.4478 -1.7018)
			(end -1.4478 1.7018)
			(stroke
				(width 0.1524)
				(type default)
			)
			(layer "F.SilkS")
		)
		(fp_line
			(start -1.27 1.524)
			(end -1.27 0.6604)
			(stroke
				(width 0.4826)
				(type default)
			)
			(layer "F.SilkS")
		)
		(fp_line
			(start 1.4478 1.7018)
			(end 1.4478 -1.7018)
			(stroke
				(width 0.1524)
				(type default)
			)
			(layer "F.SilkS")
		)
		(fp_line
			(start -1.4478 1.7018)
			(end 1.4478 1.7018)
			(stroke
				(width 0.1524)
				(type default)
			)
			(layer "F.SilkS")
		)
		(fp_poly
			(pts
				(xy -1.524 -1.778) (xy 1.524 -1.778) (xy 1.524 1.778) (xy -1.524 1.778)
			)
			(stroke
				(width 0)
				(type default)
			)
			(fill no)
			(layer "F.CrtYd")
		)
		(fp_poly
			(pts
				(xy -1.524 -1.778) (xy 1.524 -1.778) (xy 1.524 1.778) (xy -1.524 1.778)
			)
			(stroke
				(width 0)
				(type default)
			)
			(fill no)
			(layer "F.Fab")
		)
		(pad "1" smd rect
			(at -0.65024 0.9398 90)
			(size 0.4064 1.016)
			(layers "F.Cu" "F.Mask" "F.Paste")
			(net "GND")
		)
		(pad "2" smd rect
			(at 0 0.9398 90)
			(size 0.4064 1.016)
			(layers "F.Cu" "F.Mask" "F.Paste")
			(net "SW_PWR_R_HDD23")
		)
		(pad "3" smd rect
			(at 0.65024 0.9398 90)
			(size 0.4064 1.016)
			(layers "F.Cu" "F.Mask" "F.Paste")
			(net "SW_HDD_P23")
		)
		(pad "4" smd rect
			(at 0.65024 -0.9398 90)
			(size 0.4064 1.016)
			(layers "F.Cu" "F.Mask" "F.Paste")
			(net "GND")
		)
		(pad "5" smd rect
			(at 0 -0.9398 90)
			(size 0.4064 1.016)
			(layers "F.Cu" "F.Mask" "F.Paste")
			(net "SW_HDD_G23")
		)
		(pad "6" smd rect
			(at -0.65024 -0.9398 90)
			(size 0.4064 1.016)
			(layers "F.Cu" "F.Mask" "F.Paste")
			(net "SW_HDD_R23")
		)
	)
	(footprint ""
		(layer "F.Cu")
		(at 334.899 -167.872918 -90)
		(property "Reference" "Q108"
			(at 0 0 270)
			(layer "F.SilkS")
			(hide yes)
			(effects
				(font
					(size 1.27 1.27)
				)
			)
		)
		(property "Value" "AO4406AL-GP"
			(at -3.707384 -1.5367 270)
			(unlocked yes)
			(layer "F.Fab")
			(hide yes)
			(effects
				(font
					(size 1.016 1.016)
					(thickness 0.1524)
				)
			)
		)
		(property "Device Type" "SOIC8H69"
			(at -3.707384 -3.0607 270)
			(unlocked yes)
			(layer "F.Fab")
			(hide yes)
			(effects
				(font
					(size 1.016 1.016)
					(thickness 0.1524)
				)
			)
		)
		(duplicate_pad_numbers_are_jumpers no)
		(fp_line
			(start -2.6289 3.4417)
			(end -2.6289 1.4732)
			(stroke
				(width 0.381)
				(type default)
			)
			(layer "F.SilkS")
		)
		(fp_line
			(start -2.7432 1.4224)
			(end -2.6416 1.4224)
			(stroke
				(width 0.1524)
				(type default)
			)
			(layer "F.SilkS")
		)
		(fp_line
			(start -2.7432 1.4224)
			(end 2.1336 1.4224)
			(stroke
				(width 0.1524)
				(type default)
			)
			(layer "F.SilkS")
		)
		(fp_line
			(start 2.1336 1.4224)
			(end 2.1336 -1.4224)
			(stroke
				(width 0.1524)
				(type default)
			)
			(layer "F.SilkS")
		)
		(fp_line
			(start -2.1844 -0.0508)
			(end -2.7178 0.508)
			(stroke
				(width 0.1524)
				(type default)
			)
			(layer "F.SilkS")
		)
		(fp_line
			(start -2.7178 -0.508)
			(end -2.1844 -0.0508)
			(stroke
				(width 0.1524)
				(type default)
			)
			(layer "F.SilkS")
		)
		(fp_line
			(start -2.7432 -1.4224)
			(end -2.7432 1.4224)
			(stroke
				(width 0.1524)
				(type default)
			)
			(layer "F.SilkS")
		)
		(fp_line
			(start 2.1336 -1.4224)
			(end -2.7432 -1.4224)
			(stroke
				(width 0.1524)
				(type default)
			)
			(layer "F.SilkS")
		)
		(fp_poly
			(pts
				(xy -2.2098 -1.4224) (xy -2.2098 1.4224) (xy 2.2098 1.4224) (xy 2.2098 -1.4224)
			)
			(stroke
				(width 0)
				(type default)
			)
			(fill yes)
			(layer "F.SilkS")
		)
		(fp_rect
			(start -2.450084 2.999994)
			(end 2.450084 -2.999994)
			(stroke
				(width 0)
				(type default)
			)
			(fill no)
			(layer "F.CrtYd")
		)
		(fp_poly
			(pts
				(xy -2.8194 3.6322) (xy -2.8194 -3.6322) (xy 2.8194 -3.6322) (xy 2.8194 1.18364) (xy 2.450084 1.18364)
				(xy 2.450084 -2.999994) (xy -2.450084 -2.999994) (xy -2.450084 2.999994) (xy 2.450084 2.999994)
				(xy 2.450084 1.18618) (xy 2.8194 1.18618) (xy 2.8194 3.6322)
			)
			(stroke
				(width 0)
				(type default)
			)
			(fill no)
			(layer "F.CrtYd")
		)
		(fp_rect
			(start -2.8194 3.6322)
			(end 2.8194 -3.6322)
			(stroke
				(width 0)
				(type default)
			)
			(fill no)
			(layer "F.Fab")
		)
		(pad "1" smd rect
			(at -1.905 2.54 270)
			(size 0.635 1.651)
			(layers "F.Cu" "F.Mask" "F.Paste")
			(net "P5V_HDD18")
		)
		(pad "2" smd rect
			(at -0.635 2.54 270)
			(size 0.635 1.651)
			(layers "F.Cu" "F.Mask" "F.Paste")
			(net "P5V_HDD18")
		)
		(pad "3" smd rect
			(at 0.635 2.54 270)
			(size 0.635 1.651)
			(layers "F.Cu" "F.Mask" "F.Paste")
			(net "P5V_HDD18")
		)
		(pad "4" smd rect
			(at 1.905 2.54 270)
			(size 0.635 1.651)
			(layers "F.Cu" "F.Mask" "F.Paste")
			(net "SW_HDD_P18")
		)
		(pad "5" smd rect
			(at 1.905 -2.54 270)
			(size 0.635 1.651)
			(layers "F.Cu" "F.Mask" "F.Paste")
			(net "P5V_A_3")
		)
		(pad "6" smd rect
			(at 0.635 -2.54 270)
			(size 0.635 1.651)
			(layers "F.Cu" "F.Mask" "F.Paste")
			(net "P5V_A_3")
		)
		(pad "7" smd rect
			(at -0.635 -2.54 270)
			(size 0.635 1.651)
			(layers "F.Cu" "F.Mask" "F.Paste")
			(net "P5V_A_3")
		)
		(pad "8" smd rect
			(at -1.905 -2.54 270)
			(size 0.635 1.651)
			(layers "F.Cu" "F.Mask" "F.Paste")
			(net "P5V_A_3")
		)
	)
	(footprint ""
		(layer "F.Cu")
		(at 114.699796 -61.000894 -90)
		(property "Reference" "C392"
			(at 0 0 270)
			(layer "F.SilkS")
			(hide yes)
			(effects
				(font
					(size 1.27 1.27)
				)
			)
		)
		(property "Value" "SC10U16V6KX-2GP"
			(at -0.0762 -5.1308 270)
			(unlocked yes)
			(layer "F.Fab")
			(hide yes)
			(effects
				(font
					(size 1.016 1.016)
					(thickness 0.1524)
				)
			)
		)
		(property "Device Type" "C1206H71"
			(at -0.127 -6.6548 270)
			(unlocked yes)
			(layer "F.Fab")
			(hide yes)
			(effects
				(font
					(size 1.016 1.016)
					(thickness 0.1524)
				)
			)
		)
		(duplicate_pad_numbers_are_jumpers no)
		(fp_line
			(start -1.016 2.2352)
			(end -1.016 0.8382)
			(stroke
				(width 0.1524)
				(type default)
			)
			(layer "F.SilkS")
		)
		(fp_line
			(start 1.016 2.2352)
			(end -1.016 2.2352)
			(stroke
				(width 0.1524)
				(type default)
			)
			(layer "F.SilkS")
		)
		(fp_line
			(start 1.016 0.8382)
			(end 1.016 2.2352)
			(stroke
				(width 0.1524)
				(type default)
			)
			(layer "F.SilkS")
		)
		(fp_line
			(start -1.016 -0.8382)
			(end -1.016 -2.2352)
			(stroke
				(width 0.1524)
				(type default)
			)
			(layer "F.SilkS")
		)
		(fp_line
			(start -1.016 -2.2352)
			(end 1.016 -2.2352)
			(stroke
				(width 0.1524)
				(type default)
			)
			(layer "F.SilkS")
		)
		(fp_line
			(start 1.016 -2.2352)
			(end 1.016 -0.8382)
			(stroke
				(width 0.1524)
				(type default)
			)
			(layer "F.SilkS")
		)
		(fp_rect
			(start -1.0922 2.3114)
			(end 1.0922 -2.3114)
			(stroke
				(width 0)
				(type default)
			)
			(fill no)
			(layer "F.CrtYd")
		)
		(fp_poly
			(pts
				(xy 1.0922 -2.3114) (xy 1.0922 2.3114) (xy -1.0922 2.3114) (xy -1.0922 -2.3114)
			)
			(stroke
				(width 0)
				(type default)
			)
			(fill no)
			(layer "F.Fab")
		)
		(pad "1" smd rect
			(at 0 -1.397 270)
			(size 1.651 1.27)
			(layers "F.Cu" "F.Mask" "F.Paste")
			(net "P5V_HDD27")
		)
		(pad "2" smd rect
			(at 0 1.397 270)
			(size 1.651 1.27)
			(layers "F.Cu" "F.Mask" "F.Paste")
			(net "GND")
		)
	)
	(footprint ""
		(layer "F.Cu")
		(at 174.498 -280.993342 90)
		(property "Reference" "R252"
			(at 0 0 90)
			(layer "F.SilkS")
			(hide yes)
			(effects
				(font
					(size 1.27 1.27)
				)
			)
		)
		(property "Value" "4K7R2J-2-GP"
			(at 0.064008 -3.993896 90)
			(unlocked yes)
			(layer "F.Fab")
			(hide yes)
			(effects
				(font
					(size 1.016 1.016)
					(thickness 0.1524)
				)
			)
		)
		(property "Device Type" "R402H16"
			(at 0.064008 -5.517896 90)
			(unlocked yes)
			(layer "F.Fab")
			(hide yes)
			(effects
				(font
					(size 1.016 1.016)
					(thickness 0.1524)
				)
			)
		)
		(duplicate_pad_numbers_are_jumpers no)
		(fp_line
			(start 0.508 -0.9398)
			(end -0.508 -0.9398)
			(stroke
				(width 0.1524)
				(type default)
			)
			(layer "F.SilkS")
		)
		(fp_line
			(start -0.508 -0.9398)
			(end -0.508 0.9398)
			(stroke
				(width 0.1524)
				(type default)
			)
			(layer "F.SilkS")
		)
		(fp_rect
			(start -0.508 0.9398)
			(end 0.508 -0.9398)
			(stroke
				(width 0)
				(type default)
			)
			(fill no)
			(layer "F.CrtYd")
		)
		(fp_rect
			(start -0.508 0.9398)
			(end 0.508 -0.9398)
			(stroke
				(width 0)
				(type default)
			)
			(fill no)
			(layer "F.Fab")
		)
		(pad "1" smd custom
			(at 0 -0.4445 90)
			(size 0.1397 0.1397)
			(layers "F.Cu" "F.Mask" "F.Paste")
			(net "P12V_A")
			(options
				(clearance outline)
				(anchor circle)
			)
			(primitives
				(gr_poly
					(pts
						(arc
							(start -0.1778 -0.2794)
							(mid -0.249642 -0.249642)
							(end -0.2794 -0.1778)
						)
						(arc
							(start -0.2794 0.1778)
							(mid -0.249642 0.249642)
							(end -0.1778 0.2794)
						)
						(arc
							(start 0.1778 0.2794)
							(mid 0.249642 0.249642)
							(end 0.2794 0.1778)
						)
						(arc
							(start 0.2794 -0.1778)
							(mid 0.249642 -0.249642)
							(end 0.1778 -0.2794)
						)
					)
					(width 0)
					(fill yes)
				)
			)
		)
		(pad "2" smd custom
			(at 0 0.4445 90)
			(size 0.1397 0.1397)
			(layers "F.Cu" "F.Mask" "F.Paste")
			(net "SW_HDD_P5")
			(options
				(clearance outline)
				(anchor circle)
			)
			(primitives
				(gr_poly
					(pts
						(arc
							(start -0.1778 -0.2794)
							(mid -0.249642 -0.249642)
							(end -0.2794 -0.1778)
						)
						(arc
							(start -0.2794 0.1778)
							(mid -0.249642 0.249642)
							(end -0.1778 0.2794)
						)
						(arc
							(start 0.1778 0.2794)
							(mid 0.249642 0.249642)
							(end 0.2794 0.1778)
						)
						(arc
							(start 0.2794 -0.1778)
							(mid 0.249642 -0.249642)
							(end 0.1778 -0.2794)
						)
					)
					(width 0)
					(fill yes)
				)
			)
		)
	)
	(footprint ""
		(layer "F.Cu")
		(at 36.178998 -65.064894 90)
		(property "Reference" "R686"
			(at 0 0 90)
			(layer "F.SilkS")
			(hide yes)
			(effects
				(font
					(size 1.27 1.27)
				)
			)
		)
		(property "Value" "220R3F-1-GP"
			(at -0.0254 -2.5146 90)
			(unlocked yes)
			(layer "F.Fab")
			(hide yes)
			(effects
				(font
					(size 1.016 1.016)
					(thickness 0.1524)
				)
			)
		)
		(property "Device Type" "R603H22"
			(at -0.0254 -4.0386 90)
			(unlocked yes)
			(layer "F.Fab")
			(hide yes)
			(effects
				(font
					(size 1.016 1.016)
					(thickness 0.1524)
				)
			)
		)
		(duplicate_pad_numbers_are_jumpers no)
		(fp_line
			(start 0.2032 0)
			(end 0.4826 0)
			(stroke
				(width 0.2032)
				(type default)
			)
			(layer "F.SilkS")
		)
		(fp_line
			(start -0.4826 0)
			(end -0.2032 0)
			(stroke
				(width 0.2032)
				(type default)
			)
			(layer "F.SilkS")
		)
		(fp_rect
			(start -0.5842 1.3335)
			(end 0.5842 -1.3335)
			(stroke
				(width 0)
				(type default)
			)
			(fill no)
			(layer "F.CrtYd")
		)
		(fp_rect
			(start -0.5842 1.3335)
			(end 0.5842 -1.3335)
			(stroke
				(width 0)
				(type default)
			)
			(fill no)
			(layer "F.Fab")
		)
		(pad "1" smd custom
			(at 0 -0.762 90)
			(size 0.2159 0.2159)
			(layers "F.Cu" "F.Mask" "F.Paste")
			(net "HDD_PRSNT_24")
			(options
				(clearance outline)
				(anchor circle)
			)
			(primitives
				(gr_poly
					(pts
						(arc
							(start -0.3302 -0.4318)
							(mid -0.402042 -0.402042)
							(end -0.4318 -0.3302)
						)
						(arc
							(start -0.4318 0.3302)
							(mid -0.402042 0.402042)
							(end -0.3302 0.4318)
						)
						(arc
							(start 0.3302 0.4318)
							(mid 0.402042 0.402042)
							(end 0.4318 0.3302)
						)
						(arc
							(start 0.4318 -0.3302)
							(mid 0.402042 -0.402042)
							(end 0.3302 -0.4318)
						)
					)
					(width 0)
					(fill yes)
				)
			)
		)
		(pad "2" smd custom
			(at 0 0.762 90)
			(size 0.2159 0.2159)
			(layers "F.Cu" "F.Mask" "F.Paste")
			(net "DRIVE_A_24_INS")
			(options
				(clearance outline)
				(anchor circle)
			)
			(primitives
				(gr_poly
					(pts
						(arc
							(start -0.3302 -0.4318)
							(mid -0.402042 -0.402042)
							(end -0.4318 -0.3302)
						)
						(arc
							(start -0.4318 0.3302)
							(mid -0.402042 0.402042)
							(end -0.3302 0.4318)
						)
						(arc
							(start 0.3302 0.4318)
							(mid 0.402042 0.402042)
							(end 0.4318 0.3302)
						)
						(arc
							(start 0.4318 -0.3302)
							(mid 0.402042 -0.402042)
							(end 0.3302 -0.4318)
						)
					)
					(width 0)
					(fill yes)
				)
			)
		)
	)
	(footprint ""
		(layer "F.Cu")
		(at 400.03095 -45.735494 180)
		(property "Reference" "R879"
			(at 0 0 180)
			(layer "F.SilkS")
			(hide yes)
			(effects
				(font
					(size 1.27 1.27)
				)
			)
		)
		(property "Value" "4K7R2J-2-GP"
			(at 0.064008 -3.993896 180)
			(unlocked yes)
			(layer "F.Fab")
			(hide yes)
			(effects
				(font
					(size 1.016 1.016)
					(thickness 0.1524)
				)
			)
		)
		(property "Device Type" "R402H16"
			(at 0.064008 -5.517896 180)
			(unlocked yes)
			(layer "F.Fab")
			(hide yes)
			(effects
				(font
					(size 1.016 1.016)
					(thickness 0.1524)
				)
			)
		)
		(duplicate_pad_numbers_are_jumpers no)
		(fp_line
			(start 0.508 -0.9398)
			(end -0.508 -0.9398)
			(stroke
				(width 0.1524)
				(type default)
			)
			(layer "F.SilkS")
		)
		(fp_line
			(start -0.508 -0.9398)
			(end -0.508 0.9398)
			(stroke
				(width 0.1524)
				(type default)
			)
			(layer "F.SilkS")
		)
		(fp_rect
			(start -0.508 0.9398)
			(end 0.508 -0.9398)
			(stroke
				(width 0)
				(type default)
			)
			(fill no)
			(layer "F.CrtYd")
		)
		(fp_rect
			(start -0.508 0.9398)
			(end 0.508 -0.9398)
			(stroke
				(width 0)
				(type default)
			)
			(fill no)
			(layer "F.Fab")
		)
		(pad "1" smd custom
			(at 0 -0.4445 180)
			(size 0.1397 0.1397)
			(layers "F.Cu" "F.Mask" "F.Paste")
			(net "P12V_A")
			(options
				(clearance outline)
				(anchor circle)
			)
			(primitives
				(gr_poly
					(pts
						(arc
							(start -0.1778 -0.2794)
							(mid -0.249642 -0.249642)
							(end -0.2794 -0.1778)
						)
						(arc
							(start -0.2794 0.1778)
							(mid -0.249642 0.249642)
							(end -0.1778 0.2794)
						)
						(arc
							(start 0.1778 0.2794)
							(mid 0.249642 0.249642)
							(end 0.2794 0.1778)
						)
						(arc
							(start 0.2794 -0.1778)
							(mid 0.249642 -0.249642)
							(end 0.1778 -0.2794)
						)
					)
					(width 0)
					(fill yes)
				)
			)
		)
		(pad "2" smd custom
			(at 0 0.4445 180)
			(size 0.1397 0.1397)
			(layers "F.Cu" "F.Mask" "F.Paste")
			(net "SW_HDD_R32")
			(options
				(clearance outline)
				(anchor circle)
			)
			(primitives
				(gr_poly
					(pts
						(arc
							(start -0.1778 -0.2794)
							(mid -0.249642 -0.249642)
							(end -0.2794 -0.1778)
						)
						(arc
							(start -0.2794 0.1778)
							(mid -0.249642 0.249642)
							(end -0.1778 0.2794)
						)
						(arc
							(start 0.1778 0.2794)
							(mid 0.249642 0.249642)
							(end 0.2794 0.1778)
						)
						(arc
							(start 0.2794 -0.1778)
							(mid 0.249642 -0.249642)
							(end 0.1778 -0.2794)
						)
					)
					(width 0)
					(fill yes)
				)
			)
		)
	)
	(footprint ""
		(layer "F.Cu")
		(at 458.9399 -279.596342 90)
		(property "Reference" "C178"
			(at 0 0 90)
			(layer "F.SilkS")
			(hide yes)
			(effects
				(font
					(size 1.27 1.27)
				)
			)
		)
		(property "Value" "SCD033U25V2KX-GP"
			(at 1.1811 -2.7051 90)
			(unlocked yes)
			(layer "F.Fab")
			(hide yes)
			(effects
				(font
					(size 1.016 1.016)
					(thickness 0.1524)
				)
			)
		)
		(property "Device Type" "C402H22"
			(at 1.1811 -4.2291 90)
			(unlocked yes)
			(layer "F.Fab")
			(hide yes)
			(effects
				(font
					(size 1.016 1.016)
					(thickness 0.1524)
				)
			)
		)
		(duplicate_pad_numbers_are_jumpers no)
		(fp_rect
			(start -0.4318 0.9525)
			(end 0.4318 -0.9525)
			(stroke
				(width 0)
				(type default)
			)
			(fill no)
			(layer "F.CrtYd")
		)
		(fp_rect
			(start -0.4318 0.9525)
			(end 0.4318 -0.9525)
			(stroke
				(width 0)
				(type default)
			)
			(fill no)
			(layer "F.Fab")
		)
		(pad "1" smd custom
			(at 0 -0.4445 90)
			(size 0.1524 0.1524)
			(layers "F.Cu" "F.Mask" "F.Paste")
			(net "SW_HDD_P10")
			(options
				(clearance outline)
				(anchor circle)
			)
			(primitives
				(gr_poly
					(pts
						(arc
							(start 0.3048 -0.2032)
							(mid 0.275042 -0.275042)
							(end 0.2032 -0.3048)
						)
						(arc
							(start -0.2032 -0.3048)
							(mid -0.275042 -0.275042)
							(end -0.3048 -0.2032)
						)
						(arc
							(start -0.3048 0.2032)
							(mid -0.275042 0.275042)
							(end -0.2032 0.3048)
						)
						(arc
							(start 0.2032 0.3048)
							(mid 0.275042 0.275042)
							(end 0.3048 0.2032)
						)
					)
					(width 0)
					(fill yes)
				)
			)
		)
		(pad "2" smd custom
			(at 0 0.4445 90)
			(size 0.1524 0.1524)
			(layers "F.Cu" "F.Mask" "F.Paste")
			(net "GND")
			(options
				(clearance outline)
				(anchor circle)
			)
			(primitives
				(gr_poly
					(pts
						(arc
							(start 0.3048 -0.2032)
							(mid 0.275042 -0.275042)
							(end 0.2032 -0.3048)
						)
						(arc
							(start -0.2032 -0.3048)
							(mid -0.275042 -0.275042)
							(end -0.3048 -0.2032)
						)
						(arc
							(start -0.3048 0.2032)
							(mid -0.275042 0.275042)
							(end -0.2032 0.3048)
						)
						(arc
							(start 0.2032 0.3048)
							(mid 0.275042 0.275042)
							(end 0.3048 0.2032)
						)
					)
					(width 0)
					(fill yes)
				)
			)
		)
	)
	(footprint ""
		(layer "F.Cu")
		(at 318.4906 -298.704)
		(property "Reference" "TP32"
			(at 0 0 0)
			(layer "F.SilkS")
			(hide yes)
			(effects
				(font
					(size 1.27 1.27)
				)
			)
		)
		(property "Value" "TPAD32-GP"
			(at -0.0508 -1.6764 0)
			(unlocked yes)
			(layer "F.Fab")
			(hide yes)
			(effects
				(font
					(size 1.016 1.016)
					(thickness 0.1524)
				)
			)
		)
		(property "Device Type" "TPAD32"
			(at -0.0508 -3.2004 0)
			(unlocked yes)
			(layer "F.Fab")
			(hide yes)
			(effects
				(font
					(size 1.016 1.016)
					(thickness 0.1524)
				)
			)
		)
		(duplicate_pad_numbers_are_jumpers no)
		(fp_poly
			(pts
				(arc
					(start 0.4064 0)
					(mid -0.4064 0)
					(end 0.4064 0)
				)
			)
			(stroke
				(width 0)
				(type default)
			)
			(fill no)
			(layer "F.CrtYd")
		)
		(fp_poly
			(pts
				(arc
					(start 0.7112 0)
					(mid -0.7112 0)
					(end 0.7112 0)
				)
			)
			(stroke
				(width 0)
				(type default)
			)
			(fill no)
			(layer "F.Fab")
		)
		(pad "1" smd circle
			(at 0 0)
			(size 0.8128 0.8128)
			(layers "F.Cu" "F.Mask" "F.Paste")
			(net "ACT_HDD_6")
		)
	)
	(footprint ""
		(layer "F.Cu")
		(at 6.799326 -293.878254)
		(property "Reference" "Q251"
			(at 0 0 0)
			(layer "F.SilkS")
			(hide yes)
			(effects
				(font
					(size 1.27 1.27)
				)
			)
		)
		(property "Value" "2N7002K-2-GP"
			(at 0.127 -8.9662 0)
			(unlocked yes)
			(layer "F.Fab")
			(hide yes)
			(effects
				(font
					(size 1.016 1.016)
					(thickness 0.1524)
				)
			)
		)
		(property "Device Type" "SOT23DGS2D4H44"
			(at 0.127 -10.4902 0)
			(unlocked yes)
			(layer "F.Fab")
			(hide yes)
			(effects
				(font
					(size 1.016 1.016)
					(thickness 0.1524)
				)
			)
		)
		(duplicate_pad_numbers_are_jumpers no)
		(fp_line
			(start -1.651 -1.778)
			(end -1.651 1.778)
			(stroke
				(width 0.1524)
				(type default)
			)
			(layer "F.SilkS")
		)
		(fp_line
			(start -1.651 1.778)
			(end 1.651 1.778)
			(stroke
				(width 0.1524)
				(type default)
			)
			(layer "F.SilkS")
		)
		(fp_line
			(start 1.651 -1.778)
			(end -1.651 -1.778)
			(stroke
				(width 0.1524)
				(type default)
			)
			(layer "F.SilkS")
		)
		(fp_line
			(start 1.651 1.778)
			(end 1.651 -1.778)
			(stroke
				(width 0.1524)
				(type default)
			)
			(layer "F.SilkS")
		)
		(fp_poly
			(pts
				(xy -1.778 1.8796) (xy -1.778 -1.8796) (xy 1.778 -1.8796) (xy 1.778 1.8796)
			)
			(stroke
				(width 0)
				(type default)
			)
			(fill no)
			(layer "F.CrtYd")
		)
		(fp_poly
			(pts
				(xy -1.778 1.8796) (xy -1.778 -1.8796) (xy 1.778 -1.8796) (xy 1.778 1.8796)
			)
			(stroke
				(width 0)
				(type default)
			)
			(fill no)
			(layer "F.Fab")
		)
		(pad "D" smd custom
			(at 0 -0.9525)
			(size 0.1905 0.1905)
			(layers "F.Cu" "F.Mask" "F.Paste")
			(net "FLT_HDD24_N")
			(options
				(clearance outline)
				(anchor circle)
			)
			(primitives
				(gr_poly
					(pts
						(arc
							(start -0.1778 0.5715)
							(mid -0.321484 0.511984)
							(end -0.381 0.3683)
						)
						(arc
							(start -0.381 -0.3683)
							(mid -0.321484 -0.511984)
							(end -0.1778 -0.5715)
						)
						(arc
							(start 0.1778 -0.5715)
							(mid 0.321484 -0.511984)
							(end 0.381 -0.3683)
						)
						(arc
							(start 0.381 0.3683)
							(mid 0.321484 0.511984)
							(end 0.1778 0.5715)
						)
					)
					(width 0)
					(fill yes)
				)
			)
		)
		(pad "G" smd custom
			(at -0.98425 0.9525)
			(size 0.1905 0.1905)
			(layers "F.Cu" "F.Mask" "F.Paste")
			(net "DRIVE_B_24_FLT_LED")
			(options
				(clearance outline)
				(anchor circle)
			)
			(primitives
				(gr_poly
					(pts
						(arc
							(start -0.1778 0.5715)
							(mid -0.321484 0.511984)
							(end -0.381 0.3683)
						)
						(arc
							(start -0.381 -0.3683)
							(mid -0.321484 -0.511984)
							(end -0.1778 -0.5715)
						)
						(arc
							(start 0.1778 -0.5715)
							(mid 0.321484 -0.511984)
							(end 0.381 -0.3683)
						)
						(arc
							(start 0.381 0.3683)
							(mid 0.321484 0.511984)
							(end 0.1778 0.5715)
						)
					)
					(width 0)
					(fill yes)
				)
			)
		)
		(pad "S" smd custom
			(at 0.98425 0.9525)
			(size 0.1905 0.1905)
			(layers "F.Cu" "F.Mask" "F.Paste")
			(net "GND")
			(options
				(clearance outline)
				(anchor circle)
			)
			(primitives
				(gr_poly
					(pts
						(arc
							(start -0.1778 0.5715)
							(mid -0.321484 0.511984)
							(end -0.381 0.3683)
						)
						(arc
							(start -0.381 -0.3683)
							(mid -0.321484 -0.511984)
							(end -0.1778 -0.5715)
						)
						(arc
							(start 0.1778 -0.5715)
							(mid 0.321484 -0.511984)
							(end 0.381 -0.3683)
						)
						(arc
							(start 0.381 0.3683)
							(mid 0.321484 0.511984)
							(end 0.1778 0.5715)
						)
					)
					(width 0)
					(fill yes)
				)
			)
		)
	)
	(footprint ""
		(layer "F.Cu")
		(at 376.9614 -142.3416 90)
		(property "Reference" "R1076"
			(at 0 0 90)
			(layer "F.SilkS")
			(hide yes)
			(effects
				(font
					(size 1.27 1.27)
				)
			)
		)
		(property "Value" "0R2J-2-GP"
			(at 0.064008 -3.993896 90)
			(unlocked yes)
			(layer "F.Fab")
			(hide yes)
			(effects
				(font
					(size 1.016 1.016)
					(thickness 0.1524)
				)
			)
		)
		(property "Device Type" "R402H16"
			(at 0.064008 -5.517896 90)
			(unlocked yes)
			(layer "F.Fab")
			(hide yes)
			(effects
				(font
					(size 1.016 1.016)
					(thickness 0.1524)
				)
			)
		)
		(duplicate_pad_numbers_are_jumpers no)
		(fp_line
			(start 0.508 -0.9398)
			(end -0.508 -0.9398)
			(stroke
				(width 0.1524)
				(type default)
			)
			(layer "F.SilkS")
		)
		(fp_line
			(start -0.508 -0.9398)
			(end -0.508 0.9398)
			(stroke
				(width 0.1524)
				(type default)
			)
			(layer "F.SilkS")
		)
		(fp_rect
			(start -0.508 0.9398)
			(end 0.508 -0.9398)
			(stroke
				(width 0)
				(type default)
			)
			(fill no)
			(layer "F.CrtYd")
		)
		(fp_rect
			(start -0.508 0.9398)
			(end 0.508 -0.9398)
			(stroke
				(width 0)
				(type default)
			)
			(fill no)
			(layer "F.Fab")
		)
		(pad "1" smd custom
			(at 0 -0.4445 90)
			(size 0.1397 0.1397)
			(layers "F.Cu" "F.Mask" "F.Paste")
			(net "MB1_SCL_R")
			(options
				(clearance outline)
				(anchor circle)
			)
			(primitives
				(gr_poly
					(pts
						(arc
							(start -0.1778 -0.2794)
							(mid -0.249642 -0.249642)
							(end -0.2794 -0.1778)
						)
						(arc
							(start -0.2794 0.1778)
							(mid -0.249642 0.249642)
							(end -0.1778 0.2794)
						)
						(arc
							(start 0.1778 0.2794)
							(mid 0.249642 0.249642)
							(end 0.2794 0.1778)
						)
						(arc
							(start 0.2794 -0.1778)
							(mid 0.249642 -0.249642)
							(end 0.1778 -0.2794)
						)
					)
					(width 0)
					(fill yes)
				)
			)
		)
		(pad "2" smd custom
			(at 0 0.4445 90)
			(size 0.1397 0.1397)
			(layers "F.Cu" "F.Mask" "F.Paste")
			(net "I2C_BMC_B_MISC_SCL")
			(options
				(clearance outline)
				(anchor circle)
			)
			(primitives
				(gr_poly
					(pts
						(arc
							(start -0.1778 -0.2794)
							(mid -0.249642 -0.249642)
							(end -0.2794 -0.1778)
						)
						(arc
							(start -0.2794 0.1778)
							(mid -0.249642 0.249642)
							(end -0.1778 0.2794)
						)
						(arc
							(start 0.1778 0.2794)
							(mid 0.249642 0.249642)
							(end 0.2794 0.1778)
						)
						(arc
							(start 0.2794 -0.1778)
							(mid 0.249642 -0.249642)
							(end 0.1778 -0.2794)
						)
					)
					(width 0)
					(fill yes)
				)
			)
		)
	)
	(footprint ""
		(layer "F.Cu")
		(at 116.739162 -159.939228 90)
		(property "Reference" "R485"
			(at 0 0 90)
			(layer "F.SilkS")
			(hide yes)
			(effects
				(font
					(size 1.27 1.27)
				)
			)
		)
		(property "Value" "0R2J-2-GP"
			(at 0.064008 -3.993896 90)
			(unlocked yes)
			(layer "F.Fab")
			(hide yes)
			(effects
				(font
					(size 1.016 1.016)
					(thickness 0.1524)
				)
			)
		)
		(property "Device Type" "R402H16"
			(at 0.064008 -5.517896 90)
			(unlocked yes)
			(layer "F.Fab")
			(hide yes)
			(effects
				(font
					(size 1.016 1.016)
					(thickness 0.1524)
				)
			)
		)
		(duplicate_pad_numbers_are_jumpers no)
		(fp_line
			(start 0.508 -0.9398)
			(end -0.508 -0.9398)
			(stroke
				(width 0.1524)
				(type default)
			)
			(layer "F.SilkS")
		)
		(fp_line
			(start -0.508 -0.9398)
			(end -0.508 0.9398)
			(stroke
				(width 0.1524)
				(type default)
			)
			(layer "F.SilkS")
		)
		(fp_rect
			(start -0.508 0.9398)
			(end 0.508 -0.9398)
			(stroke
				(width 0)
				(type default)
			)
			(fill no)
			(layer "F.CrtYd")
		)
		(fp_rect
			(start -0.508 0.9398)
			(end 0.508 -0.9398)
			(stroke
				(width 0)
				(type default)
			)
			(fill no)
			(layer "F.Fab")
		)
		(pad "1" smd custom
			(at 0 -0.4445 90)
			(size 0.1397 0.1397)
			(layers "F.Cu" "F.Mask" "F.Paste")
			(net "DRIVE_A_15_PWR")
			(options
				(clearance outline)
				(anchor circle)
			)
			(primitives
				(gr_poly
					(pts
						(arc
							(start -0.1778 -0.2794)
							(mid -0.249642 -0.249642)
							(end -0.2794 -0.1778)
						)
						(arc
							(start -0.2794 0.1778)
							(mid -0.249642 0.249642)
							(end -0.1778 0.2794)
						)
						(arc
							(start 0.1778 0.2794)
							(mid 0.249642 0.249642)
							(end 0.2794 0.1778)
						)
						(arc
							(start 0.2794 -0.1778)
							(mid 0.249642 -0.249642)
							(end 0.1778 -0.2794)
						)
					)
					(width 0)
					(fill yes)
				)
			)
		)
		(pad "2" smd custom
			(at 0 0.4445 90)
			(size 0.1397 0.1397)
			(layers "F.Cu" "F.Mask" "F.Paste")
			(net "SW_PWR_R_HDD15")
			(options
				(clearance outline)
				(anchor circle)
			)
			(primitives
				(gr_poly
					(pts
						(arc
							(start -0.1778 -0.2794)
							(mid -0.249642 -0.249642)
							(end -0.2794 -0.1778)
						)
						(arc
							(start -0.2794 0.1778)
							(mid -0.249642 0.249642)
							(end -0.1778 0.2794)
						)
						(arc
							(start 0.1778 0.2794)
							(mid 0.249642 0.249642)
							(end 0.2794 0.1778)
						)
						(arc
							(start 0.2794 -0.1778)
							(mid 0.249642 -0.249642)
							(end 0.1778 -0.2794)
						)
					)
					(width 0)
					(fill yes)
				)
			)
		)
	)
	(footprint ""
		(layer "F.Cu")
		(at 81.51495 -127.254)
		(property "Reference" "R292"
			(at 0 0 0)
			(layer "F.SilkS")
			(hide yes)
			(effects
				(font
					(size 1.27 1.27)
				)
			)
		)
		(property "Value" "91R3F-1-GP"
			(at -0.0254 -2.5146 0)
			(unlocked yes)
			(layer "F.Fab")
			(hide yes)
			(effects
				(font
					(size 1.016 1.016)
					(thickness 0.1524)
				)
			)
		)
		(property "Device Type" "R603H22"
			(at -0.0254 -4.0386 0)
			(unlocked yes)
			(layer "F.Fab")
			(hide yes)
			(effects
				(font
					(size 1.016 1.016)
					(thickness 0.1524)
				)
			)
		)
		(duplicate_pad_numbers_are_jumpers no)
		(fp_line
			(start -0.4826 0)
			(end -0.2032 0)
			(stroke
				(width 0.2032)
				(type default)
			)
			(layer "F.SilkS")
		)
		(fp_line
			(start 0.2032 0)
			(end 0.4826 0)
			(stroke
				(width 0.2032)
				(type default)
			)
			(layer "F.SilkS")
		)
		(fp_rect
			(start -0.5842 1.3335)
			(end 0.5842 -1.3335)
			(stroke
				(width 0)
				(type default)
			)
			(fill no)
			(layer "F.CrtYd")
		)
		(fp_rect
			(start -0.5842 1.3335)
			(end 0.5842 -1.3335)
			(stroke
				(width 0)
				(type default)
			)
			(fill no)
			(layer "F.Fab")
		)
		(pad "1" smd custom
			(at 0 -0.762)
			(size 0.2159 0.2159)
			(layers "F.Cu" "F.Mask" "F.Paste")
			(net "P5V_A_1")
			(options
				(clearance outline)
				(anchor circle)
			)
			(primitives
				(gr_poly
					(pts
						(arc
							(start -0.3302 -0.4318)
							(mid -0.402042 -0.402042)
							(end -0.4318 -0.3302)
						)
						(arc
							(start -0.4318 0.3302)
							(mid -0.402042 0.402042)
							(end -0.3302 0.4318)
						)
						(arc
							(start 0.3302 0.4318)
							(mid 0.402042 0.402042)
							(end 0.4318 0.3302)
						)
						(arc
							(start 0.4318 -0.3302)
							(mid 0.402042 -0.402042)
							(end 0.3302 -0.4318)
						)
					)
					(width 0)
					(fill yes)
				)
			)
		)
		(pad "2" smd custom
			(at 0 0.762)
			(size 0.2159 0.2159)
			(layers "F.Cu" "F.Mask" "F.Paste")
			(net "DRV_ACT_14")
			(options
				(clearance outline)
				(anchor circle)
			)
			(primitives
				(gr_poly
					(pts
						(arc
							(start -0.3302 -0.4318)
							(mid -0.402042 -0.402042)
							(end -0.4318 -0.3302)
						)
						(arc
							(start -0.4318 0.3302)
							(mid -0.402042 0.402042)
							(end -0.3302 0.4318)
						)
						(arc
							(start 0.3302 0.4318)
							(mid 0.402042 0.402042)
							(end 0.4318 0.3302)
						)
						(arc
							(start 0.4318 -0.3302)
							(mid 0.402042 -0.402042)
							(end 0.3302 -0.4318)
						)
					)
					(width 0)
					(fill yes)
				)
			)
		)
	)
	(footprint ""
		(layer "F.Cu")
		(at 370.1288 -139.5984 180)
		(property "Reference" "U24"
			(at 0 0 180)
			(layer "F.SilkS")
			(hide yes)
			(effects
				(font
					(size 1.27 1.27)
				)
			)
		)
		(property "Value" "ADM1278-2ACPZ-RL-1-GP"
			(at -4.7625 -7.4422 180)
			(unlocked yes)
			(layer "F.Fab")
			(hide yes)
			(effects
				(font
					(size 1.016 1.016)
					(thickness 0.1524)
				)
			)
		)
		(property "Device Type" "QFN32-G3D45-UH32"
			(at -4.7625 -8.9662 180)
			(unlocked yes)
			(layer "F.Fab")
			(hide yes)
			(effects
				(font
					(size 1.016 1.016)
					(thickness 0.1524)
				)
			)
		)
		(duplicate_pad_numbers_are_jumpers no)
		(fp_line
			(start 4.0513 -0.749808)
			(end 3.2893 -0.749808)
			(stroke
				(width 0.1524)
				(type default)
			)
			(layer "F.SilkS")
		)
		(fp_line
			(start 3.7973 1.749552)
			(end 3.2893 1.749552)
			(stroke
				(width 0.1524)
				(type default)
			)
			(layer "F.SilkS")
		)
		(fp_line
			(start 3.5179 3.5179)
			(end 2.2479 3.5179)
			(stroke
				(width 0.1524)
				(type default)
			)
			(layer "F.SilkS")
		)
		(fp_line
			(start 3.5179 2.2479)
			(end 3.5179 3.5179)
			(stroke
				(width 0.1524)
				(type default)
			)
			(layer "F.SilkS")
		)
		(fp_line
			(start -0.250698 4.0513)
			(end -0.250698 3.2893)
			(stroke
				(width 0.1524)
				(type default)
			)
			(layer "F.SilkS")
		)
		(fp_line
			(start -0.250698 -3.7973)
			(end -0.250698 -3.2893)
			(stroke
				(width 0.1524)
				(type default)
			)
			(layer "F.SilkS")
		)
		(fp_line
			(start -3.5179 3.5179)
			(end -2.2479 3.5179)
			(stroke
				(width 0.1524)
				(type default)
			)
			(layer "F.SilkS")
		)
		(fp_line
			(start -3.5179 2.2479)
			(end -3.5179 3.5179)
			(stroke
				(width 0.1524)
				(type default)
			)
			(layer "F.SilkS")
		)
		(fp_line
			(start -3.5179 -2.2479)
			(end -3.5179 -3.5179)
			(stroke
				(width 0.1524)
				(type default)
			)
			(layer "F.SilkS")
		)
		(fp_line
			(start -3.5179 -3.5179)
			(end -2.2479 -3.5179)
			(stroke
				(width 0.1524)
				(type default)
			)
			(layer "F.SilkS")
		)
		(fp_line
			(start -3.7973 1.24968)
			(end -3.2893 1.24968)
			(stroke
				(width 0.1524)
				(type default)
			)
			(layer "F.SilkS")
		)
		(fp_line
			(start -4.0513 -1.24968)
			(end -3.2893 -1.24968)
			(stroke
				(width 0.1524)
				(type default)
			)
			(layer "F.SilkS")
		)
		(fp_poly
			(pts
				(xy 2.2479 -3.5179) (xy 3.5179 -2.2479) (xy 3.5179 -3.5179)
			)
			(stroke
				(width 0)
				(type default)
			)
			(fill yes)
			(layer "F.SilkS")
		)
		(fp_rect
			(start -2.5019 2.5019)
			(end 2.5019 -2.5019)
			(stroke
				(width 0)
				(type default)
			)
			(fill no)
			(layer "F.CrtYd")
		)
		(fp_poly
			(pts
				(xy -3.5179 3.5179) (xy -3.5179 -3.5179) (xy 3.5179 -3.5179) (xy 3.5179 3.5179) (xy -2.49682 3.5179)
				(xy -2.49682 2.5019) (xy 2.5019 2.5019) (xy 2.5019 -2.5019) (xy -2.5019 -2.5019) (xy -2.5019 3.5179)
			)
			(stroke
				(width 0)
				(type default)
			)
			(fill no)
			(layer "F.CrtYd")
		)
		(fp_rect
			(start -3.5179 3.5179)
			(end 3.5179 -3.5179)
			(stroke
				(width 0)
				(type default)
			)
			(fill no)
			(layer "F.Fab")
		)
		(pad "1" smd rect
			(at 1.75006 -2.5527 180)
			(size 0.3048 0.9144)
			(layers "F.Cu" "F.Mask" "F.Paste")
			(net "MB1_PSET_R")
		)
		(pad "2" smd rect
			(at 1.249934 -2.4765 180)
			(size 0.3048 1.0668)
			(layers "F.Cu" "F.Mask" "F.Paste")
			(net "MB1_VCAP_R")
		)
		(pad "3" smd rect
			(at 0.750062 -2.4765 180)
			(size 0.3048 1.0668)
			(layers "F.Cu" "F.Mask" "F.Paste")
			(net "MB1_ISET_R")
		)
		(pad "4" smd rect
			(at 0.249936 -2.4765 180)
			(size 0.3048 1.0668)
			(layers "F.Cu" "F.Mask" "F.Paste")
			(net "MB1_ISTART_R")
		)
		(pad "5" smd rect
			(at -0.249936 -2.4765 180)
			(size 0.3048 1.0668)
			(layers "F.Cu" "F.Mask" "F.Paste")
			(net "MB1_TIME_R")
		)
		(pad "6" smd rect
			(at -0.750062 -2.4765 180)
			(size 0.3048 1.0668)
			(layers "F.Cu" "F.Mask" "F.Paste")
			(net "Net_1354")
		)
		(pad "7" smd rect
			(at -1.249934 -2.4765 180)
			(size 0.3048 1.0668)
			(layers "F.Cu" "F.Mask" "F.Paste")
			(net "MB1_CM_ADR1_R")
		)
		(pad "8" smd rect
			(at -1.75006 -2.5527 180)
			(size 0.3048 0.9144)
			(layers "F.Cu" "F.Mask" "F.Paste")
			(net "MB1_CM_ADR2_R")
		)
		(pad "9" smd rect
			(at -2.5527 -1.75006 180)
			(size 0.9144 0.3048)
			(layers "F.Cu" "F.Mask" "F.Paste")
			(net "MB1_SPISS_PD")
		)
		(pad "10" smd rect
			(at -2.4765 -1.249934 180)
			(size 1.0668 0.3048)
			(layers "F.Cu" "F.Mask" "F.Paste")
			(net "Net_1358")
		)
		(pad "11" smd rect
			(at -2.4765 -0.750062 180)
			(size 1.0668 0.3048)
			(layers "F.Cu" "F.Mask" "F.Paste")
			(net "Net_1357")
		)
		(pad "12" smd rect
			(at -2.4765 -0.249936 180)
			(size 1.0668 0.3048)
			(layers "F.Cu" "F.Mask" "F.Paste")
			(net "MB1_HS_ENABLE")
		)
		(pad "13" smd rect
			(at -2.4765 0.249936 180)
			(size 1.0668 0.3048)
			(layers "F.Cu" "F.Mask" "F.Paste")
			(net "Net_1356")
		)
		(pad "14" smd rect
			(at -2.4765 0.750062 180)
			(size 1.0668 0.3048)
			(layers "F.Cu" "F.Mask" "F.Paste")
			(net "Net_1355")
		)
		(pad "15" smd rect
			(at -2.4765 1.249934 180)
			(size 1.0668 0.3048)
			(layers "F.Cu" "F.Mask" "F.Paste")
			(net "MB1_SDA_R")
		)
		(pad "16" smd rect
			(at -2.5527 1.75006 180)
			(size 0.9144 0.3048)
			(layers "F.Cu" "F.Mask" "F.Paste")
			(net "MB1_SCL_R")
		)
		(pad "17" smd rect
			(at -1.75006 2.5527 180)
			(size 0.3048 0.9144)
			(layers "F.Cu" "F.Mask" "F.Paste")
			(net "MB1_RETRY_R")
		)
		(pad "18" smd rect
			(at -1.249934 2.4765 180)
			(size 0.3048 1.0668)
			(layers "F.Cu" "F.Mask" "F.Paste")
			(net "COMP_B_PGOOD")
		)
		(pad "19" smd rect
			(at -0.750062 2.4765 180)
			(size 0.3048 1.0668)
			(layers "F.Cu" "F.Mask" "F.Paste")
			(net "Net_1359")
		)
		(pad "20" smd rect
			(at -0.249936 2.4765 180)
			(size 0.3048 1.0668)
			(layers "F.Cu" "F.Mask" "F.Paste")
			(net "MB1_CM_VOUT_R")
		)
		(pad "21" smd rect
			(at 0.249936 2.4765 180)
			(size 0.3048 1.0668)
			(layers "F.Cu" "F.Mask" "F.Paste")
			(net "MB1_P12V_PWGIN_R")
		)
		(pad "22" smd rect
			(at 0.750062 2.4765 180)
			(size 0.3048 1.0668)
			(layers "F.Cu" "F.Mask" "F.Paste")
			(net "AGND_CURRENT_MONOB")
		)
		(pad "23" smd rect
			(at 1.249934 2.4765 180)
			(size 0.3048 1.0668)
			(layers "F.Cu" "F.Mask" "F.Paste")
			(net "GND")
		)
		(pad "24" smd rect
			(at 1.75006 2.5527 180)
			(size 0.3048 0.9144)
			(layers "F.Cu" "F.Mask" "F.Paste")
			(net "MB1_CM_GATE")
		)
		(pad "25" smd rect
			(at 2.5527 1.75006 180)
			(size 0.9144 0.3048)
			(layers "F.Cu" "F.Mask" "F.Paste")
			(net "MB1_TEMP")
		)
		(pad "26" smd rect
			(at 2.4765 1.249934 180)
			(size 1.0668 0.3048)
			(layers "F.Cu" "F.Mask" "F.Paste")
			(net "MB1_CM_SENSE_N")
		)
		(pad "27" smd rect
			(at 2.4765 0.750062 180)
			(size 1.0668 0.3048)
			(layers "F.Cu" "F.Mask" "F.Paste")
			(net "MB1_HS_SENSE_N")
		)
		(pad "28" smd rect
			(at 2.4765 0.249936 180)
			(size 1.0668 0.3048)
			(layers "F.Cu" "F.Mask" "F.Paste")
			(net "MB1_HS_SENSE_P")
		)
		(pad "29" smd rect
			(at 2.4765 -0.249936 180)
			(size 1.0668 0.3048)
			(layers "F.Cu" "F.Mask" "F.Paste")
			(net "MB1_CM_SENSE_P")
		)
		(pad "30" smd rect
			(at 2.4765 -0.750062 180)
			(size 1.0668 0.3048)
			(layers "F.Cu" "F.Mask" "F.Paste")
			(net "MB1_P12V_HS")
		)
		(pad "31" smd rect
			(at 2.4765 -1.249934 180)
			(size 1.0668 0.3048)
			(layers "F.Cu" "F.Mask" "F.Paste")
			(net "MB1_CM_UV_R")
		)
		(pad "32" smd rect
			(at 2.5527 -1.75006 180)
			(size 0.9144 0.3048)
			(layers "F.Cu" "F.Mask" "F.Paste")
			(net "MB1_CM_OV_R")
		)
		(pad "33" smd rect
			(at 0 0 180)
			(size 3.4544 3.4544)
			(layers "F.Cu" "F.Mask" "F.Paste")
			(net "AGND_CURRENT_MONOB")
		)
	)
	(footprint ""
		(layer "F.Cu")
		(at 141.042898 -283.507942 -90)
		(property "Reference" "R237"
			(at 0 0 270)
			(layer "F.SilkS")
			(hide yes)
			(effects
				(font
					(size 1.27 1.27)
				)
			)
		)
		(property "Value" "300KR2F-GP"
			(at 0.064008 -3.993896 270)
			(unlocked yes)
			(layer "F.Fab")
			(hide yes)
			(effects
				(font
					(size 1.016 1.016)
					(thickness 0.1524)
				)
			)
		)
		(property "Device Type" "R402H16"
			(at 0.064008 -5.517896 270)
			(unlocked yes)
			(layer "F.Fab")
			(hide yes)
			(effects
				(font
					(size 1.016 1.016)
					(thickness 0.1524)
				)
			)
		)
		(duplicate_pad_numbers_are_jumpers no)
		(fp_line
			(start -0.508 -0.9398)
			(end -0.508 0.9398)
			(stroke
				(width 0.1524)
				(type default)
			)
			(layer "F.SilkS")
		)
		(fp_line
			(start 0.508 -0.9398)
			(end -0.508 -0.9398)
			(stroke
				(width 0.1524)
				(type default)
			)
			(layer "F.SilkS")
		)
		(fp_rect
			(start -0.508 0.9398)
			(end 0.508 -0.9398)
			(stroke
				(width 0)
				(type default)
			)
			(fill no)
			(layer "F.CrtYd")
		)
		(fp_rect
			(start -0.508 0.9398)
			(end 0.508 -0.9398)
			(stroke
				(width 0)
				(type default)
			)
			(fill no)
			(layer "F.Fab")
		)
		(pad "1" smd custom
			(at 0 -0.4445 270)
			(size 0.1397 0.1397)
			(layers "F.Cu" "F.Mask" "F.Paste")
			(net "SW_HDD_N4")
			(options
				(clearance outline)
				(anchor circle)
			)
			(primitives
				(gr_poly
					(pts
						(arc
							(start -0.1778 -0.2794)
							(mid -0.249642 -0.249642)
							(end -0.2794 -0.1778)
						)
						(arc
							(start -0.2794 0.1778)
							(mid -0.249642 0.249642)
							(end -0.1778 0.2794)
						)
						(arc
							(start 0.1778 0.2794)
							(mid 0.249642 0.249642)
							(end 0.2794 0.1778)
						)
						(arc
							(start 0.2794 -0.1778)
							(mid 0.249642 -0.249642)
							(end 0.1778 -0.2794)
						)
					)
					(width 0)
					(fill yes)
				)
			)
		)
		(pad "2" smd custom
			(at 0 0.4445 270)
			(size 0.1397 0.1397)
			(layers "F.Cu" "F.Mask" "F.Paste")
			(net "P12V_A")
			(options
				(clearance outline)
				(anchor circle)
			)
			(primitives
				(gr_poly
					(pts
						(arc
							(start -0.1778 -0.2794)
							(mid -0.249642 -0.249642)
							(end -0.2794 -0.1778)
						)
						(arc
							(start -0.2794 0.1778)
							(mid -0.249642 0.249642)
							(end -0.1778 0.2794)
						)
						(arc
							(start 0.1778 0.2794)
							(mid 0.249642 0.249642)
							(end 0.2794 0.1778)
						)
						(arc
							(start 0.2794 -0.1778)
							(mid 0.249642 -0.249642)
							(end 0.1778 -0.2794)
						)
					)
					(width 0)
					(fill yes)
				)
			)
		)
	)
	(footprint ""
		(layer "F.Cu")
		(at 332.359 -180.826918 180)
		(property "Reference" "C275"
			(at 0 0 180)
			(layer "F.SilkS")
			(hide yes)
			(effects
				(font
					(size 1.27 1.27)
				)
			)
		)
		(property "Value" "SC10U16V6KX-2GP"
			(at -0.0762 -5.1308 180)
			(unlocked yes)
			(layer "F.Fab")
			(hide yes)
			(effects
				(font
					(size 1.016 1.016)
					(thickness 0.1524)
				)
			)
		)
		(property "Device Type" "C1206H71"
			(at -0.127 -6.6548 180)
			(unlocked yes)
			(layer "F.Fab")
			(hide yes)
			(effects
				(font
					(size 1.016 1.016)
					(thickness 0.1524)
				)
			)
		)
		(duplicate_pad_numbers_are_jumpers no)
		(fp_line
			(start 1.016 2.2352)
			(end -1.016 2.2352)
			(stroke
				(width 0.1524)
				(type default)
			)
			(layer "F.SilkS")
		)
		(fp_line
			(start 1.016 0.8382)
			(end 1.016 2.2352)
			(stroke
				(width 0.1524)
				(type default)
			)
			(layer "F.SilkS")
		)
		(fp_line
			(start 1.016 -2.2352)
			(end 1.016 -0.8382)
			(stroke
				(width 0.1524)
				(type default)
			)
			(layer "F.SilkS")
		)
		(fp_line
			(start -1.016 2.2352)
			(end -1.016 0.8382)
			(stroke
				(width 0.1524)
				(type default)
			)
			(layer "F.SilkS")
		)
		(fp_line
			(start -1.016 -0.8382)
			(end -1.016 -2.2352)
			(stroke
				(width 0.1524)
				(type default)
			)
			(layer "F.SilkS")
		)
		(fp_line
			(start -1.016 -2.2352)
			(end 1.016 -2.2352)
			(stroke
				(width 0.1524)
				(type default)
			)
			(layer "F.SilkS")
		)
		(fp_rect
			(start -1.0922 2.3114)
			(end 1.0922 -2.3114)
			(stroke
				(width 0)
				(type default)
			)
			(fill no)
			(layer "F.CrtYd")
		)
		(fp_poly
			(pts
				(xy 1.0922 -2.3114) (xy 1.0922 2.3114) (xy -1.0922 2.3114) (xy -1.0922 -2.3114)
			)
			(stroke
				(width 0)
				(type default)
			)
			(fill no)
			(layer "F.Fab")
		)
		(pad "1" smd rect
			(at 0 -1.397 180)
			(size 1.651 1.27)
			(layers "F.Cu" "F.Mask" "F.Paste")
			(net "P5V_HDD18")
		)
		(pad "2" smd rect
			(at 0 1.397 180)
			(size 1.651 1.27)
			(layers "F.Cu" "F.Mask" "F.Paste")
			(net "GND")
		)
	)
	(footprint ""
		(layer "F.Cu")
		(at 98.767646 -304.353468 180)
		(property "Reference" "R232"
			(at 0 0 180)
			(layer "F.SilkS")
			(hide yes)
			(effects
				(font
					(size 1.27 1.27)
				)
			)
		)
		(property "Value" "130R3F-GP"
			(at -0.0254 -2.5146 180)
			(unlocked yes)
			(layer "F.Fab")
			(hide yes)
			(effects
				(font
					(size 1.016 1.016)
					(thickness 0.1524)
				)
			)
		)
		(property "Device Type" "R603H22"
			(at -0.0254 -4.0386 180)
			(unlocked yes)
			(layer "F.Fab")
			(hide yes)
			(effects
				(font
					(size 1.016 1.016)
					(thickness 0.1524)
				)
			)
		)
		(duplicate_pad_numbers_are_jumpers no)
		(fp_line
			(start 0.2032 0)
			(end 0.4826 0)
			(stroke
				(width 0.2032)
				(type default)
			)
			(layer "F.SilkS")
		)
		(fp_line
			(start -0.4826 0)
			(end -0.2032 0)
			(stroke
				(width 0.2032)
				(type default)
			)
			(layer "F.SilkS")
		)
		(fp_rect
			(start -0.5842 1.3335)
			(end 0.5842 -1.3335)
			(stroke
				(width 0)
				(type default)
			)
			(fill no)
			(layer "F.CrtYd")
		)
		(fp_rect
			(start -0.5842 1.3335)
			(end 0.5842 -1.3335)
			(stroke
				(width 0)
				(type default)
			)
			(fill no)
			(layer "F.Fab")
		)
		(pad "1" smd custom
			(at 0 -0.762 180)
			(size 0.2159 0.2159)
			(layers "F.Cu" "F.Mask" "F.Paste")
			(net "P5V_B")
			(options
				(clearance outline)
				(anchor circle)
			)
			(primitives
				(gr_poly
					(pts
						(arc
							(start -0.3302 -0.4318)
							(mid -0.402042 -0.402042)
							(end -0.4318 -0.3302)
						)
						(arc
							(start -0.4318 0.3302)
							(mid -0.402042 0.402042)
							(end -0.3302 0.4318)
						)
						(arc
							(start 0.3302 0.4318)
							(mid 0.402042 0.402042)
							(end 0.4318 0.3302)
						)
						(arc
							(start 0.4318 -0.3302)
							(mid 0.402042 -0.402042)
							(end 0.3302 -0.4318)
						)
					)
					(width 0)
					(fill yes)
				)
			)
		)
		(pad "2" smd custom
			(at 0 0.762 180)
			(size 0.2159 0.2159)
			(layers "F.Cu" "F.Mask" "F.Paste")
			(net "FLT_HDD27")
			(options
				(clearance outline)
				(anchor circle)
			)
			(primitives
				(gr_poly
					(pts
						(arc
							(start -0.3302 -0.4318)
							(mid -0.402042 -0.402042)
							(end -0.4318 -0.3302)
						)
						(arc
							(start -0.4318 0.3302)
							(mid -0.402042 0.402042)
							(end -0.3302 0.4318)
						)
						(arc
							(start 0.3302 0.4318)
							(mid 0.402042 0.402042)
							(end 0.4318 0.3302)
						)
						(arc
							(start 0.4318 -0.3302)
							(mid 0.402042 -0.402042)
							(end 0.3302 -0.4318)
						)
					)
					(width 0)
					(fill yes)
				)
			)
		)
	)
	(footprint ""
		(layer "F.Cu")
		(at 431.581052 -160.735518 180)
		(property "Reference" "R627"
			(at 0 0 180)
			(layer "F.SilkS")
			(hide yes)
			(effects
				(font
					(size 1.27 1.27)
				)
			)
		)
		(property "Value" "4K7R2J-2-GP"
			(at 0.064008 -3.993896 180)
			(unlocked yes)
			(layer "F.Fab")
			(hide yes)
			(effects
				(font
					(size 1.016 1.016)
					(thickness 0.1524)
				)
			)
		)
		(property "Device Type" "R402H16"
			(at 0.064008 -5.517896 180)
			(unlocked yes)
			(layer "F.Fab")
			(hide yes)
			(effects
				(font
					(size 1.016 1.016)
					(thickness 0.1524)
				)
			)
		)
		(duplicate_pad_numbers_are_jumpers no)
		(fp_line
			(start 0.508 -0.9398)
			(end -0.508 -0.9398)
			(stroke
				(width 0.1524)
				(type default)
			)
			(layer "F.SilkS")
		)
		(fp_line
			(start -0.508 -0.9398)
			(end -0.508 0.9398)
			(stroke
				(width 0.1524)
				(type default)
			)
			(layer "F.SilkS")
		)
		(fp_rect
			(start -0.508 0.9398)
			(end 0.508 -0.9398)
			(stroke
				(width 0)
				(type default)
			)
			(fill no)
			(layer "F.CrtYd")
		)
		(fp_rect
			(start -0.508 0.9398)
			(end 0.508 -0.9398)
			(stroke
				(width 0)
				(type default)
			)
			(fill no)
			(layer "F.Fab")
		)
		(pad "1" smd custom
			(at 0 -0.4445 180)
			(size 0.1397 0.1397)
			(layers "F.Cu" "F.Mask" "F.Paste")
			(net "P12V_A")
			(options
				(clearance outline)
				(anchor circle)
			)
			(primitives
				(gr_poly
					(pts
						(arc
							(start -0.1778 -0.2794)
							(mid -0.249642 -0.249642)
							(end -0.2794 -0.1778)
						)
						(arc
							(start -0.2794 0.1778)
							(mid -0.249642 0.249642)
							(end -0.1778 0.2794)
						)
						(arc
							(start 0.1778 0.2794)
							(mid 0.249642 0.249642)
							(end 0.2794 0.1778)
						)
						(arc
							(start 0.2794 -0.1778)
							(mid 0.249642 -0.249642)
							(end 0.1778 -0.2794)
						)
					)
					(width 0)
					(fill yes)
				)
			)
		)
		(pad "2" smd custom
			(at 0 0.4445 180)
			(size 0.1397 0.1397)
			(layers "F.Cu" "F.Mask" "F.Paste")
			(net "SW_HDD_R21")
			(options
				(clearance outline)
				(anchor circle)
			)
			(primitives
				(gr_poly
					(pts
						(arc
							(start -0.1778 -0.2794)
							(mid -0.249642 -0.249642)
							(end -0.2794 -0.1778)
						)
						(arc
							(start -0.2794 0.1778)
							(mid -0.249642 0.249642)
							(end -0.1778 0.2794)
						)
						(arc
							(start 0.1778 0.2794)
							(mid 0.249642 0.249642)
							(end 0.2794 0.1778)
						)
						(arc
							(start 0.2794 -0.1778)
							(mid 0.249642 -0.249642)
							(end 0.1778 -0.2794)
						)
					)
					(width 0)
					(fill yes)
				)
			)
		)
	)
	(footprint ""
		(layer "F.Cu")
		(at 95.608902 -277.750016 -90)
		(property "Reference" "VIA38"
			(at 0 0 270)
			(layer "F.SilkS")
			(hide yes)
			(effects
				(font
					(size 1.27 1.27)
				)
			)
		)
		(property "Value" "100OHM-8L-1D6MM-L18L16-GP"
			(at -3.7211 -4.5085 270)
			(unlocked yes)
			(layer "F.Fab")
			(hide yes)
			(effects
				(font
					(size 1.016 1.016)
					(thickness 0.1524)
				)
			)
		)
		(property "Device Type" "VIA-PCIE-4P-394076"
			(at -3.7211 -6.0325 270)
			(unlocked yes)
			(layer "F.Fab")
			(hide yes)
			(effects
				(font
					(size 1.016 1.016)
					(thickness 0.1524)
				)
			)
		)
		(duplicate_pad_numbers_are_jumpers no)
		(fp_rect
			(start -1.9685 0.381)
			(end 1.9685 -0.381)
			(stroke
				(width 0)
				(type default)
			)
			(fill no)
			(layer "F.CrtYd")
		)
		(fp_rect
			(start -1.9685 0.381)
			(end 1.9685 -0.381)
			(stroke
				(width 0)
				(type default)
			)
			(fill no)
			(layer "F.Fab")
		)
		(pad "1" thru_hole circle
			(at -1.5875 0 270)
			(size 0.508 0.508)
			(drill 0.254)
			(layers "*.Cu" "*.Mask")
			(remove_unused_layers no)
			(net "GND")
			(clearance 0.127)
			(thermal_gap 0.127)
		)
		(pad "2" thru_hole circle
			(at -0.5715 0 270)
			(size 0.508 0.508)
			(drill 0.254)
			(layers "*.Cu" "*.Mask")
			(remove_unused_layers no)
			(net "PHY_DRV_A_TO_SCC_A_2_DP")
			(clearance 0.127)
			(thermal_gap 0.127)
		)
		(pad "3" thru_hole circle
			(at 0.5715 0 270)
			(size 0.508 0.508)
			(drill 0.254)
			(layers "*.Cu" "*.Mask")
			(remove_unused_layers no)
			(net "PHY_DRV_A_TO_SCC_A_2_DN")
			(clearance 0.127)
			(thermal_gap 0.127)
		)
		(pad "4" thru_hole circle
			(at 1.5875 0 270)
			(size 0.508 0.508)
			(drill 0.254)
			(layers "*.Cu" "*.Mask")
			(remove_unused_layers no)
			(net "GND")
			(clearance 0.127)
			(thermal_gap 0.127)
		)
	)
	(footprint ""
		(layer "F.Cu")
		(at 128.644396 -283.101542 -90)
		(property "Reference" "C87"
			(at 0 0 270)
			(layer "F.SilkS")
			(hide yes)
			(effects
				(font
					(size 1.27 1.27)
				)
			)
		)
		(property "Value" "SCD033U25V2KX-GP"
			(at 1.1811 -2.7051 270)
			(unlocked yes)
			(layer "F.Fab")
			(hide yes)
			(effects
				(font
					(size 1.016 1.016)
					(thickness 0.1524)
				)
			)
		)
		(property "Device Type" "C402H22"
			(at 1.1811 -4.2291 270)
			(unlocked yes)
			(layer "F.Fab")
			(hide yes)
			(effects
				(font
					(size 1.016 1.016)
					(thickness 0.1524)
				)
			)
		)
		(duplicate_pad_numbers_are_jumpers no)
		(fp_rect
			(start -0.4318 0.9525)
			(end 0.4318 -0.9525)
			(stroke
				(width 0)
				(type default)
			)
			(fill no)
			(layer "F.CrtYd")
		)
		(fp_rect
			(start -0.4318 0.9525)
			(end 0.4318 -0.9525)
			(stroke
				(width 0)
				(type default)
			)
			(fill no)
			(layer "F.Fab")
		)
		(pad "1" smd custom
			(at 0 -0.4445 270)
			(size 0.1524 0.1524)
			(layers "F.Cu" "F.Mask" "F.Paste")
			(net "SW_HDD_P3")
			(options
				(clearance outline)
				(anchor circle)
			)
			(primitives
				(gr_poly
					(pts
						(arc
							(start 0.3048 -0.2032)
							(mid 0.275042 -0.275042)
							(end 0.2032 -0.3048)
						)
						(arc
							(start -0.2032 -0.3048)
							(mid -0.275042 -0.275042)
							(end -0.3048 -0.2032)
						)
						(arc
							(start -0.3048 0.2032)
							(mid -0.275042 0.275042)
							(end -0.2032 0.3048)
						)
						(arc
							(start 0.2032 0.3048)
							(mid 0.275042 0.275042)
							(end 0.3048 0.2032)
						)
					)
					(width 0)
					(fill yes)
				)
			)
		)
		(pad "2" smd custom
			(at 0 0.4445 270)
			(size 0.1524 0.1524)
			(layers "F.Cu" "F.Mask" "F.Paste")
			(net "GND")
			(options
				(clearance outline)
				(anchor circle)
			)
			(primitives
				(gr_poly
					(pts
						(arc
							(start 0.3048 -0.2032)
							(mid 0.275042 -0.275042)
							(end 0.2032 -0.3048)
						)
						(arc
							(start -0.2032 -0.3048)
							(mid -0.275042 -0.275042)
							(end -0.3048 -0.2032)
						)
						(arc
							(start -0.3048 0.2032)
							(mid -0.275042 0.275042)
							(end -0.2032 0.3048)
						)
						(arc
							(start 0.2032 0.3048)
							(mid 0.275042 0.275042)
							(end 0.3048 0.2032)
						)
					)
					(width 0)
					(fill yes)
				)
			)
		)
	)
	(footprint ""
		(layer "F.Cu")
		(at 361.369102 -296.842942 180)
		(property "Reference" "C131"
			(at 0 0 180)
			(layer "F.SilkS")
			(hide yes)
			(effects
				(font
					(size 1.27 1.27)
				)
			)
		)
		(property "Value" "SC1U16V3KX-5GP"
			(at 0 -2.8194 180)
			(unlocked yes)
			(layer "F.Fab")
			(hide yes)
			(effects
				(font
					(size 1.016 1.016)
					(thickness 0.1524)
				)
			)
		)
		(property "Device Type" "C603H36"
			(at 0 -4.3434 180)
			(unlocked yes)
			(layer "F.Fab")
			(hide yes)
			(effects
				(font
					(size 1.016 1.016)
					(thickness 0.1524)
				)
			)
		)
		(duplicate_pad_numbers_are_jumpers no)
		(fp_line
			(start 0.508 0)
			(end -0.508 0)
			(stroke
				(width 0.2032)
				(type default)
			)
			(layer "F.SilkS")
		)
		(fp_rect
			(start -0.5842 1.3335)
			(end 0.5842 -1.3335)
			(stroke
				(width 0)
				(type default)
			)
			(fill no)
			(layer "F.CrtYd")
		)
		(fp_rect
			(start -0.5842 1.3335)
			(end 0.5842 -1.3335)
			(stroke
				(width 0)
				(type default)
			)
			(fill no)
			(layer "F.Fab")
		)
		(pad "1" smd custom
			(at 0 -0.762 180)
			(size 0.2159 0.2159)
			(layers "F.Cu" "F.Mask" "F.Paste")
			(net "P5V_HDD7")
			(options
				(clearance outline)
				(anchor circle)
			)
			(primitives
				(gr_poly
					(pts
						(arc
							(start -0.3302 -0.4318)
							(mid -0.402042 -0.402042)
							(end -0.4318 -0.3302)
						)
						(arc
							(start -0.4318 0.3302)
							(mid -0.402042 0.402042)
							(end -0.3302 0.4318)
						)
						(arc
							(start 0.3302 0.4318)
							(mid 0.402042 0.402042)
							(end 0.4318 0.3302)
						)
						(arc
							(start 0.4318 -0.3302)
							(mid 0.402042 -0.402042)
							(end 0.3302 -0.4318)
						)
					)
					(width 0)
					(fill yes)
				)
			)
		)
		(pad "2" smd custom
			(at 0 0.762 180)
			(size 0.2159 0.2159)
			(layers "F.Cu" "F.Mask" "F.Paste")
			(net "GND")
			(options
				(clearance outline)
				(anchor circle)
			)
			(primitives
				(gr_poly
					(pts
						(arc
							(start -0.3302 -0.4318)
							(mid -0.402042 -0.402042)
							(end -0.4318 -0.3302)
						)
						(arc
							(start -0.4318 0.3302)
							(mid -0.402042 0.402042)
							(end -0.3302 0.4318)
						)
						(arc
							(start 0.3302 0.4318)
							(mid 0.402042 0.402042)
							(end 0.4318 0.3302)
						)
						(arc
							(start 0.4318 -0.3302)
							(mid 0.402042 -0.402042)
							(end 0.3302 -0.4318)
						)
					)
					(width 0)
					(fill yes)
				)
			)
		)
	)
	(footprint ""
		(layer "F.Cu")
		(at 128.644396 -282.085542 90)
		(property "Reference" "R206"
			(at 0 0 90)
			(layer "F.SilkS")
			(hide yes)
			(effects
				(font
					(size 1.27 1.27)
				)
			)
		)
		(property "Value" "4K7R2J-2-GP"
			(at 0.064008 -3.993896 90)
			(unlocked yes)
			(layer "F.Fab")
			(hide yes)
			(effects
				(font
					(size 1.016 1.016)
					(thickness 0.1524)
				)
			)
		)
		(property "Device Type" "R402H16"
			(at 0.064008 -5.517896 90)
			(unlocked yes)
			(layer "F.Fab")
			(hide yes)
			(effects
				(font
					(size 1.016 1.016)
					(thickness 0.1524)
				)
			)
		)
		(duplicate_pad_numbers_are_jumpers no)
		(fp_line
			(start 0.508 -0.9398)
			(end -0.508 -0.9398)
			(stroke
				(width 0.1524)
				(type default)
			)
			(layer "F.SilkS")
		)
		(fp_line
			(start -0.508 -0.9398)
			(end -0.508 0.9398)
			(stroke
				(width 0.1524)
				(type default)
			)
			(layer "F.SilkS")
		)
		(fp_rect
			(start -0.508 0.9398)
			(end 0.508 -0.9398)
			(stroke
				(width 0)
				(type default)
			)
			(fill no)
			(layer "F.CrtYd")
		)
		(fp_rect
			(start -0.508 0.9398)
			(end 0.508 -0.9398)
			(stroke
				(width 0)
				(type default)
			)
			(fill no)
			(layer "F.Fab")
		)
		(pad "1" smd custom
			(at 0 -0.4445 90)
			(size 0.1397 0.1397)
			(layers "F.Cu" "F.Mask" "F.Paste")
			(net "P12V_A")
			(options
				(clearance outline)
				(anchor circle)
			)
			(primitives
				(gr_poly
					(pts
						(arc
							(start -0.1778 -0.2794)
							(mid -0.249642 -0.249642)
							(end -0.2794 -0.1778)
						)
						(arc
							(start -0.2794 0.1778)
							(mid -0.249642 0.249642)
							(end -0.1778 0.2794)
						)
						(arc
							(start 0.1778 0.2794)
							(mid 0.249642 0.249642)
							(end 0.2794 0.1778)
						)
						(arc
							(start 0.2794 -0.1778)
							(mid 0.249642 -0.249642)
							(end 0.1778 -0.2794)
						)
					)
					(width 0)
					(fill yes)
				)
			)
		)
		(pad "2" smd custom
			(at 0 0.4445 90)
			(size 0.1397 0.1397)
			(layers "F.Cu" "F.Mask" "F.Paste")
			(net "SW_HDD_P3")
			(options
				(clearance outline)
				(anchor circle)
			)
			(primitives
				(gr_poly
					(pts
						(arc
							(start -0.1778 -0.2794)
							(mid -0.249642 -0.249642)
							(end -0.2794 -0.1778)
						)
						(arc
							(start -0.2794 0.1778)
							(mid -0.249642 0.249642)
							(end -0.1778 0.2794)
						)
						(arc
							(start 0.1778 0.2794)
							(mid 0.249642 0.249642)
							(end 0.2794 0.1778)
						)
						(arc
							(start 0.2794 -0.1778)
							(mid 0.249642 -0.249642)
							(end 0.1778 -0.2794)
						)
					)
					(width 0)
					(fill yes)
				)
			)
		)
	)
	(footprint ""
		(layer "F.Cu")
		(at 233.299 -382.1938 180)
		(property "Reference" "R1147"
			(at 0 0 180)
			(layer "F.SilkS")
			(hide yes)
			(effects
				(font
					(size 1.27 1.27)
				)
			)
		)
		(property "Value" "10KR2J-3-GP"
			(at 0.064008 -3.993896 180)
			(unlocked yes)
			(layer "F.Fab")
			(hide yes)
			(effects
				(font
					(size 1.016 1.016)
					(thickness 0.1524)
				)
			)
		)
		(property "Device Type" "R402H16"
			(at 0.064008 -5.517896 180)
			(unlocked yes)
			(layer "F.Fab")
			(hide yes)
			(effects
				(font
					(size 1.016 1.016)
					(thickness 0.1524)
				)
			)
		)
		(duplicate_pad_numbers_are_jumpers no)
		(fp_line
			(start 0.508 -0.9398)
			(end -0.508 -0.9398)
			(stroke
				(width 0.1524)
				(type default)
			)
			(layer "F.SilkS")
		)
		(fp_line
			(start -0.508 -0.9398)
			(end -0.508 0.9398)
			(stroke
				(width 0.1524)
				(type default)
			)
			(layer "F.SilkS")
		)
		(fp_rect
			(start -0.508 0.9398)
			(end 0.508 -0.9398)
			(stroke
				(width 0)
				(type default)
			)
			(fill no)
			(layer "F.CrtYd")
		)
		(fp_rect
			(start -0.508 0.9398)
			(end 0.508 -0.9398)
			(stroke
				(width 0)
				(type default)
			)
			(fill no)
			(layer "F.Fab")
		)
		(pad "1" smd custom
			(at 0 -0.4445 180)
			(size 0.1397 0.1397)
			(layers "F.Cu" "F.Mask" "F.Paste")
			(net "GND")
			(options
				(clearance outline)
				(anchor circle)
			)
			(primitives
				(gr_poly
					(pts
						(arc
							(start -0.1778 -0.2794)
							(mid -0.249642 -0.249642)
							(end -0.2794 -0.1778)
						)
						(arc
							(start -0.2794 0.1778)
							(mid -0.249642 0.249642)
							(end -0.1778 0.2794)
						)
						(arc
							(start 0.1778 0.2794)
							(mid 0.249642 0.249642)
							(end 0.2794 0.1778)
						)
						(arc
							(start 0.2794 -0.1778)
							(mid 0.249642 -0.249642)
							(end 0.1778 -0.2794)
						)
					)
					(width 0)
					(fill yes)
				)
			)
		)
		(pad "2" smd custom
			(at 0 0.4445 180)
			(size 0.1397 0.1397)
			(layers "F.Cu" "F.Mask" "F.Paste")
			(net "MB3_RETRY_R")
			(options
				(clearance outline)
				(anchor circle)
			)
			(primitives
				(gr_poly
					(pts
						(arc
							(start -0.1778 -0.2794)
							(mid -0.249642 -0.249642)
							(end -0.2794 -0.1778)
						)
						(arc
							(start -0.2794 0.1778)
							(mid -0.249642 0.249642)
							(end -0.1778 0.2794)
						)
						(arc
							(start 0.1778 0.2794)
							(mid 0.249642 0.249642)
							(end 0.2794 0.1778)
						)
						(arc
							(start 0.2794 -0.1778)
							(mid 0.249642 -0.249642)
							(end 0.1778 -0.2794)
						)
					)
					(width 0)
					(fill yes)
				)
			)
		)
	)
	(footprint ""
		(layer "F.Cu")
		(at 472.899994 -209.399886)
		(property "Reference" "FLED12"
			(at 0 0 0)
			(layer "F.SilkS")
			(hide yes)
			(effects
				(font
					(size 1.27 1.27)
				)
			)
		)
		(property "Value" "LED-BY-19-GP"
			(at -2.132076 1.414018 0)
			(unlocked yes)
			(layer "F.Fab")
			(hide yes)
			(effects
				(font
					(size 1.016 1.016)
					(thickness 0.1524)
				)
			)
		)
		(property "Device Type" "LED-1615-4PH26"
			(at -2.132076 -0.109982 0)
			(unlocked yes)
			(layer "F.Fab")
			(hide yes)
			(effects
				(font
					(size 1.016 1.016)
					(thickness 0.1524)
				)
			)
		)
		(duplicate_pad_numbers_are_jumpers no)
		(fp_line
			(start -1.2954 0.254)
			(end -1.2954 1.6002)
			(stroke
				(width 0.508)
				(type default)
			)
			(layer "F.SilkS")
		)
		(fp_line
			(start -1.2954 1.6002)
			(end 1.2954 1.6002)
			(stroke
				(width 0.508)
				(type default)
			)
			(layer "F.SilkS")
		)
		(fp_line
			(start -1.1176 -1.4224)
			(end 1.1176 -1.4224)
			(stroke
				(width 0.1524)
				(type default)
			)
			(layer "F.SilkS")
		)
		(fp_line
			(start -1.1176 1.4224)
			(end -1.1176 -1.4224)
			(stroke
				(width 0.1524)
				(type default)
			)
			(layer "F.SilkS")
		)
		(fp_line
			(start 1.1176 -1.4224)
			(end 1.1176 1.4224)
			(stroke
				(width 0.1524)
				(type default)
			)
			(layer "F.SilkS")
		)
		(fp_line
			(start 1.1176 1.4224)
			(end -1.1176 1.4224)
			(stroke
				(width 0.1524)
				(type default)
			)
			(layer "F.SilkS")
		)
		(fp_line
			(start 1.2954 1.6002)
			(end 1.2954 0.254)
			(stroke
				(width 0.508)
				(type default)
			)
			(layer "F.SilkS")
		)
		(fp_rect
			(start -0.7493 0.8001)
			(end 0.7493 -0.8001)
			(stroke
				(width 0)
				(type default)
			)
			(fill no)
			(layer "F.CrtYd")
		)
		(fp_poly
			(pts
				(xy -1.3716 1.6764) (xy -1.3716 -1.6764) (xy 1.3716 -1.6764) (xy 1.3716 0.0635) (xy 0.7493 0.0635)
				(xy 0.7493 -0.8001) (xy -0.7493 -0.8001) (xy -0.7493 0.8001) (xy 0.7493 0.8001) (xy 0.7493 0.0762)
				(xy 1.3716 0.0762) (xy 1.3716 1.6764)
			)
			(stroke
				(width 0)
				(type default)
			)
			(fill no)
			(layer "F.CrtYd")
		)
		(fp_rect
			(start -1.3716 1.6764)
			(end 1.3716 -1.6764)
			(stroke
				(width 0)
				(type default)
			)
			(fill no)
			(layer "F.Fab")
		)
		(pad "1" smd rect
			(at 0.50038 -0.73025)
			(size 0.7112 0.8636)
			(layers "F.Cu" "F.Mask" "F.Paste")
			(net "DRV_ACT_11")
		)
		(pad "2" smd rect
			(at -0.50038 -0.73025)
			(size 0.7112 0.8636)
			(layers "F.Cu" "F.Mask" "F.Paste")
			(net "FLT_HDD11")
		)
		(pad "3" smd rect
			(at 0.50038 0.73025)
			(size 0.7112 0.8636)
			(layers "F.Cu" "F.Mask" "F.Paste")
			(net "DRV_ACT_11_N")
		)
		(pad "4" smd rect
			(at -0.50038 0.73025)
			(size 0.7112 0.8636)
			(layers "F.Cu" "F.Mask" "F.Paste")
			(net "FLT_HDD11_N")
		)
	)
	(footprint ""
		(layer "F.Cu")
		(at 253.873 -301.244 180)
		(property "Reference" "C1"
			(at 0 0 180)
			(layer "F.SilkS")
			(hide yes)
			(effects
				(font
					(size 1.27 1.27)
				)
			)
		)
		(property "Value" "SCD1U16V2KX-3GP"
			(at 1.1811 -2.7051 180)
			(unlocked yes)
			(layer "F.Fab")
			(hide yes)
			(effects
				(font
					(size 1.016 1.016)
					(thickness 0.1524)
				)
			)
		)
		(property "Device Type" "C402H22"
			(at 1.1811 -4.2291 180)
			(unlocked yes)
			(layer "F.Fab")
			(hide yes)
			(effects
				(font
					(size 1.016 1.016)
					(thickness 0.1524)
				)
			)
		)
		(duplicate_pad_numbers_are_jumpers no)
		(fp_rect
			(start -0.4318 0.9525)
			(end 0.4318 -0.9525)
			(stroke
				(width 0)
				(type default)
			)
			(fill no)
			(layer "F.CrtYd")
		)
		(fp_rect
			(start -0.4318 0.9525)
			(end 0.4318 -0.9525)
			(stroke
				(width 0)
				(type default)
			)
			(fill no)
			(layer "F.Fab")
		)
		(pad "1" smd custom
			(at 0 -0.4445 180)
			(size 0.1524 0.1524)
			(layers "F.Cu" "F.Mask" "F.Paste")
			(net "P3V3_STBY_A")
			(options
				(clearance outline)
				(anchor circle)
			)
			(primitives
				(gr_poly
					(pts
						(arc
							(start 0.3048 -0.2032)
							(mid 0.275042 -0.275042)
							(end 0.2032 -0.3048)
						)
						(arc
							(start -0.2032 -0.3048)
							(mid -0.275042 -0.275042)
							(end -0.3048 -0.2032)
						)
						(arc
							(start -0.3048 0.2032)
							(mid -0.275042 0.275042)
							(end -0.2032 0.3048)
						)
						(arc
							(start 0.2032 0.3048)
							(mid 0.275042 0.275042)
							(end 0.3048 0.2032)
						)
					)
					(width 0)
					(fill yes)
				)
			)
		)
		(pad "2" smd custom
			(at 0 0.4445 180)
			(size 0.1524 0.1524)
			(layers "F.Cu" "F.Mask" "F.Paste")
			(net "GND")
			(options
				(clearance outline)
				(anchor circle)
			)
			(primitives
				(gr_poly
					(pts
						(arc
							(start 0.3048 -0.2032)
							(mid 0.275042 -0.275042)
							(end 0.2032 -0.3048)
						)
						(arc
							(start -0.2032 -0.3048)
							(mid -0.275042 -0.275042)
							(end -0.3048 -0.2032)
						)
						(arc
							(start -0.3048 0.2032)
							(mid -0.275042 0.275042)
							(end -0.2032 0.3048)
						)
						(arc
							(start 0.2032 0.3048)
							(mid 0.275042 0.275042)
							(end 0.3048 0.2032)
						)
					)
					(width 0)
					(fill yes)
				)
			)
		)
	)
	(footprint ""
		(layer "F.Cu")
		(at 70.17258 -181.381146 90)
		(property "Reference" "R458"
			(at 0 0 90)
			(layer "F.SilkS")
			(hide yes)
			(effects
				(font
					(size 1.27 1.27)
				)
			)
		)
		(property "Value" "4K7R2J-2-GP"
			(at 0.064008 -3.993896 90)
			(unlocked yes)
			(layer "F.Fab")
			(hide yes)
			(effects
				(font
					(size 1.016 1.016)
					(thickness 0.1524)
				)
			)
		)
		(property "Device Type" "R402H16"
			(at 0.064008 -5.517896 90)
			(unlocked yes)
			(layer "F.Fab")
			(hide yes)
			(effects
				(font
					(size 1.016 1.016)
					(thickness 0.1524)
				)
			)
		)
		(duplicate_pad_numbers_are_jumpers no)
		(fp_line
			(start 0.508 -0.9398)
			(end -0.508 -0.9398)
			(stroke
				(width 0.1524)
				(type default)
			)
			(layer "F.SilkS")
		)
		(fp_line
			(start -0.508 -0.9398)
			(end -0.508 0.9398)
			(stroke
				(width 0.1524)
				(type default)
			)
			(layer "F.SilkS")
		)
		(fp_rect
			(start -0.508 0.9398)
			(end 0.508 -0.9398)
			(stroke
				(width 0)
				(type default)
			)
			(fill no)
			(layer "F.CrtYd")
		)
		(fp_rect
			(start -0.508 0.9398)
			(end 0.508 -0.9398)
			(stroke
				(width 0)
				(type default)
			)
			(fill no)
			(layer "F.Fab")
		)
		(pad "1" smd custom
			(at 0 -0.4445 90)
			(size 0.1397 0.1397)
			(layers "F.Cu" "F.Mask" "F.Paste")
			(net "DRIVE_A_2_ACT")
			(options
				(clearance outline)
				(anchor circle)
			)
			(primitives
				(gr_poly
					(pts
						(arc
							(start -0.1778 -0.2794)
							(mid -0.249642 -0.249642)
							(end -0.2794 -0.1778)
						)
						(arc
							(start -0.2794 0.1778)
							(mid -0.249642 0.249642)
							(end -0.1778 0.2794)
						)
						(arc
							(start 0.1778 0.2794)
							(mid 0.249642 0.249642)
							(end 0.2794 0.1778)
						)
						(arc
							(start 0.2794 -0.1778)
							(mid 0.249642 -0.249642)
							(end 0.1778 -0.2794)
						)
					)
					(width 0)
					(fill yes)
				)
			)
		)
		(pad "2" smd custom
			(at 0 0.4445 90)
			(size 0.1397 0.1397)
			(layers "F.Cu" "F.Mask" "F.Paste")
			(net "GND")
			(options
				(clearance outline)
				(anchor circle)
			)
			(primitives
				(gr_poly
					(pts
						(arc
							(start -0.1778 -0.2794)
							(mid -0.249642 -0.249642)
							(end -0.2794 -0.1778)
						)
						(arc
							(start -0.2794 0.1778)
							(mid -0.249642 0.249642)
							(end -0.1778 0.2794)
						)
						(arc
							(start 0.1778 0.2794)
							(mid 0.249642 0.249642)
							(end 0.2794 0.1778)
						)
						(arc
							(start 0.2794 -0.1778)
							(mid 0.249642 -0.249642)
							(end 0.1778 -0.2794)
						)
					)
					(width 0)
					(fill yes)
				)
			)
		)
	)
	(footprint ""
		(layer "F.Cu")
		(at 463.1309 -45.735494 180)
		(property "Reference" "R927"
			(at 0 0 180)
			(layer "F.SilkS")
			(hide yes)
			(effects
				(font
					(size 1.27 1.27)
				)
			)
		)
		(property "Value" "4K7R2J-2-GP"
			(at 0.064008 -3.993896 180)
			(unlocked yes)
			(layer "F.Fab")
			(hide yes)
			(effects
				(font
					(size 1.016 1.016)
					(thickness 0.1524)
				)
			)
		)
		(property "Device Type" "R402H16"
			(at 0.064008 -5.517896 180)
			(unlocked yes)
			(layer "F.Fab")
			(hide yes)
			(effects
				(font
					(size 1.016 1.016)
					(thickness 0.1524)
				)
			)
		)
		(duplicate_pad_numbers_are_jumpers no)
		(fp_line
			(start 0.508 -0.9398)
			(end -0.508 -0.9398)
			(stroke
				(width 0.1524)
				(type default)
			)
			(layer "F.SilkS")
		)
		(fp_line
			(start -0.508 -0.9398)
			(end -0.508 0.9398)
			(stroke
				(width 0.1524)
				(type default)
			)
			(layer "F.SilkS")
		)
		(fp_rect
			(start -0.508 0.9398)
			(end 0.508 -0.9398)
			(stroke
				(width 0)
				(type default)
			)
			(fill no)
			(layer "F.CrtYd")
		)
		(fp_rect
			(start -0.508 0.9398)
			(end 0.508 -0.9398)
			(stroke
				(width 0)
				(type default)
			)
			(fill no)
			(layer "F.Fab")
		)
		(pad "1" smd custom
			(at 0 -0.4445 180)
			(size 0.1397 0.1397)
			(layers "F.Cu" "F.Mask" "F.Paste")
			(net "P12V_A")
			(options
				(clearance outline)
				(anchor circle)
			)
			(primitives
				(gr_poly
					(pts
						(arc
							(start -0.1778 -0.2794)
							(mid -0.249642 -0.249642)
							(end -0.2794 -0.1778)
						)
						(arc
							(start -0.2794 0.1778)
							(mid -0.249642 0.249642)
							(end -0.1778 0.2794)
						)
						(arc
							(start 0.1778 0.2794)
							(mid 0.249642 0.249642)
							(end 0.2794 0.1778)
						)
						(arc
							(start 0.2794 -0.1778)
							(mid 0.249642 -0.249642)
							(end 0.1778 -0.2794)
						)
					)
					(width 0)
					(fill yes)
				)
			)
		)
		(pad "2" smd custom
			(at 0 0.4445 180)
			(size 0.1397 0.1397)
			(layers "F.Cu" "F.Mask" "F.Paste")
			(net "SW_HDD_R34")
			(options
				(clearance outline)
				(anchor circle)
			)
			(primitives
				(gr_poly
					(pts
						(arc
							(start -0.1778 -0.2794)
							(mid -0.249642 -0.249642)
							(end -0.2794 -0.1778)
						)
						(arc
							(start -0.2794 0.1778)
							(mid -0.249642 0.249642)
							(end -0.1778 0.2794)
						)
						(arc
							(start 0.1778 0.2794)
							(mid 0.249642 0.249642)
							(end 0.2794 0.1778)
						)
						(arc
							(start 0.2794 -0.1778)
							(mid 0.249642 -0.249642)
							(end 0.1778 -0.2794)
						)
					)
					(width 0)
					(fill yes)
				)
			)
		)
	)
	(footprint ""
		(layer "F.Cu")
		(at 361.180126 -131.764278)
		(property "Reference" "R1099"
			(at 0 0 0)
			(layer "F.SilkS")
			(hide yes)
			(effects
				(font
					(size 1.27 1.27)
				)
			)
		)
		(property "Value" "3K92R2F-GP"
			(at 0.064008 -3.993896 0)
			(unlocked yes)
			(layer "F.Fab")
			(hide yes)
			(effects
				(font
					(size 1.016 1.016)
					(thickness 0.1524)
				)
			)
		)
		(property "Device Type" "R402H16"
			(at 0.064008 -5.517896 0)
			(unlocked yes)
			(layer "F.Fab")
			(hide yes)
			(effects
				(font
					(size 1.016 1.016)
					(thickness 0.1524)
				)
			)
		)
		(duplicate_pad_numbers_are_jumpers no)
		(fp_line
			(start -0.508 -0.9398)
			(end -0.508 0.9398)
			(stroke
				(width 0.1524)
				(type default)
			)
			(layer "F.SilkS")
		)
		(fp_line
			(start 0.508 -0.9398)
			(end -0.508 -0.9398)
			(stroke
				(width 0.1524)
				(type default)
			)
			(layer "F.SilkS")
		)
		(fp_rect
			(start -0.508 0.9398)
			(end 0.508 -0.9398)
			(stroke
				(width 0)
				(type default)
			)
			(fill no)
			(layer "F.CrtYd")
		)
		(fp_rect
			(start -0.508 0.9398)
			(end 0.508 -0.9398)
			(stroke
				(width 0)
				(type default)
			)
			(fill no)
			(layer "F.Fab")
		)
		(pad "1" smd custom
			(at 0 -0.4445)
			(size 0.1397 0.1397)
			(layers "F.Cu" "F.Mask" "F.Paste")
			(net "MB1_CM_OV_R")
			(options
				(clearance outline)
				(anchor circle)
			)
			(primitives
				(gr_poly
					(pts
						(arc
							(start -0.1778 -0.2794)
							(mid -0.249642 -0.249642)
							(end -0.2794 -0.1778)
						)
						(arc
							(start -0.2794 0.1778)
							(mid -0.249642 0.249642)
							(end -0.1778 0.2794)
						)
						(arc
							(start 0.1778 0.2794)
							(mid 0.249642 0.249642)
							(end 0.2794 0.1778)
						)
						(arc
							(start 0.2794 -0.1778)
							(mid 0.249642 -0.249642)
							(end 0.1778 -0.2794)
						)
					)
					(width 0)
					(fill yes)
				)
			)
		)
		(pad "2" smd custom
			(at 0 0.4445)
			(size 0.1397 0.1397)
			(layers "F.Cu" "F.Mask" "F.Paste")
			(net "AGND_CURRENT_MONOB")
			(options
				(clearance outline)
				(anchor circle)
			)
			(primitives
				(gr_poly
					(pts
						(arc
							(start -0.1778 -0.2794)
							(mid -0.249642 -0.249642)
							(end -0.2794 -0.1778)
						)
						(arc
							(start -0.2794 0.1778)
							(mid -0.249642 0.249642)
							(end -0.1778 0.2794)
						)
						(arc
							(start 0.1778 0.2794)
							(mid 0.249642 0.249642)
							(end 0.2794 0.1778)
						)
						(arc
							(start 0.2794 -0.1778)
							(mid 0.249642 -0.249642)
							(end 0.1778 -0.2794)
						)
					)
					(width 0)
					(fill yes)
				)
			)
		)
	)
	(footprint ""
		(layer "F.Cu")
		(at 158.663386 -43.660568 90)
		(property "Reference" "C403"
			(at 0 0 90)
			(layer "F.SilkS")
			(hide yes)
			(effects
				(font
					(size 1.27 1.27)
				)
			)
		)
		(property "Value" "SCD01U16V1KX-GP"
			(at -2.8321 -1.7399 90)
			(unlocked yes)
			(layer "F.Fab")
			(hide yes)
			(effects
				(font
					(size 1.016 1.016)
					(thickness 0.1524)
				)
			)
		)
		(property "Device Type" "C0201H13"
			(at -2.8321 -3.2639 90)
			(unlocked yes)
			(layer "F.Fab")
			(hide yes)
			(effects
				(font
					(size 1.016 1.016)
					(thickness 0.1524)
				)
			)
		)
		(duplicate_pad_numbers_are_jumpers no)
		(fp_rect
			(start -0.2794 0.6477)
			(end 0.2794 -0.6477)
			(stroke
				(width 0)
				(type default)
			)
			(fill no)
			(layer "F.CrtYd")
		)
		(fp_rect
			(start -0.2794 0.6477)
			(end 0.2794 -0.6477)
			(stroke
				(width 0)
				(type default)
			)
			(fill no)
			(layer "F.Fab")
		)
		(pad "1" smd custom
			(at 0 -0.2794 90)
			(size 0.0762 0.0762)
			(layers "F.Cu" "F.Mask" "F.Paste")
			(net "SAS_HDD_RX_P28")
			(options
				(clearance outline)
				(anchor circle)
			)
			(primitives
				(gr_poly
					(pts
						(arc
							(start 0.1524 -0.127)
							(mid 0.137521 -0.162921)
							(end 0.1016 -0.1778)
						)
						(arc
							(start -0.1016 -0.1778)
							(mid -0.137521 -0.162921)
							(end -0.1524 -0.127)
						)
						(arc
							(start -0.1524 0.127)
							(mid -0.137521 0.162921)
							(end -0.1016 0.1778)
						)
						(arc
							(start 0.1016 0.1778)
							(mid 0.137521 0.162921)
							(end 0.1524 0.127)
						)
					)
					(width 0)
					(fill yes)
				)
			)
		)
		(pad "2" smd custom
			(at 0 0.2794 90)
			(size 0.0762 0.0762)
			(layers "F.Cu" "F.Mask" "F.Paste")
			(net "PHY_SCC_A_TO_DRV_A_28_DP")
			(options
				(clearance outline)
				(anchor circle)
			)
			(primitives
				(gr_poly
					(pts
						(arc
							(start 0.1524 -0.127)
							(mid 0.137521 -0.162921)
							(end 0.1016 -0.1778)
						)
						(arc
							(start -0.1016 -0.1778)
							(mid -0.137521 -0.162921)
							(end -0.1524 -0.127)
						)
						(arc
							(start -0.1524 0.127)
							(mid -0.137521 0.162921)
							(end -0.1016 0.1778)
						)
						(arc
							(start 0.1016 0.1778)
							(mid 0.137521 0.162921)
							(end 0.1524 0.127)
						)
					)
					(width 0)
					(fill yes)
				)
			)
		)
	)
	(footprint ""
		(layer "F.Cu")
		(at 146.249898 -291.000942 -90)
		(property "Reference" "C93"
			(at 0 0 270)
			(layer "F.SilkS")
			(hide yes)
			(effects
				(font
					(size 1.27 1.27)
				)
			)
		)
		(property "Value" "SC10U16V6KX-2GP"
			(at -0.0762 -5.1308 270)
			(unlocked yes)
			(layer "F.Fab")
			(hide yes)
			(effects
				(font
					(size 1.016 1.016)
					(thickness 0.1524)
				)
			)
		)
		(property "Device Type" "C1206H71"
			(at -0.127 -6.6548 270)
			(unlocked yes)
			(layer "F.Fab")
			(hide yes)
			(effects
				(font
					(size 1.016 1.016)
					(thickness 0.1524)
				)
			)
		)
		(duplicate_pad_numbers_are_jumpers no)
		(fp_line
			(start -1.016 2.2352)
			(end -1.016 0.8382)
			(stroke
				(width 0.1524)
				(type default)
			)
			(layer "F.SilkS")
		)
		(fp_line
			(start 1.016 2.2352)
			(end -1.016 2.2352)
			(stroke
				(width 0.1524)
				(type default)
			)
			(layer "F.SilkS")
		)
		(fp_line
			(start 1.016 0.8382)
			(end 1.016 2.2352)
			(stroke
				(width 0.1524)
				(type default)
			)
			(layer "F.SilkS")
		)
		(fp_line
			(start -1.016 -0.8382)
			(end -1.016 -2.2352)
			(stroke
				(width 0.1524)
				(type default)
			)
			(layer "F.SilkS")
		)
		(fp_line
			(start -1.016 -2.2352)
			(end 1.016 -2.2352)
			(stroke
				(width 0.1524)
				(type default)
			)
			(layer "F.SilkS")
		)
		(fp_line
			(start 1.016 -2.2352)
			(end 1.016 -0.8382)
			(stroke
				(width 0.1524)
				(type default)
			)
			(layer "F.SilkS")
		)
		(fp_rect
			(start -1.0922 2.3114)
			(end 1.0922 -2.3114)
			(stroke
				(width 0)
				(type default)
			)
			(fill no)
			(layer "F.CrtYd")
		)
		(fp_poly
			(pts
				(xy 1.0922 -2.3114) (xy 1.0922 2.3114) (xy -1.0922 2.3114) (xy -1.0922 -2.3114)
			)
			(stroke
				(width 0)
				(type default)
			)
			(fill no)
			(layer "F.Fab")
		)
		(pad "1" smd rect
			(at 0 -1.397 270)
			(size 1.651 1.27)
			(layers "F.Cu" "F.Mask" "F.Paste")
			(net "P5V_HDD4")
		)
		(pad "2" smd rect
			(at 0 1.397 270)
			(size 1.651 1.27)
			(layers "F.Cu" "F.Mask" "F.Paste")
			(net "GND")
		)
	)
	(footprint ""
		(layer "F.Cu")
		(at 244.348 -395.9098 180)
		(property "Reference" "R1161"
			(at 0 0 180)
			(layer "F.SilkS")
			(hide yes)
			(effects
				(font
					(size 1.27 1.27)
				)
			)
		)
		(property "Value" "21KR2F-GP"
			(at 0.064008 -3.993896 180)
			(unlocked yes)
			(layer "F.Fab")
			(hide yes)
			(effects
				(font
					(size 1.016 1.016)
					(thickness 0.1524)
				)
			)
		)
		(property "Device Type" "R402H16"
			(at 0.064008 -5.517896 180)
			(unlocked yes)
			(layer "F.Fab")
			(hide yes)
			(effects
				(font
					(size 1.016 1.016)
					(thickness 0.1524)
				)
			)
		)
		(duplicate_pad_numbers_are_jumpers no)
		(fp_line
			(start 0.508 -0.9398)
			(end -0.508 -0.9398)
			(stroke
				(width 0.1524)
				(type default)
			)
			(layer "F.SilkS")
		)
		(fp_line
			(start -0.508 -0.9398)
			(end -0.508 0.9398)
			(stroke
				(width 0.1524)
				(type default)
			)
			(layer "F.SilkS")
		)
		(fp_rect
			(start -0.508 0.9398)
			(end 0.508 -0.9398)
			(stroke
				(width 0)
				(type default)
			)
			(fill no)
			(layer "F.CrtYd")
		)
		(fp_rect
			(start -0.508 0.9398)
			(end 0.508 -0.9398)
			(stroke
				(width 0)
				(type default)
			)
			(fill no)
			(layer "F.Fab")
		)
		(pad "1" smd custom
			(at 0 -0.4445 180)
			(size 0.1397 0.1397)
			(layers "F.Cu" "F.Mask" "F.Paste")
			(net "MB3_PSET_R")
			(options
				(clearance outline)
				(anchor circle)
			)
			(primitives
				(gr_poly
					(pts
						(arc
							(start -0.1778 -0.2794)
							(mid -0.249642 -0.249642)
							(end -0.2794 -0.1778)
						)
						(arc
							(start -0.2794 0.1778)
							(mid -0.249642 0.249642)
							(end -0.1778 0.2794)
						)
						(arc
							(start 0.1778 0.2794)
							(mid 0.249642 0.249642)
							(end 0.2794 0.1778)
						)
						(arc
							(start 0.2794 -0.1778)
							(mid 0.249642 -0.249642)
							(end 0.1778 -0.2794)
						)
					)
					(width 0)
					(fill yes)
				)
			)
		)
		(pad "2" smd custom
			(at 0 0.4445 180)
			(size 0.1397 0.1397)
			(layers "F.Cu" "F.Mask" "F.Paste")
			(net "AGND_CURRENT_DPB")
			(options
				(clearance outline)
				(anchor circle)
			)
			(primitives
				(gr_poly
					(pts
						(arc
							(start -0.1778 -0.2794)
							(mid -0.249642 -0.249642)
							(end -0.2794 -0.1778)
						)
						(arc
							(start -0.2794 0.1778)
							(mid -0.249642 0.249642)
							(end -0.1778 0.2794)
						)
						(arc
							(start 0.1778 0.2794)
							(mid 0.249642 0.249642)
							(end 0.2794 0.1778)
						)
						(arc
							(start 0.2794 -0.1778)
							(mid 0.249642 -0.249642)
							(end 0.1778 -0.2794)
						)
					)
					(width 0)
					(fill yes)
				)
			)
		)
	)
	(footprint ""
		(layer "F.Cu")
		(at 469.942926 -174.857918)
		(property "Reference" "Q140"
			(at 0 0 0)
			(layer "F.SilkS")
			(hide yes)
			(effects
				(font
					(size 1.27 1.27)
				)
			)
		)
		(property "Value" "AO4407AL-GP"
			(at -3.707384 -1.5367 0)
			(unlocked yes)
			(layer "F.Fab")
			(hide yes)
			(effects
				(font
					(size 1.016 1.016)
					(thickness 0.1524)
				)
			)
		)
		(property "Device Type" "SOIC8H69"
			(at -3.707384 -3.0607 0)
			(unlocked yes)
			(layer "F.Fab")
			(hide yes)
			(effects
				(font
					(size 1.016 1.016)
					(thickness 0.1524)
				)
			)
		)
		(duplicate_pad_numbers_are_jumpers no)
		(fp_line
			(start -2.7432 -1.4224)
			(end -2.7432 1.4224)
			(stroke
				(width 0.1524)
				(type default)
			)
			(layer "F.SilkS")
		)
		(fp_line
			(start -2.7432 1.4224)
			(end -2.6416 1.4224)
			(stroke
				(width 0.1524)
				(type default)
			)
			(layer "F.SilkS")
		)
		(fp_line
			(start -2.7432 1.4224)
			(end 2.1336 1.4224)
			(stroke
				(width 0.1524)
				(type default)
			)
			(layer "F.SilkS")
		)
		(fp_line
			(start -2.7178 -0.508)
			(end -2.1844 -0.0508)
			(stroke
				(width 0.1524)
				(type default)
			)
			(layer "F.SilkS")
		)
		(fp_line
			(start -2.6289 3.4417)
			(end -2.6289 1.4732)
			(stroke
				(width 0.381)
				(type default)
			)
			(layer "F.SilkS")
		)
		(fp_line
			(start -2.1844 -0.0508)
			(end -2.7178 0.508)
			(stroke
				(width 0.1524)
				(type default)
			)
			(layer "F.SilkS")
		)
		(fp_line
			(start 2.1336 -1.4224)
			(end -2.7432 -1.4224)
			(stroke
				(width 0.1524)
				(type default)
			)
			(layer "F.SilkS")
		)
		(fp_line
			(start 2.1336 1.4224)
			(end 2.1336 -1.4224)
			(stroke
				(width 0.1524)
				(type default)
			)
			(layer "F.SilkS")
		)
		(fp_poly
			(pts
				(xy -2.2098 -1.4224) (xy -2.2098 1.4224) (xy 2.2098 1.4224) (xy 2.2098 -1.4224)
			)
			(stroke
				(width 0)
				(type default)
			)
			(fill yes)
			(layer "F.SilkS")
		)
		(fp_rect
			(start -2.450084 2.999994)
			(end 2.450084 -2.999994)
			(stroke
				(width 0)
				(type default)
			)
			(fill no)
			(layer "F.CrtYd")
		)
		(fp_poly
			(pts
				(xy -2.8194 3.6322) (xy -2.8194 -3.6322) (xy 2.8194 -3.6322) (xy 2.8194 1.18364) (xy 2.450084 1.18364)
				(xy 2.450084 -2.999994) (xy -2.450084 -2.999994) (xy -2.450084 2.999994) (xy 2.450084 2.999994)
				(xy 2.450084 1.18618) (xy 2.8194 1.18618) (xy 2.8194 3.6322)
			)
			(stroke
				(width 0)
				(type default)
			)
			(fill no)
			(layer "F.CrtYd")
		)
		(fp_rect
			(start -2.8194 3.6322)
			(end 2.8194 -3.6322)
			(stroke
				(width 0)
				(type default)
			)
			(fill no)
			(layer "F.Fab")
		)
		(pad "1" smd rect
			(at -1.905 2.54)
			(size 0.635 1.651)
			(layers "F.Cu" "F.Mask" "F.Paste")
			(net "P12V_A")
		)
		(pad "2" smd rect
			(at -0.635 2.54)
			(size 0.635 1.651)
			(layers "F.Cu" "F.Mask" "F.Paste")
			(net "P12V_A")
		)
		(pad "3" smd rect
			(at 0.635 2.54)
			(size 0.635 1.651)
			(layers "F.Cu" "F.Mask" "F.Paste")
			(net "P12V_A")
		)
		(pad "4" smd rect
			(at 1.905 2.54)
			(size 0.635 1.651)
			(layers "F.Cu" "F.Mask" "F.Paste")
			(net "SW_HDD_N23")
		)
		(pad "5" smd rect
			(at 1.905 -2.54)
			(size 0.635 1.651)
			(layers "F.Cu" "F.Mask" "F.Paste")
			(net "P12V_HDD23")
		)
		(pad "6" smd rect
			(at 0.635 -2.54)
			(size 0.635 1.651)
			(layers "F.Cu" "F.Mask" "F.Paste")
			(net "P12V_HDD23")
		)
		(pad "7" smd rect
			(at -0.635 -2.54)
			(size 0.635 1.651)
			(layers "F.Cu" "F.Mask" "F.Paste")
			(net "P12V_HDD23")
		)
		(pad "8" smd rect
			(at -1.905 -2.54)
			(size 0.635 1.651)
			(layers "F.Cu" "F.Mask" "F.Paste")
			(net "P12V_HDD23")
		)
	)
	(footprint ""
		(layer "F.Cu")
		(at 443.068202 -253.42215 -90)
		(property "Reference" "R1257"
			(at 0 0 270)
			(layer "F.SilkS")
			(hide yes)
			(effects
				(font
					(size 1.27 1.27)
				)
			)
		)
		(property "Value" "309KR2F-GP"
			(at 0.064008 -3.993896 270)
			(unlocked yes)
			(layer "F.Fab")
			(hide yes)
			(effects
				(font
					(size 1.016 1.016)
					(thickness 0.1524)
				)
			)
		)
		(property "Device Type" "R402H16"
			(at 0.064008 -5.517896 270)
			(unlocked yes)
			(layer "F.Fab")
			(hide yes)
			(effects
				(font
					(size 1.016 1.016)
					(thickness 0.1524)
				)
			)
		)
		(duplicate_pad_numbers_are_jumpers no)
		(fp_line
			(start -0.508 -0.9398)
			(end -0.508 0.9398)
			(stroke
				(width 0.1524)
				(type default)
			)
			(layer "F.SilkS")
		)
		(fp_line
			(start 0.508 -0.9398)
			(end -0.508 -0.9398)
			(stroke
				(width 0.1524)
				(type default)
			)
			(layer "F.SilkS")
		)
		(fp_rect
			(start -0.508 0.9398)
			(end 0.508 -0.9398)
			(stroke
				(width 0)
				(type default)
			)
			(fill no)
			(layer "F.CrtYd")
		)
		(fp_rect
			(start -0.508 0.9398)
			(end 0.508 -0.9398)
			(stroke
				(width 0)
				(type default)
			)
			(fill no)
			(layer "F.Fab")
		)
		(pad "1" smd custom
			(at 0 -0.4445 270)
			(size 0.1397 0.1397)
			(layers "F.Cu" "F.Mask" "F.Paste")
			(net "P5V_C_RF")
			(options
				(clearance outline)
				(anchor circle)
			)
			(primitives
				(gr_poly
					(pts
						(arc
							(start -0.1778 -0.2794)
							(mid -0.249642 -0.249642)
							(end -0.2794 -0.1778)
						)
						(arc
							(start -0.2794 0.1778)
							(mid -0.249642 0.249642)
							(end -0.1778 0.2794)
						)
						(arc
							(start 0.1778 0.2794)
							(mid 0.249642 0.249642)
							(end 0.2794 0.1778)
						)
						(arc
							(start 0.2794 -0.1778)
							(mid 0.249642 -0.249642)
							(end 0.1778 -0.2794)
						)
					)
					(width 0)
					(fill yes)
				)
			)
		)
		(pad "2" smd custom
			(at 0 0.4445 270)
			(size 0.1397 0.1397)
			(layers "F.Cu" "F.Mask" "F.Paste")
			(net "P5V_C_VREG")
			(options
				(clearance outline)
				(anchor circle)
			)
			(primitives
				(gr_poly
					(pts
						(arc
							(start -0.1778 -0.2794)
							(mid -0.249642 -0.249642)
							(end -0.2794 -0.1778)
						)
						(arc
							(start -0.2794 0.1778)
							(mid -0.249642 0.249642)
							(end -0.1778 0.2794)
						)
						(arc
							(start 0.1778 0.2794)
							(mid 0.249642 0.249642)
							(end 0.2794 0.1778)
						)
						(arc
							(start 0.2794 -0.1778)
							(mid 0.249642 -0.249642)
							(end 0.1778 -0.2794)
						)
					)
					(width 0)
					(fill yes)
				)
			)
		)
	)
	(footprint ""
		(layer "F.Cu")
		(at 32.463486 -44.219368 90)
		(property "Reference" "C350"
			(at 0 0 90)
			(layer "F.SilkS")
			(hide yes)
			(effects
				(font
					(size 1.27 1.27)
				)
			)
		)
		(property "Value" "SCD01U16V1KX-GP"
			(at -2.8321 -1.7399 90)
			(unlocked yes)
			(layer "F.Fab")
			(hide yes)
			(effects
				(font
					(size 1.016 1.016)
					(thickness 0.1524)
				)
			)
		)
		(property "Device Type" "C0201H13"
			(at -2.8321 -3.2639 90)
			(unlocked yes)
			(layer "F.Fab")
			(hide yes)
			(effects
				(font
					(size 1.016 1.016)
					(thickness 0.1524)
				)
			)
		)
		(duplicate_pad_numbers_are_jumpers no)
		(fp_rect
			(start -0.2794 0.6477)
			(end 0.2794 -0.6477)
			(stroke
				(width 0)
				(type default)
			)
			(fill no)
			(layer "F.CrtYd")
		)
		(fp_rect
			(start -0.2794 0.6477)
			(end 0.2794 -0.6477)
			(stroke
				(width 0)
				(type default)
			)
			(fill no)
			(layer "F.Fab")
		)
		(pad "1" smd custom
			(at 0 -0.2794 90)
			(size 0.0762 0.0762)
			(layers "F.Cu" "F.Mask" "F.Paste")
			(net "SAS_HDD_RX_N24")
			(options
				(clearance outline)
				(anchor circle)
			)
			(primitives
				(gr_poly
					(pts
						(arc
							(start 0.1524 -0.127)
							(mid 0.137521 -0.162921)
							(end 0.1016 -0.1778)
						)
						(arc
							(start -0.1016 -0.1778)
							(mid -0.137521 -0.162921)
							(end -0.1524 -0.127)
						)
						(arc
							(start -0.1524 0.127)
							(mid -0.137521 0.162921)
							(end -0.1016 0.1778)
						)
						(arc
							(start 0.1016 0.1778)
							(mid 0.137521 0.162921)
							(end 0.1524 0.127)
						)
					)
					(width 0)
					(fill yes)
				)
			)
		)
		(pad "2" smd custom
			(at 0 0.2794 90)
			(size 0.0762 0.0762)
			(layers "F.Cu" "F.Mask" "F.Paste")
			(net "PHY_SCC_A_TO_DRV_A_24_DN")
			(options
				(clearance outline)
				(anchor circle)
			)
			(primitives
				(gr_poly
					(pts
						(arc
							(start 0.1524 -0.127)
							(mid 0.137521 -0.162921)
							(end 0.1016 -0.1778)
						)
						(arc
							(start -0.1016 -0.1778)
							(mid -0.137521 -0.162921)
							(end -0.1524 -0.127)
						)
						(arc
							(start -0.1524 0.127)
							(mid -0.137521 0.162921)
							(end -0.1016 0.1778)
						)
						(arc
							(start 0.1016 0.1778)
							(mid 0.137521 0.162921)
							(end 0.1524 0.127)
						)
					)
					(width 0)
					(fill yes)
				)
			)
		)
	)
	(footprint ""
		(layer "F.Cu")
		(at 459.4479 -42.585894 180)
		(property "Reference" "R920"
			(at 0 0 180)
			(layer "F.SilkS")
			(hide yes)
			(effects
				(font
					(size 1.27 1.27)
				)
			)
		)
		(property "Value" "1KR2F-3-GP"
			(at 0.064008 -3.993896 180)
			(unlocked yes)
			(layer "F.Fab")
			(hide yes)
			(effects
				(font
					(size 1.016 1.016)
					(thickness 0.1524)
				)
			)
		)
		(property "Device Type" "R402H16"
			(at 0.064008 -5.517896 180)
			(unlocked yes)
			(layer "F.Fab")
			(hide yes)
			(effects
				(font
					(size 1.016 1.016)
					(thickness 0.1524)
				)
			)
		)
		(duplicate_pad_numbers_are_jumpers no)
		(fp_line
			(start 0.508 -0.9398)
			(end -0.508 -0.9398)
			(stroke
				(width 0.1524)
				(type default)
			)
			(layer "F.SilkS")
		)
		(fp_line
			(start -0.508 -0.9398)
			(end -0.508 0.9398)
			(stroke
				(width 0.1524)
				(type default)
			)
			(layer "F.SilkS")
		)
		(fp_rect
			(start -0.508 0.9398)
			(end 0.508 -0.9398)
			(stroke
				(width 0)
				(type default)
			)
			(fill no)
			(layer "F.CrtYd")
		)
		(fp_rect
			(start -0.508 0.9398)
			(end 0.508 -0.9398)
			(stroke
				(width 0)
				(type default)
			)
			(fill no)
			(layer "F.Fab")
		)
		(pad "1" smd custom
			(at 0 -0.4445 180)
			(size 0.1397 0.1397)
			(layers "F.Cu" "F.Mask" "F.Paste")
			(net "P3V3_STBY_A")
			(options
				(clearance outline)
				(anchor circle)
			)
			(primitives
				(gr_poly
					(pts
						(arc
							(start -0.1778 -0.2794)
							(mid -0.249642 -0.249642)
							(end -0.2794 -0.1778)
						)
						(arc
							(start -0.2794 0.1778)
							(mid -0.249642 0.249642)
							(end -0.1778 0.2794)
						)
						(arc
							(start 0.1778 0.2794)
							(mid 0.249642 0.249642)
							(end 0.2794 0.1778)
						)
						(arc
							(start 0.2794 -0.1778)
							(mid 0.249642 -0.249642)
							(end 0.1778 -0.2794)
						)
					)
					(width 0)
					(fill yes)
				)
			)
		)
		(pad "2" smd custom
			(at 0 0.4445 180)
			(size 0.1397 0.1397)
			(layers "F.Cu" "F.Mask" "F.Paste")
			(net "SW_PWR_R_HDD34")
			(options
				(clearance outline)
				(anchor circle)
			)
			(primitives
				(gr_poly
					(pts
						(arc
							(start -0.1778 -0.2794)
							(mid -0.249642 -0.249642)
							(end -0.2794 -0.1778)
						)
						(arc
							(start -0.2794 0.1778)
							(mid -0.249642 0.249642)
							(end -0.1778 0.2794)
						)
						(arc
							(start 0.1778 0.2794)
							(mid 0.249642 0.249642)
							(end 0.2794 0.1778)
						)
						(arc
							(start 0.2794 -0.1778)
							(mid 0.249642 -0.249642)
							(end 0.1778 -0.2794)
						)
					)
					(width 0)
					(fill yes)
				)
			)
		)
	)
	(footprint ""
		(layer "F.Cu")
		(at 255.143 -301.244 180)
		(property "Reference" "R9"
			(at 0 0 180)
			(layer "F.SilkS")
			(hide yes)
			(effects
				(font
					(size 1.27 1.27)
				)
			)
		)
		(property "Value" "10KR2F-2-GP"
			(at 0.064008 -3.993896 180)
			(unlocked yes)
			(layer "F.Fab")
			(hide yes)
			(effects
				(font
					(size 1.016 1.016)
					(thickness 0.1524)
				)
			)
		)
		(property "Device Type" "R402H16"
			(at 0.064008 -5.517896 180)
			(unlocked yes)
			(layer "F.Fab")
			(hide yes)
			(effects
				(font
					(size 1.016 1.016)
					(thickness 0.1524)
				)
			)
		)
		(duplicate_pad_numbers_are_jumpers no)
		(fp_line
			(start 0.508 -0.9398)
			(end -0.508 -0.9398)
			(stroke
				(width 0.1524)
				(type default)
			)
			(layer "F.SilkS")
		)
		(fp_line
			(start -0.508 -0.9398)
			(end -0.508 0.9398)
			(stroke
				(width 0.1524)
				(type default)
			)
			(layer "F.SilkS")
		)
		(fp_rect
			(start -0.508 0.9398)
			(end 0.508 -0.9398)
			(stroke
				(width 0)
				(type default)
			)
			(fill no)
			(layer "F.CrtYd")
		)
		(fp_rect
			(start -0.508 0.9398)
			(end 0.508 -0.9398)
			(stroke
				(width 0)
				(type default)
			)
			(fill no)
			(layer "F.Fab")
		)
		(pad "1" smd custom
			(at 0 -0.4445 180)
			(size 0.1397 0.1397)
			(layers "F.Cu" "F.Mask" "F.Paste")
			(net "EEPROM_WP")
			(options
				(clearance outline)
				(anchor circle)
			)
			(primitives
				(gr_poly
					(pts
						(arc
							(start -0.1778 -0.2794)
							(mid -0.249642 -0.249642)
							(end -0.2794 -0.1778)
						)
						(arc
							(start -0.2794 0.1778)
							(mid -0.249642 0.249642)
							(end -0.1778 0.2794)
						)
						(arc
							(start 0.1778 0.2794)
							(mid 0.249642 0.249642)
							(end 0.2794 0.1778)
						)
						(arc
							(start 0.2794 -0.1778)
							(mid 0.249642 -0.249642)
							(end 0.1778 -0.2794)
						)
					)
					(width 0)
					(fill yes)
				)
			)
		)
		(pad "2" smd custom
			(at 0 0.4445 180)
			(size 0.1397 0.1397)
			(layers "F.Cu" "F.Mask" "F.Paste")
			(net "GND")
			(options
				(clearance outline)
				(anchor circle)
			)
			(primitives
				(gr_poly
					(pts
						(arc
							(start -0.1778 -0.2794)
							(mid -0.249642 -0.249642)
							(end -0.2794 -0.1778)
						)
						(arc
							(start -0.2794 0.1778)
							(mid -0.249642 0.249642)
							(end -0.1778 0.2794)
						)
						(arc
							(start 0.1778 0.2794)
							(mid 0.249642 0.249642)
							(end 0.2794 0.1778)
						)
						(arc
							(start 0.2794 -0.1778)
							(mid 0.249642 -0.249642)
							(end 0.1778 -0.2794)
						)
					)
					(width 0)
					(fill yes)
				)
			)
		)
	)
	(footprint ""
		(layer "F.Cu")
		(at 381.36195 -291.127942 -90)
		(property "Reference" "C149"
			(at 0 0 270)
			(layer "F.SilkS")
			(hide yes)
			(effects
				(font
					(size 1.27 1.27)
				)
			)
		)
		(property "Value" "SCD01U50V2KX-1GP"
			(at 1.1811 -2.7051 270)
			(unlocked yes)
			(layer "F.Fab")
			(hide yes)
			(effects
				(font
					(size 1.016 1.016)
					(thickness 0.1524)
				)
			)
		)
		(property "Device Type" "C402H22"
			(at 1.1811 -4.2291 270)
			(unlocked yes)
			(layer "F.Fab")
			(hide yes)
			(effects
				(font
					(size 1.016 1.016)
					(thickness 0.1524)
				)
			)
		)
		(duplicate_pad_numbers_are_jumpers no)
		(fp_rect
			(start -0.4318 0.9525)
			(end 0.4318 -0.9525)
			(stroke
				(width 0)
				(type default)
			)
			(fill no)
			(layer "F.CrtYd")
		)
		(fp_rect
			(start -0.4318 0.9525)
			(end 0.4318 -0.9525)
			(stroke
				(width 0)
				(type default)
			)
			(fill no)
			(layer "F.Fab")
		)
		(pad "1" smd custom
			(at 0 -0.4445 270)
			(size 0.1524 0.1524)
			(layers "F.Cu" "F.Mask" "F.Paste")
			(net "HDD_PRSNT_8")
			(options
				(clearance outline)
				(anchor circle)
			)
			(primitives
				(gr_poly
					(pts
						(arc
							(start 0.3048 -0.2032)
							(mid 0.275042 -0.275042)
							(end 0.2032 -0.3048)
						)
						(arc
							(start -0.2032 -0.3048)
							(mid -0.275042 -0.275042)
							(end -0.3048 -0.2032)
						)
						(arc
							(start -0.3048 0.2032)
							(mid -0.275042 0.275042)
							(end -0.2032 0.3048)
						)
						(arc
							(start 0.2032 0.3048)
							(mid 0.275042 0.275042)
							(end 0.3048 0.2032)
						)
					)
					(width 0)
					(fill yes)
				)
			)
		)
		(pad "2" smd custom
			(at 0 0.4445 270)
			(size 0.1524 0.1524)
			(layers "F.Cu" "F.Mask" "F.Paste")
			(net "GND")
			(options
				(clearance outline)
				(anchor circle)
			)
			(primitives
				(gr_poly
					(pts
						(arc
							(start 0.3048 -0.2032)
							(mid 0.275042 -0.275042)
							(end 0.2032 -0.3048)
						)
						(arc
							(start -0.2032 -0.3048)
							(mid -0.275042 -0.275042)
							(end -0.3048 -0.2032)
						)
						(arc
							(start -0.3048 0.2032)
							(mid -0.275042 0.275042)
							(end -0.2032 0.3048)
						)
						(arc
							(start 0.2032 0.3048)
							(mid 0.275042 0.275042)
							(end 0.3048 0.2032)
						)
					)
					(width 0)
					(fill yes)
				)
			)
		)
	)
	(footprint ""
		(layer "F.Cu")
		(at 234.315 -382.1938 180)
		(property "Reference" "R1153"
			(at 0 0 180)
			(layer "F.SilkS")
			(hide yes)
			(effects
				(font
					(size 1.27 1.27)
				)
			)
		)
		(property "Value" "10KR2F-2-GP"
			(at 0.064008 -3.993896 180)
			(unlocked yes)
			(layer "F.Fab")
			(hide yes)
			(effects
				(font
					(size 1.016 1.016)
					(thickness 0.1524)
				)
			)
		)
		(property "Device Type" "R402H16"
			(at 0.064008 -5.517896 180)
			(unlocked yes)
			(layer "F.Fab")
			(hide yes)
			(effects
				(font
					(size 1.016 1.016)
					(thickness 0.1524)
				)
			)
		)
		(duplicate_pad_numbers_are_jumpers no)
		(fp_line
			(start 0.508 -0.9398)
			(end -0.508 -0.9398)
			(stroke
				(width 0.1524)
				(type default)
			)
			(layer "F.SilkS")
		)
		(fp_line
			(start -0.508 -0.9398)
			(end -0.508 0.9398)
			(stroke
				(width 0.1524)
				(type default)
			)
			(layer "F.SilkS")
		)
		(fp_rect
			(start -0.508 0.9398)
			(end 0.508 -0.9398)
			(stroke
				(width 0)
				(type default)
			)
			(fill no)
			(layer "F.CrtYd")
		)
		(fp_rect
			(start -0.508 0.9398)
			(end 0.508 -0.9398)
			(stroke
				(width 0)
				(type default)
			)
			(fill no)
			(layer "F.Fab")
		)
		(pad "1" smd custom
			(at 0 -0.4445 180)
			(size 0.1397 0.1397)
			(layers "F.Cu" "F.Mask" "F.Paste")
			(net "P12V_A")
			(options
				(clearance outline)
				(anchor circle)
			)
			(primitives
				(gr_poly
					(pts
						(arc
							(start -0.1778 -0.2794)
							(mid -0.249642 -0.249642)
							(end -0.2794 -0.1778)
						)
						(arc
							(start -0.2794 0.1778)
							(mid -0.249642 0.249642)
							(end -0.1778 0.2794)
						)
						(arc
							(start 0.1778 0.2794)
							(mid 0.249642 0.249642)
							(end 0.2794 0.1778)
						)
						(arc
							(start 0.2794 -0.1778)
							(mid 0.249642 -0.249642)
							(end 0.1778 -0.2794)
						)
					)
					(width 0)
					(fill yes)
				)
			)
		)
		(pad "2" smd custom
			(at 0 0.4445 180)
			(size 0.1397 0.1397)
			(layers "F.Cu" "F.Mask" "F.Paste")
			(net "P12V_A_PGOOD")
			(options
				(clearance outline)
				(anchor circle)
			)
			(primitives
				(gr_poly
					(pts
						(arc
							(start -0.1778 -0.2794)
							(mid -0.249642 -0.249642)
							(end -0.2794 -0.1778)
						)
						(arc
							(start -0.2794 0.1778)
							(mid -0.249642 0.249642)
							(end -0.1778 0.2794)
						)
						(arc
							(start 0.1778 0.2794)
							(mid 0.249642 0.249642)
							(end 0.2794 0.1778)
						)
						(arc
							(start 0.2794 -0.1778)
							(mid 0.249642 -0.249642)
							(end 0.1778 -0.2794)
						)
					)
					(width 0)
					(fill yes)
				)
			)
		)
	)
	(footprint ""
		(layer "F.Cu")
		(at 44.1198 -143.129 90)
		(property "Reference" "C615"
			(at 0 0 90)
			(layer "F.SilkS")
			(hide yes)
			(effects
				(font
					(size 1.27 1.27)
				)
			)
		)
		(property "Value" "SC10U16V5KX-7-GP-U"
			(at -0.0762 -6.1214 90)
			(unlocked yes)
			(layer "F.Fab")
			(hide yes)
			(effects
				(font
					(size 1.016 1.016)
					(thickness 0.1524)
				)
			)
		)
		(property "Device Type" "C805H58"
			(at -0.0762 -8.1534 90)
			(unlocked yes)
			(layer "F.Fab")
			(hide yes)
			(effects
				(font
					(size 1.016 1.016)
					(thickness 0.1524)
				)
			)
		)
		(duplicate_pad_numbers_are_jumpers no)
		(fp_line
			(start 0.635 0)
			(end -0.635 0)
			(stroke
				(width 0.508)
				(type default)
			)
			(layer "F.SilkS")
		)
		(fp_rect
			(start -0.9652 1.778)
			(end 0.9652 -1.778)
			(stroke
				(width 0)
				(type default)
			)
			(fill no)
			(layer "F.CrtYd")
		)
		(fp_poly
			(pts
				(xy -0.9652 -1.778) (xy 0.9652 -1.778) (xy 0.9652 1.778) (xy -0.9652 1.778)
			)
			(stroke
				(width 0)
				(type default)
			)
			(fill no)
			(layer "F.Fab")
		)
		(pad "1" smd rect
			(at 0 -0.9652 90)
			(size 1.397 1.143)
			(layers "F.Cu" "F.Mask" "F.Paste")
			(net "P12V_A_VIN_U21")
		)
		(pad "2" smd rect
			(at 0 0.9652 90)
			(size 1.397 1.143)
			(layers "F.Cu" "F.Mask" "F.Paste")
			(net "GND")
		)
	)
	(footprint ""
		(layer "F.Cu")
		(at 149.549866 -145.372074 180)
		(property "Reference" "C547"
			(at 0 0 180)
			(layer "F.SilkS")
			(hide yes)
			(effects
				(font
					(size 1.27 1.27)
				)
			)
		)
		(property "Value" "SCD1U25V2KX-2-GP"
			(at 1.1811 -2.7051 180)
			(unlocked yes)
			(layer "F.Fab")
			(hide yes)
			(effects
				(font
					(size 1.016 1.016)
					(thickness 0.1524)
				)
			)
		)
		(property "Device Type" "C402H22"
			(at 1.1811 -4.2291 180)
			(unlocked yes)
			(layer "F.Fab")
			(hide yes)
			(effects
				(font
					(size 1.016 1.016)
					(thickness 0.1524)
				)
			)
		)
		(duplicate_pad_numbers_are_jumpers no)
		(fp_rect
			(start -0.4318 0.9525)
			(end 0.4318 -0.9525)
			(stroke
				(width 0)
				(type default)
			)
			(fill no)
			(layer "F.CrtYd")
		)
		(fp_rect
			(start -0.4318 0.9525)
			(end 0.4318 -0.9525)
			(stroke
				(width 0)
				(type default)
			)
			(fill no)
			(layer "F.Fab")
		)
		(pad "1" smd custom
			(at 0 -0.4445 180)
			(size 0.1524 0.1524)
			(layers "F.Cu" "F.Mask" "F.Paste")
			(net "MB0_PSET_R")
			(options
				(clearance outline)
				(anchor circle)
			)
			(primitives
				(gr_poly
					(pts
						(arc
							(start 0.3048 -0.2032)
							(mid 0.275042 -0.275042)
							(end 0.2032 -0.3048)
						)
						(arc
							(start -0.2032 -0.3048)
							(mid -0.275042 -0.275042)
							(end -0.3048 -0.2032)
						)
						(arc
							(start -0.3048 0.2032)
							(mid -0.275042 0.275042)
							(end -0.2032 0.3048)
						)
						(arc
							(start 0.2032 0.3048)
							(mid 0.275042 0.275042)
							(end 0.3048 0.2032)
						)
					)
					(width 0)
					(fill yes)
				)
			)
		)
		(pad "2" smd custom
			(at 0 0.4445 180)
			(size 0.1524 0.1524)
			(layers "F.Cu" "F.Mask" "F.Paste")
			(net "AGND_CURRENT_MONOA")
			(options
				(clearance outline)
				(anchor circle)
			)
			(primitives
				(gr_poly
					(pts
						(arc
							(start 0.3048 -0.2032)
							(mid 0.275042 -0.275042)
							(end 0.2032 -0.3048)
						)
						(arc
							(start -0.2032 -0.3048)
							(mid -0.275042 -0.275042)
							(end -0.3048 -0.2032)
						)
						(arc
							(start -0.3048 0.2032)
							(mid -0.275042 0.275042)
							(end -0.2032 0.3048)
						)
						(arc
							(start 0.2032 0.3048)
							(mid 0.275042 0.275042)
							(end 0.3048 0.2032)
						)
					)
					(width 0)
					(fill yes)
				)
			)
		)
	)
	(footprint ""
		(layer "F.Cu")
		(at 174.0662 -285.514542 90)
		(property "Reference" "C114"
			(at 0 0 90)
			(layer "F.SilkS")
			(hide yes)
			(effects
				(font
					(size 1.27 1.27)
				)
			)
		)
		(property "Value" "SCD033U25V2KX-GP"
			(at 1.1811 -2.7051 90)
			(unlocked yes)
			(layer "F.Fab")
			(hide yes)
			(effects
				(font
					(size 1.016 1.016)
					(thickness 0.1524)
				)
			)
		)
		(property "Device Type" "C402H22"
			(at 1.1811 -4.2291 90)
			(unlocked yes)
			(layer "F.Fab")
			(hide yes)
			(effects
				(font
					(size 1.016 1.016)
					(thickness 0.1524)
				)
			)
		)
		(duplicate_pad_numbers_are_jumpers no)
		(fp_rect
			(start -0.4318 0.9525)
			(end 0.4318 -0.9525)
			(stroke
				(width 0)
				(type default)
			)
			(fill no)
			(layer "F.CrtYd")
		)
		(fp_rect
			(start -0.4318 0.9525)
			(end 0.4318 -0.9525)
			(stroke
				(width 0)
				(type default)
			)
			(fill no)
			(layer "F.Fab")
		)
		(pad "1" smd custom
			(at 0 -0.4445 90)
			(size 0.1524 0.1524)
			(layers "F.Cu" "F.Mask" "F.Paste")
			(net "P12V_A")
			(options
				(clearance outline)
				(anchor circle)
			)
			(primitives
				(gr_poly
					(pts
						(arc
							(start 0.3048 -0.2032)
							(mid 0.275042 -0.275042)
							(end 0.2032 -0.3048)
						)
						(arc
							(start -0.2032 -0.3048)
							(mid -0.275042 -0.275042)
							(end -0.3048 -0.2032)
						)
						(arc
							(start -0.3048 0.2032)
							(mid -0.275042 0.275042)
							(end -0.2032 0.3048)
						)
						(arc
							(start 0.2032 0.3048)
							(mid 0.275042 0.275042)
							(end 0.3048 0.2032)
						)
					)
					(width 0)
					(fill yes)
				)
			)
		)
		(pad "2" smd custom
			(at 0 0.4445 90)
			(size 0.1524 0.1524)
			(layers "F.Cu" "F.Mask" "F.Paste")
			(net "SW_HDD_N5")
			(options
				(clearance outline)
				(anchor circle)
			)
			(primitives
				(gr_poly
					(pts
						(arc
							(start 0.3048 -0.2032)
							(mid 0.275042 -0.275042)
							(end 0.2032 -0.3048)
						)
						(arc
							(start -0.2032 -0.3048)
							(mid -0.275042 -0.275042)
							(end -0.3048 -0.2032)
						)
						(arc
							(start -0.3048 0.2032)
							(mid -0.275042 0.275042)
							(end -0.2032 0.3048)
						)
						(arc
							(start 0.2032 0.3048)
							(mid 0.275042 0.275042)
							(end 0.3048 0.2032)
						)
					)
					(width 0)
					(fill yes)
				)
			)
		)
	)
	(footprint ""
		(layer "F.Cu")
		(at 161.997898 -292.169342 -90)
		(property "Reference" "R224"
			(at 0 0 270)
			(layer "F.SilkS")
			(hide yes)
			(effects
				(font
					(size 1.27 1.27)
				)
			)
		)
		(property "Value" "10KR2F-2-GP"
			(at 0.064008 -3.993896 270)
			(unlocked yes)
			(layer "F.Fab")
			(hide yes)
			(effects
				(font
					(size 1.016 1.016)
					(thickness 0.1524)
				)
			)
		)
		(property "Device Type" "R402H16"
			(at 0.064008 -5.517896 270)
			(unlocked yes)
			(layer "F.Fab")
			(hide yes)
			(effects
				(font
					(size 1.016 1.016)
					(thickness 0.1524)
				)
			)
		)
		(duplicate_pad_numbers_are_jumpers no)
		(fp_line
			(start -0.508 -0.9398)
			(end -0.508 0.9398)
			(stroke
				(width 0.1524)
				(type default)
			)
			(layer "F.SilkS")
		)
		(fp_line
			(start 0.508 -0.9398)
			(end -0.508 -0.9398)
			(stroke
				(width 0.1524)
				(type default)
			)
			(layer "F.SilkS")
		)
		(fp_rect
			(start -0.508 0.9398)
			(end 0.508 -0.9398)
			(stroke
				(width 0)
				(type default)
			)
			(fill no)
			(layer "F.CrtYd")
		)
		(fp_rect
			(start -0.508 0.9398)
			(end 0.508 -0.9398)
			(stroke
				(width 0)
				(type default)
			)
			(fill no)
			(layer "F.Fab")
		)
		(pad "1" smd custom
			(at 0 -0.4445 270)
			(size 0.1397 0.1397)
			(layers "F.Cu" "F.Mask" "F.Paste")
			(net "P3V3_STBY_A")
			(options
				(clearance outline)
				(anchor circle)
			)
			(primitives
				(gr_poly
					(pts
						(arc
							(start -0.1778 -0.2794)
							(mid -0.249642 -0.249642)
							(end -0.2794 -0.1778)
						)
						(arc
							(start -0.2794 0.1778)
							(mid -0.249642 0.249642)
							(end -0.1778 0.2794)
						)
						(arc
							(start 0.1778 0.2794)
							(mid 0.249642 0.249642)
							(end 0.2794 0.1778)
						)
						(arc
							(start 0.2794 -0.1778)
							(mid 0.249642 -0.249642)
							(end 0.1778 -0.2794)
						)
					)
					(width 0)
					(fill yes)
				)
			)
		)
		(pad "2" smd custom
			(at 0 0.4445 270)
			(size 0.1397 0.1397)
			(layers "F.Cu" "F.Mask" "F.Paste")
			(net "HDD_PRSNT_4")
			(options
				(clearance outline)
				(anchor circle)
			)
			(primitives
				(gr_poly
					(pts
						(arc
							(start -0.1778 -0.2794)
							(mid -0.249642 -0.249642)
							(end -0.2794 -0.1778)
						)
						(arc
							(start -0.2794 0.1778)
							(mid -0.249642 0.249642)
							(end -0.1778 0.2794)
						)
						(arc
							(start 0.1778 0.2794)
							(mid 0.249642 0.249642)
							(end 0.2794 0.1778)
						)
						(arc
							(start 0.2794 -0.1778)
							(mid 0.249642 -0.249642)
							(end 0.1778 -0.2794)
						)
					)
					(width 0)
					(fill yes)
				)
			)
		)
	)
	(footprint ""
		(layer "F.Cu")
		(at 172.72 -169.117518 -90)
		(property "Reference" "R536"
			(at 0 0 270)
			(layer "F.SilkS")
			(hide yes)
			(effects
				(font
					(size 1.27 1.27)
				)
			)
		)
		(property "Value" "300KR2F-GP"
			(at 0.064008 -3.993896 270)
			(unlocked yes)
			(layer "F.Fab")
			(hide yes)
			(effects
				(font
					(size 1.016 1.016)
					(thickness 0.1524)
				)
			)
		)
		(property "Device Type" "R402H16"
			(at 0.064008 -5.517896 270)
			(unlocked yes)
			(layer "F.Fab")
			(hide yes)
			(effects
				(font
					(size 1.016 1.016)
					(thickness 0.1524)
				)
			)
		)
		(duplicate_pad_numbers_are_jumpers no)
		(fp_line
			(start -0.508 -0.9398)
			(end -0.508 0.9398)
			(stroke
				(width 0.1524)
				(type default)
			)
			(layer "F.SilkS")
		)
		(fp_line
			(start 0.508 -0.9398)
			(end -0.508 -0.9398)
			(stroke
				(width 0.1524)
				(type default)
			)
			(layer "F.SilkS")
		)
		(fp_rect
			(start -0.508 0.9398)
			(end 0.508 -0.9398)
			(stroke
				(width 0)
				(type default)
			)
			(fill no)
			(layer "F.CrtYd")
		)
		(fp_rect
			(start -0.508 0.9398)
			(end 0.508 -0.9398)
			(stroke
				(width 0)
				(type default)
			)
			(fill no)
			(layer "F.Fab")
		)
		(pad "1" smd custom
			(at 0 -0.4445 270)
			(size 0.1397 0.1397)
			(layers "F.Cu" "F.Mask" "F.Paste")
			(net "SW_HDD_N17")
			(options
				(clearance outline)
				(anchor circle)
			)
			(primitives
				(gr_poly
					(pts
						(arc
							(start -0.1778 -0.2794)
							(mid -0.249642 -0.249642)
							(end -0.2794 -0.1778)
						)
						(arc
							(start -0.2794 0.1778)
							(mid -0.249642 0.249642)
							(end -0.1778 0.2794)
						)
						(arc
							(start 0.1778 0.2794)
							(mid 0.249642 0.249642)
							(end 0.2794 0.1778)
						)
						(arc
							(start 0.2794 -0.1778)
							(mid 0.249642 -0.249642)
							(end 0.1778 -0.2794)
						)
					)
					(width 0)
					(fill yes)
				)
			)
		)
		(pad "2" smd custom
			(at 0 0.4445 270)
			(size 0.1397 0.1397)
			(layers "F.Cu" "F.Mask" "F.Paste")
			(net "P12V_A")
			(options
				(clearance outline)
				(anchor circle)
			)
			(primitives
				(gr_poly
					(pts
						(arc
							(start -0.1778 -0.2794)
							(mid -0.249642 -0.249642)
							(end -0.2794 -0.1778)
						)
						(arc
							(start -0.2794 0.1778)
							(mid -0.249642 0.249642)
							(end -0.1778 0.2794)
						)
						(arc
							(start 0.1778 0.2794)
							(mid 0.249642 0.249642)
							(end 0.2794 0.1778)
						)
						(arc
							(start 0.2794 -0.1778)
							(mid 0.249642 -0.249642)
							(end 0.1778 -0.2794)
						)
					)
					(width 0)
					(fill yes)
				)
			)
		)
	)
	(footprint ""
		(layer "F.Cu")
		(at 395.20495 -157.585918)
		(property "Reference" "R602"
			(at 0 0 0)
			(layer "F.SilkS")
			(hide yes)
			(effects
				(font
					(size 1.27 1.27)
				)
			)
		)
		(property "Value" "4K7R2J-2-GP"
			(at 0.064008 -3.993896 0)
			(unlocked yes)
			(layer "F.Fab")
			(hide yes)
			(effects
				(font
					(size 1.016 1.016)
					(thickness 0.1524)
				)
			)
		)
		(property "Device Type" "R402H16"
			(at 0.064008 -5.517896 0)
			(unlocked yes)
			(layer "F.Fab")
			(hide yes)
			(effects
				(font
					(size 1.016 1.016)
					(thickness 0.1524)
				)
			)
		)
		(duplicate_pad_numbers_are_jumpers no)
		(fp_line
			(start -0.508 -0.9398)
			(end -0.508 0.9398)
			(stroke
				(width 0.1524)
				(type default)
			)
			(layer "F.SilkS")
		)
		(fp_line
			(start 0.508 -0.9398)
			(end -0.508 -0.9398)
			(stroke
				(width 0.1524)
				(type default)
			)
			(layer "F.SilkS")
		)
		(fp_rect
			(start -0.508 0.9398)
			(end 0.508 -0.9398)
			(stroke
				(width 0)
				(type default)
			)
			(fill no)
			(layer "F.CrtYd")
		)
		(fp_rect
			(start -0.508 0.9398)
			(end 0.508 -0.9398)
			(stroke
				(width 0)
				(type default)
			)
			(fill no)
			(layer "F.Fab")
		)
		(pad "1" smd custom
			(at 0 -0.4445)
			(size 0.1397 0.1397)
			(layers "F.Cu" "F.Mask" "F.Paste")
			(net "SW_PWR_R_HDD20")
			(options
				(clearance outline)
				(anchor circle)
			)
			(primitives
				(gr_poly
					(pts
						(arc
							(start -0.1778 -0.2794)
							(mid -0.249642 -0.249642)
							(end -0.2794 -0.1778)
						)
						(arc
							(start -0.2794 0.1778)
							(mid -0.249642 0.249642)
							(end -0.1778 0.2794)
						)
						(arc
							(start 0.1778 0.2794)
							(mid 0.249642 0.249642)
							(end 0.2794 0.1778)
						)
						(arc
							(start 0.2794 -0.1778)
							(mid 0.249642 -0.249642)
							(end 0.1778 -0.2794)
						)
					)
					(width 0)
					(fill yes)
				)
			)
		)
		(pad "2" smd custom
			(at 0 0.4445)
			(size 0.1397 0.1397)
			(layers "F.Cu" "F.Mask" "F.Paste")
			(net "GND")
			(options
				(clearance outline)
				(anchor circle)
			)
			(primitives
				(gr_poly
					(pts
						(arc
							(start -0.1778 -0.2794)
							(mid -0.249642 -0.249642)
							(end -0.2794 -0.1778)
						)
						(arc
							(start -0.2794 0.1778)
							(mid -0.249642 0.249642)
							(end -0.1778 0.2794)
						)
						(arc
							(start 0.1778 0.2794)
							(mid 0.249642 0.249642)
							(end 0.2794 0.1778)
						)
						(arc
							(start 0.2794 -0.1778)
							(mid 0.249642 -0.249642)
							(end 0.1778 -0.2794)
						)
					)
					(width 0)
					(fill yes)
				)
			)
		)
	)
	(footprint ""
		(layer "F.Cu")
		(at 222.69196 -342.573356)
		(property "Reference" "R24"
			(at 0 0 0)
			(layer "F.SilkS")
			(hide yes)
			(effects
				(font
					(size 1.27 1.27)
				)
			)
		)
		(property "Value" "4K7R2F-GP"
			(at 0.064008 -3.993896 0)
			(unlocked yes)
			(layer "F.Fab")
			(hide yes)
			(effects
				(font
					(size 1.016 1.016)
					(thickness 0.1524)
				)
			)
		)
		(property "Device Type" "R402H16"
			(at 0.064008 -5.517896 0)
			(unlocked yes)
			(layer "F.Fab")
			(hide yes)
			(effects
				(font
					(size 1.016 1.016)
					(thickness 0.1524)
				)
			)
		)
		(duplicate_pad_numbers_are_jumpers no)
		(fp_line
			(start -0.508 -0.9398)
			(end -0.508 0.9398)
			(stroke
				(width 0.1524)
				(type default)
			)
			(layer "F.SilkS")
		)
		(fp_line
			(start 0.508 -0.9398)
			(end -0.508 -0.9398)
			(stroke
				(width 0.1524)
				(type default)
			)
			(layer "F.SilkS")
		)
		(fp_rect
			(start -0.508 0.9398)
			(end 0.508 -0.9398)
			(stroke
				(width 0)
				(type default)
			)
			(fill no)
			(layer "F.CrtYd")
		)
		(fp_rect
			(start -0.508 0.9398)
			(end 0.508 -0.9398)
			(stroke
				(width 0)
				(type default)
			)
			(fill no)
			(layer "F.Fab")
		)
		(pad "1" smd custom
			(at 0 -0.4445)
			(size 0.1397 0.1397)
			(layers "F.Cu" "F.Mask" "F.Paste")
			(net "P3V3_STBY_A")
			(options
				(clearance outline)
				(anchor circle)
			)
			(primitives
				(gr_poly
					(pts
						(arc
							(start -0.1778 -0.2794)
							(mid -0.249642 -0.249642)
							(end -0.2794 -0.1778)
						)
						(arc
							(start -0.2794 0.1778)
							(mid -0.249642 0.249642)
							(end -0.1778 0.2794)
						)
						(arc
							(start 0.1778 0.2794)
							(mid 0.249642 0.249642)
							(end 0.2794 0.1778)
						)
						(arc
							(start 0.2794 -0.1778)
							(mid 0.249642 -0.249642)
							(end 0.1778 -0.2794)
						)
					)
					(width 0)
					(fill yes)
				)
			)
		)
		(pad "2" smd custom
			(at 0 0.4445)
			(size 0.1397 0.1397)
			(layers "F.Cu" "F.Mask" "F.Paste")
			(net "VOL_SEN_ADDR1")
			(options
				(clearance outline)
				(anchor circle)
			)
			(primitives
				(gr_poly
					(pts
						(arc
							(start -0.1778 -0.2794)
							(mid -0.249642 -0.249642)
							(end -0.2794 -0.1778)
						)
						(arc
							(start -0.2794 0.1778)
							(mid -0.249642 0.249642)
							(end -0.1778 0.2794)
						)
						(arc
							(start 0.1778 0.2794)
							(mid 0.249642 0.249642)
							(end 0.2794 0.1778)
						)
						(arc
							(start 0.2794 -0.1778)
							(mid 0.249642 -0.249642)
							(end 0.1778 -0.2794)
						)
					)
					(width 0)
					(fill yes)
				)
			)
		)
	)
	(footprint ""
		(layer "F.Cu")
		(at 154.399996 -57.909968 -90)
		(property "Reference" "HDDSAS28"
			(at 0 0 270)
			(layer "F.SilkS")
			(hide yes)
			(effects
				(font
					(size 1.27 1.27)
				)
			)
		)
		(property "Value" "SKT-SAS15P-14P-45-GP"
			(at -20.7645 -8.9789 270)
			(unlocked yes)
			(layer "F.Fab")
			(hide yes)
			(effects
				(font
					(size 1.016 1.016)
					(thickness 0.1524)
				)
			)
		)
		(property "Device Type" "10120818-001C-TRLF"
			(at -20.7645 -10.5029 270)
			(unlocked yes)
			(layer "F.Fab")
			(hide yes)
			(effects
				(font
					(size 1.016 1.016)
					(thickness 0.1524)
				)
			)
		)
		(duplicate_pad_numbers_are_jumpers no)
		(fp_line
			(start 1.651 4.2926)
			(end 1.651 3.0099)
			(stroke
				(width 0.1524)
				(type default)
			)
			(layer "F.SilkS")
		)
		(fp_line
			(start 8.509 4.2926)
			(end 1.651 4.2926)
			(stroke
				(width 0.1524)
				(type default)
			)
			(layer "F.SilkS")
		)
		(fp_line
			(start -23.4188 3.0099)
			(end -23.4188 -3.2512)
			(stroke
				(width 0.1524)
				(type default)
			)
			(layer "F.SilkS")
		)
		(fp_line
			(start 1.651 3.0099)
			(end -23.4188 3.0099)
			(stroke
				(width 0.1524)
				(type default)
			)
			(layer "F.SilkS")
		)
		(fp_line
			(start 8.509 3.0099)
			(end 8.509 4.2926)
			(stroke
				(width 0.1524)
				(type default)
			)
			(layer "F.SilkS")
		)
		(fp_line
			(start 23.4188 3.0099)
			(end 8.509 3.0099)
			(stroke
				(width 0.1524)
				(type default)
			)
			(layer "F.SilkS")
		)
		(fp_line
			(start -23.4188 -3.2512)
			(end 23.4188 -3.2512)
			(stroke
				(width 0.1524)
				(type default)
			)
			(layer "F.SilkS")
		)
		(fp_line
			(start 23.4188 -3.2512)
			(end 23.4188 3.0099)
			(stroke
				(width 0.1524)
				(type default)
			)
			(layer "F.SilkS")
		)
		(fp_line
			(start 15.5067 -3.3401)
			(end 16.2687 -3.3401)
			(stroke
				(width 0.3302)
				(type default)
			)
			(layer "F.SilkS")
		)
		(fp_poly
			(pts
				(xy 15.868904 -3.230372) (xy 16.503904 -3.865372) (xy 15.233904 -3.865372)
			)
			(stroke
				(width 0)
				(type default)
			)
			(fill yes)
			(layer "F.SilkS")
		)
		(fp_poly
			(pts
				(xy -22.8727 -2.7559) (xy 22.8727 -2.7559) (xy 22.8727 2.7559) (xy 8.255 2.7559) (xy 8.255 3.5179)
				(xy 1.905 3.5179) (xy 1.905 2.7559) (xy -22.8727 2.7559)
			)
			(stroke
				(width 0)
				(type default)
			)
			(fill no)
			(layer "F.CrtYd")
		)
		(fp_poly
			(pts
				(xy 1.397 4.5466) (xy 1.397 3.2639) (xy -23.6728 3.2639) (xy -23.6728 -3.5052) (xy 23.6728 -3.5052)
				(xy 23.6728 -0.00635) (xy 22.8727 -0.00635) (xy 22.8727 -2.7559) (xy -22.8727 -2.7559) (xy -22.8727 2.7559)
				(xy 1.905 2.7559) (xy 1.905 3.5179) (xy 8.255 3.5179) (xy 8.255 2.7559) (xy 22.8727 2.7559) (xy 22.8727 0.00635)
				(xy 23.6728 0.00635) (xy 23.6728 3.2639) (xy 8.763 3.2639) (xy 8.763 4.5466)
			)
			(stroke
				(width 0)
				(type default)
			)
			(fill no)
			(layer "F.CrtYd")
		)
		(fp_poly
			(pts
				(xy 1.397 4.5466) (xy 1.397 3.2639) (xy -23.6728 3.2639) (xy -23.6728 -3.5052) (xy 23.6728 -3.5052)
				(xy 23.6728 3.2639) (xy 8.763 3.2639) (xy 8.763 4.5466)
			)
			(stroke
				(width 0)
				(type default)
			)
			(fill no)
			(layer "F.Fab")
		)
		(pad "" np_thru_hole circle
			(at -18.874994 0 270)
			(size 0.254 0.254)
			(drill 1.3462)
			(layers "*.Cu" "*.Mask")
			(clearance 0.9017)
			(thermal_gap 0.9017)
		)
		(pad "" np_thru_hole circle
			(at 18.874994 0 270)
			(size 0.254 0.254)
			(drill 0.9398)
			(layers "*.Cu" "*.Mask")
			(clearance 0.6985)
			(thermal_gap 0.6985)
		)
		(pad "G1" smd rect
			(at 21.874988 0 270)
			(size 2.5908 2.5908)
			(layers "F.Cu" "F.Mask" "F.Paste")
			(net "GND")
		)
		(pad "G2" smd rect
			(at -21.874988 0 270)
			(size 2.5908 2.5908)
			(layers "F.Cu" "F.Mask" "F.Paste")
			(net "GND")
		)
		(pad "P1" smd rect
			(at 1.905 -1.82499 270)
			(size 0.6096 2.3622)
			(layers "F.Cu" "F.Mask" "F.Paste")
			(net "Net_2071")
		)
		(pad "P2" smd rect
			(at 0.635 -1.82499 270)
			(size 0.6096 2.3622)
			(layers "F.Cu" "F.Mask" "F.Paste")
			(net "Net_2072")
		)
		(pad "P3" smd rect
			(at -0.635 -1.82499 270)
			(size 0.6096 2.3622)
			(layers "F.Cu" "F.Mask" "F.Paste")
			(net "Net_2073")
		)
		(pad "P4" smd rect
			(at -1.905 -1.82499 270)
			(size 0.6096 2.3622)
			(layers "F.Cu" "F.Mask" "F.Paste")
			(net "GND")
		)
		(pad "P5" smd rect
			(at -3.175 -1.82499 270)
			(size 0.6096 2.3622)
			(layers "F.Cu" "F.Mask" "F.Paste")
			(net "HDD_PRSNT_28")
		)
		(pad "P6" smd rect
			(at -4.445 -1.82499 270)
			(size 0.6096 2.3622)
			(layers "F.Cu" "F.Mask" "F.Paste")
			(net "GND")
		)
		(pad "P7" smd rect
			(at -5.715 -1.82499 270)
			(size 0.6096 2.3622)
			(layers "F.Cu" "F.Mask" "F.Paste")
			(net "5V_PRE_28")
		)
		(pad "P8" smd rect
			(at -6.985 -1.82499 270)
			(size 0.6096 2.3622)
			(layers "F.Cu" "F.Mask" "F.Paste")
			(net "P5V_HDD28")
		)
		(pad "P9" smd rect
			(at -8.255 -1.82499 270)
			(size 0.6096 2.3622)
			(layers "F.Cu" "F.Mask" "F.Paste")
			(net "P5V_HDD28")
		)
		(pad "P10" smd rect
			(at -9.525 -1.82499 270)
			(size 0.6096 2.3622)
			(layers "F.Cu" "F.Mask" "F.Paste")
			(net "GND")
		)
		(pad "P11" smd rect
			(at -10.795 -1.82499 270)
			(size 0.6096 2.3622)
			(layers "F.Cu" "F.Mask" "F.Paste")
			(net "ACT_HDD_28")
		)
		(pad "P12" smd rect
			(at -12.065 -1.82499 270)
			(size 0.6096 2.3622)
			(layers "F.Cu" "F.Mask" "F.Paste")
			(net "GND")
		)
		(pad "P13" smd rect
			(at -13.335 -1.82499 270)
			(size 0.6096 2.3622)
			(layers "F.Cu" "F.Mask" "F.Paste")
			(net "12V_PRE_28")
		)
		(pad "P14" smd rect
			(at -14.605 -1.82499 270)
			(size 0.6096 2.3622)
			(layers "F.Cu" "F.Mask" "F.Paste")
			(net "P12V_HDD28")
		)
		(pad "P15" smd rect
			(at -15.875 -1.82499 270)
			(size 0.6096 2.3622)
			(layers "F.Cu" "F.Mask" "F.Paste")
			(net "P12V_HDD28")
		)
		(pad "S1" smd rect
			(at 15.875 -1.82499 270)
			(size 0.6096 2.3622)
			(layers "F.Cu" "F.Mask" "F.Paste")
			(net "GND")
		)
		(pad "S2" smd rect
			(at 14.605 -1.82499 270)
			(size 0.6096 2.3622)
			(layers "F.Cu" "F.Mask" "F.Paste")
			(net "SAS_HDD_RX_P28")
		)
		(pad "S3" smd rect
			(at 13.335 -1.82499 270)
			(size 0.6096 2.3622)
			(layers "F.Cu" "F.Mask" "F.Paste")
			(net "SAS_HDD_RX_N28")
		)
		(pad "S4" smd rect
			(at 12.065 -1.82499 270)
			(size 0.6096 2.3622)
			(layers "F.Cu" "F.Mask" "F.Paste")
			(net "GND")
		)
		(pad "S5" smd rect
			(at 10.795 -1.82499 270)
			(size 0.6096 2.3622)
			(layers "F.Cu" "F.Mask" "F.Paste")
			(net "PHY_DRV_A_TO_SCC_A_28_DN")
		)
		(pad "S6" smd rect
			(at 9.525 -1.82499 270)
			(size 0.6096 2.3622)
			(layers "F.Cu" "F.Mask" "F.Paste")
			(net "PHY_DRV_A_TO_SCC_A_28_DP")
		)
		(pad "S7" smd rect
			(at 8.255 -1.82499 270)
			(size 0.6096 2.3622)
			(layers "F.Cu" "F.Mask" "F.Paste")
			(net "GND")
		)
		(pad "S8" smd rect
			(at 7.480046 2.845054 270)
			(size 0.508 2.3622)
			(layers "F.Cu" "F.Mask" "F.Paste")
			(net "GND")
		)
		(pad "S9" smd rect
			(at 6.679946 2.845054 270)
			(size 0.508 2.3622)
			(layers "F.Cu" "F.Mask" "F.Paste")
			(net "Net_466")
		)
		(pad "S10" smd rect
			(at 5.8801 2.845054 270)
			(size 0.508 2.3622)
			(layers "F.Cu" "F.Mask" "F.Paste")
			(net "Net_358")
		)
		(pad "S11" smd rect
			(at 5.08 2.845054 270)
			(size 0.508 2.3622)
			(layers "F.Cu" "F.Mask" "F.Paste")
			(net "GND")
		)
		(pad "S12" smd rect
			(at 4.2799 2.845054 270)
			(size 0.508 2.3622)
			(layers "F.Cu" "F.Mask" "F.Paste")
			(net "Net_394")
		)
		(pad "S13" smd rect
			(at 3.480054 2.845054 270)
			(size 0.508 2.3622)
			(layers "F.Cu" "F.Mask" "F.Paste")
			(net "Net_430")
		)
		(pad "S14" smd rect
			(at 2.679954 2.845054 270)
			(size 0.508 2.3622)
			(layers "F.Cu" "F.Mask" "F.Paste")
			(net "GND")
		)
		(zone
			(layer "F.Cu")
			(hatch none 0.5)
			(connect_pads
				(clearance 0)
			)
			(min_thickness 0.25)
			(keepout
				(tracks allowed)
				(vias not_allowed)
				(pads allowed)
				(copperpour not_allowed)
				(footprints allowed)
			)
			(placement
				(enabled no)
				(sheetname "")
			)
			(fill
				(thermal_gap 0.5)
				(thermal_bridge_width 0.5)
				(island_removal_mode 0)
			)
			(polygon
				(pts
					(xy 158.057596 -74.648568) (xy 150.983696 -74.648568) (xy 150.983696 -81.582768) (xy 152.088596 -81.582768)
					(xy 152.088596 -77.467968) (xy 156.711396 -77.467968) (xy 156.711396 -81.582768) (xy 158.057596 -81.582768)
				)
			)
		)
		(zone
			(layer "F.Cu")
			(hatch none 0.5)
			(connect_pads
				(clearance 0)
			)
			(min_thickness 0.25)
			(keepout
				(tracks not_allowed)
				(vias allowed)
				(pads allowed)
				(copperpour not_allowed)
				(footprints allowed)
			)
			(placement
				(enabled no)
				(sheetname "")
			)
			(fill
				(thermal_gap 0.5)
				(thermal_bridge_width 0.5)
				(island_removal_mode 0)
			)
			(polygon
				(pts
					(xy 158.057596 -74.648568) (xy 150.983696 -74.648568) (xy 150.983696 -81.582768) (xy 152.088596 -81.582768)
					(xy 152.088596 -77.467968) (xy 156.711396 -77.467968) (xy 156.711396 -81.582768) (xy 158.057596 -81.582768)
				)
			)
		)
		(zone
			(layer "F.Cu")
			(hatch none 0.5)
			(connect_pads
				(clearance 0)
			)
			(min_thickness 0.25)
			(keepout
				(tracks not_allowed)
				(vias allowed)
				(pads allowed)
				(copperpour not_allowed)
				(footprints allowed)
			)
			(placement
				(enabled no)
				(sheetname "")
			)
			(fill
				(thermal_gap 0.5)
				(thermal_bridge_width 0.5)
				(island_removal_mode 0)
			)
			(polygon
				(pts
					(xy 158.057596 -41.171368) (xy 150.983696 -41.171368) (xy 150.983696 -34.237168) (xy 152.088596 -34.237168)
					(xy 152.088596 -38.351968) (xy 156.711396 -38.351968) (xy 156.711396 -34.237168) (xy 158.057596 -34.237168)
				)
			)
		)
		(zone
			(layer "F.Cu")
			(hatch none 0.5)
			(connect_pads
				(clearance 0)
			)
			(min_thickness 0.25)
			(keepout
				(tracks allowed)
				(vias not_allowed)
				(pads allowed)
				(copperpour not_allowed)
				(footprints allowed)
			)
			(placement
				(enabled no)
				(sheetname "")
			)
			(fill
				(thermal_gap 0.5)
				(thermal_bridge_width 0.5)
				(island_removal_mode 0)
			)
			(polygon
				(pts
					(xy 158.057596 -41.171368) (xy 150.983696 -41.171368) (xy 150.983696 -34.237168) (xy 152.088596 -34.237168)
					(xy 152.088596 -38.351968) (xy 156.711396 -38.351968) (xy 156.711396 -34.237168) (xy 158.057596 -34.237168)
				)
			)
		)
		(zone
			(layers "F.Cu" "B.Cu" "In1.Cu" "In2.Cu" "In3.Cu" "In4.Cu" "In5.Cu" "In6.Cu"
				"In7.Cu" "In8.Cu" "In9.Cu" "In10.Cu"
			)
			(hatch none 0.5)
			(connect_pads
				(clearance 0)
			)
			(min_thickness 0.25)
			(keepout
				(tracks not_allowed)
				(vias allowed)
				(pads allowed)
				(copperpour not_allowed)
				(footprints allowed)
			)
			(placement
				(enabled no)
				(sheetname "")
			)
			(fill
				(thermal_gap 0.5)
				(thermal_bridge_width 0.5)
				(island_removal_mode 0)
			)
			(polygon
				(pts
					(arc
						(start 155.174696 -39.034974)
						(mid 153.625296 -39.034974)
						(end 155.174696 -39.034974)
					)
				)
			)
		)
		(zone
			(layers "F.Cu" "B.Cu" "In1.Cu" "In2.Cu" "In3.Cu" "In4.Cu" "In5.Cu" "In6.Cu"
				"In7.Cu" "In8.Cu" "In9.Cu" "In10.Cu"
			)
			(hatch none 0.5)
			(connect_pads
				(clearance 0)
			)
			(min_thickness 0.25)
			(keepout
				(tracks not_allowed)
				(vias allowed)
				(pads allowed)
				(copperpour not_allowed)
				(footprints allowed)
			)
			(placement
				(enabled no)
				(sheetname "")
			)
			(fill
				(thermal_gap 0.5)
				(thermal_bridge_width 0.5)
				(island_removal_mode 0)
			)
			(polygon
				(pts
					(arc
						(start 155.377896 -76.784962)
						(mid 153.422096 -76.784962)
						(end 155.377896 -76.784962)
					)
				)
			)
		)
	)
	(footprint ""
		(layer "F.Cu")
		(at 383.08915 -273.940016 90)
		(property "Reference" "VIA3"
			(at 0 0 90)
			(layer "F.SilkS")
			(hide yes)
			(effects
				(font
					(size 1.27 1.27)
				)
			)
		)
		(property "Value" "100OHM-8L-1D6MM-L18L16-GP"
			(at -3.7211 -4.5085 90)
			(unlocked yes)
			(layer "F.Fab")
			(hide yes)
			(effects
				(font
					(size 1.016 1.016)
					(thickness 0.1524)
				)
			)
		)
		(property "Device Type" "VIA-PCIE-4P-394076"
			(at -3.7211 -6.0325 90)
			(unlocked yes)
			(layer "F.Fab")
			(hide yes)
			(effects
				(font
					(size 1.016 1.016)
					(thickness 0.1524)
				)
			)
		)
		(duplicate_pad_numbers_are_jumpers no)
		(fp_rect
			(start -1.9685 0.381)
			(end 1.9685 -0.381)
			(stroke
				(width 0)
				(type default)
			)
			(fill no)
			(layer "F.CrtYd")
		)
		(fp_rect
			(start -1.9685 0.381)
			(end 1.9685 -0.381)
			(stroke
				(width 0)
				(type default)
			)
			(fill no)
			(layer "F.Fab")
		)
		(pad "1" thru_hole circle
			(at -1.5875 0 90)
			(size 0.508 0.508)
			(drill 0.254)
			(layers "*.Cu" "*.Mask")
			(remove_unused_layers no)
			(net "GND")
			(clearance 0.127)
			(thermal_gap 0.127)
		)
		(pad "2" thru_hole circle
			(at -0.5715 0 90)
			(size 0.508 0.508)
			(drill 0.254)
			(layers "*.Cu" "*.Mask")
			(remove_unused_layers no)
			(net "PHY_SCC_A_TO_DRV_A_8_DP")
			(clearance 0.127)
			(thermal_gap 0.127)
		)
		(pad "3" thru_hole circle
			(at 0.5715 0 90)
			(size 0.508 0.508)
			(drill 0.254)
			(layers "*.Cu" "*.Mask")
			(remove_unused_layers no)
			(net "PHY_SCC_A_TO_DRV_A_8_DN")
			(clearance 0.127)
			(thermal_gap 0.127)
		)
		(pad "4" thru_hole circle
			(at 1.5875 0 90)
			(size 0.508 0.508)
			(drill 0.254)
			(layers "*.Cu" "*.Mask")
			(remove_unused_layers no)
			(net "GND")
			(clearance 0.127)
			(thermal_gap 0.127)
		)
	)
	(footprint ""
		(layer "F.Cu")
		(at 23.732998 -177.270918)
		(property "Reference" "R405"
			(at 0 0 0)
			(layer "F.SilkS")
			(hide yes)
			(effects
				(font
					(size 1.27 1.27)
				)
			)
		)
		(property "Value" "2R6F-GP"
			(at -0.0508 -4.8514 0)
			(unlocked yes)
			(layer "F.Fab")
			(hide yes)
			(effects
				(font
					(size 1.016 1.016)
					(thickness 0.1524)
				)
			)
		)
		(property "Device Type" "R1206H26"
			(at 0 -6.3754 0)
			(unlocked yes)
			(layer "F.Fab")
			(hide yes)
			(effects
				(font
					(size 1.016 1.016)
					(thickness 0.1524)
				)
			)
		)
		(duplicate_pad_numbers_are_jumpers no)
		(fp_line
			(start -1.016 -2.2352)
			(end 1.016 -2.2352)
			(stroke
				(width 0.1524)
				(type default)
			)
			(layer "F.SilkS")
		)
		(fp_line
			(start -1.016 2.2352)
			(end -1.016 -2.2352)
			(stroke
				(width 0.1524)
				(type default)
			)
			(layer "F.SilkS")
		)
		(fp_line
			(start 1.016 -2.2352)
			(end 1.016 2.2352)
			(stroke
				(width 0.1524)
				(type default)
			)
			(layer "F.SilkS")
		)
		(fp_line
			(start 1.016 2.2352)
			(end -1.016 2.2352)
			(stroke
				(width 0.1524)
				(type default)
			)
			(layer "F.SilkS")
		)
		(fp_rect
			(start -1.0922 2.3114)
			(end 1.0922 -2.3114)
			(stroke
				(width 0)
				(type default)
			)
			(fill no)
			(layer "F.CrtYd")
		)
		(fp_poly
			(pts
				(xy -1.0922 -2.3114) (xy 1.0922 -2.3114) (xy 1.0922 2.3114) (xy -1.0922 2.3114)
			)
			(stroke
				(width 0)
				(type default)
			)
			(fill no)
			(layer "F.Fab")
		)
		(pad "1" smd rect
			(at 0 -1.397)
			(size 1.651 1.27)
			(layers "F.Cu" "F.Mask" "F.Paste")
			(net "P5V_HDD12")
		)
		(pad "2" smd rect
			(at 0 1.397)
			(size 1.651 1.27)
			(layers "F.Cu" "F.Mask" "F.Paste")
			(net "5V_PRE_12")
		)
	)
	(footprint ""
		(layer "F.Cu")
		(at 342.955626 -127.767334 180)
		(property "Reference" "Q246"
			(at 0 0 180)
			(layer "F.SilkS")
			(hide yes)
			(effects
				(font
					(size 1.27 1.27)
				)
			)
		)
		(property "Value" "2N7002K-2-GP"
			(at 0.127 -8.9662 180)
			(unlocked yes)
			(layer "F.Fab")
			(hide yes)
			(effects
				(font
					(size 1.016 1.016)
					(thickness 0.1524)
				)
			)
		)
		(property "Device Type" "SOT23DGS2D4H44"
			(at 0.127 -10.4902 180)
			(unlocked yes)
			(layer "F.Fab")
			(hide yes)
			(effects
				(font
					(size 1.016 1.016)
					(thickness 0.1524)
				)
			)
		)
		(duplicate_pad_numbers_are_jumpers no)
		(fp_line
			(start 1.651 1.778)
			(end 1.651 -1.778)
			(stroke
				(width 0.1524)
				(type default)
			)
			(layer "F.SilkS")
		)
		(fp_line
			(start 1.651 -1.778)
			(end -1.651 -1.778)
			(stroke
				(width 0.1524)
				(type default)
			)
			(layer "F.SilkS")
		)
		(fp_line
			(start -1.651 1.778)
			(end 1.651 1.778)
			(stroke
				(width 0.1524)
				(type default)
			)
			(layer "F.SilkS")
		)
		(fp_line
			(start -1.651 -1.778)
			(end -1.651 1.778)
			(stroke
				(width 0.1524)
				(type default)
			)
			(layer "F.SilkS")
		)
		(fp_poly
			(pts
				(xy -1.778 1.8796) (xy -1.778 -1.8796) (xy 1.778 -1.8796) (xy 1.778 1.8796)
			)
			(stroke
				(width 0)
				(type default)
			)
			(fill no)
			(layer "F.CrtYd")
		)
		(fp_poly
			(pts
				(xy -1.778 1.8796) (xy -1.778 -1.8796) (xy 1.778 -1.8796) (xy 1.778 1.8796)
			)
			(stroke
				(width 0)
				(type default)
			)
			(fill no)
			(layer "F.Fab")
		)
		(pad "D" smd custom
			(at 0 -0.9525 180)
			(size 0.1905 0.1905)
			(layers "F.Cu" "F.Mask" "F.Paste")
			(net "FLT_HDD19_N")
			(options
				(clearance outline)
				(anchor circle)
			)
			(primitives
				(gr_poly
					(pts
						(arc
							(start -0.1778 0.5715)
							(mid -0.321484 0.511984)
							(end -0.381 0.3683)
						)
						(arc
							(start -0.381 -0.3683)
							(mid -0.321484 -0.511984)
							(end -0.1778 -0.5715)
						)
						(arc
							(start 0.1778 -0.5715)
							(mid 0.321484 -0.511984)
							(end 0.381 -0.3683)
						)
						(arc
							(start 0.381 0.3683)
							(mid 0.321484 0.511984)
							(end 0.1778 0.5715)
						)
					)
					(width 0)
					(fill yes)
				)
			)
		)
		(pad "G" smd custom
			(at -0.98425 0.9525 180)
			(size 0.1905 0.1905)
			(layers "F.Cu" "F.Mask" "F.Paste")
			(net "DRIVE_A_19_FLT_LED")
			(options
				(clearance outline)
				(anchor circle)
			)
			(primitives
				(gr_poly
					(pts
						(arc
							(start -0.1778 0.5715)
							(mid -0.321484 0.511984)
							(end -0.381 0.3683)
						)
						(arc
							(start -0.381 -0.3683)
							(mid -0.321484 -0.511984)
							(end -0.1778 -0.5715)
						)
						(arc
							(start 0.1778 -0.5715)
							(mid 0.321484 -0.511984)
							(end 0.381 -0.3683)
						)
						(arc
							(start 0.381 0.3683)
							(mid 0.321484 0.511984)
							(end 0.1778 0.5715)
						)
					)
					(width 0)
					(fill yes)
				)
			)
		)
		(pad "S" smd custom
			(at 0.98425 0.9525 180)
			(size 0.1905 0.1905)
			(layers "F.Cu" "F.Mask" "F.Paste")
			(net "GND")
			(options
				(clearance outline)
				(anchor circle)
			)
			(primitives
				(gr_poly
					(pts
						(arc
							(start -0.1778 0.5715)
							(mid -0.321484 0.511984)
							(end -0.381 0.3683)
						)
						(arc
							(start -0.381 -0.3683)
							(mid -0.321484 -0.511984)
							(end -0.1778 -0.5715)
						)
						(arc
							(start 0.1778 -0.5715)
							(mid 0.321484 -0.511984)
							(end 0.381 -0.3683)
						)
						(arc
							(start 0.381 0.3683)
							(mid 0.321484 0.511984)
							(end 0.1778 0.5715)
						)
					)
					(width 0)
					(fill yes)
				)
			)
		)
	)
	(footprint ""
		(layer "F.Cu")
		(at 266.991338 -150.47341)
		(property "Reference" "TP189"
			(at 0 0 0)
			(layer "F.SilkS")
			(hide yes)
			(effects
				(font
					(size 1.27 1.27)
				)
			)
		)
		(property "Value" "TPAD32-GP"
			(at -0.0508 -1.6764 0)
			(unlocked yes)
			(layer "F.Fab")
			(hide yes)
			(effects
				(font
					(size 1.016 1.016)
					(thickness 0.1524)
				)
			)
		)
		(property "Device Type" "TPAD32"
			(at -0.0508 -3.2004 0)
			(unlocked yes)
			(layer "F.Fab")
			(hide yes)
			(effects
				(font
					(size 1.016 1.016)
					(thickness 0.1524)
				)
			)
		)
		(duplicate_pad_numbers_are_jumpers no)
		(fp_poly
			(pts
				(arc
					(start 0.4064 0)
					(mid -0.4064 0)
					(end 0.4064 0)
				)
			)
			(stroke
				(width 0)
				(type default)
			)
			(fill no)
			(layer "F.CrtYd")
		)
		(fp_poly
			(pts
				(arc
					(start 0.7112 0)
					(mid -0.7112 0)
					(end 0.7112 0)
				)
			)
			(stroke
				(width 0)
				(type default)
			)
			(fill no)
			(layer "F.Fab")
		)
		(pad "1" smd circle
			(at 0 0)
			(size 0.8128 0.8128)
			(layers "F.Cu" "F.Mask" "F.Paste")
			(net "TP_COMP_B_KR_P0_TX_DP")
		)
	)
	(footprint ""
		(layer "F.Cu")
		(at 22.996398 -48.554894 90)
		(property "Reference" "R695"
			(at 0 0 90)
			(layer "F.SilkS")
			(hide yes)
			(effects
				(font
					(size 1.27 1.27)
				)
			)
		)
		(property "Value" "4K7R2J-2-GP"
			(at 0.064008 -3.993896 90)
			(unlocked yes)
			(layer "F.Fab")
			(hide yes)
			(effects
				(font
					(size 1.016 1.016)
					(thickness 0.1524)
				)
			)
		)
		(property "Device Type" "R402H16"
			(at 0.064008 -5.517896 90)
			(unlocked yes)
			(layer "F.Fab")
			(hide yes)
			(effects
				(font
					(size 1.016 1.016)
					(thickness 0.1524)
				)
			)
		)
		(duplicate_pad_numbers_are_jumpers no)
		(fp_line
			(start 0.508 -0.9398)
			(end -0.508 -0.9398)
			(stroke
				(width 0.1524)
				(type default)
			)
			(layer "F.SilkS")
		)
		(fp_line
			(start -0.508 -0.9398)
			(end -0.508 0.9398)
			(stroke
				(width 0.1524)
				(type default)
			)
			(layer "F.SilkS")
		)
		(fp_rect
			(start -0.508 0.9398)
			(end 0.508 -0.9398)
			(stroke
				(width 0)
				(type default)
			)
			(fill no)
			(layer "F.CrtYd")
		)
		(fp_rect
			(start -0.508 0.9398)
			(end 0.508 -0.9398)
			(stroke
				(width 0)
				(type default)
			)
			(fill no)
			(layer "F.Fab")
		)
		(pad "1" smd custom
			(at 0 -0.4445 90)
			(size 0.1397 0.1397)
			(layers "F.Cu" "F.Mask" "F.Paste")
			(net "SW_PWR_R_HDD24")
			(options
				(clearance outline)
				(anchor circle)
			)
			(primitives
				(gr_poly
					(pts
						(arc
							(start -0.1778 -0.2794)
							(mid -0.249642 -0.249642)
							(end -0.2794 -0.1778)
						)
						(arc
							(start -0.2794 0.1778)
							(mid -0.249642 0.249642)
							(end -0.1778 0.2794)
						)
						(arc
							(start 0.1778 0.2794)
							(mid 0.249642 0.249642)
							(end 0.2794 0.1778)
						)
						(arc
							(start 0.2794 -0.1778)
							(mid 0.249642 -0.249642)
							(end 0.1778 -0.2794)
						)
					)
					(width 0)
					(fill yes)
				)
			)
		)
		(pad "2" smd custom
			(at 0 0.4445 90)
			(size 0.1397 0.1397)
			(layers "F.Cu" "F.Mask" "F.Paste")
			(net "GND")
			(options
				(clearance outline)
				(anchor circle)
			)
			(primitives
				(gr_poly
					(pts
						(arc
							(start -0.1778 -0.2794)
							(mid -0.249642 -0.249642)
							(end -0.2794 -0.1778)
						)
						(arc
							(start -0.2794 0.1778)
							(mid -0.249642 0.249642)
							(end -0.1778 0.2794)
						)
						(arc
							(start 0.1778 0.2794)
							(mid 0.249642 0.249642)
							(end 0.2794 0.1778)
						)
						(arc
							(start 0.2794 -0.1778)
							(mid 0.249642 -0.249642)
							(end 0.1778 -0.2794)
						)
					)
					(width 0)
					(fill yes)
				)
			)
		)
	)
	(footprint ""
		(layer "F.Cu")
		(at 281.2034 -280.1366)
		(property "Reference" "C37"
			(at 0 0 0)
			(layer "F.SilkS")
			(hide yes)
			(effects
				(font
					(size 1.27 1.27)
				)
			)
		)
		(property "Value" "SC1U16V3KX-5GP"
			(at 0 -2.8194 0)
			(unlocked yes)
			(layer "F.Fab")
			(hide yes)
			(effects
				(font
					(size 1.016 1.016)
					(thickness 0.1524)
				)
			)
		)
		(property "Device Type" "C603H36"
			(at 0 -4.3434 0)
			(unlocked yes)
			(layer "F.Fab")
			(hide yes)
			(effects
				(font
					(size 1.016 1.016)
					(thickness 0.1524)
				)
			)
		)
		(duplicate_pad_numbers_are_jumpers no)
		(fp_line
			(start 0.508 0)
			(end -0.508 0)
			(stroke
				(width 0.2032)
				(type default)
			)
			(layer "F.SilkS")
		)
		(fp_rect
			(start -0.5842 1.3335)
			(end 0.5842 -1.3335)
			(stroke
				(width 0)
				(type default)
			)
			(fill no)
			(layer "F.CrtYd")
		)
		(fp_rect
			(start -0.5842 1.3335)
			(end 0.5842 -1.3335)
			(stroke
				(width 0)
				(type default)
			)
			(fill no)
			(layer "F.Fab")
		)
		(pad "1" smd custom
			(at 0 -0.762)
			(size 0.2159 0.2159)
			(layers "F.Cu" "F.Mask" "F.Paste")
			(net "P3V3_STBY_A")
			(options
				(clearance outline)
				(anchor circle)
			)
			(primitives
				(gr_poly
					(pts
						(arc
							(start -0.3302 -0.4318)
							(mid -0.402042 -0.402042)
							(end -0.4318 -0.3302)
						)
						(arc
							(start -0.4318 0.3302)
							(mid -0.402042 0.402042)
							(end -0.3302 0.4318)
						)
						(arc
							(start 0.3302 0.4318)
							(mid 0.402042 0.402042)
							(end 0.4318 0.3302)
						)
						(arc
							(start 0.4318 -0.3302)
							(mid 0.402042 -0.402042)
							(end 0.3302 -0.4318)
						)
					)
					(width 0)
					(fill yes)
				)
			)
		)
		(pad "2" smd custom
			(at 0 0.762)
			(size 0.2159 0.2159)
			(layers "F.Cu" "F.Mask" "F.Paste")
			(net "GND")
			(options
				(clearance outline)
				(anchor circle)
			)
			(primitives
				(gr_poly
					(pts
						(arc
							(start -0.3302 -0.4318)
							(mid -0.402042 -0.402042)
							(end -0.4318 -0.3302)
						)
						(arc
							(start -0.4318 0.3302)
							(mid -0.402042 0.402042)
							(end -0.3302 0.4318)
						)
						(arc
							(start 0.3302 0.4318)
							(mid 0.402042 0.402042)
							(end 0.4318 0.3302)
						)
						(arc
							(start 0.4318 -0.3302)
							(mid 0.402042 -0.402042)
							(end 0.3302 -0.4318)
						)
					)
					(width 0)
					(fill yes)
				)
			)
		)
	)
	(footprint ""
		(layer "F.Cu")
		(at 272.542 -309.105046 180)
		(property "Reference" "VIA63"
			(at 0 0 180)
			(layer "F.SilkS")
			(hide yes)
			(effects
				(font
					(size 1.27 1.27)
				)
			)
		)
		(property "Value" "100OHM-8L-1D6MM-L18L16-GP"
			(at -3.7211 -4.5085 180)
			(unlocked yes)
			(layer "F.Fab")
			(hide yes)
			(effects
				(font
					(size 1.016 1.016)
					(thickness 0.1524)
				)
			)
		)
		(property "Device Type" "VIA-PCIE-4P-394076"
			(at -3.7211 -6.0325 180)
			(unlocked yes)
			(layer "F.Fab")
			(hide yes)
			(effects
				(font
					(size 1.016 1.016)
					(thickness 0.1524)
				)
			)
		)
		(duplicate_pad_numbers_are_jumpers no)
		(fp_rect
			(start -1.9685 0.381)
			(end 1.9685 -0.381)
			(stroke
				(width 0)
				(type default)
			)
			(fill no)
			(layer "F.CrtYd")
		)
		(fp_rect
			(start -1.9685 0.381)
			(end 1.9685 -0.381)
			(stroke
				(width 0)
				(type default)
			)
			(fill no)
			(layer "F.Fab")
		)
		(pad "1" thru_hole circle
			(at -1.5875 0 180)
			(size 0.508 0.508)
			(drill 0.254)
			(layers "*.Cu" "*.Mask")
			(remove_unused_layers no)
			(net "GND")
			(clearance 0.127)
			(thermal_gap 0.127)
		)
		(pad "2" thru_hole circle
			(at -0.5715 0 180)
			(size 0.508 0.508)
			(drill 0.254)
			(layers "*.Cu" "*.Mask")
			(remove_unused_layers no)
			(net "PHY_SCC_A_TO_DRV_A_28_DP")
			(clearance 0.127)
			(thermal_gap 0.127)
		)
		(pad "3" thru_hole circle
			(at 0.5715 0 180)
			(size 0.508 0.508)
			(drill 0.254)
			(layers "*.Cu" "*.Mask")
			(remove_unused_layers no)
			(net "PHY_SCC_A_TO_DRV_A_28_DN")
			(clearance 0.127)
			(thermal_gap 0.127)
		)
		(pad "4" thru_hole circle
			(at 1.5875 0 180)
			(size 0.508 0.508)
			(drill 0.254)
			(layers "*.Cu" "*.Mask")
			(remove_unused_layers no)
			(net "GND")
			(clearance 0.127)
			(thermal_gap 0.127)
		)
	)
	(footprint ""
		(layer "F.Cu")
		(at 174.498 -282.034742 -90)
		(property "Reference" "C113"
			(at 0 0 270)
			(layer "F.SilkS")
			(hide yes)
			(effects
				(font
					(size 1.27 1.27)
				)
			)
		)
		(property "Value" "SCD033U25V2KX-GP"
			(at 1.1811 -2.7051 270)
			(unlocked yes)
			(layer "F.Fab")
			(hide yes)
			(effects
				(font
					(size 1.016 1.016)
					(thickness 0.1524)
				)
			)
		)
		(property "Device Type" "C402H22"
			(at 1.1811 -4.2291 270)
			(unlocked yes)
			(layer "F.Fab")
			(hide yes)
			(effects
				(font
					(size 1.016 1.016)
					(thickness 0.1524)
				)
			)
		)
		(duplicate_pad_numbers_are_jumpers no)
		(fp_rect
			(start -0.4318 0.9525)
			(end 0.4318 -0.9525)
			(stroke
				(width 0)
				(type default)
			)
			(fill no)
			(layer "F.CrtYd")
		)
		(fp_rect
			(start -0.4318 0.9525)
			(end 0.4318 -0.9525)
			(stroke
				(width 0)
				(type default)
			)
			(fill no)
			(layer "F.Fab")
		)
		(pad "1" smd custom
			(at 0 -0.4445 270)
			(size 0.1524 0.1524)
			(layers "F.Cu" "F.Mask" "F.Paste")
			(net "SW_HDD_P5")
			(options
				(clearance outline)
				(anchor circle)
			)
			(primitives
				(gr_poly
					(pts
						(arc
							(start 0.3048 -0.2032)
							(mid 0.275042 -0.275042)
							(end 0.2032 -0.3048)
						)
						(arc
							(start -0.2032 -0.3048)
							(mid -0.275042 -0.275042)
							(end -0.3048 -0.2032)
						)
						(arc
							(start -0.3048 0.2032)
							(mid -0.275042 0.275042)
							(end -0.2032 0.3048)
						)
						(arc
							(start 0.2032 0.3048)
							(mid 0.275042 0.275042)
							(end 0.3048 0.2032)
						)
					)
					(width 0)
					(fill yes)
				)
			)
		)
		(pad "2" smd custom
			(at 0 0.4445 270)
			(size 0.1524 0.1524)
			(layers "F.Cu" "F.Mask" "F.Paste")
			(net "GND")
			(options
				(clearance outline)
				(anchor circle)
			)
			(primitives
				(gr_poly
					(pts
						(arc
							(start 0.3048 -0.2032)
							(mid 0.275042 -0.275042)
							(end 0.2032 -0.3048)
						)
						(arc
							(start -0.2032 -0.3048)
							(mid -0.275042 -0.275042)
							(end -0.3048 -0.2032)
						)
						(arc
							(start -0.3048 0.2032)
							(mid -0.275042 0.275042)
							(end -0.2032 0.3048)
						)
						(arc
							(start 0.2032 0.3048)
							(mid 0.275042 0.275042)
							(end 0.3048 0.2032)
						)
					)
					(width 0)
					(fill yes)
				)
			)
		)
	)
	(footprint ""
		(layer "F.Cu")
		(at 401.80895 -172.851318 90)
		(property "Reference" "C309"
			(at 0 0 90)
			(layer "F.SilkS")
			(hide yes)
			(effects
				(font
					(size 1.27 1.27)
				)
			)
		)
		(property "Value" "SCD033U25V2KX-GP"
			(at 1.1811 -2.7051 90)
			(unlocked yes)
			(layer "F.Fab")
			(hide yes)
			(effects
				(font
					(size 1.016 1.016)
					(thickness 0.1524)
				)
			)
		)
		(property "Device Type" "C402H22"
			(at 1.1811 -4.2291 90)
			(unlocked yes)
			(layer "F.Fab")
			(hide yes)
			(effects
				(font
					(size 1.016 1.016)
					(thickness 0.1524)
				)
			)
		)
		(duplicate_pad_numbers_are_jumpers no)
		(fp_rect
			(start -0.4318 0.9525)
			(end 0.4318 -0.9525)
			(stroke
				(width 0)
				(type default)
			)
			(fill no)
			(layer "F.CrtYd")
		)
		(fp_rect
			(start -0.4318 0.9525)
			(end 0.4318 -0.9525)
			(stroke
				(width 0)
				(type default)
			)
			(fill no)
			(layer "F.Fab")
		)
		(pad "1" smd custom
			(at 0 -0.4445 90)
			(size 0.1524 0.1524)
			(layers "F.Cu" "F.Mask" "F.Paste")
			(net "P12V_A")
			(options
				(clearance outline)
				(anchor circle)
			)
			(primitives
				(gr_poly
					(pts
						(arc
							(start 0.3048 -0.2032)
							(mid 0.275042 -0.275042)
							(end 0.2032 -0.3048)
						)
						(arc
							(start -0.2032 -0.3048)
							(mid -0.275042 -0.275042)
							(end -0.3048 -0.2032)
						)
						(arc
							(start -0.3048 0.2032)
							(mid -0.275042 0.275042)
							(end -0.2032 0.3048)
						)
						(arc
							(start 0.2032 0.3048)
							(mid 0.275042 0.275042)
							(end 0.3048 0.2032)
						)
					)
					(width 0)
					(fill yes)
				)
			)
		)
		(pad "2" smd custom
			(at 0 0.4445 90)
			(size 0.1524 0.1524)
			(layers "F.Cu" "F.Mask" "F.Paste")
			(net "SW_HDD_N20")
			(options
				(clearance outline)
				(anchor circle)
			)
			(primitives
				(gr_poly
					(pts
						(arc
							(start 0.3048 -0.2032)
							(mid 0.275042 -0.275042)
							(end 0.2032 -0.3048)
						)
						(arc
							(start -0.2032 -0.3048)
							(mid -0.275042 -0.275042)
							(end -0.3048 -0.2032)
						)
						(arc
							(start -0.3048 0.2032)
							(mid -0.275042 0.275042)
							(end -0.2032 0.3048)
						)
						(arc
							(start 0.2032 0.3048)
							(mid 0.275042 0.275042)
							(end 0.3048 0.2032)
						)
					)
					(width 0)
					(fill yes)
				)
			)
		)
	)
	(footprint ""
		(layer "F.Cu")
		(at 48.425354 -276.99589 180)
		(property "Reference" "D1"
			(at 0 0 180)
			(layer "F.SilkS")
			(hide yes)
			(effects
				(font
					(size 1.27 1.27)
				)
			)
		)
		(property "Value" "RB551V30-GP"
			(at 0 -6.7818 180)
			(unlocked yes)
			(layer "F.Fab")
			(hide yes)
			(effects
				(font
					(size 1.016 1.016)
					(thickness 0.1524)
				)
			)
		)
		(property "Device Type" "SOD323AKH38"
			(at 0 -8.6868 180)
			(unlocked yes)
			(layer "F.Fab")
			(hide yes)
			(effects
				(font
					(size 1.016 1.016)
					(thickness 0.1524)
				)
			)
		)
		(duplicate_pad_numbers_are_jumpers no)
		(fp_line
			(start 0.889 2.159)
			(end -0.889 2.159)
			(stroke
				(width 0.1524)
				(type default)
			)
			(layer "F.SilkS")
		)
		(fp_line
			(start 0.889 -1.9304)
			(end 0.889 2.159)
			(stroke
				(width 0.1524)
				(type default)
			)
			(layer "F.SilkS")
		)
		(fp_line
			(start 0.762 2.0574)
			(end -0.762 2.0574)
			(stroke
				(width 0.508)
				(type default)
			)
			(layer "F.SilkS")
		)
		(fp_line
			(start -0.889 2.159)
			(end -0.889 -1.9304)
			(stroke
				(width 0.1524)
				(type default)
			)
			(layer "F.SilkS")
		)
		(fp_line
			(start -0.889 -1.9304)
			(end 0.889 -1.9304)
			(stroke
				(width 0.1524)
				(type default)
			)
			(layer "F.SilkS")
		)
		(fp_rect
			(start -1.016 2.3114)
			(end 1.016 -2.0066)
			(stroke
				(width 0)
				(type default)
			)
			(fill no)
			(layer "F.CrtYd")
		)
		(fp_poly
			(pts
				(xy -1.016 -2.0066) (xy 1.016 -2.0066) (xy 1.016 2.3114) (xy -1.016 2.3114)
			)
			(stroke
				(width 0)
				(type default)
			)
			(fill no)
			(layer "F.Fab")
		)
		(pad "A" smd rect
			(at 0 -1.143 180)
			(size 0.5588 1.016)
			(layers "F.Cu" "F.Mask" "F.Paste")
			(net "SW_HDD_R1")
		)
		(pad "K" smd rect
			(at 0 1.143 180)
			(size 0.5588 1.016)
			(layers "F.Cu" "F.Mask" "F.Paste")
			(net "SW_HDD_N1")
		)
	)
	(footprint ""
		(layer "F.Cu")
		(at 334.980534 -21.45157)
		(property "Reference" "R80"
			(at 0 0 0)
			(layer "F.SilkS")
			(hide yes)
			(effects
				(font
					(size 1.27 1.27)
				)
			)
		)
		(property "Value" "4K7R2F-GP"
			(at 0.064008 -3.993896 0)
			(unlocked yes)
			(layer "F.Fab")
			(hide yes)
			(effects
				(font
					(size 1.016 1.016)
					(thickness 0.1524)
				)
			)
		)
		(property "Device Type" "R402H16"
			(at 0.064008 -5.517896 0)
			(unlocked yes)
			(layer "F.Fab")
			(hide yes)
			(effects
				(font
					(size 1.016 1.016)
					(thickness 0.1524)
				)
			)
		)
		(duplicate_pad_numbers_are_jumpers no)
		(fp_line
			(start -0.508 -0.9398)
			(end -0.508 0.9398)
			(stroke
				(width 0.1524)
				(type default)
			)
			(layer "F.SilkS")
		)
		(fp_line
			(start 0.508 -0.9398)
			(end -0.508 -0.9398)
			(stroke
				(width 0.1524)
				(type default)
			)
			(layer "F.SilkS")
		)
		(fp_rect
			(start -0.508 0.9398)
			(end 0.508 -0.9398)
			(stroke
				(width 0)
				(type default)
			)
			(fill no)
			(layer "F.CrtYd")
		)
		(fp_rect
			(start -0.508 0.9398)
			(end 0.508 -0.9398)
			(stroke
				(width 0)
				(type default)
			)
			(fill no)
			(layer "F.Fab")
		)
		(pad "1" smd custom
			(at 0 -0.4445)
			(size 0.1397 0.1397)
			(layers "F.Cu" "F.Mask" "F.Paste")
			(net "IO_EXP11_A1")
			(options
				(clearance outline)
				(anchor circle)
			)
			(primitives
				(gr_poly
					(pts
						(arc
							(start -0.1778 -0.2794)
							(mid -0.249642 -0.249642)
							(end -0.2794 -0.1778)
						)
						(arc
							(start -0.2794 0.1778)
							(mid -0.249642 0.249642)
							(end -0.1778 0.2794)
						)
						(arc
							(start 0.1778 0.2794)
							(mid 0.249642 0.249642)
							(end 0.2794 0.1778)
						)
						(arc
							(start 0.2794 -0.1778)
							(mid 0.249642 -0.249642)
							(end 0.1778 -0.2794)
						)
					)
					(width 0)
					(fill yes)
				)
			)
		)
		(pad "2" smd custom
			(at 0 0.4445)
			(size 0.1397 0.1397)
			(layers "F.Cu" "F.Mask" "F.Paste")
			(net "GND")
			(options
				(clearance outline)
				(anchor circle)
			)
			(primitives
				(gr_poly
					(pts
						(arc
							(start -0.1778 -0.2794)
							(mid -0.249642 -0.249642)
							(end -0.2794 -0.1778)
						)
						(arc
							(start -0.2794 0.1778)
							(mid -0.249642 0.249642)
							(end -0.1778 0.2794)
						)
						(arc
							(start 0.1778 0.2794)
							(mid 0.249642 0.249642)
							(end 0.2794 0.1778)
						)
						(arc
							(start 0.2794 -0.1778)
							(mid 0.249642 -0.249642)
							(end 0.1778 -0.2794)
						)
					)
					(width 0)
					(fill yes)
				)
			)
		)
	)
	(footprint ""
		(layer "F.Cu")
		(at 54.546246 -274.871942 -90)
		(property "Reference" "R163"
			(at 0 0 270)
			(layer "F.SilkS")
			(hide yes)
			(effects
				(font
					(size 1.27 1.27)
				)
			)
		)
		(property "Value" "0R2J-2-GP"
			(at 0.064008 -3.993896 270)
			(unlocked yes)
			(layer "F.Fab")
			(hide yes)
			(effects
				(font
					(size 1.016 1.016)
					(thickness 0.1524)
				)
			)
		)
		(property "Device Type" "R402H16"
			(at 0.064008 -5.517896 270)
			(unlocked yes)
			(layer "F.Fab")
			(hide yes)
			(effects
				(font
					(size 1.016 1.016)
					(thickness 0.1524)
				)
			)
		)
		(duplicate_pad_numbers_are_jumpers no)
		(fp_line
			(start -0.508 -0.9398)
			(end -0.508 0.9398)
			(stroke
				(width 0.1524)
				(type default)
			)
			(layer "F.SilkS")
		)
		(fp_line
			(start 0.508 -0.9398)
			(end -0.508 -0.9398)
			(stroke
				(width 0.1524)
				(type default)
			)
			(layer "F.SilkS")
		)
		(fp_rect
			(start -0.508 0.9398)
			(end 0.508 -0.9398)
			(stroke
				(width 0)
				(type default)
			)
			(fill no)
			(layer "F.CrtYd")
		)
		(fp_rect
			(start -0.508 0.9398)
			(end 0.508 -0.9398)
			(stroke
				(width 0)
				(type default)
			)
			(fill no)
			(layer "F.Fab")
		)
		(pad "1" smd custom
			(at 0 -0.4445 270)
			(size 0.1397 0.1397)
			(layers "F.Cu" "F.Mask" "F.Paste")
			(net "DRIVE_A_1_PWR")
			(options
				(clearance outline)
				(anchor circle)
			)
			(primitives
				(gr_poly
					(pts
						(arc
							(start -0.1778 -0.2794)
							(mid -0.249642 -0.249642)
							(end -0.2794 -0.1778)
						)
						(arc
							(start -0.2794 0.1778)
							(mid -0.249642 0.249642)
							(end -0.1778 0.2794)
						)
						(arc
							(start 0.1778 0.2794)
							(mid 0.249642 0.249642)
							(end 0.2794 0.1778)
						)
						(arc
							(start 0.2794 -0.1778)
							(mid 0.249642 -0.249642)
							(end 0.1778 -0.2794)
						)
					)
					(width 0)
					(fill yes)
				)
			)
		)
		(pad "2" smd custom
			(at 0 0.4445 270)
			(size 0.1397 0.1397)
			(layers "F.Cu" "F.Mask" "F.Paste")
			(net "SW_PWR_R_HDD1")
			(options
				(clearance outline)
				(anchor circle)
			)
			(primitives
				(gr_poly
					(pts
						(arc
							(start -0.1778 -0.2794)
							(mid -0.249642 -0.249642)
							(end -0.2794 -0.1778)
						)
						(arc
							(start -0.2794 0.1778)
							(mid -0.249642 0.249642)
							(end -0.1778 0.2794)
						)
						(arc
							(start 0.1778 0.2794)
							(mid 0.249642 0.249642)
							(end 0.2794 0.1778)
						)
						(arc
							(start 0.2794 -0.1778)
							(mid 0.249642 -0.249642)
							(end 0.1778 -0.2794)
						)
					)
					(width 0)
					(fill yes)
				)
			)
		)
	)
	(footprint ""
		(layer "F.Cu")
		(at 240.3602 -382.1938)
		(property "Reference" "R1158"
			(at 0 0 0)
			(layer "F.SilkS")
			(hide yes)
			(effects
				(font
					(size 1.27 1.27)
				)
			)
		)
		(property "Value" "11KR2F-L-GP"
			(at 0.064008 -3.993896 0)
			(unlocked yes)
			(layer "F.Fab")
			(hide yes)
			(effects
				(font
					(size 1.016 1.016)
					(thickness 0.1524)
				)
			)
		)
		(property "Device Type" "R402H16"
			(at 0.064008 -5.517896 0)
			(unlocked yes)
			(layer "F.Fab")
			(hide yes)
			(effects
				(font
					(size 1.016 1.016)
					(thickness 0.1524)
				)
			)
		)
		(duplicate_pad_numbers_are_jumpers no)
		(fp_line
			(start -0.508 -0.9398)
			(end -0.508 0.9398)
			(stroke
				(width 0.1524)
				(type default)
			)
			(layer "F.SilkS")
		)
		(fp_line
			(start 0.508 -0.9398)
			(end -0.508 -0.9398)
			(stroke
				(width 0.1524)
				(type default)
			)
			(layer "F.SilkS")
		)
		(fp_rect
			(start -0.508 0.9398)
			(end 0.508 -0.9398)
			(stroke
				(width 0)
				(type default)
			)
			(fill no)
			(layer "F.CrtYd")
		)
		(fp_rect
			(start -0.508 0.9398)
			(end 0.508 -0.9398)
			(stroke
				(width 0)
				(type default)
			)
			(fill no)
			(layer "F.Fab")
		)
		(pad "1" smd custom
			(at 0 -0.4445)
			(size 0.1397 0.1397)
			(layers "F.Cu" "F.Mask" "F.Paste")
			(net "MB3_P12V_PWGIN_R")
			(options
				(clearance outline)
				(anchor circle)
			)
			(primitives
				(gr_poly
					(pts
						(arc
							(start -0.1778 -0.2794)
							(mid -0.249642 -0.249642)
							(end -0.2794 -0.1778)
						)
						(arc
							(start -0.2794 0.1778)
							(mid -0.249642 0.249642)
							(end -0.1778 0.2794)
						)
						(arc
							(start 0.1778 0.2794)
							(mid 0.249642 0.249642)
							(end 0.2794 0.1778)
						)
						(arc
							(start 0.2794 -0.1778)
							(mid 0.249642 -0.249642)
							(end 0.1778 -0.2794)
						)
					)
					(width 0)
					(fill yes)
				)
			)
		)
		(pad "2" smd custom
			(at 0 0.4445)
			(size 0.1397 0.1397)
			(layers "F.Cu" "F.Mask" "F.Paste")
			(net "AGND_CURRENT_DPB")
			(options
				(clearance outline)
				(anchor circle)
			)
			(primitives
				(gr_poly
					(pts
						(arc
							(start -0.1778 -0.2794)
							(mid -0.249642 -0.249642)
							(end -0.2794 -0.1778)
						)
						(arc
							(start -0.2794 0.1778)
							(mid -0.249642 0.249642)
							(end -0.1778 0.2794)
						)
						(arc
							(start 0.1778 0.2794)
							(mid 0.249642 0.249642)
							(end 0.2794 0.1778)
						)
						(arc
							(start 0.2794 -0.1778)
							(mid 0.249642 -0.249642)
							(end 0.1778 -0.2794)
						)
					)
					(width 0)
					(fill yes)
				)
			)
		)
	)
	(footprint ""
		(layer "F.Cu")
		(at 81.625948 -45.633894)
		(property "Reference" "R745"
			(at 0 0 0)
			(layer "F.SilkS")
			(hide yes)
			(effects
				(font
					(size 1.27 1.27)
				)
			)
		)
		(property "Value" "0R2J-2-GP"
			(at 0.064008 -3.993896 0)
			(unlocked yes)
			(layer "F.Fab")
			(hide yes)
			(effects
				(font
					(size 1.016 1.016)
					(thickness 0.1524)
				)
			)
		)
		(property "Device Type" "R402H16"
			(at 0.064008 -5.517896 0)
			(unlocked yes)
			(layer "F.Fab")
			(hide yes)
			(effects
				(font
					(size 1.016 1.016)
					(thickness 0.1524)
				)
			)
		)
		(duplicate_pad_numbers_are_jumpers no)
		(fp_line
			(start -0.508 -0.9398)
			(end -0.508 0.9398)
			(stroke
				(width 0.1524)
				(type default)
			)
			(layer "F.SilkS")
		)
		(fp_line
			(start 0.508 -0.9398)
			(end -0.508 -0.9398)
			(stroke
				(width 0.1524)
				(type default)
			)
			(layer "F.SilkS")
		)
		(fp_rect
			(start -0.508 0.9398)
			(end 0.508 -0.9398)
			(stroke
				(width 0)
				(type default)
			)
			(fill no)
			(layer "F.CrtYd")
		)
		(fp_rect
			(start -0.508 0.9398)
			(end 0.508 -0.9398)
			(stroke
				(width 0)
				(type default)
			)
			(fill no)
			(layer "F.Fab")
		)
		(pad "1" smd custom
			(at 0 -0.4445)
			(size 0.1397 0.1397)
			(layers "F.Cu" "F.Mask" "F.Paste")
			(net "SW_HDD_G26")
			(options
				(clearance outline)
				(anchor circle)
			)
			(primitives
				(gr_poly
					(pts
						(arc
							(start -0.1778 -0.2794)
							(mid -0.249642 -0.249642)
							(end -0.2794 -0.1778)
						)
						(arc
							(start -0.2794 0.1778)
							(mid -0.249642 0.249642)
							(end -0.1778 0.2794)
						)
						(arc
							(start 0.1778 0.2794)
							(mid 0.249642 0.249642)
							(end 0.2794 0.1778)
						)
						(arc
							(start 0.2794 -0.1778)
							(mid 0.249642 -0.249642)
							(end 0.1778 -0.2794)
						)
					)
					(width 0)
					(fill yes)
				)
			)
		)
		(pad "2" smd custom
			(at 0 0.4445)
			(size 0.1397 0.1397)
			(layers "F.Cu" "F.Mask" "F.Paste")
			(net "SW_HDD_R26")
			(options
				(clearance outline)
				(anchor circle)
			)
			(primitives
				(gr_poly
					(pts
						(arc
							(start -0.1778 -0.2794)
							(mid -0.249642 -0.249642)
							(end -0.2794 -0.1778)
						)
						(arc
							(start -0.2794 0.1778)
							(mid -0.249642 0.249642)
							(end -0.1778 0.2794)
						)
						(arc
							(start 0.1778 0.2794)
							(mid 0.249642 0.249642)
							(end 0.2794 0.1778)
						)
						(arc
							(start 0.2794 -0.1778)
							(mid 0.249642 -0.249642)
							(end 0.1778 -0.2794)
						)
					)
					(width 0)
					(fill yes)
				)
			)
		)
	)
	(footprint ""
		(layer "F.Cu")
		(at 469.942926 -168.482518 -90)
		(property "Reference" "R672"
			(at 0 0 270)
			(layer "F.SilkS")
			(hide yes)
			(effects
				(font
					(size 1.27 1.27)
				)
			)
		)
		(property "Value" "300KR2F-GP"
			(at 0.064008 -3.993896 270)
			(unlocked yes)
			(layer "F.Fab")
			(hide yes)
			(effects
				(font
					(size 1.016 1.016)
					(thickness 0.1524)
				)
			)
		)
		(property "Device Type" "R402H16"
			(at 0.064008 -5.517896 270)
			(unlocked yes)
			(layer "F.Fab")
			(hide yes)
			(effects
				(font
					(size 1.016 1.016)
					(thickness 0.1524)
				)
			)
		)
		(duplicate_pad_numbers_are_jumpers no)
		(fp_line
			(start -0.508 -0.9398)
			(end -0.508 0.9398)
			(stroke
				(width 0.1524)
				(type default)
			)
			(layer "F.SilkS")
		)
		(fp_line
			(start 0.508 -0.9398)
			(end -0.508 -0.9398)
			(stroke
				(width 0.1524)
				(type default)
			)
			(layer "F.SilkS")
		)
		(fp_rect
			(start -0.508 0.9398)
			(end 0.508 -0.9398)
			(stroke
				(width 0)
				(type default)
			)
			(fill no)
			(layer "F.CrtYd")
		)
		(fp_rect
			(start -0.508 0.9398)
			(end 0.508 -0.9398)
			(stroke
				(width 0)
				(type default)
			)
			(fill no)
			(layer "F.Fab")
		)
		(pad "1" smd custom
			(at 0 -0.4445 270)
			(size 0.1397 0.1397)
			(layers "F.Cu" "F.Mask" "F.Paste")
			(net "SW_HDD_N23")
			(options
				(clearance outline)
				(anchor circle)
			)
			(primitives
				(gr_poly
					(pts
						(arc
							(start -0.1778 -0.2794)
							(mid -0.249642 -0.249642)
							(end -0.2794 -0.1778)
						)
						(arc
							(start -0.2794 0.1778)
							(mid -0.249642 0.249642)
							(end -0.1778 0.2794)
						)
						(arc
							(start 0.1778 0.2794)
							(mid 0.249642 0.249642)
							(end 0.2794 0.1778)
						)
						(arc
							(start 0.2794 -0.1778)
							(mid 0.249642 -0.249642)
							(end 0.1778 -0.2794)
						)
					)
					(width 0)
					(fill yes)
				)
			)
		)
		(pad "2" smd custom
			(at 0 0.4445 270)
			(size 0.1397 0.1397)
			(layers "F.Cu" "F.Mask" "F.Paste")
			(net "P12V_A")
			(options
				(clearance outline)
				(anchor circle)
			)
			(primitives
				(gr_poly
					(pts
						(arc
							(start -0.1778 -0.2794)
							(mid -0.249642 -0.249642)
							(end -0.2794 -0.1778)
						)
						(arc
							(start -0.2794 0.1778)
							(mid -0.249642 0.249642)
							(end -0.1778 0.2794)
						)
						(arc
							(start 0.1778 0.2794)
							(mid 0.249642 0.249642)
							(end 0.2794 0.1778)
						)
						(arc
							(start 0.2794 -0.1778)
							(mid 0.249642 -0.249642)
							(end 0.1778 -0.2794)
						)
					)
					(width 0)
					(fill yes)
				)
			)
		)
	)
	(footprint ""
		(layer "F.Cu")
		(at 150.136098 -301.287942)
		(property "Reference" "C96"
			(at 0 0 0)
			(layer "F.SilkS")
			(hide yes)
			(effects
				(font
					(size 1.27 1.27)
				)
			)
		)
		(property "Value" "SC4D7U25V5KX-1-GP"
			(at -0.0762 -6.1214 0)
			(unlocked yes)
			(layer "F.Fab")
			(hide yes)
			(effects
				(font
					(size 1.016 1.016)
					(thickness 0.1524)
				)
			)
		)
		(property "Device Type" "C805H58"
			(at -0.0762 -8.1534 0)
			(unlocked yes)
			(layer "F.Fab")
			(hide yes)
			(effects
				(font
					(size 1.016 1.016)
					(thickness 0.1524)
				)
			)
		)
		(duplicate_pad_numbers_are_jumpers no)
		(fp_line
			(start 0.635 0)
			(end -0.635 0)
			(stroke
				(width 0.508)
				(type default)
			)
			(layer "F.SilkS")
		)
		(fp_rect
			(start -0.9652 1.778)
			(end 0.9652 -1.778)
			(stroke
				(width 0)
				(type default)
			)
			(fill no)
			(layer "F.CrtYd")
		)
		(fp_poly
			(pts
				(xy -0.9652 -1.778) (xy 0.9652 -1.778) (xy 0.9652 1.778) (xy -0.9652 1.778)
			)
			(stroke
				(width 0)
				(type default)
			)
			(fill no)
			(layer "F.Fab")
		)
		(pad "1" smd rect
			(at 0 -0.9652)
			(size 1.397 1.143)
			(layers "F.Cu" "F.Mask" "F.Paste")
			(net "P12V_HDD4")
		)
		(pad "2" smd rect
			(at 0 0.9652)
			(size 1.397 1.143)
			(layers "F.Cu" "F.Mask" "F.Paste")
			(net "GND")
		)
	)
	(footprint ""
		(layer "F.Cu")
		(at 410.414978 -127.254)
		(property "Reference" "R338"
			(at 0 0 0)
			(layer "F.SilkS")
			(hide yes)
			(effects
				(font
					(size 1.27 1.27)
				)
			)
		)
		(property "Value" "91R3F-1-GP"
			(at -0.0254 -2.5146 0)
			(unlocked yes)
			(layer "F.Fab")
			(hide yes)
			(effects
				(font
					(size 1.016 1.016)
					(thickness 0.1524)
				)
			)
		)
		(property "Device Type" "R603H22"
			(at -0.0254 -4.0386 0)
			(unlocked yes)
			(layer "F.Fab")
			(hide yes)
			(effects
				(font
					(size 1.016 1.016)
					(thickness 0.1524)
				)
			)
		)
		(duplicate_pad_numbers_are_jumpers no)
		(fp_line
			(start -0.4826 0)
			(end -0.2032 0)
			(stroke
				(width 0.2032)
				(type default)
			)
			(layer "F.SilkS")
		)
		(fp_line
			(start 0.2032 0)
			(end 0.4826 0)
			(stroke
				(width 0.2032)
				(type default)
			)
			(layer "F.SilkS")
		)
		(fp_rect
			(start -0.5842 1.3335)
			(end 0.5842 -1.3335)
			(stroke
				(width 0)
				(type default)
			)
			(fill no)
			(layer "F.CrtYd")
		)
		(fp_rect
			(start -0.5842 1.3335)
			(end 0.5842 -1.3335)
			(stroke
				(width 0)
				(type default)
			)
			(fill no)
			(layer "F.Fab")
		)
		(pad "1" smd custom
			(at 0 -0.762)
			(size 0.2159 0.2159)
			(layers "F.Cu" "F.Mask" "F.Paste")
			(net "P5V_A_4")
			(options
				(clearance outline)
				(anchor circle)
			)
			(primitives
				(gr_poly
					(pts
						(arc
							(start -0.3302 -0.4318)
							(mid -0.402042 -0.402042)
							(end -0.4318 -0.3302)
						)
						(arc
							(start -0.4318 0.3302)
							(mid -0.402042 0.402042)
							(end -0.3302 0.4318)
						)
						(arc
							(start 0.3302 0.4318)
							(mid 0.402042 0.402042)
							(end 0.4318 0.3302)
						)
						(arc
							(start 0.4318 -0.3302)
							(mid 0.402042 -0.402042)
							(end 0.3302 -0.4318)
						)
					)
					(width 0)
					(fill yes)
				)
			)
		)
		(pad "2" smd custom
			(at 0 0.762)
			(size 0.2159 0.2159)
			(layers "F.Cu" "F.Mask" "F.Paste")
			(net "DRV_ACT_21")
			(options
				(clearance outline)
				(anchor circle)
			)
			(primitives
				(gr_poly
					(pts
						(arc
							(start -0.3302 -0.4318)
							(mid -0.402042 -0.402042)
							(end -0.4318 -0.3302)
						)
						(arc
							(start -0.4318 0.3302)
							(mid -0.402042 0.402042)
							(end -0.3302 0.4318)
						)
						(arc
							(start 0.3302 0.4318)
							(mid 0.402042 0.402042)
							(end 0.4318 0.3302)
						)
						(arc
							(start 0.4318 -0.3302)
							(mid 0.402042 -0.402042)
							(end 0.3302 -0.4318)
						)
					)
					(width 0)
					(fill yes)
				)
			)
		)
	)
	(footprint ""
		(layer "F.Cu")
		(at 24.240998 -189.462918 180)
		(property "Reference" "C203"
			(at 0 0 180)
			(layer "F.SilkS")
			(hide yes)
			(effects
				(font
					(size 1.27 1.27)
				)
			)
		)
		(property "Value" "SC1U25V3KX-GP"
			(at 0 -2.8194 180)
			(unlocked yes)
			(layer "F.Fab")
			(hide yes)
			(effects
				(font
					(size 1.016 1.016)
					(thickness 0.1524)
				)
			)
		)
		(property "Device Type" "C603H36"
			(at 0 -4.3434 180)
			(unlocked yes)
			(layer "F.Fab")
			(hide yes)
			(effects
				(font
					(size 1.016 1.016)
					(thickness 0.1524)
				)
			)
		)
		(duplicate_pad_numbers_are_jumpers no)
		(fp_line
			(start 0.508 0)
			(end -0.508 0)
			(stroke
				(width 0.2032)
				(type default)
			)
			(layer "F.SilkS")
		)
		(fp_rect
			(start -0.5842 1.3335)
			(end 0.5842 -1.3335)
			(stroke
				(width 0)
				(type default)
			)
			(fill no)
			(layer "F.CrtYd")
		)
		(fp_rect
			(start -0.5842 1.3335)
			(end 0.5842 -1.3335)
			(stroke
				(width 0)
				(type default)
			)
			(fill no)
			(layer "F.Fab")
		)
		(pad "1" smd custom
			(at 0 -0.762 180)
			(size 0.2159 0.2159)
			(layers "F.Cu" "F.Mask" "F.Paste")
			(net "P12V_HDD12")
			(options
				(clearance outline)
				(anchor circle)
			)
			(primitives
				(gr_poly
					(pts
						(arc
							(start -0.3302 -0.4318)
							(mid -0.402042 -0.402042)
							(end -0.4318 -0.3302)
						)
						(arc
							(start -0.4318 0.3302)
							(mid -0.402042 0.402042)
							(end -0.3302 0.4318)
						)
						(arc
							(start 0.3302 0.4318)
							(mid 0.402042 0.402042)
							(end 0.4318 0.3302)
						)
						(arc
							(start 0.4318 -0.3302)
							(mid 0.402042 -0.402042)
							(end 0.3302 -0.4318)
						)
					)
					(width 0)
					(fill yes)
				)
			)
		)
		(pad "2" smd custom
			(at 0 0.762 180)
			(size 0.2159 0.2159)
			(layers "F.Cu" "F.Mask" "F.Paste")
			(net "GND")
			(options
				(clearance outline)
				(anchor circle)
			)
			(primitives
				(gr_poly
					(pts
						(arc
							(start -0.3302 -0.4318)
							(mid -0.402042 -0.402042)
							(end -0.4318 -0.3302)
						)
						(arc
							(start -0.4318 0.3302)
							(mid -0.402042 0.402042)
							(end -0.3302 0.4318)
						)
						(arc
							(start 0.3302 0.4318)
							(mid 0.402042 0.402042)
							(end 0.4318 0.3302)
						)
						(arc
							(start 0.4318 -0.3302)
							(mid 0.402042 -0.402042)
							(end 0.3302 -0.4318)
						)
					)
					(width 0)
					(fill yes)
				)
			)
		)
	)
	(footprint ""
		(layer "F.Cu")
		(at 263.9314 -230.3018)
		(property "Reference" "R89"
			(at 0 0 0)
			(layer "F.SilkS")
			(hide yes)
			(effects
				(font
					(size 1.27 1.27)
				)
			)
		)
		(property "Value" "4K7R2F-GP"
			(at 0.064008 -3.993896 0)
			(unlocked yes)
			(layer "F.Fab")
			(hide yes)
			(effects
				(font
					(size 1.016 1.016)
					(thickness 0.1524)
				)
			)
		)
		(property "Device Type" "R402H16"
			(at 0.064008 -5.517896 0)
			(unlocked yes)
			(layer "F.Fab")
			(hide yes)
			(effects
				(font
					(size 1.016 1.016)
					(thickness 0.1524)
				)
			)
		)
		(duplicate_pad_numbers_are_jumpers no)
		(fp_line
			(start -0.508 -0.9398)
			(end -0.508 0.9398)
			(stroke
				(width 0.1524)
				(type default)
			)
			(layer "F.SilkS")
		)
		(fp_line
			(start 0.508 -0.9398)
			(end -0.508 -0.9398)
			(stroke
				(width 0.1524)
				(type default)
			)
			(layer "F.SilkS")
		)
		(fp_rect
			(start -0.508 0.9398)
			(end 0.508 -0.9398)
			(stroke
				(width 0)
				(type default)
			)
			(fill no)
			(layer "F.CrtYd")
		)
		(fp_rect
			(start -0.508 0.9398)
			(end 0.508 -0.9398)
			(stroke
				(width 0)
				(type default)
			)
			(fill no)
			(layer "F.Fab")
		)
		(pad "1" smd custom
			(at 0 -0.4445)
			(size 0.1397 0.1397)
			(layers "F.Cu" "F.Mask" "F.Paste")
			(net "IO_EXP3_A0")
			(options
				(clearance outline)
				(anchor circle)
			)
			(primitives
				(gr_poly
					(pts
						(arc
							(start -0.1778 -0.2794)
							(mid -0.249642 -0.249642)
							(end -0.2794 -0.1778)
						)
						(arc
							(start -0.2794 0.1778)
							(mid -0.249642 0.249642)
							(end -0.1778 0.2794)
						)
						(arc
							(start 0.1778 0.2794)
							(mid 0.249642 0.249642)
							(end 0.2794 0.1778)
						)
						(arc
							(start 0.2794 -0.1778)
							(mid 0.249642 -0.249642)
							(end 0.1778 -0.2794)
						)
					)
					(width 0)
					(fill yes)
				)
			)
		)
		(pad "2" smd custom
			(at 0 0.4445)
			(size 0.1397 0.1397)
			(layers "F.Cu" "F.Mask" "F.Paste")
			(net "GND")
			(options
				(clearance outline)
				(anchor circle)
			)
			(primitives
				(gr_poly
					(pts
						(arc
							(start -0.1778 -0.2794)
							(mid -0.249642 -0.249642)
							(end -0.2794 -0.1778)
						)
						(arc
							(start -0.2794 0.1778)
							(mid -0.249642 0.249642)
							(end -0.1778 0.2794)
						)
						(arc
							(start 0.1778 0.2794)
							(mid 0.249642 0.249642)
							(end 0.2794 0.1778)
						)
						(arc
							(start 0.2794 -0.1778)
							(mid 0.249642 -0.249642)
							(end 0.1778 -0.2794)
						)
					)
					(width 0)
					(fill yes)
				)
			)
		)
	)
	(footprint ""
		(layer "F.Cu")
		(at 431.454052 -292.016942)
		(property "Reference" "Q56"
			(at 0 0 0)
			(layer "F.SilkS")
			(hide yes)
			(effects
				(font
					(size 1.27 1.27)
				)
			)
		)
		(property "Value" "AO4407AL-GP"
			(at -3.707384 -1.5367 0)
			(unlocked yes)
			(layer "F.Fab")
			(hide yes)
			(effects
				(font
					(size 1.016 1.016)
					(thickness 0.1524)
				)
			)
		)
		(property "Device Type" "SOIC8H69"
			(at -3.707384 -3.0607 0)
			(unlocked yes)
			(layer "F.Fab")
			(hide yes)
			(effects
				(font
					(size 1.016 1.016)
					(thickness 0.1524)
				)
			)
		)
		(duplicate_pad_numbers_are_jumpers no)
		(fp_line
			(start -2.7432 -1.4224)
			(end -2.7432 1.4224)
			(stroke
				(width 0.1524)
				(type default)
			)
			(layer "F.SilkS")
		)
		(fp_line
			(start -2.7432 1.4224)
			(end -2.6416 1.4224)
			(stroke
				(width 0.1524)
				(type default)
			)
			(layer "F.SilkS")
		)
		(fp_line
			(start -2.7432 1.4224)
			(end 2.1336 1.4224)
			(stroke
				(width 0.1524)
				(type default)
			)
			(layer "F.SilkS")
		)
		(fp_line
			(start -2.7178 -0.508)
			(end -2.1844 -0.0508)
			(stroke
				(width 0.1524)
				(type default)
			)
			(layer "F.SilkS")
		)
		(fp_line
			(start -2.6289 3.4417)
			(end -2.6289 1.4732)
			(stroke
				(width 0.381)
				(type default)
			)
			(layer "F.SilkS")
		)
		(fp_line
			(start -2.1844 -0.0508)
			(end -2.7178 0.508)
			(stroke
				(width 0.1524)
				(type default)
			)
			(layer "F.SilkS")
		)
		(fp_line
			(start 2.1336 -1.4224)
			(end -2.7432 -1.4224)
			(stroke
				(width 0.1524)
				(type default)
			)
			(layer "F.SilkS")
		)
		(fp_line
			(start 2.1336 1.4224)
			(end 2.1336 -1.4224)
			(stroke
				(width 0.1524)
				(type default)
			)
			(layer "F.SilkS")
		)
		(fp_poly
			(pts
				(xy -2.2098 -1.4224) (xy -2.2098 1.4224) (xy 2.2098 1.4224) (xy 2.2098 -1.4224)
			)
			(stroke
				(width 0)
				(type default)
			)
			(fill yes)
			(layer "F.SilkS")
		)
		(fp_rect
			(start -2.450084 2.999994)
			(end 2.450084 -2.999994)
			(stroke
				(width 0)
				(type default)
			)
			(fill no)
			(layer "F.CrtYd")
		)
		(fp_poly
			(pts
				(xy -2.8194 3.6322) (xy -2.8194 -3.6322) (xy 2.8194 -3.6322) (xy 2.8194 1.18364) (xy 2.450084 1.18364)
				(xy 2.450084 -2.999994) (xy -2.450084 -2.999994) (xy -2.450084 2.999994) (xy 2.450084 2.999994)
				(xy 2.450084 1.18618) (xy 2.8194 1.18618) (xy 2.8194 3.6322)
			)
			(stroke
				(width 0)
				(type default)
			)
			(fill no)
			(layer "F.CrtYd")
		)
		(fp_rect
			(start -2.8194 3.6322)
			(end 2.8194 -3.6322)
			(stroke
				(width 0)
				(type default)
			)
			(fill no)
			(layer "F.Fab")
		)
		(pad "1" smd rect
			(at -1.905 2.54)
			(size 0.635 1.651)
			(layers "F.Cu" "F.Mask" "F.Paste")
			(net "P12V_A")
		)
		(pad "2" smd rect
			(at -0.635 2.54)
			(size 0.635 1.651)
			(layers "F.Cu" "F.Mask" "F.Paste")
			(net "P12V_A")
		)
		(pad "3" smd rect
			(at 0.635 2.54)
			(size 0.635 1.651)
			(layers "F.Cu" "F.Mask" "F.Paste")
			(net "P12V_A")
		)
		(pad "4" smd rect
			(at 1.905 2.54)
			(size 0.635 1.651)
			(layers "F.Cu" "F.Mask" "F.Paste")
			(net "SW_HDD_N9")
		)
		(pad "5" smd rect
			(at 1.905 -2.54)
			(size 0.635 1.651)
			(layers "F.Cu" "F.Mask" "F.Paste")
			(net "P12V_HDD9")
		)
		(pad "6" smd rect
			(at 0.635 -2.54)
			(size 0.635 1.651)
			(layers "F.Cu" "F.Mask" "F.Paste")
			(net "P12V_HDD9")
		)
		(pad "7" smd rect
			(at -0.635 -2.54)
			(size 0.635 1.651)
			(layers "F.Cu" "F.Mask" "F.Paste")
			(net "P12V_HDD9")
		)
		(pad "8" smd rect
			(at -1.905 -2.54)
			(size 0.635 1.651)
			(layers "F.Cu" "F.Mask" "F.Paste")
			(net "P12V_HDD9")
		)
	)
	(footprint ""
		(layer "F.Cu")
		(at 359.681526 -132.196078 90)
		(property "Reference" "R1097"
			(at 0 0 90)
			(layer "F.SilkS")
			(hide yes)
			(effects
				(font
					(size 1.27 1.27)
				)
			)
		)
		(property "Value" "49K9R2F-L-GP"
			(at 0.064008 -3.993896 90)
			(unlocked yes)
			(layer "F.Fab")
			(hide yes)
			(effects
				(font
					(size 1.016 1.016)
					(thickness 0.1524)
				)
			)
		)
		(property "Device Type" "R402H16"
			(at 0.064008 -5.517896 90)
			(unlocked yes)
			(layer "F.Fab")
			(hide yes)
			(effects
				(font
					(size 1.016 1.016)
					(thickness 0.1524)
				)
			)
		)
		(duplicate_pad_numbers_are_jumpers no)
		(fp_line
			(start 0.508 -0.9398)
			(end -0.508 -0.9398)
			(stroke
				(width 0.1524)
				(type default)
			)
			(layer "F.SilkS")
		)
		(fp_line
			(start -0.508 -0.9398)
			(end -0.508 0.9398)
			(stroke
				(width 0.1524)
				(type default)
			)
			(layer "F.SilkS")
		)
		(fp_rect
			(start -0.508 0.9398)
			(end 0.508 -0.9398)
			(stroke
				(width 0)
				(type default)
			)
			(fill no)
			(layer "F.CrtYd")
		)
		(fp_rect
			(start -0.508 0.9398)
			(end 0.508 -0.9398)
			(stroke
				(width 0)
				(type default)
			)
			(fill no)
			(layer "F.Fab")
		)
		(pad "1" smd custom
			(at 0 -0.4445 90)
			(size 0.1397 0.1397)
			(layers "F.Cu" "F.Mask" "F.Paste")
			(net "P12V_B")
			(options
				(clearance outline)
				(anchor circle)
			)
			(primitives
				(gr_poly
					(pts
						(arc
							(start -0.1778 -0.2794)
							(mid -0.249642 -0.249642)
							(end -0.2794 -0.1778)
						)
						(arc
							(start -0.2794 0.1778)
							(mid -0.249642 0.249642)
							(end -0.1778 0.2794)
						)
						(arc
							(start 0.1778 0.2794)
							(mid 0.249642 0.249642)
							(end 0.2794 0.1778)
						)
						(arc
							(start 0.2794 -0.1778)
							(mid 0.249642 -0.249642)
							(end 0.1778 -0.2794)
						)
					)
					(width 0)
					(fill yes)
				)
			)
		)
		(pad "2" smd custom
			(at 0 0.4445 90)
			(size 0.1397 0.1397)
			(layers "F.Cu" "F.Mask" "F.Paste")
			(net "MB1_CM_OV_R")
			(options
				(clearance outline)
				(anchor circle)
			)
			(primitives
				(gr_poly
					(pts
						(arc
							(start -0.1778 -0.2794)
							(mid -0.249642 -0.249642)
							(end -0.2794 -0.1778)
						)
						(arc
							(start -0.2794 0.1778)
							(mid -0.249642 0.249642)
							(end -0.1778 0.2794)
						)
						(arc
							(start 0.1778 0.2794)
							(mid 0.249642 0.249642)
							(end 0.2794 0.1778)
						)
						(arc
							(start 0.2794 -0.1778)
							(mid 0.249642 -0.249642)
							(end 0.1778 -0.2794)
						)
					)
					(width 0)
					(fill yes)
				)
			)
		)
	)
	(footprint ""
		(layer "F.Cu")
		(at 174.117 -162.157918 180)
		(property "Reference" "R537"
			(at 0 0 180)
			(layer "F.SilkS")
			(hide yes)
			(effects
				(font
					(size 1.27 1.27)
				)
			)
		)
		(property "Value" "200KR2F-L-GP"
			(at 0.064008 -3.993896 180)
			(unlocked yes)
			(layer "F.Fab")
			(hide yes)
			(effects
				(font
					(size 1.016 1.016)
					(thickness 0.1524)
				)
			)
		)
		(property "Device Type" "R402H16"
			(at 0.064008 -5.517896 180)
			(unlocked yes)
			(layer "F.Fab")
			(hide yes)
			(effects
				(font
					(size 1.016 1.016)
					(thickness 0.1524)
				)
			)
		)
		(duplicate_pad_numbers_are_jumpers no)
		(fp_line
			(start 0.508 -0.9398)
			(end -0.508 -0.9398)
			(stroke
				(width 0.1524)
				(type default)
			)
			(layer "F.SilkS")
		)
		(fp_line
			(start -0.508 -0.9398)
			(end -0.508 0.9398)
			(stroke
				(width 0.1524)
				(type default)
			)
			(layer "F.SilkS")
		)
		(fp_rect
			(start -0.508 0.9398)
			(end 0.508 -0.9398)
			(stroke
				(width 0)
				(type default)
			)
			(fill no)
			(layer "F.CrtYd")
		)
		(fp_rect
			(start -0.508 0.9398)
			(end 0.508 -0.9398)
			(stroke
				(width 0)
				(type default)
			)
			(fill no)
			(layer "F.Fab")
		)
		(pad "1" smd custom
			(at 0 -0.4445 180)
			(size 0.1397 0.1397)
			(layers "F.Cu" "F.Mask" "F.Paste")
			(net "SW_HDD_R17")
			(options
				(clearance outline)
				(anchor circle)
			)
			(primitives
				(gr_poly
					(pts
						(arc
							(start -0.1778 -0.2794)
							(mid -0.249642 -0.249642)
							(end -0.2794 -0.1778)
						)
						(arc
							(start -0.2794 0.1778)
							(mid -0.249642 0.249642)
							(end -0.1778 0.2794)
						)
						(arc
							(start 0.1778 0.2794)
							(mid 0.249642 0.249642)
							(end 0.2794 0.1778)
						)
						(arc
							(start 0.2794 -0.1778)
							(mid 0.249642 -0.249642)
							(end 0.1778 -0.2794)
						)
					)
					(width 0)
					(fill yes)
				)
			)
		)
		(pad "2" smd custom
			(at 0 0.4445 180)
			(size 0.1397 0.1397)
			(layers "F.Cu" "F.Mask" "F.Paste")
			(net "SW_HDD_N17")
			(options
				(clearance outline)
				(anchor circle)
			)
			(primitives
				(gr_poly
					(pts
						(arc
							(start -0.1778 -0.2794)
							(mid -0.249642 -0.249642)
							(end -0.2794 -0.1778)
						)
						(arc
							(start -0.2794 0.1778)
							(mid -0.249642 0.249642)
							(end -0.1778 0.2794)
						)
						(arc
							(start 0.1778 0.2794)
							(mid 0.249642 0.249642)
							(end 0.2794 0.1778)
						)
						(arc
							(start 0.2794 -0.1778)
							(mid 0.249642 -0.249642)
							(end 0.1778 -0.2794)
						)
					)
					(width 0)
					(fill yes)
				)
			)
		)
	)
	(footprint ""
		(layer "F.Cu")
		(at 181.483 -62.270894)
		(property "Reference" "R796"
			(at 0 0 0)
			(layer "F.SilkS")
			(hide yes)
			(effects
				(font
					(size 1.27 1.27)
				)
			)
		)
		(property "Value" "2R6F-GP"
			(at -0.0508 -4.8514 0)
			(unlocked yes)
			(layer "F.Fab")
			(hide yes)
			(effects
				(font
					(size 1.016 1.016)
					(thickness 0.1524)
				)
			)
		)
		(property "Device Type" "R1206H26"
			(at 0 -6.3754 0)
			(unlocked yes)
			(layer "F.Fab")
			(hide yes)
			(effects
				(font
					(size 1.016 1.016)
					(thickness 0.1524)
				)
			)
		)
		(duplicate_pad_numbers_are_jumpers no)
		(fp_line
			(start -1.016 -2.2352)
			(end 1.016 -2.2352)
			(stroke
				(width 0.1524)
				(type default)
			)
			(layer "F.SilkS")
		)
		(fp_line
			(start -1.016 2.2352)
			(end -1.016 -2.2352)
			(stroke
				(width 0.1524)
				(type default)
			)
			(layer "F.SilkS")
		)
		(fp_line
			(start 1.016 -2.2352)
			(end 1.016 2.2352)
			(stroke
				(width 0.1524)
				(type default)
			)
			(layer "F.SilkS")
		)
		(fp_line
			(start 1.016 2.2352)
			(end -1.016 2.2352)
			(stroke
				(width 0.1524)
				(type default)
			)
			(layer "F.SilkS")
		)
		(fp_rect
			(start -1.0922 2.3114)
			(end 1.0922 -2.3114)
			(stroke
				(width 0)
				(type default)
			)
			(fill no)
			(layer "F.CrtYd")
		)
		(fp_poly
			(pts
				(xy -1.0922 -2.3114) (xy 1.0922 -2.3114) (xy 1.0922 2.3114) (xy -1.0922 2.3114)
			)
			(stroke
				(width 0)
				(type default)
			)
			(fill no)
			(layer "F.Fab")
		)
		(pad "1" smd rect
			(at 0 -1.397)
			(size 1.651 1.27)
			(layers "F.Cu" "F.Mask" "F.Paste")
			(net "P5V_HDD29")
		)
		(pad "2" smd rect
			(at 0 1.397)
			(size 1.651 1.27)
			(layers "F.Cu" "F.Mask" "F.Paste")
			(net "5V_PRE_29")
		)
	)
	(footprint ""
		(layer "F.Cu")
		(at 242.7478 -260.5532 180)
		(property "Reference" "R41"
			(at 0 0 180)
			(layer "F.SilkS")
			(hide yes)
			(effects
				(font
					(size 1.27 1.27)
				)
			)
		)
		(property "Value" "4K7R2F-GP"
			(at 0.064008 -3.993896 180)
			(unlocked yes)
			(layer "F.Fab")
			(hide yes)
			(effects
				(font
					(size 1.016 1.016)
					(thickness 0.1524)
				)
			)
		)
		(property "Device Type" "R402H16"
			(at 0.064008 -5.517896 180)
			(unlocked yes)
			(layer "F.Fab")
			(hide yes)
			(effects
				(font
					(size 1.016 1.016)
					(thickness 0.1524)
				)
			)
		)
		(duplicate_pad_numbers_are_jumpers no)
		(fp_line
			(start 0.508 -0.9398)
			(end -0.508 -0.9398)
			(stroke
				(width 0.1524)
				(type default)
			)
			(layer "F.SilkS")
		)
		(fp_line
			(start -0.508 -0.9398)
			(end -0.508 0.9398)
			(stroke
				(width 0.1524)
				(type default)
			)
			(layer "F.SilkS")
		)
		(fp_rect
			(start -0.508 0.9398)
			(end 0.508 -0.9398)
			(stroke
				(width 0)
				(type default)
			)
			(fill no)
			(layer "F.CrtYd")
		)
		(fp_rect
			(start -0.508 0.9398)
			(end 0.508 -0.9398)
			(stroke
				(width 0)
				(type default)
			)
			(fill no)
			(layer "F.Fab")
		)
		(pad "1" smd custom
			(at 0 -0.4445 180)
			(size 0.1397 0.1397)
			(layers "F.Cu" "F.Mask" "F.Paste")
			(net "IO_EXP5_A0")
			(options
				(clearance outline)
				(anchor circle)
			)
			(primitives
				(gr_poly
					(pts
						(arc
							(start -0.1778 -0.2794)
							(mid -0.249642 -0.249642)
							(end -0.2794 -0.1778)
						)
						(arc
							(start -0.2794 0.1778)
							(mid -0.249642 0.249642)
							(end -0.1778 0.2794)
						)
						(arc
							(start 0.1778 0.2794)
							(mid 0.249642 0.249642)
							(end 0.2794 0.1778)
						)
						(arc
							(start 0.2794 -0.1778)
							(mid 0.249642 -0.249642)
							(end 0.1778 -0.2794)
						)
					)
					(width 0)
					(fill yes)
				)
			)
		)
		(pad "2" smd custom
			(at 0 0.4445 180)
			(size 0.1397 0.1397)
			(layers "F.Cu" "F.Mask" "F.Paste")
			(net "GND")
			(options
				(clearance outline)
				(anchor circle)
			)
			(primitives
				(gr_poly
					(pts
						(arc
							(start -0.1778 -0.2794)
							(mid -0.249642 -0.249642)
							(end -0.2794 -0.1778)
						)
						(arc
							(start -0.2794 0.1778)
							(mid -0.249642 0.249642)
							(end -0.1778 0.2794)
						)
						(arc
							(start 0.1778 0.2794)
							(mid 0.249642 0.249642)
							(end 0.2794 0.1778)
						)
						(arc
							(start 0.2794 -0.1778)
							(mid 0.249642 -0.249642)
							(end 0.1778 -0.2794)
						)
					)
					(width 0)
					(fill yes)
				)
			)
		)
	)
	(footprint ""
		(layer "F.Cu")
		(at 346.192602 -291.356542 90)
		(property "Reference" "R588"
			(at 0 0 90)
			(layer "F.SilkS")
			(hide yes)
			(effects
				(font
					(size 1.27 1.27)
				)
			)
		)
		(property "Value" "4K7R2J-2-GP"
			(at 0.064008 -3.993896 90)
			(unlocked yes)
			(layer "F.Fab")
			(hide yes)
			(effects
				(font
					(size 1.016 1.016)
					(thickness 0.1524)
				)
			)
		)
		(property "Device Type" "R402H16"
			(at 0.064008 -5.517896 90)
			(unlocked yes)
			(layer "F.Fab")
			(hide yes)
			(effects
				(font
					(size 1.016 1.016)
					(thickness 0.1524)
				)
			)
		)
		(duplicate_pad_numbers_are_jumpers no)
		(fp_line
			(start 0.508 -0.9398)
			(end -0.508 -0.9398)
			(stroke
				(width 0.1524)
				(type default)
			)
			(layer "F.SilkS")
		)
		(fp_line
			(start -0.508 -0.9398)
			(end -0.508 0.9398)
			(stroke
				(width 0.1524)
				(type default)
			)
			(layer "F.SilkS")
		)
		(fp_rect
			(start -0.508 0.9398)
			(end 0.508 -0.9398)
			(stroke
				(width 0)
				(type default)
			)
			(fill no)
			(layer "F.CrtYd")
		)
		(fp_rect
			(start -0.508 0.9398)
			(end 0.508 -0.9398)
			(stroke
				(width 0)
				(type default)
			)
			(fill no)
			(layer "F.Fab")
		)
		(pad "1" smd custom
			(at 0 -0.4445 90)
			(size 0.1397 0.1397)
			(layers "F.Cu" "F.Mask" "F.Paste")
			(net "DRIVE_B_31_FLT_LED")
			(options
				(clearance outline)
				(anchor circle)
			)
			(primitives
				(gr_poly
					(pts
						(arc
							(start -0.1778 -0.2794)
							(mid -0.249642 -0.249642)
							(end -0.2794 -0.1778)
						)
						(arc
							(start -0.2794 0.1778)
							(mid -0.249642 0.249642)
							(end -0.1778 0.2794)
						)
						(arc
							(start 0.1778 0.2794)
							(mid 0.249642 0.249642)
							(end 0.2794 0.1778)
						)
						(arc
							(start 0.2794 -0.1778)
							(mid 0.249642 -0.249642)
							(end 0.1778 -0.2794)
						)
					)
					(width 0)
					(fill yes)
				)
			)
		)
		(pad "2" smd custom
			(at 0 0.4445 90)
			(size 0.1397 0.1397)
			(layers "F.Cu" "F.Mask" "F.Paste")
			(net "GND")
			(options
				(clearance outline)
				(anchor circle)
			)
			(primitives
				(gr_poly
					(pts
						(arc
							(start -0.1778 -0.2794)
							(mid -0.249642 -0.249642)
							(end -0.2794 -0.1778)
						)
						(arc
							(start -0.2794 0.1778)
							(mid -0.249642 0.249642)
							(end -0.1778 0.2794)
						)
						(arc
							(start 0.1778 0.2794)
							(mid 0.249642 0.249642)
							(end 0.2794 0.1778)
						)
						(arc
							(start 0.2794 -0.1778)
							(mid 0.249642 -0.249642)
							(end 0.1778 -0.2794)
						)
					)
					(width 0)
					(fill yes)
				)
			)
		)
	)
	(footprint ""
		(layer "F.Cu")
		(at 370.259102 -57.851294 90)
		(property "Reference" "C452"
			(at 0 0 90)
			(layer "F.SilkS")
			(hide yes)
			(effects
				(font
					(size 1.27 1.27)
				)
			)
		)
		(property "Value" "SCD033U25V2KX-GP"
			(at 1.1811 -2.7051 90)
			(unlocked yes)
			(layer "F.Fab")
			(hide yes)
			(effects
				(font
					(size 1.016 1.016)
					(thickness 0.1524)
				)
			)
		)
		(property "Device Type" "C402H22"
			(at 1.1811 -4.2291 90)
			(unlocked yes)
			(layer "F.Fab")
			(hide yes)
			(effects
				(font
					(size 1.016 1.016)
					(thickness 0.1524)
				)
			)
		)
		(duplicate_pad_numbers_are_jumpers no)
		(fp_rect
			(start -0.4318 0.9525)
			(end 0.4318 -0.9525)
			(stroke
				(width 0)
				(type default)
			)
			(fill no)
			(layer "F.CrtYd")
		)
		(fp_rect
			(start -0.4318 0.9525)
			(end 0.4318 -0.9525)
			(stroke
				(width 0)
				(type default)
			)
			(fill no)
			(layer "F.Fab")
		)
		(pad "1" smd custom
			(at 0 -0.4445 90)
			(size 0.1524 0.1524)
			(layers "F.Cu" "F.Mask" "F.Paste")
			(net "P12V_A")
			(options
				(clearance outline)
				(anchor circle)
			)
			(primitives
				(gr_poly
					(pts
						(arc
							(start 0.3048 -0.2032)
							(mid 0.275042 -0.275042)
							(end 0.2032 -0.3048)
						)
						(arc
							(start -0.2032 -0.3048)
							(mid -0.275042 -0.275042)
							(end -0.3048 -0.2032)
						)
						(arc
							(start -0.3048 0.2032)
							(mid -0.275042 0.275042)
							(end -0.2032 0.3048)
						)
						(arc
							(start 0.2032 0.3048)
							(mid 0.275042 0.275042)
							(end 0.3048 0.2032)
						)
					)
					(width 0)
					(fill yes)
				)
			)
		)
		(pad "2" smd custom
			(at 0 0.4445 90)
			(size 0.1524 0.1524)
			(layers "F.Cu" "F.Mask" "F.Paste")
			(net "SW_HDD_N31")
			(options
				(clearance outline)
				(anchor circle)
			)
			(primitives
				(gr_poly
					(pts
						(arc
							(start 0.3048 -0.2032)
							(mid 0.275042 -0.275042)
							(end 0.2032 -0.3048)
						)
						(arc
							(start -0.2032 -0.3048)
							(mid -0.275042 -0.275042)
							(end -0.3048 -0.2032)
						)
						(arc
							(start -0.3048 0.2032)
							(mid -0.275042 0.275042)
							(end -0.2032 0.3048)
						)
						(arc
							(start 0.2032 0.3048)
							(mid 0.275042 0.275042)
							(end 0.3048 0.2032)
						)
					)
					(width 0)
					(fill yes)
				)
			)
		)
	)
	(footprint ""
		(layer "F.Cu")
		(at 260.8326 -229.6668 -90)
		(property "Reference" "R432"
			(at 0 0 270)
			(layer "F.SilkS")
			(hide yes)
			(effects
				(font
					(size 1.27 1.27)
				)
			)
		)
		(property "Value" "1KR2F-3-GP"
			(at 0.064008 -3.993896 270)
			(unlocked yes)
			(layer "F.Fab")
			(hide yes)
			(effects
				(font
					(size 1.016 1.016)
					(thickness 0.1524)
				)
			)
		)
		(property "Device Type" "R402H16"
			(at 0.064008 -5.517896 270)
			(unlocked yes)
			(layer "F.Fab")
			(hide yes)
			(effects
				(font
					(size 1.016 1.016)
					(thickness 0.1524)
				)
			)
		)
		(duplicate_pad_numbers_are_jumpers no)
		(fp_line
			(start -0.508 -0.9398)
			(end -0.508 0.9398)
			(stroke
				(width 0.1524)
				(type default)
			)
			(layer "F.SilkS")
		)
		(fp_line
			(start 0.508 -0.9398)
			(end -0.508 -0.9398)
			(stroke
				(width 0.1524)
				(type default)
			)
			(layer "F.SilkS")
		)
		(fp_rect
			(start -0.508 0.9398)
			(end 0.508 -0.9398)
			(stroke
				(width 0)
				(type default)
			)
			(fill no)
			(layer "F.CrtYd")
		)
		(fp_rect
			(start -0.508 0.9398)
			(end 0.508 -0.9398)
			(stroke
				(width 0)
				(type default)
			)
			(fill no)
			(layer "F.Fab")
		)
		(pad "1" smd custom
			(at 0 -0.4445 270)
			(size 0.1397 0.1397)
			(layers "F.Cu" "F.Mask" "F.Paste")
			(net "P3V3_STBY_A")
			(options
				(clearance outline)
				(anchor circle)
			)
			(primitives
				(gr_poly
					(pts
						(arc
							(start -0.1778 -0.2794)
							(mid -0.249642 -0.249642)
							(end -0.2794 -0.1778)
						)
						(arc
							(start -0.2794 0.1778)
							(mid -0.249642 0.249642)
							(end -0.1778 0.2794)
						)
						(arc
							(start 0.1778 0.2794)
							(mid 0.249642 0.249642)
							(end 0.2794 0.1778)
						)
						(arc
							(start 0.2794 -0.1778)
							(mid 0.249642 -0.249642)
							(end 0.1778 -0.2794)
						)
					)
					(width 0)
					(fill yes)
				)
			)
		)
		(pad "2" smd custom
			(at 0 0.4445 270)
			(size 0.1397 0.1397)
			(layers "F.Cu" "F.Mask" "F.Paste")
			(net "I2C_DRIVE_A_PWR_SDA")
			(options
				(clearance outline)
				(anchor circle)
			)
			(primitives
				(gr_poly
					(pts
						(arc
							(start -0.1778 -0.2794)
							(mid -0.249642 -0.249642)
							(end -0.2794 -0.1778)
						)
						(arc
							(start -0.2794 0.1778)
							(mid -0.249642 0.249642)
							(end -0.1778 0.2794)
						)
						(arc
							(start 0.1778 0.2794)
							(mid 0.249642 0.249642)
							(end 0.2794 0.1778)
						)
						(arc
							(start 0.2794 -0.1778)
							(mid 0.249642 -0.249642)
							(end 0.1778 -0.2794)
						)
					)
					(width 0)
					(fill yes)
				)
			)
		)
	)
	(footprint ""
		(layer "F.Cu")
		(at 190.8048 -52.197 -90)
		(property "Reference" "R797"
			(at 0 0 270)
			(layer "F.SilkS")
			(hide yes)
			(effects
				(font
					(size 1.27 1.27)
				)
			)
		)
		(property "Value" "10KR2F-2-GP"
			(at 0.064008 -3.993896 270)
			(unlocked yes)
			(layer "F.Fab")
			(hide yes)
			(effects
				(font
					(size 1.016 1.016)
					(thickness 0.1524)
				)
			)
		)
		(property "Device Type" "R402H16"
			(at 0.064008 -5.517896 270)
			(unlocked yes)
			(layer "F.Fab")
			(hide yes)
			(effects
				(font
					(size 1.016 1.016)
					(thickness 0.1524)
				)
			)
		)
		(duplicate_pad_numbers_are_jumpers no)
		(fp_line
			(start -0.508 -0.9398)
			(end -0.508 0.9398)
			(stroke
				(width 0.1524)
				(type default)
			)
			(layer "F.SilkS")
		)
		(fp_line
			(start 0.508 -0.9398)
			(end -0.508 -0.9398)
			(stroke
				(width 0.1524)
				(type default)
			)
			(layer "F.SilkS")
		)
		(fp_rect
			(start -0.508 0.9398)
			(end 0.508 -0.9398)
			(stroke
				(width 0)
				(type default)
			)
			(fill no)
			(layer "F.CrtYd")
		)
		(fp_rect
			(start -0.508 0.9398)
			(end 0.508 -0.9398)
			(stroke
				(width 0)
				(type default)
			)
			(fill no)
			(layer "F.Fab")
		)
		(pad "1" smd custom
			(at 0 -0.4445 270)
			(size 0.1397 0.1397)
			(layers "F.Cu" "F.Mask" "F.Paste")
			(net "P3V3_STBY_A")
			(options
				(clearance outline)
				(anchor circle)
			)
			(primitives
				(gr_poly
					(pts
						(arc
							(start -0.1778 -0.2794)
							(mid -0.249642 -0.249642)
							(end -0.2794 -0.1778)
						)
						(arc
							(start -0.2794 0.1778)
							(mid -0.249642 0.249642)
							(end -0.1778 0.2794)
						)
						(arc
							(start 0.1778 0.2794)
							(mid 0.249642 0.249642)
							(end 0.2794 0.1778)
						)
						(arc
							(start 0.2794 -0.1778)
							(mid 0.249642 -0.249642)
							(end 0.1778 -0.2794)
						)
					)
					(width 0)
					(fill yes)
				)
			)
		)
		(pad "2" smd custom
			(at 0 0.4445 270)
			(size 0.1397 0.1397)
			(layers "F.Cu" "F.Mask" "F.Paste")
			(net "HDD_PRSNT_29")
			(options
				(clearance outline)
				(anchor circle)
			)
			(primitives
				(gr_poly
					(pts
						(arc
							(start -0.1778 -0.2794)
							(mid -0.249642 -0.249642)
							(end -0.2794 -0.1778)
						)
						(arc
							(start -0.2794 0.1778)
							(mid -0.249642 0.249642)
							(end -0.1778 0.2794)
						)
						(arc
							(start 0.1778 0.2794)
							(mid 0.249642 0.249642)
							(end 0.2794 0.1778)
						)
						(arc
							(start 0.2794 -0.1778)
							(mid 0.249642 -0.249642)
							(end 0.1778 -0.2794)
						)
					)
					(width 0)
					(fill yes)
				)
			)
		)
	)
	(footprint ""
		(layer "F.Cu")
		(at 27.178 -247.777 90)
		(property "Reference" "C598"
			(at 0 0 90)
			(layer "F.SilkS")
			(hide yes)
			(effects
				(font
					(size 1.27 1.27)
				)
			)
		)
		(property "Value" "SC10U16V5KX-7-GP-U"
			(at -0.0762 -6.1214 90)
			(unlocked yes)
			(layer "F.Fab")
			(hide yes)
			(effects
				(font
					(size 1.016 1.016)
					(thickness 0.1524)
				)
			)
		)
		(property "Device Type" "C805H58"
			(at -0.0762 -8.1534 90)
			(unlocked yes)
			(layer "F.Fab")
			(hide yes)
			(effects
				(font
					(size 1.016 1.016)
					(thickness 0.1524)
				)
			)
		)
		(duplicate_pad_numbers_are_jumpers no)
		(fp_line
			(start 0.635 0)
			(end -0.635 0)
			(stroke
				(width 0.508)
				(type default)
			)
			(layer "F.SilkS")
		)
		(fp_rect
			(start -0.9652 1.778)
			(end 0.9652 -1.778)
			(stroke
				(width 0)
				(type default)
			)
			(fill no)
			(layer "F.CrtYd")
		)
		(fp_poly
			(pts
				(xy -0.9652 -1.778) (xy 0.9652 -1.778) (xy 0.9652 1.778) (xy -0.9652 1.778)
			)
			(stroke
				(width 0)
				(type default)
			)
			(fill no)
			(layer "F.Fab")
		)
		(pad "1" smd rect
			(at 0 -0.9652 90)
			(size 1.397 1.143)
			(layers "F.Cu" "F.Mask" "F.Paste")
			(net "P12V_A_VIN_U20")
		)
		(pad "2" smd rect
			(at 0 0.9652 90)
			(size 1.397 1.143)
			(layers "F.Cu" "F.Mask" "F.Paste")
			(net "GND")
		)
	)
	(footprint ""
		(layer "F.Cu")
		(at 472.244928 -127.254)
		(property "Reference" "R343"
			(at 0 0 0)
			(layer "F.SilkS")
			(hide yes)
			(effects
				(font
					(size 1.27 1.27)
				)
			)
		)
		(property "Value" "130R3F-GP"
			(at -0.0254 -2.5146 0)
			(unlocked yes)
			(layer "F.Fab")
			(hide yes)
			(effects
				(font
					(size 1.016 1.016)
					(thickness 0.1524)
				)
			)
		)
		(property "Device Type" "R603H22"
			(at -0.0254 -4.0386 0)
			(unlocked yes)
			(layer "F.Fab")
			(hide yes)
			(effects
				(font
					(size 1.016 1.016)
					(thickness 0.1524)
				)
			)
		)
		(duplicate_pad_numbers_are_jumpers no)
		(fp_line
			(start -0.4826 0)
			(end -0.2032 0)
			(stroke
				(width 0.2032)
				(type default)
			)
			(layer "F.SilkS")
		)
		(fp_line
			(start 0.2032 0)
			(end 0.4826 0)
			(stroke
				(width 0.2032)
				(type default)
			)
			(layer "F.SilkS")
		)
		(fp_rect
			(start -0.5842 1.3335)
			(end 0.5842 -1.3335)
			(stroke
				(width 0)
				(type default)
			)
			(fill no)
			(layer "F.CrtYd")
		)
		(fp_rect
			(start -0.5842 1.3335)
			(end 0.5842 -1.3335)
			(stroke
				(width 0)
				(type default)
			)
			(fill no)
			(layer "F.Fab")
		)
		(pad "1" smd custom
			(at 0 -0.762)
			(size 0.2159 0.2159)
			(layers "F.Cu" "F.Mask" "F.Paste")
			(net "P5V_A_4")
			(options
				(clearance outline)
				(anchor circle)
			)
			(primitives
				(gr_poly
					(pts
						(arc
							(start -0.3302 -0.4318)
							(mid -0.402042 -0.402042)
							(end -0.4318 -0.3302)
						)
						(arc
							(start -0.4318 0.3302)
							(mid -0.402042 0.402042)
							(end -0.3302 0.4318)
						)
						(arc
							(start 0.3302 0.4318)
							(mid 0.402042 0.402042)
							(end 0.4318 0.3302)
						)
						(arc
							(start 0.4318 -0.3302)
							(mid 0.402042 -0.402042)
							(end 0.3302 -0.4318)
						)
					)
					(width 0)
					(fill yes)
				)
			)
		)
		(pad "2" smd custom
			(at 0 0.762)
			(size 0.2159 0.2159)
			(layers "F.Cu" "F.Mask" "F.Paste")
			(net "FLT_HDD23")
			(options
				(clearance outline)
				(anchor circle)
			)
			(primitives
				(gr_poly
					(pts
						(arc
							(start -0.3302 -0.4318)
							(mid -0.402042 -0.402042)
							(end -0.4318 -0.3302)
						)
						(arc
							(start -0.4318 0.3302)
							(mid -0.402042 0.402042)
							(end -0.3302 0.4318)
						)
						(arc
							(start 0.3302 0.4318)
							(mid 0.402042 0.402042)
							(end 0.4318 0.3302)
						)
						(arc
							(start 0.4318 -0.3302)
							(mid 0.402042 -0.402042)
							(end 0.3302 -0.4318)
						)
					)
					(width 0)
					(fill yes)
				)
			)
		)
	)
	(footprint ""
		(layer "F.Cu")
		(at 222.6056 -114.3508 -90)
		(property "Reference" "R178"
			(at 0 0 270)
			(layer "F.SilkS")
			(hide yes)
			(effects
				(font
					(size 1.27 1.27)
				)
			)
		)
		(property "Value" "0R2J-2-GP"
			(at 0.064008 -3.993896 270)
			(unlocked yes)
			(layer "F.Fab")
			(hide yes)
			(effects
				(font
					(size 1.016 1.016)
					(thickness 0.1524)
				)
			)
		)
		(property "Device Type" "R402H16"
			(at 0.064008 -5.517896 270)
			(unlocked yes)
			(layer "F.Fab")
			(hide yes)
			(effects
				(font
					(size 1.016 1.016)
					(thickness 0.1524)
				)
			)
		)
		(duplicate_pad_numbers_are_jumpers no)
		(fp_line
			(start -0.508 -0.9398)
			(end -0.508 0.9398)
			(stroke
				(width 0.1524)
				(type default)
			)
			(layer "F.SilkS")
		)
		(fp_line
			(start 0.508 -0.9398)
			(end -0.508 -0.9398)
			(stroke
				(width 0.1524)
				(type default)
			)
			(layer "F.SilkS")
		)
		(fp_rect
			(start -0.508 0.9398)
			(end 0.508 -0.9398)
			(stroke
				(width 0)
				(type default)
			)
			(fill no)
			(layer "F.CrtYd")
		)
		(fp_rect
			(start -0.508 0.9398)
			(end 0.508 -0.9398)
			(stroke
				(width 0)
				(type default)
			)
			(fill no)
			(layer "F.Fab")
		)
		(pad "1" smd custom
			(at 0 -0.4445 270)
			(size 0.1397 0.1397)
			(layers "F.Cu" "F.Mask" "F.Paste")
			(net "SLOT3_SVR_ID0_GPIO1")
			(options
				(clearance outline)
				(anchor circle)
			)
			(primitives
				(gr_poly
					(pts
						(arc
							(start -0.1778 -0.2794)
							(mid -0.249642 -0.249642)
							(end -0.2794 -0.1778)
						)
						(arc
							(start -0.2794 0.1778)
							(mid -0.249642 0.249642)
							(end -0.1778 0.2794)
						)
						(arc
							(start 0.1778 0.2794)
							(mid 0.249642 0.249642)
							(end 0.2794 0.1778)
						)
						(arc
							(start 0.2794 -0.1778)
							(mid 0.249642 -0.249642)
							(end 0.1778 -0.2794)
						)
					)
					(width 0)
					(fill yes)
				)
			)
		)
		(pad "2" smd custom
			(at 0 0.4445 270)
			(size 0.1397 0.1397)
			(layers "F.Cu" "F.Mask" "F.Paste")
			(net "COMP_A_BMC_A_SPARE_1")
			(options
				(clearance outline)
				(anchor circle)
			)
			(primitives
				(gr_poly
					(pts
						(arc
							(start -0.1778 -0.2794)
							(mid -0.249642 -0.249642)
							(end -0.2794 -0.1778)
						)
						(arc
							(start -0.2794 0.1778)
							(mid -0.249642 0.249642)
							(end -0.1778 0.2794)
						)
						(arc
							(start 0.1778 0.2794)
							(mid 0.249642 0.249642)
							(end 0.2794 0.1778)
						)
						(arc
							(start 0.2794 -0.1778)
							(mid 0.249642 -0.249642)
							(end 0.1778 -0.2794)
						)
					)
					(width 0)
					(fill yes)
				)
			)
		)
	)
	(footprint ""
		(layer "F.Cu")
		(at 178.181 -48.554894 180)
		(property "Reference" "Q175"
			(at 0 0 180)
			(layer "F.SilkS")
			(hide yes)
			(effects
				(font
					(size 1.27 1.27)
				)
			)
		)
		(property "Value" "2N7002KDW-GP"
			(at -2.3622 -8.2042 180)
			(unlocked yes)
			(layer "F.Fab")
			(hide yes)
			(effects
				(font
					(size 1.016 1.016)
					(thickness 0.1524)
				)
			)
		)
		(property "Device Type" "SOT-363H44"
			(at -2.3622 -10.1092 180)
			(unlocked yes)
			(layer "F.Fab")
			(hide yes)
			(effects
				(font
					(size 1.016 1.016)
					(thickness 0.1524)
				)
			)
		)
		(duplicate_pad_numbers_are_jumpers no)
		(fp_line
			(start 1.4478 1.7018)
			(end 1.4478 -1.7018)
			(stroke
				(width 0.1524)
				(type default)
			)
			(layer "F.SilkS")
		)
		(fp_line
			(start 1.4478 -1.7018)
			(end -1.4478 -1.7018)
			(stroke
				(width 0.1524)
				(type default)
			)
			(layer "F.SilkS")
		)
		(fp_line
			(start -1.27 1.524)
			(end -1.27 0.6604)
			(stroke
				(width 0.4826)
				(type default)
			)
			(layer "F.SilkS")
		)
		(fp_line
			(start -1.4478 1.7018)
			(end 1.4478 1.7018)
			(stroke
				(width 0.1524)
				(type default)
			)
			(layer "F.SilkS")
		)
		(fp_line
			(start -1.4478 -1.7018)
			(end -1.4478 1.7018)
			(stroke
				(width 0.1524)
				(type default)
			)
			(layer "F.SilkS")
		)
		(fp_poly
			(pts
				(xy -1.524 -1.778) (xy 1.524 -1.778) (xy 1.524 1.778) (xy -1.524 1.778)
			)
			(stroke
				(width 0)
				(type default)
			)
			(fill no)
			(layer "F.CrtYd")
		)
		(fp_poly
			(pts
				(xy -1.524 -1.778) (xy 1.524 -1.778) (xy 1.524 1.778) (xy -1.524 1.778)
			)
			(stroke
				(width 0)
				(type default)
			)
			(fill no)
			(layer "F.Fab")
		)
		(pad "1" smd rect
			(at -0.65024 0.9398 180)
			(size 0.4064 1.016)
			(layers "F.Cu" "F.Mask" "F.Paste")
			(net "GND")
		)
		(pad "2" smd rect
			(at 0 0.9398 180)
			(size 0.4064 1.016)
			(layers "F.Cu" "F.Mask" "F.Paste")
			(net "SW_PWR_R_HDD29")
		)
		(pad "3" smd rect
			(at 0.65024 0.9398 180)
			(size 0.4064 1.016)
			(layers "F.Cu" "F.Mask" "F.Paste")
			(net "SW_HDD_P29")
		)
		(pad "4" smd rect
			(at 0.65024 -0.9398 180)
			(size 0.4064 1.016)
			(layers "F.Cu" "F.Mask" "F.Paste")
			(net "GND")
		)
		(pad "5" smd rect
			(at 0 -0.9398 180)
			(size 0.4064 1.016)
			(layers "F.Cu" "F.Mask" "F.Paste")
			(net "SW_HDD_G29")
		)
		(pad "6" smd rect
			(at -0.65024 -0.9398 180)
			(size 0.4064 1.016)
			(layers "F.Cu" "F.Mask" "F.Paste")
			(net "SW_HDD_R29")
		)
	)
	(footprint ""
		(layer "F.Cu")
		(at 87.036148 -71.287894)
		(property "Reference" "C383"
			(at 0 0 0)
			(layer "F.SilkS")
			(hide yes)
			(effects
				(font
					(size 1.27 1.27)
				)
			)
		)
		(property "Value" "SC4D7U25V5KX-1-GP"
			(at -0.0762 -6.1214 0)
			(unlocked yes)
			(layer "F.Fab")
			(hide yes)
			(effects
				(font
					(size 1.016 1.016)
					(thickness 0.1524)
				)
			)
		)
		(property "Device Type" "C805H58"
			(at -0.0762 -8.1534 0)
			(unlocked yes)
			(layer "F.Fab")
			(hide yes)
			(effects
				(font
					(size 1.016 1.016)
					(thickness 0.1524)
				)
			)
		)
		(duplicate_pad_numbers_are_jumpers no)
		(fp_line
			(start 0.635 0)
			(end -0.635 0)
			(stroke
				(width 0.508)
				(type default)
			)
			(layer "F.SilkS")
		)
		(fp_rect
			(start -0.9652 1.778)
			(end 0.9652 -1.778)
			(stroke
				(width 0)
				(type default)
			)
			(fill no)
			(layer "F.CrtYd")
		)
		(fp_poly
			(pts
				(xy -0.9652 -1.778) (xy 0.9652 -1.778) (xy 0.9652 1.778) (xy -0.9652 1.778)
			)
			(stroke
				(width 0)
				(type default)
			)
			(fill no)
			(layer "F.Fab")
		)
		(pad "1" smd rect
			(at 0 -0.9652)
			(size 1.397 1.143)
			(layers "F.Cu" "F.Mask" "F.Paste")
			(net "P12V_HDD26")
		)
		(pad "2" smd rect
			(at 0 0.9652)
			(size 1.397 1.143)
			(layers "F.Cu" "F.Mask" "F.Paste")
			(net "GND")
		)
	)
	(footprint ""
		(layer "F.Cu")
		(at 361.369102 -304.335942 180)
		(property "Reference" "C138"
			(at 0 0 180)
			(layer "F.SilkS")
			(hide yes)
			(effects
				(font
					(size 1.27 1.27)
				)
			)
		)
		(property "Value" "SC1U25V3KX-GP"
			(at 0 -2.8194 180)
			(unlocked yes)
			(layer "F.Fab")
			(hide yes)
			(effects
				(font
					(size 1.016 1.016)
					(thickness 0.1524)
				)
			)
		)
		(property "Device Type" "C603H36"
			(at 0 -4.3434 180)
			(unlocked yes)
			(layer "F.Fab")
			(hide yes)
			(effects
				(font
					(size 1.016 1.016)
					(thickness 0.1524)
				)
			)
		)
		(duplicate_pad_numbers_are_jumpers no)
		(fp_line
			(start 0.508 0)
			(end -0.508 0)
			(stroke
				(width 0.2032)
				(type default)
			)
			(layer "F.SilkS")
		)
		(fp_rect
			(start -0.5842 1.3335)
			(end 0.5842 -1.3335)
			(stroke
				(width 0)
				(type default)
			)
			(fill no)
			(layer "F.CrtYd")
		)
		(fp_rect
			(start -0.5842 1.3335)
			(end 0.5842 -1.3335)
			(stroke
				(width 0)
				(type default)
			)
			(fill no)
			(layer "F.Fab")
		)
		(pad "1" smd custom
			(at 0 -0.762 180)
			(size 0.2159 0.2159)
			(layers "F.Cu" "F.Mask" "F.Paste")
			(net "P12V_HDD7")
			(options
				(clearance outline)
				(anchor circle)
			)
			(primitives
				(gr_poly
					(pts
						(arc
							(start -0.3302 -0.4318)
							(mid -0.402042 -0.402042)
							(end -0.4318 -0.3302)
						)
						(arc
							(start -0.4318 0.3302)
							(mid -0.402042 0.402042)
							(end -0.3302 0.4318)
						)
						(arc
							(start 0.3302 0.4318)
							(mid 0.402042 0.402042)
							(end 0.4318 0.3302)
						)
						(arc
							(start 0.4318 -0.3302)
							(mid 0.402042 -0.402042)
							(end 0.3302 -0.4318)
						)
					)
					(width 0)
					(fill yes)
				)
			)
		)
		(pad "2" smd custom
			(at 0 0.762 180)
			(size 0.2159 0.2159)
			(layers "F.Cu" "F.Mask" "F.Paste")
			(net "GND")
			(options
				(clearance outline)
				(anchor circle)
			)
			(primitives
				(gr_poly
					(pts
						(arc
							(start -0.3302 -0.4318)
							(mid -0.402042 -0.402042)
							(end -0.4318 -0.3302)
						)
						(arc
							(start -0.4318 0.3302)
							(mid -0.402042 0.402042)
							(end -0.3302 0.4318)
						)
						(arc
							(start 0.3302 0.4318)
							(mid 0.402042 0.402042)
							(end 0.4318 0.3302)
						)
						(arc
							(start 0.4318 -0.3302)
							(mid 0.402042 -0.402042)
							(end 0.3302 -0.4318)
						)
					)
					(width 0)
					(fill yes)
				)
			)
		)
	)
	(footprint ""
		(layer "F.Cu")
		(at 346.700094 -209.399886)
		(property "Reference" "FLED8"
			(at 0 0 0)
			(layer "F.SilkS")
			(hide yes)
			(effects
				(font
					(size 1.27 1.27)
				)
			)
		)
		(property "Value" "LED-BY-19-GP"
			(at -2.132076 1.414018 0)
			(unlocked yes)
			(layer "F.Fab")
			(hide yes)
			(effects
				(font
					(size 1.016 1.016)
					(thickness 0.1524)
				)
			)
		)
		(property "Device Type" "LED-1615-4PH26"
			(at -2.132076 -0.109982 0)
			(unlocked yes)
			(layer "F.Fab")
			(hide yes)
			(effects
				(font
					(size 1.016 1.016)
					(thickness 0.1524)
				)
			)
		)
		(duplicate_pad_numbers_are_jumpers no)
		(fp_line
			(start -1.2954 0.254)
			(end -1.2954 1.6002)
			(stroke
				(width 0.508)
				(type default)
			)
			(layer "F.SilkS")
		)
		(fp_line
			(start -1.2954 1.6002)
			(end 1.2954 1.6002)
			(stroke
				(width 0.508)
				(type default)
			)
			(layer "F.SilkS")
		)
		(fp_line
			(start -1.1176 -1.4224)
			(end 1.1176 -1.4224)
			(stroke
				(width 0.1524)
				(type default)
			)
			(layer "F.SilkS")
		)
		(fp_line
			(start -1.1176 1.4224)
			(end -1.1176 -1.4224)
			(stroke
				(width 0.1524)
				(type default)
			)
			(layer "F.SilkS")
		)
		(fp_line
			(start 1.1176 -1.4224)
			(end 1.1176 1.4224)
			(stroke
				(width 0.1524)
				(type default)
			)
			(layer "F.SilkS")
		)
		(fp_line
			(start 1.1176 1.4224)
			(end -1.1176 1.4224)
			(stroke
				(width 0.1524)
				(type default)
			)
			(layer "F.SilkS")
		)
		(fp_line
			(start 1.2954 1.6002)
			(end 1.2954 0.254)
			(stroke
				(width 0.508)
				(type default)
			)
			(layer "F.SilkS")
		)
		(fp_rect
			(start -0.7493 0.8001)
			(end 0.7493 -0.8001)
			(stroke
				(width 0)
				(type default)
			)
			(fill no)
			(layer "F.CrtYd")
		)
		(fp_poly
			(pts
				(xy -1.3716 1.6764) (xy -1.3716 -1.6764) (xy 1.3716 -1.6764) (xy 1.3716 0.0635) (xy 0.7493 0.0635)
				(xy 0.7493 -0.8001) (xy -0.7493 -0.8001) (xy -0.7493 0.8001) (xy 0.7493 0.8001) (xy 0.7493 0.0762)
				(xy 1.3716 0.0762) (xy 1.3716 1.6764)
			)
			(stroke
				(width 0)
				(type default)
			)
			(fill no)
			(layer "F.CrtYd")
		)
		(fp_rect
			(start -1.3716 1.6764)
			(end 1.3716 -1.6764)
			(stroke
				(width 0)
				(type default)
			)
			(fill no)
			(layer "F.Fab")
		)
		(pad "1" smd rect
			(at 0.50038 -0.73025)
			(size 0.7112 0.8636)
			(layers "F.Cu" "F.Mask" "F.Paste")
			(net "DRV_ACT_7")
		)
		(pad "2" smd rect
			(at -0.50038 -0.73025)
			(size 0.7112 0.8636)
			(layers "F.Cu" "F.Mask" "F.Paste")
			(net "FLT_HDD7")
		)
		(pad "3" smd rect
			(at 0.50038 0.73025)
			(size 0.7112 0.8636)
			(layers "F.Cu" "F.Mask" "F.Paste")
			(net "DRV_ACT_7_N")
		)
		(pad "4" smd rect
			(at -0.50038 0.73025)
			(size 0.7112 0.8636)
			(layers "F.Cu" "F.Mask" "F.Paste")
			(net "FLT_HDD7_N")
		)
	)
	(footprint ""
		(layer "F.Cu")
		(at 381.38735 -62.143894 90)
		(property "Reference" "R866"
			(at 0 0 90)
			(layer "F.SilkS")
			(hide yes)
			(effects
				(font
					(size 1.27 1.27)
				)
			)
		)
		(property "Value" "10KR2F-2-GP"
			(at 0.064008 -3.993896 90)
			(unlocked yes)
			(layer "F.Fab")
			(hide yes)
			(effects
				(font
					(size 1.016 1.016)
					(thickness 0.1524)
				)
			)
		)
		(property "Device Type" "R402H16"
			(at 0.064008 -5.517896 90)
			(unlocked yes)
			(layer "F.Fab")
			(hide yes)
			(effects
				(font
					(size 1.016 1.016)
					(thickness 0.1524)
				)
			)
		)
		(duplicate_pad_numbers_are_jumpers no)
		(fp_line
			(start 0.508 -0.9398)
			(end -0.508 -0.9398)
			(stroke
				(width 0.1524)
				(type default)
			)
			(layer "F.SilkS")
		)
		(fp_line
			(start -0.508 -0.9398)
			(end -0.508 0.9398)
			(stroke
				(width 0.1524)
				(type default)
			)
			(layer "F.SilkS")
		)
		(fp_rect
			(start -0.508 0.9398)
			(end 0.508 -0.9398)
			(stroke
				(width 0)
				(type default)
			)
			(fill no)
			(layer "F.CrtYd")
		)
		(fp_rect
			(start -0.508 0.9398)
			(end 0.508 -0.9398)
			(stroke
				(width 0)
				(type default)
			)
			(fill no)
			(layer "F.Fab")
		)
		(pad "1" smd custom
			(at 0 -0.4445 90)
			(size 0.1397 0.1397)
			(layers "F.Cu" "F.Mask" "F.Paste")
			(net "P3V3_STBY_A")
			(options
				(clearance outline)
				(anchor circle)
			)
			(primitives
				(gr_poly
					(pts
						(arc
							(start -0.1778 -0.2794)
							(mid -0.249642 -0.249642)
							(end -0.2794 -0.1778)
						)
						(arc
							(start -0.2794 0.1778)
							(mid -0.249642 0.249642)
							(end -0.1778 0.2794)
						)
						(arc
							(start 0.1778 0.2794)
							(mid 0.249642 0.249642)
							(end 0.2794 0.1778)
						)
						(arc
							(start 0.2794 -0.1778)
							(mid 0.249642 -0.249642)
							(end 0.1778 -0.2794)
						)
					)
					(width 0)
					(fill yes)
				)
			)
		)
		(pad "2" smd custom
			(at 0 0.4445 90)
			(size 0.1397 0.1397)
			(layers "F.Cu" "F.Mask" "F.Paste")
			(net "HDD_PRSNT_32")
			(options
				(clearance outline)
				(anchor circle)
			)
			(primitives
				(gr_poly
					(pts
						(arc
							(start -0.1778 -0.2794)
							(mid -0.249642 -0.249642)
							(end -0.2794 -0.1778)
						)
						(arc
							(start -0.2794 0.1778)
							(mid -0.249642 0.249642)
							(end -0.1778 0.2794)
						)
						(arc
							(start 0.1778 0.2794)
							(mid 0.249642 0.249642)
							(end 0.2794 0.1778)
						)
						(arc
							(start 0.2794 -0.1778)
							(mid 0.249642 -0.249642)
							(end 0.1778 -0.2794)
						)
					)
					(width 0)
					(fill yes)
				)
			)
		)
	)
	(footprint ""
		(layer "F.Cu")
		(at 394.56995 -165.104318 90)
		(property "Reference" "C308"
			(at 0 0 90)
			(layer "F.SilkS")
			(hide yes)
			(effects
				(font
					(size 1.27 1.27)
				)
			)
		)
		(property "Value" "SCD033U25V2KX-GP"
			(at 1.1811 -2.7051 90)
			(unlocked yes)
			(layer "F.Fab")
			(hide yes)
			(effects
				(font
					(size 1.016 1.016)
					(thickness 0.1524)
				)
			)
		)
		(property "Device Type" "C402H22"
			(at 1.1811 -4.2291 90)
			(unlocked yes)
			(layer "F.Fab")
			(hide yes)
			(effects
				(font
					(size 1.016 1.016)
					(thickness 0.1524)
				)
			)
		)
		(duplicate_pad_numbers_are_jumpers no)
		(fp_rect
			(start -0.4318 0.9525)
			(end 0.4318 -0.9525)
			(stroke
				(width 0)
				(type default)
			)
			(fill no)
			(layer "F.CrtYd")
		)
		(fp_rect
			(start -0.4318 0.9525)
			(end 0.4318 -0.9525)
			(stroke
				(width 0)
				(type default)
			)
			(fill no)
			(layer "F.Fab")
		)
		(pad "1" smd custom
			(at 0 -0.4445 90)
			(size 0.1524 0.1524)
			(layers "F.Cu" "F.Mask" "F.Paste")
			(net "SW_HDD_P20")
			(options
				(clearance outline)
				(anchor circle)
			)
			(primitives
				(gr_poly
					(pts
						(arc
							(start 0.3048 -0.2032)
							(mid 0.275042 -0.275042)
							(end 0.2032 -0.3048)
						)
						(arc
							(start -0.2032 -0.3048)
							(mid -0.275042 -0.275042)
							(end -0.3048 -0.2032)
						)
						(arc
							(start -0.3048 0.2032)
							(mid -0.275042 0.275042)
							(end -0.2032 0.3048)
						)
						(arc
							(start 0.2032 0.3048)
							(mid 0.275042 0.275042)
							(end 0.3048 0.2032)
						)
					)
					(width 0)
					(fill yes)
				)
			)
		)
		(pad "2" smd custom
			(at 0 0.4445 90)
			(size 0.1524 0.1524)
			(layers "F.Cu" "F.Mask" "F.Paste")
			(net "GND")
			(options
				(clearance outline)
				(anchor circle)
			)
			(primitives
				(gr_poly
					(pts
						(arc
							(start 0.3048 -0.2032)
							(mid 0.275042 -0.275042)
							(end 0.2032 -0.3048)
						)
						(arc
							(start -0.2032 -0.3048)
							(mid -0.275042 -0.275042)
							(end -0.3048 -0.2032)
						)
						(arc
							(start -0.3048 0.2032)
							(mid -0.275042 0.275042)
							(end -0.2032 0.3048)
						)
						(arc
							(start 0.2032 0.3048)
							(mid 0.275042 0.275042)
							(end 0.3048 0.2032)
						)
					)
					(width 0)
					(fill yes)
				)
			)
		)
	)
	(footprint ""
		(layer "F.Cu")
		(at 261.932166 -339.754464 90)
		(property "Reference" "R381"
			(at 0 0 90)
			(layer "F.SilkS")
			(hide yes)
			(effects
				(font
					(size 1.27 1.27)
				)
			)
		)
		(property "Value" "10KR2F-2-GP"
			(at 0.064008 -3.993896 90)
			(unlocked yes)
			(layer "F.Fab")
			(hide yes)
			(effects
				(font
					(size 1.016 1.016)
					(thickness 0.1524)
				)
			)
		)
		(property "Device Type" "R402H16"
			(at 0.064008 -5.517896 90)
			(unlocked yes)
			(layer "F.Fab")
			(hide yes)
			(effects
				(font
					(size 1.016 1.016)
					(thickness 0.1524)
				)
			)
		)
		(duplicate_pad_numbers_are_jumpers no)
		(fp_line
			(start 0.508 -0.9398)
			(end -0.508 -0.9398)
			(stroke
				(width 0.1524)
				(type default)
			)
			(layer "F.SilkS")
		)
		(fp_line
			(start -0.508 -0.9398)
			(end -0.508 0.9398)
			(stroke
				(width 0.1524)
				(type default)
			)
			(layer "F.SilkS")
		)
		(fp_rect
			(start -0.508 0.9398)
			(end 0.508 -0.9398)
			(stroke
				(width 0)
				(type default)
			)
			(fill no)
			(layer "F.CrtYd")
		)
		(fp_rect
			(start -0.508 0.9398)
			(end 0.508 -0.9398)
			(stroke
				(width 0)
				(type default)
			)
			(fill no)
			(layer "F.Fab")
		)
		(pad "1" smd custom
			(at 0 -0.4445 90)
			(size 0.1397 0.1397)
			(layers "F.Cu" "F.Mask" "F.Paste")
			(net "P3V3_STBY_A")
			(options
				(clearance outline)
				(anchor circle)
			)
			(primitives
				(gr_poly
					(pts
						(arc
							(start -0.1778 -0.2794)
							(mid -0.249642 -0.249642)
							(end -0.2794 -0.1778)
						)
						(arc
							(start -0.2794 0.1778)
							(mid -0.249642 0.249642)
							(end -0.1778 0.2794)
						)
						(arc
							(start 0.1778 0.2794)
							(mid 0.249642 0.249642)
							(end 0.2794 0.1778)
						)
						(arc
							(start 0.2794 -0.1778)
							(mid 0.249642 -0.249642)
							(end 0.1778 -0.2794)
						)
					)
					(width 0)
					(fill yes)
				)
			)
		)
		(pad "2" smd custom
			(at 0 0.4445 90)
			(size 0.1397 0.1397)
			(layers "F.Cu" "F.Mask" "F.Paste")
			(net "SCC_A_TYPE_0")
			(options
				(clearance outline)
				(anchor circle)
			)
			(primitives
				(gr_poly
					(pts
						(arc
							(start -0.1778 -0.2794)
							(mid -0.249642 -0.249642)
							(end -0.2794 -0.1778)
						)
						(arc
							(start -0.2794 0.1778)
							(mid -0.249642 0.249642)
							(end -0.1778 0.2794)
						)
						(arc
							(start 0.1778 0.2794)
							(mid 0.249642 0.249642)
							(end 0.2794 0.1778)
						)
						(arc
							(start 0.2794 -0.1778)
							(mid 0.249642 -0.249642)
							(end 0.1778 -0.2794)
						)
					)
					(width 0)
					(fill yes)
				)
			)
		)
	)
	(footprint ""
		(layer "F.Cu")
		(at 333.501746 -28.98775)
		(property "Reference" "C20"
			(at 0 0 0)
			(layer "F.SilkS")
			(hide yes)
			(effects
				(font
					(size 1.27 1.27)
				)
			)
		)
		(property "Value" "SC1U16V3KX-5GP"
			(at 0 -2.8194 0)
			(unlocked yes)
			(layer "F.Fab")
			(hide yes)
			(effects
				(font
					(size 1.016 1.016)
					(thickness 0.1524)
				)
			)
		)
		(property "Device Type" "C603H36"
			(at 0 -4.3434 0)
			(unlocked yes)
			(layer "F.Fab")
			(hide yes)
			(effects
				(font
					(size 1.016 1.016)
					(thickness 0.1524)
				)
			)
		)
		(duplicate_pad_numbers_are_jumpers no)
		(fp_line
			(start 0.508 0)
			(end -0.508 0)
			(stroke
				(width 0.2032)
				(type default)
			)
			(layer "F.SilkS")
		)
		(fp_rect
			(start -0.5842 1.3335)
			(end 0.5842 -1.3335)
			(stroke
				(width 0)
				(type default)
			)
			(fill no)
			(layer "F.CrtYd")
		)
		(fp_rect
			(start -0.5842 1.3335)
			(end 0.5842 -1.3335)
			(stroke
				(width 0)
				(type default)
			)
			(fill no)
			(layer "F.Fab")
		)
		(pad "1" smd custom
			(at 0 -0.762)
			(size 0.2159 0.2159)
			(layers "F.Cu" "F.Mask" "F.Paste")
			(net "P3V3_STBY_B")
			(options
				(clearance outline)
				(anchor circle)
			)
			(primitives
				(gr_poly
					(pts
						(arc
							(start -0.3302 -0.4318)
							(mid -0.402042 -0.402042)
							(end -0.4318 -0.3302)
						)
						(arc
							(start -0.4318 0.3302)
							(mid -0.402042 0.402042)
							(end -0.3302 0.4318)
						)
						(arc
							(start 0.3302 0.4318)
							(mid 0.402042 0.402042)
							(end 0.4318 0.3302)
						)
						(arc
							(start 0.4318 -0.3302)
							(mid 0.402042 -0.402042)
							(end 0.3302 -0.4318)
						)
					)
					(width 0)
					(fill yes)
				)
			)
		)
		(pad "2" smd custom
			(at 0 0.762)
			(size 0.2159 0.2159)
			(layers "F.Cu" "F.Mask" "F.Paste")
			(net "GND")
			(options
				(clearance outline)
				(anchor circle)
			)
			(primitives
				(gr_poly
					(pts
						(arc
							(start -0.3302 -0.4318)
							(mid -0.402042 -0.402042)
							(end -0.4318 -0.3302)
						)
						(arc
							(start -0.4318 0.3302)
							(mid -0.402042 0.402042)
							(end -0.3302 0.4318)
						)
						(arc
							(start 0.3302 0.4318)
							(mid 0.402042 0.402042)
							(end 0.4318 0.3302)
						)
						(arc
							(start 0.4318 -0.3302)
							(mid 0.402042 -0.402042)
							(end 0.3302 -0.4318)
						)
					)
					(width 0)
					(fill yes)
				)
			)
		)
	)
	(footprint ""
		(layer "F.Cu")
		(at 377.788932 -283.957522 90)
		(property "Reference" "R580"
			(at 0 0 90)
			(layer "F.SilkS")
			(hide yes)
			(effects
				(font
					(size 1.27 1.27)
				)
			)
		)
		(property "Value" "4K7R2J-2-GP"
			(at 0.064008 -3.993896 90)
			(unlocked yes)
			(layer "F.Fab")
			(hide yes)
			(effects
				(font
					(size 1.016 1.016)
					(thickness 0.1524)
				)
			)
		)
		(property "Device Type" "R402H16"
			(at 0.064008 -5.517896 90)
			(unlocked yes)
			(layer "F.Fab")
			(hide yes)
			(effects
				(font
					(size 1.016 1.016)
					(thickness 0.1524)
				)
			)
		)
		(duplicate_pad_numbers_are_jumpers no)
		(fp_line
			(start 0.508 -0.9398)
			(end -0.508 -0.9398)
			(stroke
				(width 0.1524)
				(type default)
			)
			(layer "F.SilkS")
		)
		(fp_line
			(start -0.508 -0.9398)
			(end -0.508 0.9398)
			(stroke
				(width 0.1524)
				(type default)
			)
			(layer "F.SilkS")
		)
		(fp_rect
			(start -0.508 0.9398)
			(end 0.508 -0.9398)
			(stroke
				(width 0)
				(type default)
			)
			(fill no)
			(layer "F.CrtYd")
		)
		(fp_rect
			(start -0.508 0.9398)
			(end 0.508 -0.9398)
			(stroke
				(width 0)
				(type default)
			)
			(fill no)
			(layer "F.Fab")
		)
		(pad "1" smd custom
			(at 0 -0.4445 90)
			(size 0.1397 0.1397)
			(layers "F.Cu" "F.Mask" "F.Paste")
			(net "DRIVE_B_32_ACT")
			(options
				(clearance outline)
				(anchor circle)
			)
			(primitives
				(gr_poly
					(pts
						(arc
							(start -0.1778 -0.2794)
							(mid -0.249642 -0.249642)
							(end -0.2794 -0.1778)
						)
						(arc
							(start -0.2794 0.1778)
							(mid -0.249642 0.249642)
							(end -0.1778 0.2794)
						)
						(arc
							(start 0.1778 0.2794)
							(mid 0.249642 0.249642)
							(end 0.2794 0.1778)
						)
						(arc
							(start 0.2794 -0.1778)
							(mid 0.249642 -0.249642)
							(end 0.1778 -0.2794)
						)
					)
					(width 0)
					(fill yes)
				)
			)
		)
		(pad "2" smd custom
			(at 0 0.4445 90)
			(size 0.1397 0.1397)
			(layers "F.Cu" "F.Mask" "F.Paste")
			(net "GND")
			(options
				(clearance outline)
				(anchor circle)
			)
			(primitives
				(gr_poly
					(pts
						(arc
							(start -0.1778 -0.2794)
							(mid -0.249642 -0.249642)
							(end -0.2794 -0.1778)
						)
						(arc
							(start -0.2794 0.1778)
							(mid -0.249642 0.249642)
							(end -0.1778 0.2794)
						)
						(arc
							(start 0.1778 0.2794)
							(mid 0.249642 0.249642)
							(end 0.2794 0.1778)
						)
						(arc
							(start 0.2794 -0.1778)
							(mid 0.249642 -0.249642)
							(end 0.1778 -0.2794)
						)
					)
					(width 0)
					(fill yes)
				)
			)
		)
	)
	(footprint ""
		(layer "F.Cu")
		(at 236.601 -395.9098 180)
		(property "Reference" "C584"
			(at 0 0 180)
			(layer "F.SilkS")
			(hide yes)
			(effects
				(font
					(size 1.27 1.27)
				)
			)
		)
		(property "Value" "SCD22U16V2KX-GP"
			(at 1.1811 -2.7051 180)
			(unlocked yes)
			(layer "F.Fab")
			(hide yes)
			(effects
				(font
					(size 1.016 1.016)
					(thickness 0.1524)
				)
			)
		)
		(property "Device Type" "C402H22"
			(at 1.1811 -4.2291 180)
			(unlocked yes)
			(layer "F.Fab")
			(hide yes)
			(effects
				(font
					(size 1.016 1.016)
					(thickness 0.1524)
				)
			)
		)
		(duplicate_pad_numbers_are_jumpers no)
		(fp_rect
			(start -0.4318 0.9525)
			(end 0.4318 -0.9525)
			(stroke
				(width 0)
				(type default)
			)
			(fill no)
			(layer "F.CrtYd")
		)
		(fp_rect
			(start -0.4318 0.9525)
			(end 0.4318 -0.9525)
			(stroke
				(width 0)
				(type default)
			)
			(fill no)
			(layer "F.Fab")
		)
		(pad "1" smd custom
			(at 0 -0.4445 180)
			(size 0.1524 0.1524)
			(layers "F.Cu" "F.Mask" "F.Paste")
			(net "MB3_TIME_R")
			(options
				(clearance outline)
				(anchor circle)
			)
			(primitives
				(gr_poly
					(pts
						(arc
							(start 0.3048 -0.2032)
							(mid 0.275042 -0.275042)
							(end 0.2032 -0.3048)
						)
						(arc
							(start -0.2032 -0.3048)
							(mid -0.275042 -0.275042)
							(end -0.3048 -0.2032)
						)
						(arc
							(start -0.3048 0.2032)
							(mid -0.275042 0.275042)
							(end -0.2032 0.3048)
						)
						(arc
							(start 0.2032 0.3048)
							(mid 0.275042 0.275042)
							(end 0.3048 0.2032)
						)
					)
					(width 0)
					(fill yes)
				)
			)
		)
		(pad "2" smd custom
			(at 0 0.4445 180)
			(size 0.1524 0.1524)
			(layers "F.Cu" "F.Mask" "F.Paste")
			(net "AGND_CURRENT_DPB")
			(options
				(clearance outline)
				(anchor circle)
			)
			(primitives
				(gr_poly
					(pts
						(arc
							(start 0.3048 -0.2032)
							(mid 0.275042 -0.275042)
							(end 0.2032 -0.3048)
						)
						(arc
							(start -0.2032 -0.3048)
							(mid -0.275042 -0.275042)
							(end -0.3048 -0.2032)
						)
						(arc
							(start -0.3048 0.2032)
							(mid -0.275042 0.275042)
							(end -0.2032 0.3048)
						)
						(arc
							(start 0.2032 0.3048)
							(mid 0.275042 0.275042)
							(end 0.3048 0.2032)
						)
					)
					(width 0)
					(fill yes)
				)
			)
		)
	)
	(footprint ""
		(layer "F.Cu")
		(at 174.625 -46.649894 180)
		(property "Reference" "D29"
			(at 0 0 180)
			(layer "F.SilkS")
			(hide yes)
			(effects
				(font
					(size 1.27 1.27)
				)
			)
		)
		(property "Value" "RB551V30-GP"
			(at 0 -6.7818 180)
			(unlocked yes)
			(layer "F.Fab")
			(hide yes)
			(effects
				(font
					(size 1.016 1.016)
					(thickness 0.1524)
				)
			)
		)
		(property "Device Type" "SOD323AKH38"
			(at 0 -8.6868 180)
			(unlocked yes)
			(layer "F.Fab")
			(hide yes)
			(effects
				(font
					(size 1.016 1.016)
					(thickness 0.1524)
				)
			)
		)
		(duplicate_pad_numbers_are_jumpers no)
		(fp_line
			(start 0.889 2.159)
			(end -0.889 2.159)
			(stroke
				(width 0.1524)
				(type default)
			)
			(layer "F.SilkS")
		)
		(fp_line
			(start 0.889 -1.9304)
			(end 0.889 2.159)
			(stroke
				(width 0.1524)
				(type default)
			)
			(layer "F.SilkS")
		)
		(fp_line
			(start 0.762 2.0574)
			(end -0.762 2.0574)
			(stroke
				(width 0.508)
				(type default)
			)
			(layer "F.SilkS")
		)
		(fp_line
			(start -0.889 2.159)
			(end -0.889 -1.9304)
			(stroke
				(width 0.1524)
				(type default)
			)
			(layer "F.SilkS")
		)
		(fp_line
			(start -0.889 -1.9304)
			(end 0.889 -1.9304)
			(stroke
				(width 0.1524)
				(type default)
			)
			(layer "F.SilkS")
		)
		(fp_rect
			(start -1.016 2.3114)
			(end 1.016 -2.0066)
			(stroke
				(width 0)
				(type default)
			)
			(fill no)
			(layer "F.CrtYd")
		)
		(fp_poly
			(pts
				(xy -1.016 -2.0066) (xy 1.016 -2.0066) (xy 1.016 2.3114) (xy -1.016 2.3114)
			)
			(stroke
				(width 0)
				(type default)
			)
			(fill no)
			(layer "F.Fab")
		)
		(pad "A" smd rect
			(at 0 -1.143 180)
			(size 0.5588 1.016)
			(layers "F.Cu" "F.Mask" "F.Paste")
			(net "SW_HDD_R29")
		)
		(pad "K" smd rect
			(at 0 1.143 180)
			(size 0.5588 1.016)
			(layers "F.Cu" "F.Mask" "F.Paste")
			(net "SW_HDD_N29")
		)
	)
	(footprint ""
		(layer "F.Cu")
		(at 135.7249 -127.254)
		(property "Reference" "R300"
			(at 0 0 0)
			(layer "F.SilkS")
			(hide yes)
			(effects
				(font
					(size 1.27 1.27)
				)
			)
		)
		(property "Value" "130R3F-GP"
			(at -0.0254 -2.5146 0)
			(unlocked yes)
			(layer "F.Fab")
			(hide yes)
			(effects
				(font
					(size 1.016 1.016)
					(thickness 0.1524)
				)
			)
		)
		(property "Device Type" "R603H22"
			(at -0.0254 -4.0386 0)
			(unlocked yes)
			(layer "F.Fab")
			(hide yes)
			(effects
				(font
					(size 1.016 1.016)
					(thickness 0.1524)
				)
			)
		)
		(duplicate_pad_numbers_are_jumpers no)
		(fp_line
			(start -0.4826 0)
			(end -0.2032 0)
			(stroke
				(width 0.2032)
				(type default)
			)
			(layer "F.SilkS")
		)
		(fp_line
			(start 0.2032 0)
			(end 0.4826 0)
			(stroke
				(width 0.2032)
				(type default)
			)
			(layer "F.SilkS")
		)
		(fp_rect
			(start -0.5842 1.3335)
			(end 0.5842 -1.3335)
			(stroke
				(width 0)
				(type default)
			)
			(fill no)
			(layer "F.CrtYd")
		)
		(fp_rect
			(start -0.5842 1.3335)
			(end 0.5842 -1.3335)
			(stroke
				(width 0)
				(type default)
			)
			(fill no)
			(layer "F.Fab")
		)
		(pad "1" smd custom
			(at 0 -0.762)
			(size 0.2159 0.2159)
			(layers "F.Cu" "F.Mask" "F.Paste")
			(net "P5V_A_2")
			(options
				(clearance outline)
				(anchor circle)
			)
			(primitives
				(gr_poly
					(pts
						(arc
							(start -0.3302 -0.4318)
							(mid -0.402042 -0.402042)
							(end -0.4318 -0.3302)
						)
						(arc
							(start -0.4318 0.3302)
							(mid -0.402042 0.402042)
							(end -0.3302 0.4318)
						)
						(arc
							(start 0.3302 0.4318)
							(mid 0.402042 0.402042)
							(end 0.4318 0.3302)
						)
						(arc
							(start 0.4318 -0.3302)
							(mid 0.402042 -0.402042)
							(end 0.3302 -0.4318)
						)
					)
					(width 0)
					(fill yes)
				)
			)
		)
		(pad "2" smd custom
			(at 0 0.762)
			(size 0.2159 0.2159)
			(layers "F.Cu" "F.Mask" "F.Paste")
			(net "FLT_HDD16")
			(options
				(clearance outline)
				(anchor circle)
			)
			(primitives
				(gr_poly
					(pts
						(arc
							(start -0.3302 -0.4318)
							(mid -0.402042 -0.402042)
							(end -0.4318 -0.3302)
						)
						(arc
							(start -0.4318 0.3302)
							(mid -0.402042 0.402042)
							(end -0.3302 0.4318)
						)
						(arc
							(start 0.3302 0.4318)
							(mid 0.402042 0.402042)
							(end 0.4318 0.3302)
						)
						(arc
							(start 0.4318 -0.3302)
							(mid 0.402042 -0.402042)
							(end 0.3302 -0.4318)
						)
					)
					(width 0)
					(fill yes)
				)
			)
		)
	)
	(footprint ""
		(layer "F.Cu")
		(at 280.055066 20.945348 -90)
		(property "Reference" "R1135"
			(at 0 0 270)
			(layer "F.SilkS")
			(hide yes)
			(effects
				(font
					(size 1.27 1.27)
				)
			)
		)
		(property "Value" "750R2F-GP"
			(at 0.064008 -3.993896 270)
			(unlocked yes)
			(layer "F.Fab")
			(hide yes)
			(effects
				(font
					(size 1.016 1.016)
					(thickness 0.1524)
				)
			)
		)
		(property "Device Type" "R402H16"
			(at 0.064008 -5.517896 270)
			(unlocked yes)
			(layer "F.Fab")
			(hide yes)
			(effects
				(font
					(size 1.016 1.016)
					(thickness 0.1524)
				)
			)
		)
		(duplicate_pad_numbers_are_jumpers no)
		(fp_line
			(start -0.508 -0.9398)
			(end -0.508 0.9398)
			(stroke
				(width 0.1524)
				(type default)
			)
			(layer "F.SilkS")
		)
		(fp_line
			(start 0.508 -0.9398)
			(end -0.508 -0.9398)
			(stroke
				(width 0.1524)
				(type default)
			)
			(layer "F.SilkS")
		)
		(fp_rect
			(start -0.508 0.9398)
			(end 0.508 -0.9398)
			(stroke
				(width 0)
				(type default)
			)
			(fill no)
			(layer "F.CrtYd")
		)
		(fp_rect
			(start -0.508 0.9398)
			(end 0.508 -0.9398)
			(stroke
				(width 0)
				(type default)
			)
			(fill no)
			(layer "F.Fab")
		)
		(pad "1" smd custom
			(at 0 -0.4445 270)
			(size 0.1397 0.1397)
			(layers "F.Cu" "F.Mask" "F.Paste")
			(net "DPB_PWR_BTN_A")
			(options
				(clearance outline)
				(anchor circle)
			)
			(primitives
				(gr_poly
					(pts
						(arc
							(start -0.1778 -0.2794)
							(mid -0.249642 -0.249642)
							(end -0.2794 -0.1778)
						)
						(arc
							(start -0.2794 0.1778)
							(mid -0.249642 0.249642)
							(end -0.1778 0.2794)
						)
						(arc
							(start 0.1778 0.2794)
							(mid 0.249642 0.249642)
							(end 0.2794 0.1778)
						)
						(arc
							(start 0.2794 -0.1778)
							(mid 0.249642 -0.249642)
							(end 0.1778 -0.2794)
						)
					)
					(width 0)
					(fill yes)
				)
			)
		)
		(pad "2" smd custom
			(at 0 0.4445 270)
			(size 0.1397 0.1397)
			(layers "F.Cu" "F.Mask" "F.Paste")
			(net "GND")
			(options
				(clearance outline)
				(anchor circle)
			)
			(primitives
				(gr_poly
					(pts
						(arc
							(start -0.1778 -0.2794)
							(mid -0.249642 -0.249642)
							(end -0.2794 -0.1778)
						)
						(arc
							(start -0.2794 0.1778)
							(mid -0.249642 0.249642)
							(end -0.1778 0.2794)
						)
						(arc
							(start 0.1778 0.2794)
							(mid 0.249642 0.249642)
							(end 0.2794 0.1778)
						)
						(arc
							(start 0.2794 -0.1778)
							(mid 0.249642 -0.249642)
							(end 0.1778 -0.2794)
						)
					)
					(width 0)
					(fill yes)
				)
			)
		)
	)
	(footprint ""
		(layer "F.Cu")
		(at 396.72895 -168.380918 -90)
		(property "Reference" "Q119"
			(at 0 0 270)
			(layer "F.SilkS")
			(hide yes)
			(effects
				(font
					(size 1.27 1.27)
				)
			)
		)
		(property "Value" "AO4406AL-GP"
			(at -3.707384 -1.5367 270)
			(unlocked yes)
			(layer "F.Fab")
			(hide yes)
			(effects
				(font
					(size 1.016 1.016)
					(thickness 0.1524)
				)
			)
		)
		(property "Device Type" "SOIC8H69"
			(at -3.707384 -3.0607 270)
			(unlocked yes)
			(layer "F.Fab")
			(hide yes)
			(effects
				(font
					(size 1.016 1.016)
					(thickness 0.1524)
				)
			)
		)
		(duplicate_pad_numbers_are_jumpers no)
		(fp_line
			(start -2.6289 3.4417)
			(end -2.6289 1.4732)
			(stroke
				(width 0.381)
				(type default)
			)
			(layer "F.SilkS")
		)
		(fp_line
			(start -2.7432 1.4224)
			(end -2.6416 1.4224)
			(stroke
				(width 0.1524)
				(type default)
			)
			(layer "F.SilkS")
		)
		(fp_line
			(start -2.7432 1.4224)
			(end 2.1336 1.4224)
			(stroke
				(width 0.1524)
				(type default)
			)
			(layer "F.SilkS")
		)
		(fp_line
			(start 2.1336 1.4224)
			(end 2.1336 -1.4224)
			(stroke
				(width 0.1524)
				(type default)
			)
			(layer "F.SilkS")
		)
		(fp_line
			(start -2.1844 -0.0508)
			(end -2.7178 0.508)
			(stroke
				(width 0.1524)
				(type default)
			)
			(layer "F.SilkS")
		)
		(fp_line
			(start -2.7178 -0.508)
			(end -2.1844 -0.0508)
			(stroke
				(width 0.1524)
				(type default)
			)
			(layer "F.SilkS")
		)
		(fp_line
			(start -2.7432 -1.4224)
			(end -2.7432 1.4224)
			(stroke
				(width 0.1524)
				(type default)
			)
			(layer "F.SilkS")
		)
		(fp_line
			(start 2.1336 -1.4224)
			(end -2.7432 -1.4224)
			(stroke
				(width 0.1524)
				(type default)
			)
			(layer "F.SilkS")
		)
		(fp_poly
			(pts
				(xy -2.2098 -1.4224) (xy -2.2098 1.4224) (xy 2.2098 1.4224) (xy 2.2098 -1.4224)
			)
			(stroke
				(width 0)
				(type default)
			)
			(fill yes)
			(layer "F.SilkS")
		)
		(fp_rect
			(start -2.450084 2.999994)
			(end 2.450084 -2.999994)
			(stroke
				(width 0)
				(type default)
			)
			(fill no)
			(layer "F.CrtYd")
		)
		(fp_poly
			(pts
				(xy -2.8194 3.6322) (xy -2.8194 -3.6322) (xy 2.8194 -3.6322) (xy 2.8194 1.18364) (xy 2.450084 1.18364)
				(xy 2.450084 -2.999994) (xy -2.450084 -2.999994) (xy -2.450084 2.999994) (xy 2.450084 2.999994)
				(xy 2.450084 1.18618) (xy 2.8194 1.18618) (xy 2.8194 3.6322)
			)
			(stroke
				(width 0)
				(type default)
			)
			(fill no)
			(layer "F.CrtYd")
		)
		(fp_rect
			(start -2.8194 3.6322)
			(end 2.8194 -3.6322)
			(stroke
				(width 0)
				(type default)
			)
			(fill no)
			(layer "F.Fab")
		)
		(pad "1" smd rect
			(at -1.905 2.54 270)
			(size 0.635 1.651)
			(layers "F.Cu" "F.Mask" "F.Paste")
			(net "P5V_HDD20")
		)
		(pad "2" smd rect
			(at -0.635 2.54 270)
			(size 0.635 1.651)
			(layers "F.Cu" "F.Mask" "F.Paste")
			(net "P5V_HDD20")
		)
		(pad "3" smd rect
			(at 0.635 2.54 270)
			(size 0.635 1.651)
			(layers "F.Cu" "F.Mask" "F.Paste")
			(net "P5V_HDD20")
		)
		(pad "4" smd rect
			(at 1.905 2.54 270)
			(size 0.635 1.651)
			(layers "F.Cu" "F.Mask" "F.Paste")
			(net "SW_HDD_P20")
		)
		(pad "5" smd rect
			(at 1.905 -2.54 270)
			(size 0.635 1.651)
			(layers "F.Cu" "F.Mask" "F.Paste")
			(net "P5V_A_3")
		)
		(pad "6" smd rect
			(at 0.635 -2.54 270)
			(size 0.635 1.651)
			(layers "F.Cu" "F.Mask" "F.Paste")
			(net "P5V_A_3")
		)
		(pad "7" smd rect
			(at -0.635 -2.54 270)
			(size 0.635 1.651)
			(layers "F.Cu" "F.Mask" "F.Paste")
			(net "P5V_A_3")
		)
		(pad "8" smd rect
			(at -1.905 -2.54 270)
			(size 0.635 1.651)
			(layers "F.Cu" "F.Mask" "F.Paste")
			(net "P5V_A_3")
		)
	)
	(footprint ""
		(layer "F.Cu")
		(at 276.6822 18.727928)
		(property "Reference" "Q3"
			(at 0 0 0)
			(layer "F.SilkS")
			(hide yes)
			(effects
				(font
					(size 1.27 1.27)
				)
			)
		)
		(property "Value" "2N7002KDW-GP"
			(at -2.3622 -8.2042 0)
			(unlocked yes)
			(layer "F.Fab")
			(hide yes)
			(effects
				(font
					(size 1.016 1.016)
					(thickness 0.1524)
				)
			)
		)
		(property "Device Type" "SOT-363H44"
			(at -2.3622 -10.1092 0)
			(unlocked yes)
			(layer "F.Fab")
			(hide yes)
			(effects
				(font
					(size 1.016 1.016)
					(thickness 0.1524)
				)
			)
		)
		(duplicate_pad_numbers_are_jumpers no)
		(fp_line
			(start -1.4478 -1.7018)
			(end -1.4478 1.7018)
			(stroke
				(width 0.1524)
				(type default)
			)
			(layer "F.SilkS")
		)
		(fp_line
			(start -1.4478 1.7018)
			(end 1.4478 1.7018)
			(stroke
				(width 0.1524)
				(type default)
			)
			(layer "F.SilkS")
		)
		(fp_line
			(start -1.27 1.524)
			(end -1.27 0.6604)
			(stroke
				(width 0.4826)
				(type default)
			)
			(layer "F.SilkS")
		)
		(fp_line
			(start 1.4478 -1.7018)
			(end -1.4478 -1.7018)
			(stroke
				(width 0.1524)
				(type default)
			)
			(layer "F.SilkS")
		)
		(fp_line
			(start 1.4478 1.7018)
			(end 1.4478 -1.7018)
			(stroke
				(width 0.1524)
				(type default)
			)
			(layer "F.SilkS")
		)
		(fp_poly
			(pts
				(xy -1.524 -1.778) (xy 1.524 -1.778) (xy 1.524 1.778) (xy -1.524 1.778)
			)
			(stroke
				(width 0)
				(type default)
			)
			(fill no)
			(layer "F.CrtYd")
		)
		(fp_poly
			(pts
				(xy -1.524 -1.778) (xy 1.524 -1.778) (xy 1.524 1.778) (xy -1.524 1.778)
			)
			(stroke
				(width 0)
				(type default)
			)
			(fill no)
			(layer "F.Fab")
		)
		(pad "1" smd rect
			(at -0.65024 0.9398)
			(size 0.4064 1.016)
			(layers "F.Cu" "F.Mask" "F.Paste")
			(net "GND")
		)
		(pad "2" smd rect
			(at 0 0.9398)
			(size 0.4064 1.016)
			(layers "F.Cu" "F.Mask" "F.Paste")
			(net "SCC_B_PWR_LED")
		)
		(pad "3" smd rect
			(at 0.65024 0.9398)
			(size 0.4064 1.016)
			(layers "F.Cu" "F.Mask" "F.Paste")
			(net "SYS_PWR_LED_B")
		)
		(pad "4" smd rect
			(at 0.65024 -0.9398)
			(size 0.4064 1.016)
			(layers "F.Cu" "F.Mask" "F.Paste")
			(net "GND")
		)
		(pad "5" smd rect
			(at 0 -0.9398)
			(size 0.4064 1.016)
			(layers "F.Cu" "F.Mask" "F.Paste")
			(net "IOM_B_PWR_LED")
		)
		(pad "6" smd rect
			(at -0.65024 -0.9398)
			(size 0.4064 1.016)
			(layers "F.Cu" "F.Mask" "F.Paste")
			(net "SYS_PWR_LED_B")
		)
	)
	(footprint ""
		(layer "F.Cu")
		(at 332.105 -275.252942 -90)
		(property "Reference" "Q37"
			(at 0 0 270)
			(layer "F.SilkS")
			(hide yes)
			(effects
				(font
					(size 1.27 1.27)
				)
			)
		)
		(property "Value" "2N7002KDW-GP"
			(at -2.3622 -8.2042 270)
			(unlocked yes)
			(layer "F.Fab")
			(hide yes)
			(effects
				(font
					(size 1.016 1.016)
					(thickness 0.1524)
				)
			)
		)
		(property "Device Type" "SOT-363H44"
			(at -2.3622 -10.1092 270)
			(unlocked yes)
			(layer "F.Fab")
			(hide yes)
			(effects
				(font
					(size 1.016 1.016)
					(thickness 0.1524)
				)
			)
		)
		(duplicate_pad_numbers_are_jumpers no)
		(fp_line
			(start -1.4478 1.7018)
			(end 1.4478 1.7018)
			(stroke
				(width 0.1524)
				(type default)
			)
			(layer "F.SilkS")
		)
		(fp_line
			(start 1.4478 1.7018)
			(end 1.4478 -1.7018)
			(stroke
				(width 0.1524)
				(type default)
			)
			(layer "F.SilkS")
		)
		(fp_line
			(start -1.27 1.524)
			(end -1.27 0.6604)
			(stroke
				(width 0.4826)
				(type default)
			)
			(layer "F.SilkS")
		)
		(fp_line
			(start -1.4478 -1.7018)
			(end -1.4478 1.7018)
			(stroke
				(width 0.1524)
				(type default)
			)
			(layer "F.SilkS")
		)
		(fp_line
			(start 1.4478 -1.7018)
			(end -1.4478 -1.7018)
			(stroke
				(width 0.1524)
				(type default)
			)
			(layer "F.SilkS")
		)
		(fp_poly
			(pts
				(xy -1.524 -1.778) (xy 1.524 -1.778) (xy 1.524 1.778) (xy -1.524 1.778)
			)
			(stroke
				(width 0)
				(type default)
			)
			(fill no)
			(layer "F.CrtYd")
		)
		(fp_poly
			(pts
				(xy -1.524 -1.778) (xy 1.524 -1.778) (xy 1.524 1.778) (xy -1.524 1.778)
			)
			(stroke
				(width 0)
				(type default)
			)
			(fill no)
			(layer "F.Fab")
		)
		(pad "1" smd rect
			(at -0.65024 0.9398 270)
			(size 0.4064 1.016)
			(layers "F.Cu" "F.Mask" "F.Paste")
			(net "GND")
		)
		(pad "2" smd rect
			(at 0 0.9398 270)
			(size 0.4064 1.016)
			(layers "F.Cu" "F.Mask" "F.Paste")
			(net "SW_PWR_R_HDD6")
		)
		(pad "3" smd rect
			(at 0.65024 0.9398 270)
			(size 0.4064 1.016)
			(layers "F.Cu" "F.Mask" "F.Paste")
			(net "SW_HDD_P6")
		)
		(pad "4" smd rect
			(at 0.65024 -0.9398 270)
			(size 0.4064 1.016)
			(layers "F.Cu" "F.Mask" "F.Paste")
			(net "GND")
		)
		(pad "5" smd rect
			(at 0 -0.9398 270)
			(size 0.4064 1.016)
			(layers "F.Cu" "F.Mask" "F.Paste")
			(net "SW_HDD_G6")
		)
		(pad "6" smd rect
			(at -0.65024 -0.9398 270)
			(size 0.4064 1.016)
			(layers "F.Cu" "F.Mask" "F.Paste")
			(net "SW_HDD_R6")
		)
	)
	(footprint ""
		(layer "F.Cu")
		(at 329.819 -74.335894 180)
		(property "Reference" "C437"
			(at 0 0 180)
			(layer "F.SilkS")
			(hide yes)
			(effects
				(font
					(size 1.27 1.27)
				)
			)
		)
		(property "Value" "SC1U25V3KX-GP"
			(at 0 -2.8194 180)
			(unlocked yes)
			(layer "F.Fab")
			(hide yes)
			(effects
				(font
					(size 1.016 1.016)
					(thickness 0.1524)
				)
			)
		)
		(property "Device Type" "C603H36"
			(at 0 -4.3434 180)
			(unlocked yes)
			(layer "F.Fab")
			(hide yes)
			(effects
				(font
					(size 1.016 1.016)
					(thickness 0.1524)
				)
			)
		)
		(duplicate_pad_numbers_are_jumpers no)
		(fp_line
			(start 0.508 0)
			(end -0.508 0)
			(stroke
				(width 0.2032)
				(type default)
			)
			(layer "F.SilkS")
		)
		(fp_rect
			(start -0.5842 1.3335)
			(end 0.5842 -1.3335)
			(stroke
				(width 0)
				(type default)
			)
			(fill no)
			(layer "F.CrtYd")
		)
		(fp_rect
			(start -0.5842 1.3335)
			(end 0.5842 -1.3335)
			(stroke
				(width 0)
				(type default)
			)
			(fill no)
			(layer "F.Fab")
		)
		(pad "1" smd custom
			(at 0 -0.762 180)
			(size 0.2159 0.2159)
			(layers "F.Cu" "F.Mask" "F.Paste")
			(net "P12V_HDD30")
			(options
				(clearance outline)
				(anchor circle)
			)
			(primitives
				(gr_poly
					(pts
						(arc
							(start -0.3302 -0.4318)
							(mid -0.402042 -0.402042)
							(end -0.4318 -0.3302)
						)
						(arc
							(start -0.4318 0.3302)
							(mid -0.402042 0.402042)
							(end -0.3302 0.4318)
						)
						(arc
							(start 0.3302 0.4318)
							(mid 0.402042 0.402042)
							(end 0.4318 0.3302)
						)
						(arc
							(start 0.4318 -0.3302)
							(mid 0.402042 -0.402042)
							(end 0.3302 -0.4318)
						)
					)
					(width 0)
					(fill yes)
				)
			)
		)
		(pad "2" smd custom
			(at 0 0.762 180)
			(size 0.2159 0.2159)
			(layers "F.Cu" "F.Mask" "F.Paste")
			(net "GND")
			(options
				(clearance outline)
				(anchor circle)
			)
			(primitives
				(gr_poly
					(pts
						(arc
							(start -0.3302 -0.4318)
							(mid -0.402042 -0.402042)
							(end -0.4318 -0.3302)
						)
						(arc
							(start -0.4318 0.3302)
							(mid -0.402042 0.402042)
							(end -0.3302 0.4318)
						)
						(arc
							(start 0.3302 0.4318)
							(mid 0.402042 0.402042)
							(end 0.4318 0.3302)
						)
						(arc
							(start 0.4318 -0.3302)
							(mid 0.402042 -0.402042)
							(end 0.3302 -0.4318)
						)
					)
					(width 0)
					(fill yes)
				)
			)
		)
	)
	(footprint ""
		(layer "F.Cu")
		(at 466.3948 -288.26968 180)
		(property "Reference" "R599"
			(at 0 0 180)
			(layer "F.SilkS")
			(hide yes)
			(effects
				(font
					(size 1.27 1.27)
				)
			)
		)
		(property "Value" "4K7R2J-2-GP"
			(at 0.064008 -3.993896 180)
			(unlocked yes)
			(layer "F.Fab")
			(hide yes)
			(effects
				(font
					(size 1.016 1.016)
					(thickness 0.1524)
				)
			)
		)
		(property "Device Type" "R402H16"
			(at 0.064008 -5.517896 180)
			(unlocked yes)
			(layer "F.Fab")
			(hide yes)
			(effects
				(font
					(size 1.016 1.016)
					(thickness 0.1524)
				)
			)
		)
		(duplicate_pad_numbers_are_jumpers no)
		(fp_line
			(start 0.508 -0.9398)
			(end -0.508 -0.9398)
			(stroke
				(width 0.1524)
				(type default)
			)
			(layer "F.SilkS")
		)
		(fp_line
			(start -0.508 -0.9398)
			(end -0.508 0.9398)
			(stroke
				(width 0.1524)
				(type default)
			)
			(layer "F.SilkS")
		)
		(fp_rect
			(start -0.508 0.9398)
			(end 0.508 -0.9398)
			(stroke
				(width 0)
				(type default)
			)
			(fill no)
			(layer "F.CrtYd")
		)
		(fp_rect
			(start -0.508 0.9398)
			(end 0.508 -0.9398)
			(stroke
				(width 0)
				(type default)
			)
			(fill no)
			(layer "F.Fab")
		)
		(pad "1" smd custom
			(at 0 -0.4445 180)
			(size 0.1397 0.1397)
			(layers "F.Cu" "F.Mask" "F.Paste")
			(net "DRIVE_B_35_ACT")
			(options
				(clearance outline)
				(anchor circle)
			)
			(primitives
				(gr_poly
					(pts
						(arc
							(start -0.1778 -0.2794)
							(mid -0.249642 -0.249642)
							(end -0.2794 -0.1778)
						)
						(arc
							(start -0.2794 0.1778)
							(mid -0.249642 0.249642)
							(end -0.1778 0.2794)
						)
						(arc
							(start 0.1778 0.2794)
							(mid 0.249642 0.249642)
							(end 0.2794 0.1778)
						)
						(arc
							(start 0.2794 -0.1778)
							(mid 0.249642 -0.249642)
							(end 0.1778 -0.2794)
						)
					)
					(width 0)
					(fill yes)
				)
			)
		)
		(pad "2" smd custom
			(at 0 0.4445 180)
			(size 0.1397 0.1397)
			(layers "F.Cu" "F.Mask" "F.Paste")
			(net "GND")
			(options
				(clearance outline)
				(anchor circle)
			)
			(primitives
				(gr_poly
					(pts
						(arc
							(start -0.1778 -0.2794)
							(mid -0.249642 -0.249642)
							(end -0.2794 -0.1778)
						)
						(arc
							(start -0.2794 0.1778)
							(mid -0.249642 0.249642)
							(end -0.1778 0.2794)
						)
						(arc
							(start 0.1778 0.2794)
							(mid 0.249642 0.249642)
							(end 0.2794 0.1778)
						)
						(arc
							(start 0.2794 -0.1778)
							(mid 0.249642 -0.249642)
							(end 0.1778 -0.2794)
						)
					)
					(width 0)
					(fill yes)
				)
			)
		)
	)
	(footprint ""
		(layer "F.Cu")
		(at 223.843342 -207.290162 90)
		(property "Reference" "R416"
			(at 0 0 90)
			(layer "F.SilkS")
			(hide yes)
			(effects
				(font
					(size 1.27 1.27)
				)
			)
		)
		(property "Value" "0R2J-2-GP"
			(at 0.064008 -3.993896 90)
			(unlocked yes)
			(layer "F.Fab")
			(hide yes)
			(effects
				(font
					(size 1.016 1.016)
					(thickness 0.1524)
				)
			)
		)
		(property "Device Type" "R402H16"
			(at 0.064008 -5.517896 90)
			(unlocked yes)
			(layer "F.Fab")
			(hide yes)
			(effects
				(font
					(size 1.016 1.016)
					(thickness 0.1524)
				)
			)
		)
		(duplicate_pad_numbers_are_jumpers no)
		(fp_line
			(start 0.508 -0.9398)
			(end -0.508 -0.9398)
			(stroke
				(width 0.1524)
				(type default)
			)
			(layer "F.SilkS")
		)
		(fp_line
			(start -0.508 -0.9398)
			(end -0.508 0.9398)
			(stroke
				(width 0.1524)
				(type default)
			)
			(layer "F.SilkS")
		)
		(fp_rect
			(start -0.508 0.9398)
			(end 0.508 -0.9398)
			(stroke
				(width 0)
				(type default)
			)
			(fill no)
			(layer "F.CrtYd")
		)
		(fp_rect
			(start -0.508 0.9398)
			(end 0.508 -0.9398)
			(stroke
				(width 0)
				(type default)
			)
			(fill no)
			(layer "F.Fab")
		)
		(pad "1" smd custom
			(at 0 -0.4445 90)
			(size 0.1397 0.1397)
			(layers "F.Cu" "F.Mask" "F.Paste")
			(net "I2C_SCC_A_SCL_BUF")
			(options
				(clearance outline)
				(anchor circle)
			)
			(primitives
				(gr_poly
					(pts
						(arc
							(start -0.1778 -0.2794)
							(mid -0.249642 -0.249642)
							(end -0.2794 -0.1778)
						)
						(arc
							(start -0.2794 0.1778)
							(mid -0.249642 0.249642)
							(end -0.1778 0.2794)
						)
						(arc
							(start 0.1778 0.2794)
							(mid 0.249642 0.249642)
							(end 0.2794 0.1778)
						)
						(arc
							(start 0.2794 -0.1778)
							(mid 0.249642 -0.249642)
							(end 0.1778 -0.2794)
						)
					)
					(width 0)
					(fill yes)
				)
			)
		)
		(pad "2" smd custom
			(at 0 0.4445 90)
			(size 0.1397 0.1397)
			(layers "F.Cu" "F.Mask" "F.Paste")
			(net "I2C_SCC_A_SCL")
			(options
				(clearance outline)
				(anchor circle)
			)
			(primitives
				(gr_poly
					(pts
						(arc
							(start -0.1778 -0.2794)
							(mid -0.249642 -0.249642)
							(end -0.2794 -0.1778)
						)
						(arc
							(start -0.2794 0.1778)
							(mid -0.249642 0.249642)
							(end -0.1778 0.2794)
						)
						(arc
							(start 0.1778 0.2794)
							(mid 0.249642 0.249642)
							(end 0.2794 0.1778)
						)
						(arc
							(start 0.2794 -0.1778)
							(mid 0.249642 -0.249642)
							(end 0.1778 -0.2794)
						)
					)
					(width 0)
					(fill yes)
				)
			)
		)
	)
	(footprint ""
		(layer "F.Cu")
		(at 332.74 -163.554918 -90)
		(property "Reference" "R551"
			(at 0 0 270)
			(layer "F.SilkS")
			(hide yes)
			(effects
				(font
					(size 1.27 1.27)
				)
			)
		)
		(property "Value" "4K7R2J-2-GP"
			(at 0.064008 -3.993896 270)
			(unlocked yes)
			(layer "F.Fab")
			(hide yes)
			(effects
				(font
					(size 1.016 1.016)
					(thickness 0.1524)
				)
			)
		)
		(property "Device Type" "R402H16"
			(at 0.064008 -5.517896 270)
			(unlocked yes)
			(layer "F.Fab")
			(hide yes)
			(effects
				(font
					(size 1.016 1.016)
					(thickness 0.1524)
				)
			)
		)
		(duplicate_pad_numbers_are_jumpers no)
		(fp_line
			(start -0.508 -0.9398)
			(end -0.508 0.9398)
			(stroke
				(width 0.1524)
				(type default)
			)
			(layer "F.SilkS")
		)
		(fp_line
			(start 0.508 -0.9398)
			(end -0.508 -0.9398)
			(stroke
				(width 0.1524)
				(type default)
			)
			(layer "F.SilkS")
		)
		(fp_rect
			(start -0.508 0.9398)
			(end 0.508 -0.9398)
			(stroke
				(width 0)
				(type default)
			)
			(fill no)
			(layer "F.CrtYd")
		)
		(fp_rect
			(start -0.508 0.9398)
			(end 0.508 -0.9398)
			(stroke
				(width 0)
				(type default)
			)
			(fill no)
			(layer "F.Fab")
		)
		(pad "1" smd custom
			(at 0 -0.4445 270)
			(size 0.1397 0.1397)
			(layers "F.Cu" "F.Mask" "F.Paste")
			(net "P12V_A")
			(options
				(clearance outline)
				(anchor circle)
			)
			(primitives
				(gr_poly
					(pts
						(arc
							(start -0.1778 -0.2794)
							(mid -0.249642 -0.249642)
							(end -0.2794 -0.1778)
						)
						(arc
							(start -0.2794 0.1778)
							(mid -0.249642 0.249642)
							(end -0.1778 0.2794)
						)
						(arc
							(start 0.1778 0.2794)
							(mid 0.249642 0.249642)
							(end 0.2794 0.1778)
						)
						(arc
							(start 0.2794 -0.1778)
							(mid 0.249642 -0.249642)
							(end 0.1778 -0.2794)
						)
					)
					(width 0)
					(fill yes)
				)
			)
		)
		(pad "2" smd custom
			(at 0 0.4445 270)
			(size 0.1397 0.1397)
			(layers "F.Cu" "F.Mask" "F.Paste")
			(net "SW_HDD_P18")
			(options
				(clearance outline)
				(anchor circle)
			)
			(primitives
				(gr_poly
					(pts
						(arc
							(start -0.1778 -0.2794)
							(mid -0.249642 -0.249642)
							(end -0.2794 -0.1778)
						)
						(arc
							(start -0.2794 0.1778)
							(mid -0.249642 0.249642)
							(end -0.1778 0.2794)
						)
						(arc
							(start 0.1778 0.2794)
							(mid 0.249642 0.249642)
							(end 0.2794 0.1778)
						)
						(arc
							(start 0.2794 -0.1778)
							(mid 0.249642 -0.249642)
							(end 0.1778 -0.2794)
						)
					)
					(width 0)
					(fill yes)
				)
			)
		)
	)
	(footprint ""
		(layer "F.Cu")
		(at 11.647678 -130.306064 -90)
		(property "Reference" "R501"
			(at 0 0 270)
			(layer "F.SilkS")
			(hide yes)
			(effects
				(font
					(size 1.27 1.27)
				)
			)
		)
		(property "Value" "4K7R2J-2-GP"
			(at 0.064008 -3.993896 270)
			(unlocked yes)
			(layer "F.Fab")
			(hide yes)
			(effects
				(font
					(size 1.016 1.016)
					(thickness 0.1524)
				)
			)
		)
		(property "Device Type" "R402H16"
			(at 0.064008 -5.517896 270)
			(unlocked yes)
			(layer "F.Fab")
			(hide yes)
			(effects
				(font
					(size 1.016 1.016)
					(thickness 0.1524)
				)
			)
		)
		(duplicate_pad_numbers_are_jumpers no)
		(fp_line
			(start -0.508 -0.9398)
			(end -0.508 0.9398)
			(stroke
				(width 0.1524)
				(type default)
			)
			(layer "F.SilkS")
		)
		(fp_line
			(start 0.508 -0.9398)
			(end -0.508 -0.9398)
			(stroke
				(width 0.1524)
				(type default)
			)
			(layer "F.SilkS")
		)
		(fp_rect
			(start -0.508 0.9398)
			(end 0.508 -0.9398)
			(stroke
				(width 0)
				(type default)
			)
			(fill no)
			(layer "F.CrtYd")
		)
		(fp_rect
			(start -0.508 0.9398)
			(end 0.508 -0.9398)
			(stroke
				(width 0)
				(type default)
			)
			(fill no)
			(layer "F.Fab")
		)
		(pad "1" smd custom
			(at 0 -0.4445 270)
			(size 0.1397 0.1397)
			(layers "F.Cu" "F.Mask" "F.Paste")
			(net "DRIVE_A_12_ACT")
			(options
				(clearance outline)
				(anchor circle)
			)
			(primitives
				(gr_poly
					(pts
						(arc
							(start -0.1778 -0.2794)
							(mid -0.249642 -0.249642)
							(end -0.2794 -0.1778)
						)
						(arc
							(start -0.2794 0.1778)
							(mid -0.249642 0.249642)
							(end -0.1778 0.2794)
						)
						(arc
							(start 0.1778 0.2794)
							(mid 0.249642 0.249642)
							(end 0.2794 0.1778)
						)
						(arc
							(start 0.2794 -0.1778)
							(mid 0.249642 -0.249642)
							(end 0.1778 -0.2794)
						)
					)
					(width 0)
					(fill yes)
				)
			)
		)
		(pad "2" smd custom
			(at 0 0.4445 270)
			(size 0.1397 0.1397)
			(layers "F.Cu" "F.Mask" "F.Paste")
			(net "GND")
			(options
				(clearance outline)
				(anchor circle)
			)
			(primitives
				(gr_poly
					(pts
						(arc
							(start -0.1778 -0.2794)
							(mid -0.249642 -0.249642)
							(end -0.2794 -0.1778)
						)
						(arc
							(start -0.2794 0.1778)
							(mid -0.249642 0.249642)
							(end -0.1778 0.2794)
						)
						(arc
							(start 0.1778 0.2794)
							(mid 0.249642 0.249642)
							(end 0.2794 0.1778)
						)
						(arc
							(start 0.2794 -0.1778)
							(mid 0.249642 -0.249642)
							(end 0.1778 -0.2794)
						)
					)
					(width 0)
					(fill yes)
				)
			)
		)
	)
	(footprint ""
		(layer "F.Cu")
		(at 376.412252 -128.21158 180)
		(property "Reference" "R539"
			(at 0 0 180)
			(layer "F.SilkS")
			(hide yes)
			(effects
				(font
					(size 1.27 1.27)
				)
			)
		)
		(property "Value" "4K7R2J-2-GP"
			(at 0.064008 -3.993896 180)
			(unlocked yes)
			(layer "F.Fab")
			(hide yes)
			(effects
				(font
					(size 1.016 1.016)
					(thickness 0.1524)
				)
			)
		)
		(property "Device Type" "R402H16"
			(at 0.064008 -5.517896 180)
			(unlocked yes)
			(layer "F.Fab")
			(hide yes)
			(effects
				(font
					(size 1.016 1.016)
					(thickness 0.1524)
				)
			)
		)
		(duplicate_pad_numbers_are_jumpers no)
		(fp_line
			(start 0.508 -0.9398)
			(end -0.508 -0.9398)
			(stroke
				(width 0.1524)
				(type default)
			)
			(layer "F.SilkS")
		)
		(fp_line
			(start -0.508 -0.9398)
			(end -0.508 0.9398)
			(stroke
				(width 0.1524)
				(type default)
			)
			(layer "F.SilkS")
		)
		(fp_rect
			(start -0.508 0.9398)
			(end 0.508 -0.9398)
			(stroke
				(width 0)
				(type default)
			)
			(fill no)
			(layer "F.CrtYd")
		)
		(fp_rect
			(start -0.508 0.9398)
			(end 0.508 -0.9398)
			(stroke
				(width 0)
				(type default)
			)
			(fill no)
			(layer "F.Fab")
		)
		(pad "1" smd custom
			(at 0 -0.4445 180)
			(size 0.1397 0.1397)
			(layers "F.Cu" "F.Mask" "F.Paste")
			(net "DRIVE_A_20_FLT_LED")
			(options
				(clearance outline)
				(anchor circle)
			)
			(primitives
				(gr_poly
					(pts
						(arc
							(start -0.1778 -0.2794)
							(mid -0.249642 -0.249642)
							(end -0.2794 -0.1778)
						)
						(arc
							(start -0.2794 0.1778)
							(mid -0.249642 0.249642)
							(end -0.1778 0.2794)
						)
						(arc
							(start 0.1778 0.2794)
							(mid 0.249642 0.249642)
							(end 0.2794 0.1778)
						)
						(arc
							(start 0.2794 -0.1778)
							(mid 0.249642 -0.249642)
							(end 0.1778 -0.2794)
						)
					)
					(width 0)
					(fill yes)
				)
			)
		)
		(pad "2" smd custom
			(at 0 0.4445 180)
			(size 0.1397 0.1397)
			(layers "F.Cu" "F.Mask" "F.Paste")
			(net "GND")
			(options
				(clearance outline)
				(anchor circle)
			)
			(primitives
				(gr_poly
					(pts
						(arc
							(start -0.1778 -0.2794)
							(mid -0.249642 -0.249642)
							(end -0.2794 -0.1778)
						)
						(arc
							(start -0.2794 0.1778)
							(mid -0.249642 0.249642)
							(end -0.1778 0.2794)
						)
						(arc
							(start 0.1778 0.2794)
							(mid 0.249642 0.249642)
							(end 0.2794 0.1778)
						)
						(arc
							(start 0.2794 -0.1778)
							(mid 0.249642 -0.249642)
							(end 0.1778 -0.2794)
						)
					)
					(width 0)
					(fill yes)
				)
			)
		)
	)
	(footprint ""
		(layer "F.Cu")
		(at 161.878264 -304.310796 180)
		(property "Reference" "R255"
			(at 0 0 180)
			(layer "F.SilkS")
			(hide yes)
			(effects
				(font
					(size 1.27 1.27)
				)
			)
		)
		(property "Value" "130R3F-GP"
			(at -0.0254 -2.5146 180)
			(unlocked yes)
			(layer "F.Fab")
			(hide yes)
			(effects
				(font
					(size 1.016 1.016)
					(thickness 0.1524)
				)
			)
		)
		(property "Device Type" "R603H22"
			(at -0.0254 -4.0386 180)
			(unlocked yes)
			(layer "F.Fab")
			(hide yes)
			(effects
				(font
					(size 1.016 1.016)
					(thickness 0.1524)
				)
			)
		)
		(duplicate_pad_numbers_are_jumpers no)
		(fp_line
			(start 0.2032 0)
			(end 0.4826 0)
			(stroke
				(width 0.2032)
				(type default)
			)
			(layer "F.SilkS")
		)
		(fp_line
			(start -0.4826 0)
			(end -0.2032 0)
			(stroke
				(width 0.2032)
				(type default)
			)
			(layer "F.SilkS")
		)
		(fp_rect
			(start -0.5842 1.3335)
			(end 0.5842 -1.3335)
			(stroke
				(width 0)
				(type default)
			)
			(fill no)
			(layer "F.CrtYd")
		)
		(fp_rect
			(start -0.5842 1.3335)
			(end 0.5842 -1.3335)
			(stroke
				(width 0)
				(type default)
			)
			(fill no)
			(layer "F.Fab")
		)
		(pad "1" smd custom
			(at 0 -0.762 180)
			(size 0.2159 0.2159)
			(layers "F.Cu" "F.Mask" "F.Paste")
			(net "P5V_B")
			(options
				(clearance outline)
				(anchor circle)
			)
			(primitives
				(gr_poly
					(pts
						(arc
							(start -0.3302 -0.4318)
							(mid -0.402042 -0.402042)
							(end -0.4318 -0.3302)
						)
						(arc
							(start -0.4318 0.3302)
							(mid -0.402042 0.402042)
							(end -0.3302 0.4318)
						)
						(arc
							(start 0.3302 0.4318)
							(mid 0.402042 0.402042)
							(end 0.4318 0.3302)
						)
						(arc
							(start 0.4318 -0.3302)
							(mid 0.402042 -0.402042)
							(end 0.3302 -0.4318)
						)
					)
					(width 0)
					(fill yes)
				)
			)
		)
		(pad "2" smd custom
			(at 0 0.762 180)
			(size 0.2159 0.2159)
			(layers "F.Cu" "F.Mask" "F.Paste")
			(net "FLT_HDD29")
			(options
				(clearance outline)
				(anchor circle)
			)
			(primitives
				(gr_poly
					(pts
						(arc
							(start -0.3302 -0.4318)
							(mid -0.402042 -0.402042)
							(end -0.4318 -0.3302)
						)
						(arc
							(start -0.4318 0.3302)
							(mid -0.402042 0.402042)
							(end -0.3302 0.4318)
						)
						(arc
							(start 0.3302 0.4318)
							(mid 0.402042 0.402042)
							(end 0.4318 0.3302)
						)
						(arc
							(start 0.4318 -0.3302)
							(mid 0.402042 -0.402042)
							(end 0.3302 -0.4318)
						)
					)
					(width 0)
					(fill yes)
				)
			)
		)
	)
	(footprint ""
		(layer "F.Cu")
		(at 137.190734 -138.342624 90)
		(property "Reference" "U32"
			(at 0 0 90)
			(layer "F.SilkS")
			(hide yes)
			(effects
				(font
					(size 1.27 1.27)
				)
			)
		)
		(property "Value" "SN74LVC1G08DCKR-GP"
			(at -2.3368 -8.6868 90)
			(unlocked yes)
			(layer "F.Fab")
			(hide yes)
			(effects
				(font
					(size 1.016 1.016)
					(thickness 0.1524)
				)
			)
		)
		(property "Device Type" "SC70-5H44"
			(at -2.3114 -10.414 90)
			(unlocked yes)
			(layer "F.Fab")
			(hide yes)
			(effects
				(font
					(size 1.016 1.016)
					(thickness 0.1524)
				)
			)
		)
		(duplicate_pad_numbers_are_jumpers no)
		(fp_line
			(start 1.3843 -1.8034)
			(end 1.3843 -1.1176)
			(stroke
				(width 0.3302)
				(type default)
			)
			(layer "F.SilkS")
		)
		(fp_line
			(start 0.6604 -1.8034)
			(end 1.3843 -1.8034)
			(stroke
				(width 0.3302)
				(type default)
			)
			(layer "F.SilkS")
		)
		(fp_line
			(start 1.27 -1.7018)
			(end 1.27 1.7018)
			(stroke
				(width 0.1524)
				(type default)
			)
			(layer "F.SilkS")
		)
		(fp_line
			(start -1.27 -1.7018)
			(end 1.27 -1.7018)
			(stroke
				(width 0.1524)
				(type default)
			)
			(layer "F.SilkS")
		)
		(fp_line
			(start 1.27 1.7018)
			(end -1.27 1.7018)
			(stroke
				(width 0.1524)
				(type default)
			)
			(layer "F.SilkS")
		)
		(fp_line
			(start -1.27 1.7018)
			(end -1.27 -1.7018)
			(stroke
				(width 0.1524)
				(type default)
			)
			(layer "F.SilkS")
		)
		(fp_rect
			(start -1.524 1.9558)
			(end 1.524 -1.9558)
			(stroke
				(width 0)
				(type default)
			)
			(fill no)
			(layer "F.CrtYd")
		)
		(fp_poly
			(pts
				(xy -1.524 -1.9558) (xy 1.524 -1.9558) (xy 1.524 1.9558) (xy -1.524 1.9558)
			)
			(stroke
				(width 0)
				(type default)
			)
			(fill no)
			(layer "F.Fab")
		)
		(pad "1" smd rect
			(at 0.65024 -0.8255 90)
			(size 0.4064 1.2192)
			(layers "F.Cu" "F.Mask" "F.Paste")
			(net "P12V_A_PGOOD")
		)
		(pad "2" smd rect
			(at 0 -0.8255 90)
			(size 0.4064 1.2192)
			(layers "F.Cu" "F.Mask" "F.Paste")
			(net "COMP_A_PWR_EN")
		)
		(pad "3" smd rect
			(at -0.65024 -0.8255 90)
			(size 0.4064 1.2192)
			(layers "F.Cu" "F.Mask" "F.Paste")
			(net "GND")
		)
		(pad "4" smd rect
			(at -0.65024 0.8255 90)
			(size 0.4064 1.2192)
			(layers "F.Cu" "F.Mask" "F.Paste")
			(net "MB0_HS_ENABLE")
		)
		(pad "5" smd rect
			(at 0.65024 0.8255 90)
			(size 0.4064 1.2192)
			(layers "F.Cu" "F.Mask" "F.Paste")
			(net "P3V3_A_BIAS")
		)
	)
	(footprint ""
		(layer "F.Cu")
		(at 238.506 -256.5908)
		(property "Reference" "C13"
			(at 0 0 0)
			(layer "F.SilkS")
			(hide yes)
			(effects
				(font
					(size 1.27 1.27)
				)
			)
		)
		(property "Value" "SC1U16V3KX-5GP"
			(at 0 -2.8194 0)
			(unlocked yes)
			(layer "F.Fab")
			(hide yes)
			(effects
				(font
					(size 1.016 1.016)
					(thickness 0.1524)
				)
			)
		)
		(property "Device Type" "C603H36"
			(at 0 -4.3434 0)
			(unlocked yes)
			(layer "F.Fab")
			(hide yes)
			(effects
				(font
					(size 1.016 1.016)
					(thickness 0.1524)
				)
			)
		)
		(duplicate_pad_numbers_are_jumpers no)
		(fp_line
			(start 0.508 0)
			(end -0.508 0)
			(stroke
				(width 0.2032)
				(type default)
			)
			(layer "F.SilkS")
		)
		(fp_rect
			(start -0.5842 1.3335)
			(end 0.5842 -1.3335)
			(stroke
				(width 0)
				(type default)
			)
			(fill no)
			(layer "F.CrtYd")
		)
		(fp_rect
			(start -0.5842 1.3335)
			(end 0.5842 -1.3335)
			(stroke
				(width 0)
				(type default)
			)
			(fill no)
			(layer "F.Fab")
		)
		(pad "1" smd custom
			(at 0 -0.762)
			(size 0.2159 0.2159)
			(layers "F.Cu" "F.Mask" "F.Paste")
			(net "P3V3_STBY_A")
			(options
				(clearance outline)
				(anchor circle)
			)
			(primitives
				(gr_poly
					(pts
						(arc
							(start -0.3302 -0.4318)
							(mid -0.402042 -0.402042)
							(end -0.4318 -0.3302)
						)
						(arc
							(start -0.4318 0.3302)
							(mid -0.402042 0.402042)
							(end -0.3302 0.4318)
						)
						(arc
							(start 0.3302 0.4318)
							(mid 0.402042 0.402042)
							(end 0.4318 0.3302)
						)
						(arc
							(start 0.4318 -0.3302)
							(mid 0.402042 -0.402042)
							(end 0.3302 -0.4318)
						)
					)
					(width 0)
					(fill yes)
				)
			)
		)
		(pad "2" smd custom
			(at 0 0.762)
			(size 0.2159 0.2159)
			(layers "F.Cu" "F.Mask" "F.Paste")
			(net "GND")
			(options
				(clearance outline)
				(anchor circle)
			)
			(primitives
				(gr_poly
					(pts
						(arc
							(start -0.3302 -0.4318)
							(mid -0.402042 -0.402042)
							(end -0.4318 -0.3302)
						)
						(arc
							(start -0.4318 0.3302)
							(mid -0.402042 0.402042)
							(end -0.3302 0.4318)
						)
						(arc
							(start 0.3302 0.4318)
							(mid 0.402042 0.402042)
							(end 0.4318 0.3302)
						)
						(arc
							(start 0.4318 -0.3302)
							(mid 0.402042 -0.402042)
							(end 0.3302 -0.4318)
						)
					)
					(width 0)
					(fill yes)
				)
			)
		)
	)
	(footprint ""
		(layer "F.Cu")
		(at 272.8976 19.143472)
		(property "Reference" "R616"
			(at 0 0 0)
			(layer "F.SilkS")
			(hide yes)
			(effects
				(font
					(size 1.27 1.27)
				)
			)
		)
		(property "Value" "10KR2F-2-GP"
			(at 0.064008 -3.993896 0)
			(unlocked yes)
			(layer "F.Fab")
			(hide yes)
			(effects
				(font
					(size 1.016 1.016)
					(thickness 0.1524)
				)
			)
		)
		(property "Device Type" "R402H16"
			(at 0.064008 -5.517896 0)
			(unlocked yes)
			(layer "F.Fab")
			(hide yes)
			(effects
				(font
					(size 1.016 1.016)
					(thickness 0.1524)
				)
			)
		)
		(duplicate_pad_numbers_are_jumpers no)
		(fp_line
			(start -0.508 -0.9398)
			(end -0.508 0.9398)
			(stroke
				(width 0.1524)
				(type default)
			)
			(layer "F.SilkS")
		)
		(fp_line
			(start 0.508 -0.9398)
			(end -0.508 -0.9398)
			(stroke
				(width 0.1524)
				(type default)
			)
			(layer "F.SilkS")
		)
		(fp_rect
			(start -0.508 0.9398)
			(end 0.508 -0.9398)
			(stroke
				(width 0)
				(type default)
			)
			(fill no)
			(layer "F.CrtYd")
		)
		(fp_rect
			(start -0.508 0.9398)
			(end 0.508 -0.9398)
			(stroke
				(width 0)
				(type default)
			)
			(fill no)
			(layer "F.Fab")
		)
		(pad "1" smd custom
			(at 0 -0.4445)
			(size 0.1397 0.1397)
			(layers "F.Cu" "F.Mask" "F.Paste")
			(net "SCC_B_FAULT_LED")
			(options
				(clearance outline)
				(anchor circle)
			)
			(primitives
				(gr_poly
					(pts
						(arc
							(start -0.1778 -0.2794)
							(mid -0.249642 -0.249642)
							(end -0.2794 -0.1778)
						)
						(arc
							(start -0.2794 0.1778)
							(mid -0.249642 0.249642)
							(end -0.1778 0.2794)
						)
						(arc
							(start 0.1778 0.2794)
							(mid 0.249642 0.249642)
							(end 0.2794 0.1778)
						)
						(arc
							(start 0.2794 -0.1778)
							(mid 0.249642 -0.249642)
							(end 0.1778 -0.2794)
						)
					)
					(width 0)
					(fill yes)
				)
			)
		)
		(pad "2" smd custom
			(at 0 0.4445)
			(size 0.1397 0.1397)
			(layers "F.Cu" "F.Mask" "F.Paste")
			(net "GND")
			(options
				(clearance outline)
				(anchor circle)
			)
			(primitives
				(gr_poly
					(pts
						(arc
							(start -0.1778 -0.2794)
							(mid -0.249642 -0.249642)
							(end -0.2794 -0.1778)
						)
						(arc
							(start -0.2794 0.1778)
							(mid -0.249642 0.249642)
							(end -0.1778 0.2794)
						)
						(arc
							(start 0.1778 0.2794)
							(mid 0.249642 0.249642)
							(end 0.2794 0.1778)
						)
						(arc
							(start 0.2794 -0.1778)
							(mid 0.249642 -0.249642)
							(end 0.1778 -0.2794)
						)
					)
					(width 0)
					(fill yes)
				)
			)
		)
	)
	(footprint ""
		(layer "F.Cu")
		(at 469.904318 -49.29505 90)
		(property "Reference" "R951"
			(at 0 0 90)
			(layer "F.SilkS")
			(hide yes)
			(effects
				(font
					(size 1.27 1.27)
				)
			)
		)
		(property "Value" "200KR2F-L-GP"
			(at 0.064008 -3.993896 90)
			(unlocked yes)
			(layer "F.Fab")
			(hide yes)
			(effects
				(font
					(size 1.016 1.016)
					(thickness 0.1524)
				)
			)
		)
		(property "Device Type" "R402H16"
			(at 0.064008 -5.517896 90)
			(unlocked yes)
			(layer "F.Fab")
			(hide yes)
			(effects
				(font
					(size 1.016 1.016)
					(thickness 0.1524)
				)
			)
		)
		(duplicate_pad_numbers_are_jumpers no)
		(fp_line
			(start 0.508 -0.9398)
			(end -0.508 -0.9398)
			(stroke
				(width 0.1524)
				(type default)
			)
			(layer "F.SilkS")
		)
		(fp_line
			(start -0.508 -0.9398)
			(end -0.508 0.9398)
			(stroke
				(width 0.1524)
				(type default)
			)
			(layer "F.SilkS")
		)
		(fp_rect
			(start -0.508 0.9398)
			(end 0.508 -0.9398)
			(stroke
				(width 0)
				(type default)
			)
			(fill no)
			(layer "F.CrtYd")
		)
		(fp_rect
			(start -0.508 0.9398)
			(end 0.508 -0.9398)
			(stroke
				(width 0)
				(type default)
			)
			(fill no)
			(layer "F.Fab")
		)
		(pad "1" smd custom
			(at 0 -0.4445 90)
			(size 0.1397 0.1397)
			(layers "F.Cu" "F.Mask" "F.Paste")
			(net "SW_HDD_R35")
			(options
				(clearance outline)
				(anchor circle)
			)
			(primitives
				(gr_poly
					(pts
						(arc
							(start -0.1778 -0.2794)
							(mid -0.249642 -0.249642)
							(end -0.2794 -0.1778)
						)
						(arc
							(start -0.2794 0.1778)
							(mid -0.249642 0.249642)
							(end -0.1778 0.2794)
						)
						(arc
							(start 0.1778 0.2794)
							(mid 0.249642 0.249642)
							(end 0.2794 0.1778)
						)
						(arc
							(start 0.2794 -0.1778)
							(mid 0.249642 -0.249642)
							(end 0.1778 -0.2794)
						)
					)
					(width 0)
					(fill yes)
				)
			)
		)
		(pad "2" smd custom
			(at 0 0.4445 90)
			(size 0.1397 0.1397)
			(layers "F.Cu" "F.Mask" "F.Paste")
			(net "SW_HDD_N35")
			(options
				(clearance outline)
				(anchor circle)
			)
			(primitives
				(gr_poly
					(pts
						(arc
							(start -0.1778 -0.2794)
							(mid -0.249642 -0.249642)
							(end -0.2794 -0.1778)
						)
						(arc
							(start -0.2794 0.1778)
							(mid -0.249642 0.249642)
							(end -0.1778 0.2794)
						)
						(arc
							(start 0.1778 0.2794)
							(mid 0.249642 0.249642)
							(end 0.2794 0.1778)
						)
						(arc
							(start 0.2794 -0.1778)
							(mid 0.249642 -0.249642)
							(end 0.1778 -0.2794)
						)
					)
					(width 0)
					(fill yes)
				)
			)
		)
	)
	(footprint ""
		(layer "F.Cu")
		(at 83.393534 -31.394146 180)
		(property "Reference" "R30"
			(at 0 0 180)
			(layer "F.SilkS")
			(hide yes)
			(effects
				(font
					(size 1.27 1.27)
				)
			)
		)
		(property "Value" "0R2J-2-GP"
			(at 0.064008 -3.993896 180)
			(unlocked yes)
			(layer "F.Fab")
			(hide yes)
			(effects
				(font
					(size 1.016 1.016)
					(thickness 0.1524)
				)
			)
		)
		(property "Device Type" "R402H16"
			(at 0.064008 -5.517896 180)
			(unlocked yes)
			(layer "F.Fab")
			(hide yes)
			(effects
				(font
					(size 1.016 1.016)
					(thickness 0.1524)
				)
			)
		)
		(duplicate_pad_numbers_are_jumpers no)
		(fp_line
			(start 0.508 -0.9398)
			(end -0.508 -0.9398)
			(stroke
				(width 0.1524)
				(type default)
			)
			(layer "F.SilkS")
		)
		(fp_line
			(start -0.508 -0.9398)
			(end -0.508 0.9398)
			(stroke
				(width 0.1524)
				(type default)
			)
			(layer "F.SilkS")
		)
		(fp_rect
			(start -0.508 0.9398)
			(end 0.508 -0.9398)
			(stroke
				(width 0)
				(type default)
			)
			(fill no)
			(layer "F.CrtYd")
		)
		(fp_rect
			(start -0.508 0.9398)
			(end 0.508 -0.9398)
			(stroke
				(width 0)
				(type default)
			)
			(fill no)
			(layer "F.Fab")
		)
		(pad "1" smd custom
			(at 0 -0.4445 180)
			(size 0.1397 0.1397)
			(layers "F.Cu" "F.Mask" "F.Paste")
			(net "IO_EXP10_SCL")
			(options
				(clearance outline)
				(anchor circle)
			)
			(primitives
				(gr_poly
					(pts
						(arc
							(start -0.1778 -0.2794)
							(mid -0.249642 -0.249642)
							(end -0.2794 -0.1778)
						)
						(arc
							(start -0.2794 0.1778)
							(mid -0.249642 0.249642)
							(end -0.1778 0.2794)
						)
						(arc
							(start 0.1778 0.2794)
							(mid 0.249642 0.249642)
							(end 0.2794 0.1778)
						)
						(arc
							(start 0.2794 -0.1778)
							(mid 0.249642 -0.249642)
							(end 0.1778 -0.2794)
						)
					)
					(width 0)
					(fill yes)
				)
			)
		)
		(pad "2" smd custom
			(at 0 0.4445 180)
			(size 0.1397 0.1397)
			(layers "F.Cu" "F.Mask" "F.Paste")
			(net "I2C_BMC_A_MISC_SCL")
			(options
				(clearance outline)
				(anchor circle)
			)
			(primitives
				(gr_poly
					(pts
						(arc
							(start -0.1778 -0.2794)
							(mid -0.249642 -0.249642)
							(end -0.2794 -0.1778)
						)
						(arc
							(start -0.2794 0.1778)
							(mid -0.249642 0.249642)
							(end -0.1778 0.2794)
						)
						(arc
							(start 0.1778 0.2794)
							(mid 0.249642 0.249642)
							(end 0.2794 0.1778)
						)
						(arc
							(start 0.2794 -0.1778)
							(mid 0.249642 -0.249642)
							(end 0.1778 -0.2794)
						)
					)
					(width 0)
					(fill yes)
				)
			)
		)
	)
	(footprint ""
		(layer "F.Cu")
		(at 17.800066 -324.39991)
		(property "Reference" "RLED25"
			(at 0 0 0)
			(layer "F.SilkS")
			(hide yes)
			(effects
				(font
					(size 1.27 1.27)
				)
			)
		)
		(property "Value" "LED-BY-19-GP"
			(at -2.132076 1.414018 0)
			(unlocked yes)
			(layer "F.Fab")
			(hide yes)
			(effects
				(font
					(size 1.016 1.016)
					(thickness 0.1524)
				)
			)
		)
		(property "Device Type" "LED-1615-4PH26"
			(at -2.132076 -0.109982 0)
			(unlocked yes)
			(layer "F.Fab")
			(hide yes)
			(effects
				(font
					(size 1.016 1.016)
					(thickness 0.1524)
				)
			)
		)
		(duplicate_pad_numbers_are_jumpers no)
		(fp_line
			(start -1.2954 0.254)
			(end -1.2954 1.6002)
			(stroke
				(width 0.508)
				(type default)
			)
			(layer "F.SilkS")
		)
		(fp_line
			(start -1.2954 1.6002)
			(end 1.2954 1.6002)
			(stroke
				(width 0.508)
				(type default)
			)
			(layer "F.SilkS")
		)
		(fp_line
			(start -1.1176 -1.4224)
			(end 1.1176 -1.4224)
			(stroke
				(width 0.1524)
				(type default)
			)
			(layer "F.SilkS")
		)
		(fp_line
			(start -1.1176 1.4224)
			(end -1.1176 -1.4224)
			(stroke
				(width 0.1524)
				(type default)
			)
			(layer "F.SilkS")
		)
		(fp_line
			(start 1.1176 -1.4224)
			(end 1.1176 1.4224)
			(stroke
				(width 0.1524)
				(type default)
			)
			(layer "F.SilkS")
		)
		(fp_line
			(start 1.1176 1.4224)
			(end -1.1176 1.4224)
			(stroke
				(width 0.1524)
				(type default)
			)
			(layer "F.SilkS")
		)
		(fp_line
			(start 1.2954 1.6002)
			(end 1.2954 0.254)
			(stroke
				(width 0.508)
				(type default)
			)
			(layer "F.SilkS")
		)
		(fp_rect
			(start -0.7493 0.8001)
			(end 0.7493 -0.8001)
			(stroke
				(width 0)
				(type default)
			)
			(fill no)
			(layer "F.CrtYd")
		)
		(fp_poly
			(pts
				(xy -1.3716 1.6764) (xy -1.3716 -1.6764) (xy 1.3716 -1.6764) (xy 1.3716 0.0635) (xy 0.7493 0.0635)
				(xy 0.7493 -0.8001) (xy -0.7493 -0.8001) (xy -0.7493 0.8001) (xy 0.7493 0.8001) (xy 0.7493 0.0762)
				(xy 1.3716 0.0762) (xy 1.3716 1.6764)
			)
			(stroke
				(width 0)
				(type default)
			)
			(fill no)
			(layer "F.CrtYd")
		)
		(fp_rect
			(start -1.3716 1.6764)
			(end 1.3716 -1.6764)
			(stroke
				(width 0)
				(type default)
			)
			(fill no)
			(layer "F.Fab")
		)
		(pad "1" smd rect
			(at 0.50038 -0.73025)
			(size 0.7112 0.8636)
			(layers "F.Cu" "F.Mask" "F.Paste")
			(net "DRV_ACT_24")
		)
		(pad "2" smd rect
			(at -0.50038 -0.73025)
			(size 0.7112 0.8636)
			(layers "F.Cu" "F.Mask" "F.Paste")
			(net "FLT_HDD24")
		)
		(pad "3" smd rect
			(at 0.50038 0.73025)
			(size 0.7112 0.8636)
			(layers "F.Cu" "F.Mask" "F.Paste")
			(net "DRV_ACT_24_N")
		)
		(pad "4" smd rect
			(at -0.50038 0.73025)
			(size 0.7112 0.8636)
			(layers "F.Cu" "F.Mask" "F.Paste")
			(net "FLT_HDD24_N")
		)
	)
	(footprint ""
		(layer "F.Cu")
		(at 431.454052 -177.016918)
		(property "Reference" "Q128"
			(at 0 0 0)
			(layer "F.SilkS")
			(hide yes)
			(effects
				(font
					(size 1.27 1.27)
				)
			)
		)
		(property "Value" "AO4407AL-GP"
			(at -3.707384 -1.5367 0)
			(unlocked yes)
			(layer "F.Fab")
			(hide yes)
			(effects
				(font
					(size 1.016 1.016)
					(thickness 0.1524)
				)
			)
		)
		(property "Device Type" "SOIC8H69"
			(at -3.707384 -3.0607 0)
			(unlocked yes)
			(layer "F.Fab")
			(hide yes)
			(effects
				(font
					(size 1.016 1.016)
					(thickness 0.1524)
				)
			)
		)
		(duplicate_pad_numbers_are_jumpers no)
		(fp_line
			(start -2.7432 -1.4224)
			(end -2.7432 1.4224)
			(stroke
				(width 0.1524)
				(type default)
			)
			(layer "F.SilkS")
		)
		(fp_line
			(start -2.7432 1.4224)
			(end -2.6416 1.4224)
			(stroke
				(width 0.1524)
				(type default)
			)
			(layer "F.SilkS")
		)
		(fp_line
			(start -2.7432 1.4224)
			(end 2.1336 1.4224)
			(stroke
				(width 0.1524)
				(type default)
			)
			(layer "F.SilkS")
		)
		(fp_line
			(start -2.7178 -0.508)
			(end -2.1844 -0.0508)
			(stroke
				(width 0.1524)
				(type default)
			)
			(layer "F.SilkS")
		)
		(fp_line
			(start -2.6289 3.4417)
			(end -2.6289 1.4732)
			(stroke
				(width 0.381)
				(type default)
			)
			(layer "F.SilkS")
		)
		(fp_line
			(start -2.1844 -0.0508)
			(end -2.7178 0.508)
			(stroke
				(width 0.1524)
				(type default)
			)
			(layer "F.SilkS")
		)
		(fp_line
			(start 2.1336 -1.4224)
			(end -2.7432 -1.4224)
			(stroke
				(width 0.1524)
				(type default)
			)
			(layer "F.SilkS")
		)
		(fp_line
			(start 2.1336 1.4224)
			(end 2.1336 -1.4224)
			(stroke
				(width 0.1524)
				(type default)
			)
			(layer "F.SilkS")
		)
		(fp_poly
			(pts
				(xy -2.2098 -1.4224) (xy -2.2098 1.4224) (xy 2.2098 1.4224) (xy 2.2098 -1.4224)
			)
			(stroke
				(width 0)
				(type default)
			)
			(fill yes)
			(layer "F.SilkS")
		)
		(fp_rect
			(start -2.450084 2.999994)
			(end 2.450084 -2.999994)
			(stroke
				(width 0)
				(type default)
			)
			(fill no)
			(layer "F.CrtYd")
		)
		(fp_poly
			(pts
				(xy -2.8194 3.6322) (xy -2.8194 -3.6322) (xy 2.8194 -3.6322) (xy 2.8194 1.18364) (xy 2.450084 1.18364)
				(xy 2.450084 -2.999994) (xy -2.450084 -2.999994) (xy -2.450084 2.999994) (xy 2.450084 2.999994)
				(xy 2.450084 1.18618) (xy 2.8194 1.18618) (xy 2.8194 3.6322)
			)
			(stroke
				(width 0)
				(type default)
			)
			(fill no)
			(layer "F.CrtYd")
		)
		(fp_rect
			(start -2.8194 3.6322)
			(end 2.8194 -3.6322)
			(stroke
				(width 0)
				(type default)
			)
			(fill no)
			(layer "F.Fab")
		)
		(pad "1" smd rect
			(at -1.905 2.54)
			(size 0.635 1.651)
			(layers "F.Cu" "F.Mask" "F.Paste")
			(net "P12V_A")
		)
		(pad "2" smd rect
			(at -0.635 2.54)
			(size 0.635 1.651)
			(layers "F.Cu" "F.Mask" "F.Paste")
			(net "P12V_A")
		)
		(pad "3" smd rect
			(at 0.635 2.54)
			(size 0.635 1.651)
			(layers "F.Cu" "F.Mask" "F.Paste")
			(net "P12V_A")
		)
		(pad "4" smd rect
			(at 1.905 2.54)
			(size 0.635 1.651)
			(layers "F.Cu" "F.Mask" "F.Paste")
			(net "SW_HDD_N21")
		)
		(pad "5" smd rect
			(at 1.905 -2.54)
			(size 0.635 1.651)
			(layers "F.Cu" "F.Mask" "F.Paste")
			(net "P12V_HDD21")
		)
		(pad "6" smd rect
			(at 0.635 -2.54)
			(size 0.635 1.651)
			(layers "F.Cu" "F.Mask" "F.Paste")
			(net "P12V_HDD21")
		)
		(pad "7" smd rect
			(at -0.635 -2.54)
			(size 0.635 1.651)
			(layers "F.Cu" "F.Mask" "F.Paste")
			(net "P12V_HDD21")
		)
		(pad "8" smd rect
			(at -1.905 -2.54)
			(size 0.635 1.651)
			(layers "F.Cu" "F.Mask" "F.Paste")
			(net "P12V_HDD21")
		)
	)
	(footprint ""
		(layer "F.Cu")
		(at 262.141462 10.22985 180)
		(property "Reference" "C43"
			(at 0 0 180)
			(layer "F.SilkS")
			(hide yes)
			(effects
				(font
					(size 1.27 1.27)
				)
			)
		)
		(property "Value" "SCD1U16V2KX-3GP"
			(at 1.1811 -2.7051 180)
			(unlocked yes)
			(layer "F.Fab")
			(hide yes)
			(effects
				(font
					(size 1.016 1.016)
					(thickness 0.1524)
				)
			)
		)
		(property "Device Type" "C402H22"
			(at 1.1811 -4.2291 180)
			(unlocked yes)
			(layer "F.Fab")
			(hide yes)
			(effects
				(font
					(size 1.016 1.016)
					(thickness 0.1524)
				)
			)
		)
		(duplicate_pad_numbers_are_jumpers no)
		(fp_rect
			(start -0.4318 0.9525)
			(end 0.4318 -0.9525)
			(stroke
				(width 0)
				(type default)
			)
			(fill no)
			(layer "F.CrtYd")
		)
		(fp_rect
			(start -0.4318 0.9525)
			(end 0.4318 -0.9525)
			(stroke
				(width 0)
				(type default)
			)
			(fill no)
			(layer "F.Fab")
		)
		(pad "1" smd custom
			(at 0 -0.4445 180)
			(size 0.1524 0.1524)
			(layers "F.Cu" "F.Mask" "F.Paste")
			(net "P5V_A_2")
			(options
				(clearance outline)
				(anchor circle)
			)
			(primitives
				(gr_poly
					(pts
						(arc
							(start 0.3048 -0.2032)
							(mid 0.275042 -0.275042)
							(end 0.2032 -0.3048)
						)
						(arc
							(start -0.2032 -0.3048)
							(mid -0.275042 -0.275042)
							(end -0.3048 -0.2032)
						)
						(arc
							(start -0.3048 0.2032)
							(mid -0.275042 0.275042)
							(end -0.2032 0.3048)
						)
						(arc
							(start 0.2032 0.3048)
							(mid 0.275042 0.275042)
							(end 0.3048 0.2032)
						)
					)
					(width 0)
					(fill yes)
				)
			)
		)
		(pad "2" smd custom
			(at 0 0.4445 180)
			(size 0.1524 0.1524)
			(layers "F.Cu" "F.Mask" "F.Paste")
			(net "GND")
			(options
				(clearance outline)
				(anchor circle)
			)
			(primitives
				(gr_poly
					(pts
						(arc
							(start 0.3048 -0.2032)
							(mid 0.275042 -0.275042)
							(end 0.2032 -0.3048)
						)
						(arc
							(start -0.2032 -0.3048)
							(mid -0.275042 -0.275042)
							(end -0.3048 -0.2032)
						)
						(arc
							(start -0.3048 0.2032)
							(mid -0.275042 0.275042)
							(end -0.2032 0.3048)
						)
						(arc
							(start 0.2032 0.3048)
							(mid 0.275042 0.275042)
							(end 0.3048 0.2032)
						)
					)
					(width 0)
					(fill yes)
				)
			)
		)
	)
	(footprint ""
		(layer "F.Cu")
		(at 479.340926 -74.462894 180)
		(property "Reference" "C502"
			(at 0 0 180)
			(layer "F.SilkS")
			(hide yes)
			(effects
				(font
					(size 1.27 1.27)
				)
			)
		)
		(property "Value" "SC1U25V3KX-GP"
			(at 0 -2.8194 180)
			(unlocked yes)
			(layer "F.Fab")
			(hide yes)
			(effects
				(font
					(size 1.016 1.016)
					(thickness 0.1524)
				)
			)
		)
		(property "Device Type" "C603H36"
			(at 0 -4.3434 180)
			(unlocked yes)
			(layer "F.Fab")
			(hide yes)
			(effects
				(font
					(size 1.016 1.016)
					(thickness 0.1524)
				)
			)
		)
		(duplicate_pad_numbers_are_jumpers no)
		(fp_line
			(start 0.508 0)
			(end -0.508 0)
			(stroke
				(width 0.2032)
				(type default)
			)
			(layer "F.SilkS")
		)
		(fp_rect
			(start -0.5842 1.3335)
			(end 0.5842 -1.3335)
			(stroke
				(width 0)
				(type default)
			)
			(fill no)
			(layer "F.CrtYd")
		)
		(fp_rect
			(start -0.5842 1.3335)
			(end 0.5842 -1.3335)
			(stroke
				(width 0)
				(type default)
			)
			(fill no)
			(layer "F.Fab")
		)
		(pad "1" smd custom
			(at 0 -0.762 180)
			(size 0.2159 0.2159)
			(layers "F.Cu" "F.Mask" "F.Paste")
			(net "P12V_HDD35")
			(options
				(clearance outline)
				(anchor circle)
			)
			(primitives
				(gr_poly
					(pts
						(arc
							(start -0.3302 -0.4318)
							(mid -0.402042 -0.402042)
							(end -0.4318 -0.3302)
						)
						(arc
							(start -0.4318 0.3302)
							(mid -0.402042 0.402042)
							(end -0.3302 0.4318)
						)
						(arc
							(start 0.3302 0.4318)
							(mid 0.402042 0.402042)
							(end 0.4318 0.3302)
						)
						(arc
							(start 0.4318 -0.3302)
							(mid 0.402042 -0.402042)
							(end 0.3302 -0.4318)
						)
					)
					(width 0)
					(fill yes)
				)
			)
		)
		(pad "2" smd custom
			(at 0 0.762 180)
			(size 0.2159 0.2159)
			(layers "F.Cu" "F.Mask" "F.Paste")
			(net "GND")
			(options
				(clearance outline)
				(anchor circle)
			)
			(primitives
				(gr_poly
					(pts
						(arc
							(start -0.3302 -0.4318)
							(mid -0.402042 -0.402042)
							(end -0.4318 -0.3302)
						)
						(arc
							(start -0.4318 0.3302)
							(mid -0.402042 0.402042)
							(end -0.3302 0.4318)
						)
						(arc
							(start 0.3302 0.4318)
							(mid 0.402042 0.402042)
							(end 0.4318 0.3302)
						)
						(arc
							(start 0.4318 -0.3302)
							(mid 0.402042 -0.402042)
							(end 0.3302 -0.4318)
						)
					)
					(width 0)
					(fill yes)
				)
			)
		)
	)
	(footprint ""
		(layer "F.Cu")
		(at 419.389052 -162.749992 -90)
		(property "Reference" "VIA25"
			(at 0 0 270)
			(layer "F.SilkS")
			(hide yes)
			(effects
				(font
					(size 1.27 1.27)
				)
			)
		)
		(property "Value" "100OHM-8L-1D6MM-L18L16-GP"
			(at -3.7211 -4.5085 270)
			(unlocked yes)
			(layer "F.Fab")
			(hide yes)
			(effects
				(font
					(size 1.016 1.016)
					(thickness 0.1524)
				)
			)
		)
		(property "Device Type" "VIA-PCIE-4P-394076"
			(at -3.7211 -6.0325 270)
			(unlocked yes)
			(layer "F.Fab")
			(hide yes)
			(effects
				(font
					(size 1.016 1.016)
					(thickness 0.1524)
				)
			)
		)
		(duplicate_pad_numbers_are_jumpers no)
		(fp_rect
			(start -1.9685 0.381)
			(end 1.9685 -0.381)
			(stroke
				(width 0)
				(type default)
			)
			(fill no)
			(layer "F.CrtYd")
		)
		(fp_rect
			(start -1.9685 0.381)
			(end 1.9685 -0.381)
			(stroke
				(width 0)
				(type default)
			)
			(fill no)
			(layer "F.Fab")
		)
		(pad "1" thru_hole circle
			(at -1.5875 0 270)
			(size 0.508 0.508)
			(drill 0.254)
			(layers "*.Cu" "*.Mask")
			(remove_unused_layers no)
			(net "GND")
			(clearance 0.127)
			(thermal_gap 0.127)
		)
		(pad "2" thru_hole circle
			(at -0.5715 0 270)
			(size 0.508 0.508)
			(drill 0.254)
			(layers "*.Cu" "*.Mask")
			(remove_unused_layers no)
			(net "PHY_DRV_A_TO_SCC_A_21_DP")
			(clearance 0.127)
			(thermal_gap 0.127)
		)
		(pad "3" thru_hole circle
			(at 0.5715 0 270)
			(size 0.508 0.508)
			(drill 0.254)
			(layers "*.Cu" "*.Mask")
			(remove_unused_layers no)
			(net "PHY_DRV_A_TO_SCC_A_21_DN")
			(clearance 0.127)
			(thermal_gap 0.127)
		)
		(pad "4" thru_hole circle
			(at 1.5875 0 270)
			(size 0.508 0.508)
			(drill 0.254)
			(layers "*.Cu" "*.Mask")
			(remove_unused_layers no)
			(net "GND")
			(clearance 0.127)
			(thermal_gap 0.127)
		)
	)
	(footprint ""
		(layer "F.Cu")
		(at 395.369542 -283.25445 180)
		(property "Reference" "Q48"
			(at 0 0 180)
			(layer "F.SilkS")
			(hide yes)
			(effects
				(font
					(size 1.27 1.27)
				)
			)
		)
		(property "Value" "AO4406AL-GP"
			(at -3.707384 -1.5367 180)
			(unlocked yes)
			(layer "F.Fab")
			(hide yes)
			(effects
				(font
					(size 1.016 1.016)
					(thickness 0.1524)
				)
			)
		)
		(property "Device Type" "SOIC8H69"
			(at -3.707384 -3.0607 180)
			(unlocked yes)
			(layer "F.Fab")
			(hide yes)
			(effects
				(font
					(size 1.016 1.016)
					(thickness 0.1524)
				)
			)
		)
		(duplicate_pad_numbers_are_jumpers no)
		(fp_line
			(start 2.1336 1.4224)
			(end 2.1336 -1.4224)
			(stroke
				(width 0.1524)
				(type default)
			)
			(layer "F.SilkS")
		)
		(fp_line
			(start 2.1336 -1.4224)
			(end -2.7432 -1.4224)
			(stroke
				(width 0.1524)
				(type default)
			)
			(layer "F.SilkS")
		)
		(fp_line
			(start -2.1844 -0.0508)
			(end -2.7178 0.508)
			(stroke
				(width 0.1524)
				(type default)
			)
			(layer "F.SilkS")
		)
		(fp_line
			(start -2.6289 3.4417)
			(end -2.6289 1.4732)
			(stroke
				(width 0.381)
				(type default)
			)
			(layer "F.SilkS")
		)
		(fp_line
			(start -2.7178 -0.508)
			(end -2.1844 -0.0508)
			(stroke
				(width 0.1524)
				(type default)
			)
			(layer "F.SilkS")
		)
		(fp_line
			(start -2.7432 1.4224)
			(end 2.1336 1.4224)
			(stroke
				(width 0.1524)
				(type default)
			)
			(layer "F.SilkS")
		)
		(fp_line
			(start -2.7432 1.4224)
			(end -2.6416 1.4224)
			(stroke
				(width 0.1524)
				(type default)
			)
			(layer "F.SilkS")
		)
		(fp_line
			(start -2.7432 -1.4224)
			(end -2.7432 1.4224)
			(stroke
				(width 0.1524)
				(type default)
			)
			(layer "F.SilkS")
		)
		(fp_poly
			(pts
				(xy -2.2098 -1.4224) (xy -2.2098 1.4224) (xy 2.2098 1.4224) (xy 2.2098 -1.4224)
			)
			(stroke
				(width 0)
				(type default)
			)
			(fill yes)
			(layer "F.SilkS")
		)
		(fp_rect
			(start -2.450084 2.999994)
			(end 2.450084 -2.999994)
			(stroke
				(width 0)
				(type default)
			)
			(fill no)
			(layer "F.CrtYd")
		)
		(fp_poly
			(pts
				(xy -2.8194 3.6322) (xy -2.8194 -3.6322) (xy 2.8194 -3.6322) (xy 2.8194 1.18364) (xy 2.450084 1.18364)
				(xy 2.450084 -2.999994) (xy -2.450084 -2.999994) (xy -2.450084 2.999994) (xy 2.450084 2.999994)
				(xy 2.450084 1.18618) (xy 2.8194 1.18618) (xy 2.8194 3.6322)
			)
			(stroke
				(width 0)
				(type default)
			)
			(fill no)
			(layer "F.CrtYd")
		)
		(fp_rect
			(start -2.8194 3.6322)
			(end 2.8194 -3.6322)
			(stroke
				(width 0)
				(type default)
			)
			(fill no)
			(layer "F.Fab")
		)
		(pad "1" smd rect
			(at -1.905 2.54 180)
			(size 0.635 1.651)
			(layers "F.Cu" "F.Mask" "F.Paste")
			(net "P5V_HDD8")
		)
		(pad "2" smd rect
			(at -0.635 2.54 180)
			(size 0.635 1.651)
			(layers "F.Cu" "F.Mask" "F.Paste")
			(net "P5V_HDD8")
		)
		(pad "3" smd rect
			(at 0.635 2.54 180)
			(size 0.635 1.651)
			(layers "F.Cu" "F.Mask" "F.Paste")
			(net "P5V_HDD8")
		)
		(pad "4" smd rect
			(at 1.905 2.54 180)
			(size 0.635 1.651)
			(layers "F.Cu" "F.Mask" "F.Paste")
			(net "SW_HDD_P8")
		)
		(pad "5" smd rect
			(at 1.905 -2.54 180)
			(size 0.635 1.651)
			(layers "F.Cu" "F.Mask" "F.Paste")
			(net "P5V_A_3")
		)
		(pad "6" smd rect
			(at 0.635 -2.54 180)
			(size 0.635 1.651)
			(layers "F.Cu" "F.Mask" "F.Paste")
			(net "P5V_A_3")
		)
		(pad "7" smd rect
			(at -0.635 -2.54 180)
			(size 0.635 1.651)
			(layers "F.Cu" "F.Mask" "F.Paste")
			(net "P5V_A_3")
		)
		(pad "8" smd rect
			(at -1.905 -2.54 180)
			(size 0.635 1.651)
			(layers "F.Cu" "F.Mask" "F.Paste")
			(net "P5V_A_3")
		)
	)
	(footprint ""
		(layer "F.Cu")
		(at 86.121748 -44.821094 -90)
		(property "Reference" "R739"
			(at 0 0 270)
			(layer "F.SilkS")
			(hide yes)
			(effects
				(font
					(size 1.27 1.27)
				)
			)
		)
		(property "Value" "0R2J-2-GP"
			(at 0.064008 -3.993896 270)
			(unlocked yes)
			(layer "F.Fab")
			(hide yes)
			(effects
				(font
					(size 1.016 1.016)
					(thickness 0.1524)
				)
			)
		)
		(property "Device Type" "R402H16"
			(at 0.064008 -5.517896 270)
			(unlocked yes)
			(layer "F.Fab")
			(hide yes)
			(effects
				(font
					(size 1.016 1.016)
					(thickness 0.1524)
				)
			)
		)
		(duplicate_pad_numbers_are_jumpers no)
		(fp_line
			(start -0.508 -0.9398)
			(end -0.508 0.9398)
			(stroke
				(width 0.1524)
				(type default)
			)
			(layer "F.SilkS")
		)
		(fp_line
			(start 0.508 -0.9398)
			(end -0.508 -0.9398)
			(stroke
				(width 0.1524)
				(type default)
			)
			(layer "F.SilkS")
		)
		(fp_rect
			(start -0.508 0.9398)
			(end 0.508 -0.9398)
			(stroke
				(width 0)
				(type default)
			)
			(fill no)
			(layer "F.CrtYd")
		)
		(fp_rect
			(start -0.508 0.9398)
			(end 0.508 -0.9398)
			(stroke
				(width 0)
				(type default)
			)
			(fill no)
			(layer "F.Fab")
		)
		(pad "1" smd custom
			(at 0 -0.4445 270)
			(size 0.1397 0.1397)
			(layers "F.Cu" "F.Mask" "F.Paste")
			(net "DRIVE_A_26_PWR")
			(options
				(clearance outline)
				(anchor circle)
			)
			(primitives
				(gr_poly
					(pts
						(arc
							(start -0.1778 -0.2794)
							(mid -0.249642 -0.249642)
							(end -0.2794 -0.1778)
						)
						(arc
							(start -0.2794 0.1778)
							(mid -0.249642 0.249642)
							(end -0.1778 0.2794)
						)
						(arc
							(start 0.1778 0.2794)
							(mid 0.249642 0.249642)
							(end 0.2794 0.1778)
						)
						(arc
							(start 0.2794 -0.1778)
							(mid 0.249642 -0.249642)
							(end 0.1778 -0.2794)
						)
					)
					(width 0)
					(fill yes)
				)
			)
		)
		(pad "2" smd custom
			(at 0 0.4445 270)
			(size 0.1397 0.1397)
			(layers "F.Cu" "F.Mask" "F.Paste")
			(net "SW_PWR_R_HDD26")
			(options
				(clearance outline)
				(anchor circle)
			)
			(primitives
				(gr_poly
					(pts
						(arc
							(start -0.1778 -0.2794)
							(mid -0.249642 -0.249642)
							(end -0.2794 -0.1778)
						)
						(arc
							(start -0.2794 0.1778)
							(mid -0.249642 0.249642)
							(end -0.1778 0.2794)
						)
						(arc
							(start 0.1778 0.2794)
							(mid 0.249642 0.249642)
							(end 0.2794 0.1778)
						)
						(arc
							(start 0.2794 -0.1778)
							(mid 0.249642 -0.249642)
							(end 0.1778 -0.2794)
						)
					)
					(width 0)
					(fill yes)
				)
			)
		)
	)
	(footprint ""
		(layer "F.Cu")
		(at 269.57655 11.6078 180)
		(property "Reference" "R139"
			(at 0 0 180)
			(layer "F.SilkS")
			(hide yes)
			(effects
				(font
					(size 1.27 1.27)
				)
			)
		)
		(property "Value" "4K7R2F-GP"
			(at 0.064008 -3.993896 180)
			(unlocked yes)
			(layer "F.Fab")
			(hide yes)
			(effects
				(font
					(size 1.016 1.016)
					(thickness 0.1524)
				)
			)
		)
		(property "Device Type" "R402H16"
			(at 0.064008 -5.517896 180)
			(unlocked yes)
			(layer "F.Fab")
			(hide yes)
			(effects
				(font
					(size 1.016 1.016)
					(thickness 0.1524)
				)
			)
		)
		(duplicate_pad_numbers_are_jumpers no)
		(fp_line
			(start 0.508 -0.9398)
			(end -0.508 -0.9398)
			(stroke
				(width 0.1524)
				(type default)
			)
			(layer "F.SilkS")
		)
		(fp_line
			(start -0.508 -0.9398)
			(end -0.508 0.9398)
			(stroke
				(width 0.1524)
				(type default)
			)
			(layer "F.SilkS")
		)
		(fp_rect
			(start -0.508 0.9398)
			(end 0.508 -0.9398)
			(stroke
				(width 0)
				(type default)
			)
			(fill no)
			(layer "F.CrtYd")
		)
		(fp_rect
			(start -0.508 0.9398)
			(end 0.508 -0.9398)
			(stroke
				(width 0)
				(type default)
			)
			(fill no)
			(layer "F.Fab")
		)
		(pad "1" smd custom
			(at 0 -0.4445 180)
			(size 0.1397 0.1397)
			(layers "F.Cu" "F.Mask" "F.Paste")
			(net "USB_EN_2")
			(options
				(clearance outline)
				(anchor circle)
			)
			(primitives
				(gr_poly
					(pts
						(arc
							(start -0.1778 -0.2794)
							(mid -0.249642 -0.249642)
							(end -0.2794 -0.1778)
						)
						(arc
							(start -0.2794 0.1778)
							(mid -0.249642 0.249642)
							(end -0.1778 0.2794)
						)
						(arc
							(start 0.1778 0.2794)
							(mid 0.249642 0.249642)
							(end 0.2794 0.1778)
						)
						(arc
							(start 0.2794 -0.1778)
							(mid 0.249642 -0.249642)
							(end 0.1778 -0.2794)
						)
					)
					(width 0)
					(fill yes)
				)
			)
		)
		(pad "2" smd custom
			(at 0 0.4445 180)
			(size 0.1397 0.1397)
			(layers "F.Cu" "F.Mask" "F.Paste")
			(net "GND")
			(options
				(clearance outline)
				(anchor circle)
			)
			(primitives
				(gr_poly
					(pts
						(arc
							(start -0.1778 -0.2794)
							(mid -0.249642 -0.249642)
							(end -0.2794 -0.1778)
						)
						(arc
							(start -0.2794 0.1778)
							(mid -0.249642 0.249642)
							(end -0.1778 0.2794)
						)
						(arc
							(start 0.1778 0.2794)
							(mid 0.249642 0.249642)
							(end 0.2794 0.1778)
						)
						(arc
							(start 0.2794 -0.1778)
							(mid 0.249642 -0.249642)
							(end 0.1778 -0.2794)
						)
					)
					(width 0)
					(fill yes)
				)
			)
		)
	)
	(footprint ""
		(layer "F.Cu")
		(at 174.5742 -53.152294 -90)
		(property "Reference" "C425"
			(at 0 0 270)
			(layer "F.SilkS")
			(hide yes)
			(effects
				(font
					(size 1.27 1.27)
				)
			)
		)
		(property "Value" "SCD033U25V2KX-GP"
			(at 1.1811 -2.7051 270)
			(unlocked yes)
			(layer "F.Fab")
			(hide yes)
			(effects
				(font
					(size 1.016 1.016)
					(thickness 0.1524)
				)
			)
		)
		(property "Device Type" "C402H22"
			(at 1.1811 -4.2291 270)
			(unlocked yes)
			(layer "F.Fab")
			(hide yes)
			(effects
				(font
					(size 1.016 1.016)
					(thickness 0.1524)
				)
			)
		)
		(duplicate_pad_numbers_are_jumpers no)
		(fp_rect
			(start -0.4318 0.9525)
			(end 0.4318 -0.9525)
			(stroke
				(width 0)
				(type default)
			)
			(fill no)
			(layer "F.CrtYd")
		)
		(fp_rect
			(start -0.4318 0.9525)
			(end 0.4318 -0.9525)
			(stroke
				(width 0)
				(type default)
			)
			(fill no)
			(layer "F.Fab")
		)
		(pad "1" smd custom
			(at 0 -0.4445 270)
			(size 0.1524 0.1524)
			(layers "F.Cu" "F.Mask" "F.Paste")
			(net "SW_HDD_P29")
			(options
				(clearance outline)
				(anchor circle)
			)
			(primitives
				(gr_poly
					(pts
						(arc
							(start 0.3048 -0.2032)
							(mid 0.275042 -0.275042)
							(end 0.2032 -0.3048)
						)
						(arc
							(start -0.2032 -0.3048)
							(mid -0.275042 -0.275042)
							(end -0.3048 -0.2032)
						)
						(arc
							(start -0.3048 0.2032)
							(mid -0.275042 0.275042)
							(end -0.2032 0.3048)
						)
						(arc
							(start 0.2032 0.3048)
							(mid 0.275042 0.275042)
							(end 0.3048 0.2032)
						)
					)
					(width 0)
					(fill yes)
				)
			)
		)
		(pad "2" smd custom
			(at 0 0.4445 270)
			(size 0.1524 0.1524)
			(layers "F.Cu" "F.Mask" "F.Paste")
			(net "GND")
			(options
				(clearance outline)
				(anchor circle)
			)
			(primitives
				(gr_poly
					(pts
						(arc
							(start 0.3048 -0.2032)
							(mid 0.275042 -0.275042)
							(end 0.2032 -0.3048)
						)
						(arc
							(start -0.2032 -0.3048)
							(mid -0.275042 -0.275042)
							(end -0.3048 -0.2032)
						)
						(arc
							(start -0.3048 0.2032)
							(mid -0.275042 0.275042)
							(end -0.2032 0.3048)
						)
						(arc
							(start 0.2032 0.3048)
							(mid 0.275042 0.275042)
							(end 0.3048 0.2032)
						)
					)
					(width 0)
					(fill yes)
				)
			)
		)
	)
	(footprint ""
		(layer "F.Cu")
		(at 256.9718 -238.506 -90)
		(property "Reference" "C30"
			(at 0 0 270)
			(layer "F.SilkS")
			(hide yes)
			(effects
				(font
					(size 1.27 1.27)
				)
			)
		)
		(property "Value" "SCD1U16V2KX-3GP"
			(at 1.1811 -2.7051 270)
			(unlocked yes)
			(layer "F.Fab")
			(hide yes)
			(effects
				(font
					(size 1.016 1.016)
					(thickness 0.1524)
				)
			)
		)
		(property "Device Type" "C402H22"
			(at 1.1811 -4.2291 270)
			(unlocked yes)
			(layer "F.Fab")
			(hide yes)
			(effects
				(font
					(size 1.016 1.016)
					(thickness 0.1524)
				)
			)
		)
		(duplicate_pad_numbers_are_jumpers no)
		(fp_rect
			(start -0.4318 0.9525)
			(end 0.4318 -0.9525)
			(stroke
				(width 0)
				(type default)
			)
			(fill no)
			(layer "F.CrtYd")
		)
		(fp_rect
			(start -0.4318 0.9525)
			(end 0.4318 -0.9525)
			(stroke
				(width 0)
				(type default)
			)
			(fill no)
			(layer "F.Fab")
		)
		(pad "1" smd custom
			(at 0 -0.4445 270)
			(size 0.1524 0.1524)
			(layers "F.Cu" "F.Mask" "F.Paste")
			(net "GPIO_VCC_U9")
			(options
				(clearance outline)
				(anchor circle)
			)
			(primitives
				(gr_poly
					(pts
						(arc
							(start 0.3048 -0.2032)
							(mid 0.275042 -0.275042)
							(end 0.2032 -0.3048)
						)
						(arc
							(start -0.2032 -0.3048)
							(mid -0.275042 -0.275042)
							(end -0.3048 -0.2032)
						)
						(arc
							(start -0.3048 0.2032)
							(mid -0.275042 0.275042)
							(end -0.2032 0.3048)
						)
						(arc
							(start 0.2032 0.3048)
							(mid 0.275042 0.275042)
							(end 0.3048 0.2032)
						)
					)
					(width 0)
					(fill yes)
				)
			)
		)
		(pad "2" smd custom
			(at 0 0.4445 270)
			(size 0.1524 0.1524)
			(layers "F.Cu" "F.Mask" "F.Paste")
			(net "GND")
			(options
				(clearance outline)
				(anchor circle)
			)
			(primitives
				(gr_poly
					(pts
						(arc
							(start 0.3048 -0.2032)
							(mid 0.275042 -0.275042)
							(end 0.2032 -0.3048)
						)
						(arc
							(start -0.2032 -0.3048)
							(mid -0.275042 -0.275042)
							(end -0.3048 -0.2032)
						)
						(arc
							(start -0.3048 0.2032)
							(mid -0.275042 0.275042)
							(end -0.2032 0.3048)
						)
						(arc
							(start 0.2032 0.3048)
							(mid 0.275042 0.275042)
							(end 0.3048 0.2032)
						)
					)
					(width 0)
					(fill yes)
				)
			)
		)
	)
	(footprint ""
		(layer "F.Cu")
		(at 49.349914 -324.39991)
		(property "Reference" "RLED26"
			(at 0 0 0)
			(layer "F.SilkS")
			(hide yes)
			(effects
				(font
					(size 1.27 1.27)
				)
			)
		)
		(property "Value" "LED-BY-19-GP"
			(at -2.132076 1.414018 0)
			(unlocked yes)
			(layer "F.Fab")
			(hide yes)
			(effects
				(font
					(size 1.016 1.016)
					(thickness 0.1524)
				)
			)
		)
		(property "Device Type" "LED-1615-4PH26"
			(at -2.132076 -0.109982 0)
			(unlocked yes)
			(layer "F.Fab")
			(hide yes)
			(effects
				(font
					(size 1.016 1.016)
					(thickness 0.1524)
				)
			)
		)
		(duplicate_pad_numbers_are_jumpers no)
		(fp_line
			(start -1.2954 0.254)
			(end -1.2954 1.6002)
			(stroke
				(width 0.508)
				(type default)
			)
			(layer "F.SilkS")
		)
		(fp_line
			(start -1.2954 1.6002)
			(end 1.2954 1.6002)
			(stroke
				(width 0.508)
				(type default)
			)
			(layer "F.SilkS")
		)
		(fp_line
			(start -1.1176 -1.4224)
			(end 1.1176 -1.4224)
			(stroke
				(width 0.1524)
				(type default)
			)
			(layer "F.SilkS")
		)
		(fp_line
			(start -1.1176 1.4224)
			(end -1.1176 -1.4224)
			(stroke
				(width 0.1524)
				(type default)
			)
			(layer "F.SilkS")
		)
		(fp_line
			(start 1.1176 -1.4224)
			(end 1.1176 1.4224)
			(stroke
				(width 0.1524)
				(type default)
			)
			(layer "F.SilkS")
		)
		(fp_line
			(start 1.1176 1.4224)
			(end -1.1176 1.4224)
			(stroke
				(width 0.1524)
				(type default)
			)
			(layer "F.SilkS")
		)
		(fp_line
			(start 1.2954 1.6002)
			(end 1.2954 0.254)
			(stroke
				(width 0.508)
				(type default)
			)
			(layer "F.SilkS")
		)
		(fp_rect
			(start -0.7493 0.8001)
			(end 0.7493 -0.8001)
			(stroke
				(width 0)
				(type default)
			)
			(fill no)
			(layer "F.CrtYd")
		)
		(fp_poly
			(pts
				(xy -1.3716 1.6764) (xy -1.3716 -1.6764) (xy 1.3716 -1.6764) (xy 1.3716 0.0635) (xy 0.7493 0.0635)
				(xy 0.7493 -0.8001) (xy -0.7493 -0.8001) (xy -0.7493 0.8001) (xy 0.7493 0.8001) (xy 0.7493 0.0762)
				(xy 1.3716 0.0762) (xy 1.3716 1.6764)
			)
			(stroke
				(width 0)
				(type default)
			)
			(fill no)
			(layer "F.CrtYd")
		)
		(fp_rect
			(start -1.3716 1.6764)
			(end 1.3716 -1.6764)
			(stroke
				(width 0)
				(type default)
			)
			(fill no)
			(layer "F.Fab")
		)
		(pad "1" smd rect
			(at 0.50038 -0.73025)
			(size 0.7112 0.8636)
			(layers "F.Cu" "F.Mask" "F.Paste")
			(net "DRV_ACT_25")
		)
		(pad "2" smd rect
			(at -0.50038 -0.73025)
			(size 0.7112 0.8636)
			(layers "F.Cu" "F.Mask" "F.Paste")
			(net "FLT_HDD25")
		)
		(pad "3" smd rect
			(at 0.50038 0.73025)
			(size 0.7112 0.8636)
			(layers "F.Cu" "F.Mask" "F.Paste")
			(net "DRV_ACT_25_N")
		)
		(pad "4" smd rect
			(at -0.50038 0.73025)
			(size 0.7112 0.8636)
			(layers "F.Cu" "F.Mask" "F.Paste")
			(net "FLT_HDD25_N")
		)
	)
	(footprint ""
		(layer "F.Cu")
		(at 224.553526 -149.120098 -90)
		(property "Reference" "TP225"
			(at 0 0 270)
			(layer "F.SilkS")
			(hide yes)
			(effects
				(font
					(size 1.27 1.27)
				)
			)
		)
		(property "Value" "TPAD32-GP"
			(at -0.0508 -1.6764 270)
			(unlocked yes)
			(layer "F.Fab")
			(hide yes)
			(effects
				(font
					(size 1.016 1.016)
					(thickness 0.1524)
				)
			)
		)
		(property "Device Type" "TPAD32"
			(at -0.0508 -3.2004 270)
			(unlocked yes)
			(layer "F.Fab")
			(hide yes)
			(effects
				(font
					(size 1.016 1.016)
					(thickness 0.1524)
				)
			)
		)
		(duplicate_pad_numbers_are_jumpers no)
		(fp_poly
			(pts
				(arc
					(start 0 -0.4064)
					(mid 0 0.4064)
					(end 0 -0.4064)
				)
			)
			(stroke
				(width 0)
				(type default)
			)
			(fill no)
			(layer "F.CrtYd")
		)
		(fp_poly
			(pts
				(arc
					(start 0 -0.7112)
					(mid 0 0.7112)
					(end 0 -0.7112)
				)
			)
			(stroke
				(width 0)
				(type default)
			)
			(fill no)
			(layer "F.Fab")
		)
		(pad "1" smd circle
			(at 0 0 270)
			(size 0.8128 0.8128)
			(layers "F.Cu" "F.Mask" "F.Paste")
			(net "TP_SMB_COMP_A_NIC_SDA")
		)
	)
	(footprint ""
		(layer "F.Cu")
		(at 399.14195 -163.300918 90)
		(property "Reference" "D20"
			(at 0 0 90)
			(layer "F.SilkS")
			(hide yes)
			(effects
				(font
					(size 1.27 1.27)
				)
			)
		)
		(property "Value" "RB551V30-GP"
			(at 0 -6.7818 90)
			(unlocked yes)
			(layer "F.Fab")
			(hide yes)
			(effects
				(font
					(size 1.016 1.016)
					(thickness 0.1524)
				)
			)
		)
		(property "Device Type" "SOD323AKH38"
			(at 0 -8.6868 90)
			(unlocked yes)
			(layer "F.Fab")
			(hide yes)
			(effects
				(font
					(size 1.016 1.016)
					(thickness 0.1524)
				)
			)
		)
		(duplicate_pad_numbers_are_jumpers no)
		(fp_line
			(start 0.889 -1.9304)
			(end 0.889 2.159)
			(stroke
				(width 0.1524)
				(type default)
			)
			(layer "F.SilkS")
		)
		(fp_line
			(start -0.889 -1.9304)
			(end 0.889 -1.9304)
			(stroke
				(width 0.1524)
				(type default)
			)
			(layer "F.SilkS")
		)
		(fp_line
			(start 0.762 2.0574)
			(end -0.762 2.0574)
			(stroke
				(width 0.508)
				(type default)
			)
			(layer "F.SilkS")
		)
		(fp_line
			(start 0.889 2.159)
			(end -0.889 2.159)
			(stroke
				(width 0.1524)
				(type default)
			)
			(layer "F.SilkS")
		)
		(fp_line
			(start -0.889 2.159)
			(end -0.889 -1.9304)
			(stroke
				(width 0.1524)
				(type default)
			)
			(layer "F.SilkS")
		)
		(fp_rect
			(start -1.016 2.3114)
			(end 1.016 -2.0066)
			(stroke
				(width 0)
				(type default)
			)
			(fill no)
			(layer "F.CrtYd")
		)
		(fp_poly
			(pts
				(xy -1.016 -2.0066) (xy 1.016 -2.0066) (xy 1.016 2.3114) (xy -1.016 2.3114)
			)
			(stroke
				(width 0)
				(type default)
			)
			(fill no)
			(layer "F.Fab")
		)
		(pad "A" smd rect
			(at 0 -1.143 90)
			(size 0.5588 1.016)
			(layers "F.Cu" "F.Mask" "F.Paste")
			(net "SW_HDD_R20")
		)
		(pad "K" smd rect
			(at 0 1.143 90)
			(size 0.5588 1.016)
			(layers "F.Cu" "F.Mask" "F.Paste")
			(net "SW_HDD_N20")
		)
	)
	(footprint ""
		(layer "F.Cu")
		(at 455.203052 -246.047006 -90)
		(property "Reference" "R496"
			(at 0 0 270)
			(layer "F.SilkS")
			(hide yes)
			(effects
				(font
					(size 1.27 1.27)
				)
			)
		)
		(property "Value" "4K7R2J-2-GP"
			(at 0.064008 -3.993896 270)
			(unlocked yes)
			(layer "F.Fab")
			(hide yes)
			(effects
				(font
					(size 1.016 1.016)
					(thickness 0.1524)
				)
			)
		)
		(property "Device Type" "R402H16"
			(at 0.064008 -5.517896 270)
			(unlocked yes)
			(layer "F.Fab")
			(hide yes)
			(effects
				(font
					(size 1.016 1.016)
					(thickness 0.1524)
				)
			)
		)
		(duplicate_pad_numbers_are_jumpers no)
		(fp_line
			(start -0.508 -0.9398)
			(end -0.508 0.9398)
			(stroke
				(width 0.1524)
				(type default)
			)
			(layer "F.SilkS")
		)
		(fp_line
			(start 0.508 -0.9398)
			(end -0.508 -0.9398)
			(stroke
				(width 0.1524)
				(type default)
			)
			(layer "F.SilkS")
		)
		(fp_rect
			(start -0.508 0.9398)
			(end 0.508 -0.9398)
			(stroke
				(width 0)
				(type default)
			)
			(fill no)
			(layer "F.CrtYd")
		)
		(fp_rect
			(start -0.508 0.9398)
			(end 0.508 -0.9398)
			(stroke
				(width 0)
				(type default)
			)
			(fill no)
			(layer "F.Fab")
		)
		(pad "1" smd custom
			(at 0 -0.4445 270)
			(size 0.1397 0.1397)
			(layers "F.Cu" "F.Mask" "F.Paste")
			(net "DRIVE_A_11_ACT")
			(options
				(clearance outline)
				(anchor circle)
			)
			(primitives
				(gr_poly
					(pts
						(arc
							(start -0.1778 -0.2794)
							(mid -0.249642 -0.249642)
							(end -0.2794 -0.1778)
						)
						(arc
							(start -0.2794 0.1778)
							(mid -0.249642 0.249642)
							(end -0.1778 0.2794)
						)
						(arc
							(start 0.1778 0.2794)
							(mid 0.249642 0.249642)
							(end 0.2794 0.1778)
						)
						(arc
							(start 0.2794 -0.1778)
							(mid 0.249642 -0.249642)
							(end 0.1778 -0.2794)
						)
					)
					(width 0)
					(fill yes)
				)
			)
		)
		(pad "2" smd custom
			(at 0 0.4445 270)
			(size 0.1397 0.1397)
			(layers "F.Cu" "F.Mask" "F.Paste")
			(net "GND")
			(options
				(clearance outline)
				(anchor circle)
			)
			(primitives
				(gr_poly
					(pts
						(arc
							(start -0.1778 -0.2794)
							(mid -0.249642 -0.249642)
							(end -0.2794 -0.1778)
						)
						(arc
							(start -0.2794 0.1778)
							(mid -0.249642 0.249642)
							(end -0.1778 0.2794)
						)
						(arc
							(start 0.1778 0.2794)
							(mid 0.249642 0.249642)
							(end 0.2794 0.1778)
						)
						(arc
							(start 0.2794 -0.1778)
							(mid 0.249642 -0.249642)
							(end 0.1778 -0.2794)
						)
					)
					(width 0)
					(fill yes)
				)
			)
		)
	)
	(footprint ""
		(layer "F.Cu")
		(at 257.994912 -230.251)
		(property "Reference" "R434"
			(at 0 0 0)
			(layer "F.SilkS")
			(hide yes)
			(effects
				(font
					(size 1.27 1.27)
				)
			)
		)
		(property "Value" "1KR2F-3-GP"
			(at 0.064008 -3.993896 0)
			(unlocked yes)
			(layer "F.Fab")
			(hide yes)
			(effects
				(font
					(size 1.016 1.016)
					(thickness 0.1524)
				)
			)
		)
		(property "Device Type" "R402H16"
			(at 0.064008 -5.517896 0)
			(unlocked yes)
			(layer "F.Fab")
			(hide yes)
			(effects
				(font
					(size 1.016 1.016)
					(thickness 0.1524)
				)
			)
		)
		(duplicate_pad_numbers_are_jumpers no)
		(fp_line
			(start -0.508 -0.9398)
			(end -0.508 0.9398)
			(stroke
				(width 0.1524)
				(type default)
			)
			(layer "F.SilkS")
		)
		(fp_line
			(start 0.508 -0.9398)
			(end -0.508 -0.9398)
			(stroke
				(width 0.1524)
				(type default)
			)
			(layer "F.SilkS")
		)
		(fp_rect
			(start -0.508 0.9398)
			(end 0.508 -0.9398)
			(stroke
				(width 0)
				(type default)
			)
			(fill no)
			(layer "F.CrtYd")
		)
		(fp_rect
			(start -0.508 0.9398)
			(end 0.508 -0.9398)
			(stroke
				(width 0)
				(type default)
			)
			(fill no)
			(layer "F.Fab")
		)
		(pad "1" smd custom
			(at 0 -0.4445)
			(size 0.1397 0.1397)
			(layers "F.Cu" "F.Mask" "F.Paste")
			(net "P3V3_STBY_A")
			(options
				(clearance outline)
				(anchor circle)
			)
			(primitives
				(gr_poly
					(pts
						(arc
							(start -0.1778 -0.2794)
							(mid -0.249642 -0.249642)
							(end -0.2794 -0.1778)
						)
						(arc
							(start -0.2794 0.1778)
							(mid -0.249642 0.249642)
							(end -0.1778 0.2794)
						)
						(arc
							(start 0.1778 0.2794)
							(mid 0.249642 0.249642)
							(end 0.2794 0.1778)
						)
						(arc
							(start 0.2794 -0.1778)
							(mid 0.249642 -0.249642)
							(end 0.1778 -0.2794)
						)
					)
					(width 0)
					(fill yes)
				)
			)
		)
		(pad "2" smd custom
			(at 0 0.4445)
			(size 0.1397 0.1397)
			(layers "F.Cu" "F.Mask" "F.Paste")
			(net "I2C_DRIVE_A_PWR_SCL")
			(options
				(clearance outline)
				(anchor circle)
			)
			(primitives
				(gr_poly
					(pts
						(arc
							(start -0.1778 -0.2794)
							(mid -0.249642 -0.249642)
							(end -0.2794 -0.1778)
						)
						(arc
							(start -0.2794 0.1778)
							(mid -0.249642 0.249642)
							(end -0.1778 0.2794)
						)
						(arc
							(start 0.1778 0.2794)
							(mid 0.249642 0.249642)
							(end 0.2794 0.1778)
						)
						(arc
							(start 0.2794 -0.1778)
							(mid 0.249642 -0.249642)
							(end 0.1778 -0.2794)
						)
					)
					(width 0)
					(fill yes)
				)
			)
		)
	)
	(footprint ""
		(layer "F.Cu")
		(at 412.956502 -286.530034 90)
		(property "Reference" "R593"
			(at 0 0 90)
			(layer "F.SilkS")
			(hide yes)
			(effects
				(font
					(size 1.27 1.27)
				)
			)
		)
		(property "Value" "4K7R2J-2-GP"
			(at 0.064008 -3.993896 90)
			(unlocked yes)
			(layer "F.Fab")
			(hide yes)
			(effects
				(font
					(size 1.016 1.016)
					(thickness 0.1524)
				)
			)
		)
		(property "Device Type" "R402H16"
			(at 0.064008 -5.517896 90)
			(unlocked yes)
			(layer "F.Fab")
			(hide yes)
			(effects
				(font
					(size 1.016 1.016)
					(thickness 0.1524)
				)
			)
		)
		(duplicate_pad_numbers_are_jumpers no)
		(fp_line
			(start 0.508 -0.9398)
			(end -0.508 -0.9398)
			(stroke
				(width 0.1524)
				(type default)
			)
			(layer "F.SilkS")
		)
		(fp_line
			(start -0.508 -0.9398)
			(end -0.508 0.9398)
			(stroke
				(width 0.1524)
				(type default)
			)
			(layer "F.SilkS")
		)
		(fp_rect
			(start -0.508 0.9398)
			(end 0.508 -0.9398)
			(stroke
				(width 0)
				(type default)
			)
			(fill no)
			(layer "F.CrtYd")
		)
		(fp_rect
			(start -0.508 0.9398)
			(end 0.508 -0.9398)
			(stroke
				(width 0)
				(type default)
			)
			(fill no)
			(layer "F.Fab")
		)
		(pad "1" smd custom
			(at 0 -0.4445 90)
			(size 0.1397 0.1397)
			(layers "F.Cu" "F.Mask" "F.Paste")
			(net "DRIVE_B_33_FLT_LED")
			(options
				(clearance outline)
				(anchor circle)
			)
			(primitives
				(gr_poly
					(pts
						(arc
							(start -0.1778 -0.2794)
							(mid -0.249642 -0.249642)
							(end -0.2794 -0.1778)
						)
						(arc
							(start -0.2794 0.1778)
							(mid -0.249642 0.249642)
							(end -0.1778 0.2794)
						)
						(arc
							(start 0.1778 0.2794)
							(mid 0.249642 0.249642)
							(end 0.2794 0.1778)
						)
						(arc
							(start 0.2794 -0.1778)
							(mid 0.249642 -0.249642)
							(end 0.1778 -0.2794)
						)
					)
					(width 0)
					(fill yes)
				)
			)
		)
		(pad "2" smd custom
			(at 0 0.4445 90)
			(size 0.1397 0.1397)
			(layers "F.Cu" "F.Mask" "F.Paste")
			(net "GND")
			(options
				(clearance outline)
				(anchor circle)
			)
			(primitives
				(gr_poly
					(pts
						(arc
							(start -0.1778 -0.2794)
							(mid -0.249642 -0.249642)
							(end -0.2794 -0.1778)
						)
						(arc
							(start -0.2794 0.1778)
							(mid -0.249642 0.249642)
							(end -0.1778 0.2794)
						)
						(arc
							(start 0.1778 0.2794)
							(mid 0.249642 0.249642)
							(end 0.2794 0.1778)
						)
						(arc
							(start 0.2794 -0.1778)
							(mid 0.249642 -0.249642)
							(end 0.1778 -0.2794)
						)
					)
					(width 0)
					(fill yes)
				)
			)
		)
	)
	(footprint ""
		(layer "F.Cu")
		(at 133.228842 -181.42712 90)
		(property "Reference" "R470"
			(at 0 0 90)
			(layer "F.SilkS")
			(hide yes)
			(effects
				(font
					(size 1.27 1.27)
				)
			)
		)
		(property "Value" "4K7R2J-2-GP"
			(at 0.064008 -3.993896 90)
			(unlocked yes)
			(layer "F.Fab")
			(hide yes)
			(effects
				(font
					(size 1.016 1.016)
					(thickness 0.1524)
				)
			)
		)
		(property "Device Type" "R402H16"
			(at 0.064008 -5.517896 90)
			(unlocked yes)
			(layer "F.Fab")
			(hide yes)
			(effects
				(font
					(size 1.016 1.016)
					(thickness 0.1524)
				)
			)
		)
		(duplicate_pad_numbers_are_jumpers no)
		(fp_line
			(start 0.508 -0.9398)
			(end -0.508 -0.9398)
			(stroke
				(width 0.1524)
				(type default)
			)
			(layer "F.SilkS")
		)
		(fp_line
			(start -0.508 -0.9398)
			(end -0.508 0.9398)
			(stroke
				(width 0.1524)
				(type default)
			)
			(layer "F.SilkS")
		)
		(fp_rect
			(start -0.508 0.9398)
			(end 0.508 -0.9398)
			(stroke
				(width 0)
				(type default)
			)
			(fill no)
			(layer "F.CrtYd")
		)
		(fp_rect
			(start -0.508 0.9398)
			(end 0.508 -0.9398)
			(stroke
				(width 0)
				(type default)
			)
			(fill no)
			(layer "F.Fab")
		)
		(pad "1" smd custom
			(at 0 -0.4445 90)
			(size 0.1397 0.1397)
			(layers "F.Cu" "F.Mask" "F.Paste")
			(net "DRIVE_A_4_ACT")
			(options
				(clearance outline)
				(anchor circle)
			)
			(primitives
				(gr_poly
					(pts
						(arc
							(start -0.1778 -0.2794)
							(mid -0.249642 -0.249642)
							(end -0.2794 -0.1778)
						)
						(arc
							(start -0.2794 0.1778)
							(mid -0.249642 0.249642)
							(end -0.1778 0.2794)
						)
						(arc
							(start 0.1778 0.2794)
							(mid 0.249642 0.249642)
							(end 0.2794 0.1778)
						)
						(arc
							(start 0.2794 -0.1778)
							(mid 0.249642 -0.249642)
							(end 0.1778 -0.2794)
						)
					)
					(width 0)
					(fill yes)
				)
			)
		)
		(pad "2" smd custom
			(at 0 0.4445 90)
			(size 0.1397 0.1397)
			(layers "F.Cu" "F.Mask" "F.Paste")
			(net "GND")
			(options
				(clearance outline)
				(anchor circle)
			)
			(primitives
				(gr_poly
					(pts
						(arc
							(start -0.1778 -0.2794)
							(mid -0.249642 -0.249642)
							(end -0.2794 -0.1778)
						)
						(arc
							(start -0.2794 0.1778)
							(mid -0.249642 0.249642)
							(end -0.1778 0.2794)
						)
						(arc
							(start 0.1778 0.2794)
							(mid 0.249642 0.249642)
							(end 0.2794 0.1778)
						)
						(arc
							(start 0.2794 -0.1778)
							(mid 0.249642 -0.249642)
							(end 0.1778 -0.2794)
						)
					)
					(width 0)
					(fill yes)
				)
			)
		)
	)
	(footprint ""
		(layer "F.Cu")
		(at 332.105 -157.585918)
		(property "Reference" "R556"
			(at 0 0 0)
			(layer "F.SilkS")
			(hide yes)
			(effects
				(font
					(size 1.27 1.27)
				)
			)
		)
		(property "Value" "4K7R2J-2-GP"
			(at 0.064008 -3.993896 0)
			(unlocked yes)
			(layer "F.Fab")
			(hide yes)
			(effects
				(font
					(size 1.016 1.016)
					(thickness 0.1524)
				)
			)
		)
		(property "Device Type" "R402H16"
			(at 0.064008 -5.517896 0)
			(unlocked yes)
			(layer "F.Fab")
			(hide yes)
			(effects
				(font
					(size 1.016 1.016)
					(thickness 0.1524)
				)
			)
		)
		(duplicate_pad_numbers_are_jumpers no)
		(fp_line
			(start -0.508 -0.9398)
			(end -0.508 0.9398)
			(stroke
				(width 0.1524)
				(type default)
			)
			(layer "F.SilkS")
		)
		(fp_line
			(start 0.508 -0.9398)
			(end -0.508 -0.9398)
			(stroke
				(width 0.1524)
				(type default)
			)
			(layer "F.SilkS")
		)
		(fp_rect
			(start -0.508 0.9398)
			(end 0.508 -0.9398)
			(stroke
				(width 0)
				(type default)
			)
			(fill no)
			(layer "F.CrtYd")
		)
		(fp_rect
			(start -0.508 0.9398)
			(end 0.508 -0.9398)
			(stroke
				(width 0)
				(type default)
			)
			(fill no)
			(layer "F.Fab")
		)
		(pad "1" smd custom
			(at 0 -0.4445)
			(size 0.1397 0.1397)
			(layers "F.Cu" "F.Mask" "F.Paste")
			(net "SW_PWR_R_HDD18")
			(options
				(clearance outline)
				(anchor circle)
			)
			(primitives
				(gr_poly
					(pts
						(arc
							(start -0.1778 -0.2794)
							(mid -0.249642 -0.249642)
							(end -0.2794 -0.1778)
						)
						(arc
							(start -0.2794 0.1778)
							(mid -0.249642 0.249642)
							(end -0.1778 0.2794)
						)
						(arc
							(start 0.1778 0.2794)
							(mid 0.249642 0.249642)
							(end 0.2794 0.1778)
						)
						(arc
							(start 0.2794 -0.1778)
							(mid 0.249642 -0.249642)
							(end 0.1778 -0.2794)
						)
					)
					(width 0)
					(fill yes)
				)
			)
		)
		(pad "2" smd custom
			(at 0 0.4445)
			(size 0.1397 0.1397)
			(layers "F.Cu" "F.Mask" "F.Paste")
			(net "GND")
			(options
				(clearance outline)
				(anchor circle)
			)
			(primitives
				(gr_poly
					(pts
						(arc
							(start -0.1778 -0.2794)
							(mid -0.249642 -0.249642)
							(end -0.2794 -0.1778)
						)
						(arc
							(start -0.2794 0.1778)
							(mid -0.249642 0.249642)
							(end -0.1778 0.2794)
						)
						(arc
							(start 0.1778 0.2794)
							(mid 0.249642 0.249642)
							(end 0.2794 0.1778)
						)
						(arc
							(start 0.2794 -0.1778)
							(mid 0.249642 -0.249642)
							(end 0.1778 -0.2794)
						)
					)
					(width 0)
					(fill yes)
				)
			)
		)
	)
	(footprint ""
		(layer "F.Cu")
		(at 146.884898 -55.285894 180)
		(property "Reference" "Q168"
			(at 0 0 180)
			(layer "F.SilkS")
			(hide yes)
			(effects
				(font
					(size 1.27 1.27)
				)
			)
		)
		(property "Value" "AO4406AL-GP"
			(at -3.707384 -1.5367 180)
			(unlocked yes)
			(layer "F.Fab")
			(hide yes)
			(effects
				(font
					(size 1.016 1.016)
					(thickness 0.1524)
				)
			)
		)
		(property "Device Type" "SOIC8H69"
			(at -3.707384 -3.0607 180)
			(unlocked yes)
			(layer "F.Fab")
			(hide yes)
			(effects
				(font
					(size 1.016 1.016)
					(thickness 0.1524)
				)
			)
		)
		(duplicate_pad_numbers_are_jumpers no)
		(fp_line
			(start 2.1336 1.4224)
			(end 2.1336 -1.4224)
			(stroke
				(width 0.1524)
				(type default)
			)
			(layer "F.SilkS")
		)
		(fp_line
			(start 2.1336 -1.4224)
			(end -2.7432 -1.4224)
			(stroke
				(width 0.1524)
				(type default)
			)
			(layer "F.SilkS")
		)
		(fp_line
			(start -2.1844 -0.0508)
			(end -2.7178 0.508)
			(stroke
				(width 0.1524)
				(type default)
			)
			(layer "F.SilkS")
		)
		(fp_line
			(start -2.6289 3.4417)
			(end -2.6289 1.4732)
			(stroke
				(width 0.381)
				(type default)
			)
			(layer "F.SilkS")
		)
		(fp_line
			(start -2.7178 -0.508)
			(end -2.1844 -0.0508)
			(stroke
				(width 0.1524)
				(type default)
			)
			(layer "F.SilkS")
		)
		(fp_line
			(start -2.7432 1.4224)
			(end 2.1336 1.4224)
			(stroke
				(width 0.1524)
				(type default)
			)
			(layer "F.SilkS")
		)
		(fp_line
			(start -2.7432 1.4224)
			(end -2.6416 1.4224)
			(stroke
				(width 0.1524)
				(type default)
			)
			(layer "F.SilkS")
		)
		(fp_line
			(start -2.7432 -1.4224)
			(end -2.7432 1.4224)
			(stroke
				(width 0.1524)
				(type default)
			)
			(layer "F.SilkS")
		)
		(fp_poly
			(pts
				(xy -2.2098 -1.4224) (xy -2.2098 1.4224) (xy 2.2098 1.4224) (xy 2.2098 -1.4224)
			)
			(stroke
				(width 0)
				(type default)
			)
			(fill yes)
			(layer "F.SilkS")
		)
		(fp_rect
			(start -2.450084 2.999994)
			(end 2.450084 -2.999994)
			(stroke
				(width 0)
				(type default)
			)
			(fill no)
			(layer "F.CrtYd")
		)
		(fp_poly
			(pts
				(xy -2.8194 3.6322) (xy -2.8194 -3.6322) (xy 2.8194 -3.6322) (xy 2.8194 1.18364) (xy 2.450084 1.18364)
				(xy 2.450084 -2.999994) (xy -2.450084 -2.999994) (xy -2.450084 2.999994) (xy 2.450084 2.999994)
				(xy 2.450084 1.18618) (xy 2.8194 1.18618) (xy 2.8194 3.6322)
			)
			(stroke
				(width 0)
				(type default)
			)
			(fill no)
			(layer "F.CrtYd")
		)
		(fp_rect
			(start -2.8194 3.6322)
			(end 2.8194 -3.6322)
			(stroke
				(width 0)
				(type default)
			)
			(fill no)
			(layer "F.Fab")
		)
		(pad "1" smd rect
			(at -1.905 2.54 180)
			(size 0.635 1.651)
			(layers "F.Cu" "F.Mask" "F.Paste")
			(net "P5V_HDD28")
		)
		(pad "2" smd rect
			(at -0.635 2.54 180)
			(size 0.635 1.651)
			(layers "F.Cu" "F.Mask" "F.Paste")
			(net "P5V_HDD28")
		)
		(pad "3" smd rect
			(at 0.635 2.54 180)
			(size 0.635 1.651)
			(layers "F.Cu" "F.Mask" "F.Paste")
			(net "P5V_HDD28")
		)
		(pad "4" smd rect
			(at 1.905 2.54 180)
			(size 0.635 1.651)
			(layers "F.Cu" "F.Mask" "F.Paste")
			(net "SW_HDD_P28")
		)
		(pad "5" smd rect
			(at 1.905 -2.54 180)
			(size 0.635 1.651)
			(layers "F.Cu" "F.Mask" "F.Paste")
			(net "P5V_A_2")
		)
		(pad "6" smd rect
			(at 0.635 -2.54 180)
			(size 0.635 1.651)
			(layers "F.Cu" "F.Mask" "F.Paste")
			(net "P5V_A_2")
		)
		(pad "7" smd rect
			(at -0.635 -2.54 180)
			(size 0.635 1.651)
			(layers "F.Cu" "F.Mask" "F.Paste")
			(net "P5V_A_2")
		)
		(pad "8" smd rect
			(at -1.905 -2.54 180)
			(size 0.635 1.651)
			(layers "F.Cu" "F.Mask" "F.Paste")
			(net "P5V_A_2")
		)
	)
	(footprint ""
		(layer "F.Cu")
		(at 461.9879 -157.585918 180)
		(property "Reference" "R647"
			(at 0 0 180)
			(layer "F.SilkS")
			(hide yes)
			(effects
				(font
					(size 1.27 1.27)
				)
			)
		)
		(property "Value" "0R2J-2-GP"
			(at 0.064008 -3.993896 180)
			(unlocked yes)
			(layer "F.Fab")
			(hide yes)
			(effects
				(font
					(size 1.016 1.016)
					(thickness 0.1524)
				)
			)
		)
		(property "Device Type" "R402H16"
			(at 0.064008 -5.517896 180)
			(unlocked yes)
			(layer "F.Fab")
			(hide yes)
			(effects
				(font
					(size 1.016 1.016)
					(thickness 0.1524)
				)
			)
		)
		(duplicate_pad_numbers_are_jumpers no)
		(fp_line
			(start 0.508 -0.9398)
			(end -0.508 -0.9398)
			(stroke
				(width 0.1524)
				(type default)
			)
			(layer "F.SilkS")
		)
		(fp_line
			(start -0.508 -0.9398)
			(end -0.508 0.9398)
			(stroke
				(width 0.1524)
				(type default)
			)
			(layer "F.SilkS")
		)
		(fp_rect
			(start -0.508 0.9398)
			(end 0.508 -0.9398)
			(stroke
				(width 0)
				(type default)
			)
			(fill no)
			(layer "F.CrtYd")
		)
		(fp_rect
			(start -0.508 0.9398)
			(end 0.508 -0.9398)
			(stroke
				(width 0)
				(type default)
			)
			(fill no)
			(layer "F.Fab")
		)
		(pad "1" smd custom
			(at 0 -0.4445 180)
			(size 0.1397 0.1397)
			(layers "F.Cu" "F.Mask" "F.Paste")
			(net "DRIVE_A_22_PWR")
			(options
				(clearance outline)
				(anchor circle)
			)
			(primitives
				(gr_poly
					(pts
						(arc
							(start -0.1778 -0.2794)
							(mid -0.249642 -0.249642)
							(end -0.2794 -0.1778)
						)
						(arc
							(start -0.2794 0.1778)
							(mid -0.249642 0.249642)
							(end -0.1778 0.2794)
						)
						(arc
							(start 0.1778 0.2794)
							(mid 0.249642 0.249642)
							(end 0.2794 0.1778)
						)
						(arc
							(start 0.2794 -0.1778)
							(mid 0.249642 -0.249642)
							(end 0.1778 -0.2794)
						)
					)
					(width 0)
					(fill yes)
				)
			)
		)
		(pad "2" smd custom
			(at 0 0.4445 180)
			(size 0.1397 0.1397)
			(layers "F.Cu" "F.Mask" "F.Paste")
			(net "SW_PWR_R_HDD22")
			(options
				(clearance outline)
				(anchor circle)
			)
			(primitives
				(gr_poly
					(pts
						(arc
							(start -0.1778 -0.2794)
							(mid -0.249642 -0.249642)
							(end -0.2794 -0.1778)
						)
						(arc
							(start -0.2794 0.1778)
							(mid -0.249642 0.249642)
							(end -0.1778 0.2794)
						)
						(arc
							(start 0.1778 0.2794)
							(mid 0.249642 0.249642)
							(end 0.2794 0.1778)
						)
						(arc
							(start 0.2794 -0.1778)
							(mid 0.249642 -0.249642)
							(end 0.1778 -0.2794)
						)
					)
					(width 0)
					(fill yes)
				)
			)
		)
	)
	(footprint ""
		(layer "F.Cu")
		(at 303.816766 -261.373874 -90)
		(property "Reference" "R448"
			(at 0 0 270)
			(layer "F.SilkS")
			(hide yes)
			(effects
				(font
					(size 1.27 1.27)
				)
			)
		)
		(property "Value" "1KR2F-3-GP"
			(at 0.064008 -3.993896 270)
			(unlocked yes)
			(layer "F.Fab")
			(hide yes)
			(effects
				(font
					(size 1.016 1.016)
					(thickness 0.1524)
				)
			)
		)
		(property "Device Type" "R402H16"
			(at 0.064008 -5.517896 270)
			(unlocked yes)
			(layer "F.Fab")
			(hide yes)
			(effects
				(font
					(size 1.016 1.016)
					(thickness 0.1524)
				)
			)
		)
		(duplicate_pad_numbers_are_jumpers no)
		(fp_line
			(start -0.508 -0.9398)
			(end -0.508 0.9398)
			(stroke
				(width 0.1524)
				(type default)
			)
			(layer "F.SilkS")
		)
		(fp_line
			(start 0.508 -0.9398)
			(end -0.508 -0.9398)
			(stroke
				(width 0.1524)
				(type default)
			)
			(layer "F.SilkS")
		)
		(fp_rect
			(start -0.508 0.9398)
			(end 0.508 -0.9398)
			(stroke
				(width 0)
				(type default)
			)
			(fill no)
			(layer "F.CrtYd")
		)
		(fp_rect
			(start -0.508 0.9398)
			(end 0.508 -0.9398)
			(stroke
				(width 0)
				(type default)
			)
			(fill no)
			(layer "F.Fab")
		)
		(pad "1" smd custom
			(at 0 -0.4445 270)
			(size 0.1397 0.1397)
			(layers "F.Cu" "F.Mask" "F.Paste")
			(net "P3V3_STBY_A")
			(options
				(clearance outline)
				(anchor circle)
			)
			(primitives
				(gr_poly
					(pts
						(arc
							(start -0.1778 -0.2794)
							(mid -0.249642 -0.249642)
							(end -0.2794 -0.1778)
						)
						(arc
							(start -0.2794 0.1778)
							(mid -0.249642 0.249642)
							(end -0.1778 0.2794)
						)
						(arc
							(start 0.1778 0.2794)
							(mid 0.249642 0.249642)
							(end 0.2794 0.1778)
						)
						(arc
							(start 0.2794 -0.1778)
							(mid 0.249642 -0.249642)
							(end 0.1778 -0.2794)
						)
					)
					(width 0)
					(fill yes)
				)
			)
		)
		(pad "2" smd custom
			(at 0 0.4445 270)
			(size 0.1397 0.1397)
			(layers "F.Cu" "F.Mask" "F.Paste")
			(net "I2C_BMC_B_EXP_A_SCL")
			(options
				(clearance outline)
				(anchor circle)
			)
			(primitives
				(gr_poly
					(pts
						(arc
							(start -0.1778 -0.2794)
							(mid -0.249642 -0.249642)
							(end -0.2794 -0.1778)
						)
						(arc
							(start -0.2794 0.1778)
							(mid -0.249642 0.249642)
							(end -0.1778 0.2794)
						)
						(arc
							(start 0.1778 0.2794)
							(mid 0.249642 0.249642)
							(end 0.2794 0.1778)
						)
						(arc
							(start 0.2794 -0.1778)
							(mid 0.249642 -0.249642)
							(end 0.1778 -0.2794)
						)
					)
					(width 0)
					(fill yes)
				)
			)
		)
	)
	(footprint ""
		(layer "F.Cu")
		(at 329.819 -304.335942 180)
		(property "Reference" "C125"
			(at 0 0 180)
			(layer "F.SilkS")
			(hide yes)
			(effects
				(font
					(size 1.27 1.27)
				)
			)
		)
		(property "Value" "SC1U25V3KX-GP"
			(at 0 -2.8194 180)
			(unlocked yes)
			(layer "F.Fab")
			(hide yes)
			(effects
				(font
					(size 1.016 1.016)
					(thickness 0.1524)
				)
			)
		)
		(property "Device Type" "C603H36"
			(at 0 -4.3434 180)
			(unlocked yes)
			(layer "F.Fab")
			(hide yes)
			(effects
				(font
					(size 1.016 1.016)
					(thickness 0.1524)
				)
			)
		)
		(duplicate_pad_numbers_are_jumpers no)
		(fp_line
			(start 0.508 0)
			(end -0.508 0)
			(stroke
				(width 0.2032)
				(type default)
			)
			(layer "F.SilkS")
		)
		(fp_rect
			(start -0.5842 1.3335)
			(end 0.5842 -1.3335)
			(stroke
				(width 0)
				(type default)
			)
			(fill no)
			(layer "F.CrtYd")
		)
		(fp_rect
			(start -0.5842 1.3335)
			(end 0.5842 -1.3335)
			(stroke
				(width 0)
				(type default)
			)
			(fill no)
			(layer "F.Fab")
		)
		(pad "1" smd custom
			(at 0 -0.762 180)
			(size 0.2159 0.2159)
			(layers "F.Cu" "F.Mask" "F.Paste")
			(net "P12V_HDD6")
			(options
				(clearance outline)
				(anchor circle)
			)
			(primitives
				(gr_poly
					(pts
						(arc
							(start -0.3302 -0.4318)
							(mid -0.402042 -0.402042)
							(end -0.4318 -0.3302)
						)
						(arc
							(start -0.4318 0.3302)
							(mid -0.402042 0.402042)
							(end -0.3302 0.4318)
						)
						(arc
							(start 0.3302 0.4318)
							(mid 0.402042 0.402042)
							(end 0.4318 0.3302)
						)
						(arc
							(start 0.4318 -0.3302)
							(mid 0.402042 -0.402042)
							(end 0.3302 -0.4318)
						)
					)
					(width 0)
					(fill yes)
				)
			)
		)
		(pad "2" smd custom
			(at 0 0.762 180)
			(size 0.2159 0.2159)
			(layers "F.Cu" "F.Mask" "F.Paste")
			(net "GND")
			(options
				(clearance outline)
				(anchor circle)
			)
			(primitives
				(gr_poly
					(pts
						(arc
							(start -0.3302 -0.4318)
							(mid -0.402042 -0.402042)
							(end -0.4318 -0.3302)
						)
						(arc
							(start -0.4318 0.3302)
							(mid -0.402042 0.402042)
							(end -0.3302 0.4318)
						)
						(arc
							(start 0.3302 0.4318)
							(mid 0.402042 0.402042)
							(end 0.4318 0.3302)
						)
						(arc
							(start 0.4318 -0.3302)
							(mid 0.402042 -0.402042)
							(end 0.3302 -0.4318)
						)
					)
					(width 0)
					(fill yes)
				)
			)
		)
	)
	(footprint ""
		(layer "F.Cu")
		(at 164.303456 -298.744386)
		(property "Reference" "Q292"
			(at 0 0 0)
			(layer "F.SilkS")
			(hide yes)
			(effects
				(font
					(size 1.27 1.27)
				)
			)
		)
		(property "Value" "SSM3K324R-GP"
			(at 0.127 -8.9662 0)
			(unlocked yes)
			(layer "F.Fab")
			(hide yes)
			(effects
				(font
					(size 1.016 1.016)
					(thickness 0.1524)
				)
			)
		)
		(property "Device Type" "SOT23DGS2D4H35"
			(at 0.127 -10.4902 0)
			(unlocked yes)
			(layer "F.Fab")
			(hide yes)
			(effects
				(font
					(size 1.016 1.016)
					(thickness 0.1524)
				)
			)
		)
		(duplicate_pad_numbers_are_jumpers no)
		(fp_line
			(start -1.651 -1.778)
			(end -1.651 1.778)
			(stroke
				(width 0.1524)
				(type default)
			)
			(layer "F.SilkS")
		)
		(fp_line
			(start -1.651 1.778)
			(end 1.651 1.778)
			(stroke
				(width 0.1524)
				(type default)
			)
			(layer "F.SilkS")
		)
		(fp_line
			(start 1.651 -1.778)
			(end -1.651 -1.778)
			(stroke
				(width 0.1524)
				(type default)
			)
			(layer "F.SilkS")
		)
		(fp_line
			(start 1.651 1.778)
			(end 1.651 -1.778)
			(stroke
				(width 0.1524)
				(type default)
			)
			(layer "F.SilkS")
		)
		(fp_poly
			(pts
				(xy -1.778 1.8796) (xy -1.778 -1.8796) (xy 1.778 -1.8796) (xy 1.778 1.8796)
			)
			(stroke
				(width 0)
				(type default)
			)
			(fill no)
			(layer "F.CrtYd")
		)
		(fp_poly
			(pts
				(xy -1.778 1.8796) (xy -1.778 -1.8796) (xy 1.778 -1.8796) (xy 1.778 1.8796)
			)
			(stroke
				(width 0)
				(type default)
			)
			(fill no)
			(layer "F.Fab")
		)
		(pad "D" smd custom
			(at 0 -0.9525)
			(size 0.1905 0.1905)
			(layers "F.Cu" "F.Mask" "F.Paste")
			(net "DRV_ACT_29_N")
			(options
				(clearance outline)
				(anchor circle)
			)
			(primitives
				(gr_poly
					(pts
						(arc
							(start -0.1778 0.5715)
							(mid -0.321484 0.511984)
							(end -0.381 0.3683)
						)
						(arc
							(start -0.381 -0.3683)
							(mid -0.321484 -0.511984)
							(end -0.1778 -0.5715)
						)
						(arc
							(start 0.1778 -0.5715)
							(mid 0.321484 -0.511984)
							(end 0.381 -0.3683)
						)
						(arc
							(start 0.381 0.3683)
							(mid 0.321484 0.511984)
							(end 0.1778 0.5715)
						)
					)
					(width 0)
					(fill yes)
				)
			)
		)
		(pad "G" smd custom
			(at -0.98425 0.9525)
			(size 0.1905 0.1905)
			(layers "F.Cu" "F.Mask" "F.Paste")
			(net "DRIVE_B_29_ACT")
			(options
				(clearance outline)
				(anchor circle)
			)
			(primitives
				(gr_poly
					(pts
						(arc
							(start -0.1778 0.5715)
							(mid -0.321484 0.511984)
							(end -0.381 0.3683)
						)
						(arc
							(start -0.381 -0.3683)
							(mid -0.321484 -0.511984)
							(end -0.1778 -0.5715)
						)
						(arc
							(start 0.1778 -0.5715)
							(mid 0.321484 -0.511984)
							(end 0.381 -0.3683)
						)
						(arc
							(start 0.381 0.3683)
							(mid 0.321484 0.511984)
							(end 0.1778 0.5715)
						)
					)
					(width 0)
					(fill yes)
				)
			)
		)
		(pad "S" smd custom
			(at 0.98425 0.9525)
			(size 0.1905 0.1905)
			(layers "F.Cu" "F.Mask" "F.Paste")
			(net "GND")
			(options
				(clearance outline)
				(anchor circle)
			)
			(primitives
				(gr_poly
					(pts
						(arc
							(start -0.1778 0.5715)
							(mid -0.321484 0.511984)
							(end -0.381 0.3683)
						)
						(arc
							(start -0.381 -0.3683)
							(mid -0.321484 -0.511984)
							(end -0.1778 -0.5715)
						)
						(arc
							(start 0.1778 -0.5715)
							(mid 0.321484 -0.511984)
							(end 0.381 -0.3683)
						)
						(arc
							(start 0.381 0.3683)
							(mid 0.321484 0.511984)
							(end 0.1778 0.5715)
						)
					)
					(width 0)
					(fill yes)
				)
			)
		)
	)
	(footprint ""
		(layer "F.Cu")
		(at 458.9399 -163.554918 -90)
		(property "Reference" "R643"
			(at 0 0 270)
			(layer "F.SilkS")
			(hide yes)
			(effects
				(font
					(size 1.27 1.27)
				)
			)
		)
		(property "Value" "4K7R2J-2-GP"
			(at 0.064008 -3.993896 270)
			(unlocked yes)
			(layer "F.Fab")
			(hide yes)
			(effects
				(font
					(size 1.016 1.016)
					(thickness 0.1524)
				)
			)
		)
		(property "Device Type" "R402H16"
			(at 0.064008 -5.517896 270)
			(unlocked yes)
			(layer "F.Fab")
			(hide yes)
			(effects
				(font
					(size 1.016 1.016)
					(thickness 0.1524)
				)
			)
		)
		(duplicate_pad_numbers_are_jumpers no)
		(fp_line
			(start -0.508 -0.9398)
			(end -0.508 0.9398)
			(stroke
				(width 0.1524)
				(type default)
			)
			(layer "F.SilkS")
		)
		(fp_line
			(start 0.508 -0.9398)
			(end -0.508 -0.9398)
			(stroke
				(width 0.1524)
				(type default)
			)
			(layer "F.SilkS")
		)
		(fp_rect
			(start -0.508 0.9398)
			(end 0.508 -0.9398)
			(stroke
				(width 0)
				(type default)
			)
			(fill no)
			(layer "F.CrtYd")
		)
		(fp_rect
			(start -0.508 0.9398)
			(end 0.508 -0.9398)
			(stroke
				(width 0)
				(type default)
			)
			(fill no)
			(layer "F.Fab")
		)
		(pad "1" smd custom
			(at 0 -0.4445 270)
			(size 0.1397 0.1397)
			(layers "F.Cu" "F.Mask" "F.Paste")
			(net "P12V_A")
			(options
				(clearance outline)
				(anchor circle)
			)
			(primitives
				(gr_poly
					(pts
						(arc
							(start -0.1778 -0.2794)
							(mid -0.249642 -0.249642)
							(end -0.2794 -0.1778)
						)
						(arc
							(start -0.2794 0.1778)
							(mid -0.249642 0.249642)
							(end -0.1778 0.2794)
						)
						(arc
							(start 0.1778 0.2794)
							(mid 0.249642 0.249642)
							(end 0.2794 0.1778)
						)
						(arc
							(start 0.2794 -0.1778)
							(mid 0.249642 -0.249642)
							(end 0.1778 -0.2794)
						)
					)
					(width 0)
					(fill yes)
				)
			)
		)
		(pad "2" smd custom
			(at 0 0.4445 270)
			(size 0.1397 0.1397)
			(layers "F.Cu" "F.Mask" "F.Paste")
			(net "SW_HDD_P22")
			(options
				(clearance outline)
				(anchor circle)
			)
			(primitives
				(gr_poly
					(pts
						(arc
							(start -0.1778 -0.2794)
							(mid -0.249642 -0.249642)
							(end -0.2794 -0.1778)
						)
						(arc
							(start -0.2794 0.1778)
							(mid -0.249642 0.249642)
							(end -0.1778 0.2794)
						)
						(arc
							(start 0.1778 0.2794)
							(mid 0.249642 0.249642)
							(end 0.2794 0.1778)
						)
						(arc
							(start 0.2794 -0.1778)
							(mid 0.249642 -0.249642)
							(end 0.1778 -0.2794)
						)
					)
					(width 0)
					(fill yes)
				)
			)
		)
	)
	(footprint ""
		(layer "F.Cu")
		(at 271.22247 -6.929628 180)
		(property "Reference" "TP199"
			(at 0 0 180)
			(layer "F.SilkS")
			(hide yes)
			(effects
				(font
					(size 1.27 1.27)
				)
			)
		)
		(property "Value" "TPAD32-GP"
			(at -0.0508 -1.6764 180)
			(unlocked yes)
			(layer "F.Fab")
			(hide yes)
			(effects
				(font
					(size 1.016 1.016)
					(thickness 0.1524)
				)
			)
		)
		(property "Device Type" "TPAD32"
			(at -0.0508 -3.2004 180)
			(unlocked yes)
			(layer "F.Fab")
			(hide yes)
			(effects
				(font
					(size 1.016 1.016)
					(thickness 0.1524)
				)
			)
		)
		(duplicate_pad_numbers_are_jumpers no)
		(fp_poly
			(pts
				(arc
					(start -0.4064 0)
					(mid 0.4064 0)
					(end -0.4064 0)
				)
			)
			(stroke
				(width 0)
				(type default)
			)
			(fill no)
			(layer "F.CrtYd")
		)
		(fp_poly
			(pts
				(arc
					(start -0.7112 0)
					(mid 0.7112 0)
					(end -0.7112 0)
				)
			)
			(stroke
				(width 0)
				(type default)
			)
			(fill no)
			(layer "F.Fab")
		)
		(pad "1" smd circle
			(at 0 0 180)
			(size 0.8128 0.8128)
			(layers "F.Cu" "F.Mask" "F.Paste")
			(net "TP_COMP_B_NCSI_TXEN")
		)
	)
	(footprint ""
		(layer "F.Cu")
		(at 113.166652 -294.816784 -90)
		(property "Reference" "C85"
			(at 0 0 270)
			(layer "F.SilkS")
			(hide yes)
			(effects
				(font
					(size 1.27 1.27)
				)
			)
		)
		(property "Value" "SC4D7U25V5KX-1-GP"
			(at -0.0762 -6.1214 270)
			(unlocked yes)
			(layer "F.Fab")
			(hide yes)
			(effects
				(font
					(size 1.016 1.016)
					(thickness 0.1524)
				)
			)
		)
		(property "Device Type" "C805H58"
			(at -0.0762 -8.1534 270)
			(unlocked yes)
			(layer "F.Fab")
			(hide yes)
			(effects
				(font
					(size 1.016 1.016)
					(thickness 0.1524)
				)
			)
		)
		(duplicate_pad_numbers_are_jumpers no)
		(fp_line
			(start 0.635 0)
			(end -0.635 0)
			(stroke
				(width 0.508)
				(type default)
			)
			(layer "F.SilkS")
		)
		(fp_rect
			(start -0.9652 1.778)
			(end 0.9652 -1.778)
			(stroke
				(width 0)
				(type default)
			)
			(fill no)
			(layer "F.CrtYd")
		)
		(fp_poly
			(pts
				(xy -0.9652 -1.778) (xy 0.9652 -1.778) (xy 0.9652 1.778) (xy -0.9652 1.778)
			)
			(stroke
				(width 0)
				(type default)
			)
			(fill no)
			(layer "F.Fab")
		)
		(pad "1" smd rect
			(at 0 -0.9652 270)
			(size 1.397 1.143)
			(layers "F.Cu" "F.Mask" "F.Paste")
			(net "P12V_HDD3")
		)
		(pad "2" smd rect
			(at 0 0.9652 270)
			(size 1.397 1.143)
			(layers "F.Cu" "F.Mask" "F.Paste")
			(net "GND")
		)
	)
	(footprint ""
		(layer "F.Cu")
		(at 270.60017 -380.367794)
		(property "Reference" "Q226"
			(at 0 0 0)
			(layer "F.SilkS")
			(hide yes)
			(effects
				(font
					(size 1.27 1.27)
				)
			)
		)
		(property "Value" "IRFH8201TRPBF-GP"
			(at -4.2164 -4.3688 0)
			(unlocked yes)
			(layer "F.Fab")
			(hide yes)
			(effects
				(font
					(size 1.016 1.016)
					(thickness 0.1524)
				)
			)
		)
		(property "Device Type" "PPAK-5PH42"
			(at -4.2164 -5.8928 0)
			(unlocked yes)
			(layer "F.Fab")
			(hide yes)
			(effects
				(font
					(size 1.016 1.016)
					(thickness 0.1524)
				)
			)
		)
		(duplicate_pad_numbers_are_jumpers no)
		(fp_line
			(start -3.0353 4.9276)
			(end -3.0353 3.9624)
			(stroke
				(width 0.3302)
				(type default)
			)
			(layer "F.SilkS")
		)
		(fp_line
			(start -2.8956 -2.794)
			(end 2.8956 -2.794)
			(stroke
				(width 0.1524)
				(type default)
			)
			(layer "F.SilkS")
		)
		(fp_line
			(start -2.8956 4.826)
			(end -2.8956 -2.794)
			(stroke
				(width 0.1524)
				(type default)
			)
			(layer "F.SilkS")
		)
		(fp_line
			(start -1.9431 4.9276)
			(end -3.0353 4.9276)
			(stroke
				(width 0.3302)
				(type default)
			)
			(layer "F.SilkS")
		)
		(fp_line
			(start 2.8956 -2.794)
			(end 2.8956 4.826)
			(stroke
				(width 0.1524)
				(type default)
			)
			(layer "F.SilkS")
		)
		(fp_line
			(start 2.8956 4.826)
			(end -2.8956 4.826)
			(stroke
				(width 0.1524)
				(type default)
			)
			(layer "F.SilkS")
		)
		(fp_poly
			(pts
				(xy -2.3622 5.334) (xy -1.4986 5.334) (xy -1.9304 4.9022)
			)
			(stroke
				(width 0)
				(type default)
			)
			(fill yes)
			(layer "F.SilkS")
		)
		(fp_poly
			(pts
				(xy -2.6416 -0.3556) (xy -0.3556 -0.3556) (xy -0.3556 -2.54) (xy -2.6416 -2.54)
			)
			(stroke
				(width 0)
				(type default)
			)
			(fill yes)
			(layer "F.Paste")
		)
		(fp_poly
			(pts
				(xy -2.6416 2.54) (xy -0.3556 2.54) (xy -0.3556 0.3556) (xy -2.6416 0.3556)
			)
			(stroke
				(width 0)
				(type default)
			)
			(fill yes)
			(layer "F.Paste")
		)
		(fp_poly
			(pts
				(xy 0.3556 -0.3556) (xy 2.6416 -0.3556) (xy 2.6416 -2.54) (xy 0.3556 -2.54)
			)
			(stroke
				(width 0)
				(type default)
			)
			(fill yes)
			(layer "F.Paste")
		)
		(fp_poly
			(pts
				(xy 0.3556 2.54) (xy 2.6416 2.54) (xy 2.6416 0.3556) (xy 0.3556 0.3556)
			)
			(stroke
				(width 0)
				(type default)
			)
			(fill yes)
			(layer "F.Paste")
		)
		(fp_rect
			(start -2.5781 3.9878)
			(end 2.5781 -2.1082)
			(stroke
				(width 0)
				(type default)
			)
			(fill no)
			(layer "F.CrtYd")
		)
		(fp_poly
			(pts
				(xy -3.1496 5.08) (xy -3.1496 -3.048) (xy 3.1496 -3.048) (xy 3.1496 3.9751) (xy 2.5781 3.9751) (xy 2.5781 -2.1082)
				(xy -2.5781 -2.1082) (xy -2.5781 3.9878) (xy 3.1496 3.9878) (xy 3.1496 5.08)
			)
			(stroke
				(width 0)
				(type default)
			)
			(fill no)
			(layer "F.CrtYd")
		)
		(fp_rect
			(start -3.1496 5.08)
			(end 3.1496 -3.048)
			(stroke
				(width 0)
				(type default)
			)
			(fill no)
			(layer "F.Fab")
		)
		(pad "1" smd rect
			(at -1.905 3.81)
			(size 0.762 1.524)
			(layers "F.Cu" "F.Mask" "F.Paste")
			(net "P12V_A")
		)
		(pad "2" smd rect
			(at -0.635 3.81)
			(size 0.762 1.524)
			(layers "F.Cu" "F.Mask" "F.Paste")
			(net "P12V_A")
		)
		(pad "3" smd rect
			(at 0.635 3.81)
			(size 0.762 1.524)
			(layers "F.Cu" "F.Mask" "F.Paste")
			(net "P12V_A")
		)
		(pad "4" smd rect
			(at 1.905 3.81)
			(size 0.762 1.524)
			(layers "F.Cu" "F.Mask" "F.Paste")
			(net "MB3_12V_CTRL_GATE1")
		)
		(pad "5" smd rect
			(at 0 0)
			(size 5.2832 5.08)
			(layers "F.Cu" "F.Mask" "F.Paste")
			(net "MB3_P12V_IN_R")
		)
		(pad "6" smd rect
			(at 0.635 -2.032)
			(size 0.0254 0.0254)
			(layers "F.Cu" "F.Mask" "F.Paste")
			(net "MB3_P12V_IN_R")
		)
		(pad "7" smd rect
			(at -0.635 -2.032)
			(size 0.0254 0.0254)
			(layers "F.Cu" "F.Mask" "F.Paste")
			(net "MB3_P12V_IN_R")
		)
		(pad "8" smd rect
			(at -1.905 -2.032)
			(size 0.0254 0.0254)
			(layers "F.Cu" "F.Mask" "F.Paste")
			(net "MB3_P12V_IN_R")
		)
	)
	(footprint ""
		(layer "F.Cu")
		(at 213.5378 -390.8552 -90)
		(property "Reference" "R13"
			(at 0 0 270)
			(layer "F.SilkS")
			(hide yes)
			(effects
				(font
					(size 1.27 1.27)
				)
			)
		)
		(property "Value" "4K7R2J-2-GP"
			(at 0.064008 -3.993896 270)
			(unlocked yes)
			(layer "F.Fab")
			(hide yes)
			(effects
				(font
					(size 1.016 1.016)
					(thickness 0.1524)
				)
			)
		)
		(property "Device Type" "R402H16"
			(at 0.064008 -5.517896 270)
			(unlocked yes)
			(layer "F.Fab")
			(hide yes)
			(effects
				(font
					(size 1.016 1.016)
					(thickness 0.1524)
				)
			)
		)
		(duplicate_pad_numbers_are_jumpers no)
		(fp_line
			(start -0.508 -0.9398)
			(end -0.508 0.9398)
			(stroke
				(width 0.1524)
				(type default)
			)
			(layer "F.SilkS")
		)
		(fp_line
			(start 0.508 -0.9398)
			(end -0.508 -0.9398)
			(stroke
				(width 0.1524)
				(type default)
			)
			(layer "F.SilkS")
		)
		(fp_rect
			(start -0.508 0.9398)
			(end 0.508 -0.9398)
			(stroke
				(width 0)
				(type default)
			)
			(fill no)
			(layer "F.CrtYd")
		)
		(fp_rect
			(start -0.508 0.9398)
			(end 0.508 -0.9398)
			(stroke
				(width 0)
				(type default)
			)
			(fill no)
			(layer "F.Fab")
		)
		(pad "1" smd custom
			(at 0 -0.4445 270)
			(size 0.1397 0.1397)
			(layers "F.Cu" "F.Mask" "F.Paste")
			(net "P3V3_STBY_B")
			(options
				(clearance outline)
				(anchor circle)
			)
			(primitives
				(gr_poly
					(pts
						(arc
							(start -0.1778 -0.2794)
							(mid -0.249642 -0.249642)
							(end -0.2794 -0.1778)
						)
						(arc
							(start -0.2794 0.1778)
							(mid -0.249642 0.249642)
							(end -0.1778 0.2794)
						)
						(arc
							(start 0.1778 0.2794)
							(mid 0.249642 0.249642)
							(end 0.2794 0.1778)
						)
						(arc
							(start 0.2794 -0.1778)
							(mid 0.249642 -0.249642)
							(end 0.1778 -0.2794)
						)
					)
					(width 0)
					(fill yes)
				)
			)
		)
		(pad "2" smd custom
			(at 0 0.4445 270)
			(size 0.1397 0.1397)
			(layers "F.Cu" "F.Mask" "F.Paste")
			(net "BMC_B_TO_EXP_B_RESET_N")
			(options
				(clearance outline)
				(anchor circle)
			)
			(primitives
				(gr_poly
					(pts
						(arc
							(start -0.1778 -0.2794)
							(mid -0.249642 -0.249642)
							(end -0.2794 -0.1778)
						)
						(arc
							(start -0.2794 0.1778)
							(mid -0.249642 0.249642)
							(end -0.1778 0.2794)
						)
						(arc
							(start 0.1778 0.2794)
							(mid 0.249642 0.249642)
							(end 0.2794 0.1778)
						)
						(arc
							(start 0.2794 -0.1778)
							(mid 0.249642 -0.249642)
							(end 0.1778 -0.2794)
						)
					)
					(width 0)
					(fill yes)
				)
			)
		)
	)
	(footprint ""
		(layer "F.Cu")
		(at 146.630898 -292.778942 -90)
		(property "Reference" "C92"
			(at 0 0 270)
			(layer "F.SilkS")
			(hide yes)
			(effects
				(font
					(size 1.27 1.27)
				)
			)
		)
		(property "Value" "SC1U16V3KX-5GP"
			(at 0 -2.8194 270)
			(unlocked yes)
			(layer "F.Fab")
			(hide yes)
			(effects
				(font
					(size 1.016 1.016)
					(thickness 0.1524)
				)
			)
		)
		(property "Device Type" "C603H36"
			(at 0 -4.3434 270)
			(unlocked yes)
			(layer "F.Fab")
			(hide yes)
			(effects
				(font
					(size 1.016 1.016)
					(thickness 0.1524)
				)
			)
		)
		(duplicate_pad_numbers_are_jumpers no)
		(fp_line
			(start 0.508 0)
			(end -0.508 0)
			(stroke
				(width 0.2032)
				(type default)
			)
			(layer "F.SilkS")
		)
		(fp_rect
			(start -0.5842 1.3335)
			(end 0.5842 -1.3335)
			(stroke
				(width 0)
				(type default)
			)
			(fill no)
			(layer "F.CrtYd")
		)
		(fp_rect
			(start -0.5842 1.3335)
			(end 0.5842 -1.3335)
			(stroke
				(width 0)
				(type default)
			)
			(fill no)
			(layer "F.Fab")
		)
		(pad "1" smd custom
			(at 0 -0.762 270)
			(size 0.2159 0.2159)
			(layers "F.Cu" "F.Mask" "F.Paste")
			(net "P5V_HDD4")
			(options
				(clearance outline)
				(anchor circle)
			)
			(primitives
				(gr_poly
					(pts
						(arc
							(start -0.3302 -0.4318)
							(mid -0.402042 -0.402042)
							(end -0.4318 -0.3302)
						)
						(arc
							(start -0.4318 0.3302)
							(mid -0.402042 0.402042)
							(end -0.3302 0.4318)
						)
						(arc
							(start 0.3302 0.4318)
							(mid 0.402042 0.402042)
							(end 0.4318 0.3302)
						)
						(arc
							(start 0.4318 -0.3302)
							(mid 0.402042 -0.402042)
							(end 0.3302 -0.4318)
						)
					)
					(width 0)
					(fill yes)
				)
			)
		)
		(pad "2" smd custom
			(at 0 0.762 270)
			(size 0.2159 0.2159)
			(layers "F.Cu" "F.Mask" "F.Paste")
			(net "GND")
			(options
				(clearance outline)
				(anchor circle)
			)
			(primitives
				(gr_poly
					(pts
						(arc
							(start -0.3302 -0.4318)
							(mid -0.402042 -0.402042)
							(end -0.4318 -0.3302)
						)
						(arc
							(start -0.4318 0.3302)
							(mid -0.402042 0.402042)
							(end -0.3302 0.4318)
						)
						(arc
							(start 0.3302 0.4318)
							(mid 0.402042 0.402042)
							(end 0.4318 0.3302)
						)
						(arc
							(start 0.4318 -0.3302)
							(mid 0.402042 -0.402042)
							(end 0.3302 -0.4318)
						)
					)
					(width 0)
					(fill yes)
				)
			)
		)
	)
	(footprint ""
		(layer "F.Cu")
		(at 456.674982 -207.79994)
		(property "Reference" ""
			(at 0 0 0)
			(layer "F.SilkS")
			(hide yes)
			(effects
				(font
					(size 1.27 1.27)
				)
			)
		)
		(property "Value" "*"
			(at -8.398764 -8.057642 0)
			(unlocked yes)
			(layer "F.Fab")
			(hide yes)
			(effects
				(font
					(size 1.016 1.016)
					(thickness 0.1524)
				)
			)
		)
		(duplicate_pad_numbers_are_jumpers no)
		(fp_poly
			(pts
				(arc
					(start 7.3152 0)
					(mid 0 7.3152)
					(end -7.3152 0)
				)
				(arc
					(start -7.3152 -5.9944)
					(mid 0 -13.3096)
					(end 7.3152 -5.9944)
				)
			)
			(stroke
				(width 0)
				(type default)
			)
			(fill no)
			(layer "B.CrtYd")
		)
		(fp_poly
			(pts
				(arc
					(start 7.3152 0)
					(mid 0 7.3152)
					(end -7.3152 0)
				)
				(arc
					(start -7.3152 -5.9944)
					(mid 0 -13.3096)
					(end 7.3152 -5.9944)
				)
			)
			(stroke
				(width 0)
				(type default)
			)
			(fill no)
			(layer "F.CrtYd")
		)
		(fp_poly
			(pts
				(arc
					(start 7.3152 0)
					(mid 0 7.3152)
					(end -7.3152 0)
				)
				(arc
					(start -7.3152 -5.9944)
					(mid 0 -13.3096)
					(end 7.3152 -5.9944)
				)
			)
			(stroke
				(width 0)
				(type default)
			)
			(fill no)
			(layer "B.Fab")
		)
		(fp_poly
			(pts
				(arc
					(start 7.3152 0)
					(mid 0 7.3152)
					(end -7.3152 0)
				)
				(arc
					(start -7.3152 -5.9944)
					(mid 0 -13.3096)
					(end 7.3152 -5.9944)
				)
			)
			(stroke
				(width 0)
				(type default)
			)
			(fill no)
			(layer "F.Fab")
		)
		(pad "1" thru_hole oval
			(at 0 0)
			(size 14.0208 20.0152)
			(drill 0.0254
				(offset 0 -2.9972)
			)
			(layers "*.Cu" "*.Mask")
			(remove_unused_layers no)
			(net "Net_98")
			(clearance -1.002284)
			(thermal_gap 0.1524)
			(padstack
				(mode front_inner_back)
				(layer "Inner"
					(shape custom)
					(size 2.928012 2.928012)
					(options
						(anchor circle)
					)
					(primitives
						(gr_poly
							(pts
								(arc
									(start 4.571746 -2.084324)
									(mid 0.000333 7.430372)
									(end -4.571492 -2.084324)
								)
								(arc
									(start -4.571492 -2.084324)
									(mid -3.570296 -3.611977)
									(end -2.875026 -5.30098)
								)
								(arc
									(start -2.875026 -5.30098)
									(mid 0.000217 -7.43089)
									(end 2.87528 -5.30098)
								)
								(arc
									(start 2.87528 -5.30098)
									(mid 3.570511 -3.611956)
									(end 4.571746 -2.084324)
								)
							)
							(width 0)
							(fill yes)
						)
					)
					(clearance 0.1524)
				)
				(layer "B.Cu"
					(shape oval)
					(size 14.0208 20.0152)
					(offset 0 -2.9972)
					(clearance -1.002284)
				)
			)
		)
		(zone
			(layers "F.Cu" "B.Cu" "In1.Cu" "In2.Cu" "In3.Cu" "In4.Cu" "In5.Cu" "In6.Cu"
				"In7.Cu" "In8.Cu" "In9.Cu" "In10.Cu"
			)
			(hatch none 0.5)
			(connect_pads
				(clearance 0)
			)
			(min_thickness 0.25)
			(keepout
				(tracks not_allowed)
				(vias allowed)
				(pads allowed)
				(copperpour not_allowed)
				(footprints allowed)
			)
			(placement
				(enabled no)
				(sheetname "")
			)
			(fill
				(thermal_gap 0.5)
				(thermal_bridge_width 0.5)
				(island_removal_mode 0)
			)
			(polygon
				(pts
					(arc
						(start 449.664582 -213.79434)
						(mid 456.674982 -220.80474)
						(end 463.685382 -213.79434)
					)
					(arc
						(start 463.685382 -207.79994)
						(mid 456.674982 -200.78954)
						(end 449.664582 -207.79994)
					)
				)
			)
		)
	)
	(footprint ""
		(layer "F.Cu")
		(at 117.646196 -163.554918 90)
		(property "Reference" "R487"
			(at 0 0 90)
			(layer "F.SilkS")
			(hide yes)
			(effects
				(font
					(size 1.27 1.27)
				)
			)
		)
		(property "Value" "4K7R2J-2-GP"
			(at 0.064008 -3.993896 90)
			(unlocked yes)
			(layer "F.Fab")
			(hide yes)
			(effects
				(font
					(size 1.016 1.016)
					(thickness 0.1524)
				)
			)
		)
		(property "Device Type" "R402H16"
			(at 0.064008 -5.517896 90)
			(unlocked yes)
			(layer "F.Fab")
			(hide yes)
			(effects
				(font
					(size 1.016 1.016)
					(thickness 0.1524)
				)
			)
		)
		(duplicate_pad_numbers_are_jumpers no)
		(fp_line
			(start 0.508 -0.9398)
			(end -0.508 -0.9398)
			(stroke
				(width 0.1524)
				(type default)
			)
			(layer "F.SilkS")
		)
		(fp_line
			(start -0.508 -0.9398)
			(end -0.508 0.9398)
			(stroke
				(width 0.1524)
				(type default)
			)
			(layer "F.SilkS")
		)
		(fp_rect
			(start -0.508 0.9398)
			(end 0.508 -0.9398)
			(stroke
				(width 0)
				(type default)
			)
			(fill no)
			(layer "F.CrtYd")
		)
		(fp_rect
			(start -0.508 0.9398)
			(end 0.508 -0.9398)
			(stroke
				(width 0)
				(type default)
			)
			(fill no)
			(layer "F.Fab")
		)
		(pad "1" smd custom
			(at 0 -0.4445 90)
			(size 0.1397 0.1397)
			(layers "F.Cu" "F.Mask" "F.Paste")
			(net "SW_PWR_R_HDD15")
			(options
				(clearance outline)
				(anchor circle)
			)
			(primitives
				(gr_poly
					(pts
						(arc
							(start -0.1778 -0.2794)
							(mid -0.249642 -0.249642)
							(end -0.2794 -0.1778)
						)
						(arc
							(start -0.2794 0.1778)
							(mid -0.249642 0.249642)
							(end -0.1778 0.2794)
						)
						(arc
							(start 0.1778 0.2794)
							(mid 0.249642 0.249642)
							(end 0.2794 0.1778)
						)
						(arc
							(start 0.2794 -0.1778)
							(mid 0.249642 -0.249642)
							(end 0.1778 -0.2794)
						)
					)
					(width 0)
					(fill yes)
				)
			)
		)
		(pad "2" smd custom
			(at 0 0.4445 90)
			(size 0.1397 0.1397)
			(layers "F.Cu" "F.Mask" "F.Paste")
			(net "GND")
			(options
				(clearance outline)
				(anchor circle)
			)
			(primitives
				(gr_poly
					(pts
						(arc
							(start -0.1778 -0.2794)
							(mid -0.249642 -0.249642)
							(end -0.2794 -0.1778)
						)
						(arc
							(start -0.2794 0.1778)
							(mid -0.249642 0.249642)
							(end -0.1778 0.2794)
						)
						(arc
							(start 0.1778 0.2794)
							(mid 0.249642 0.249642)
							(end 0.2794 0.1778)
						)
						(arc
							(start 0.2794 -0.1778)
							(mid 0.249642 -0.249642)
							(end 0.1778 -0.2794)
						)
					)
					(width 0)
					(fill yes)
				)
			)
		)
	)
	(footprint ""
		(layer "F.Cu")
		(at 245.824502 -392.726164)
		(property "Reference" "C595"
			(at 0 0 0)
			(layer "F.SilkS")
			(hide yes)
			(effects
				(font
					(size 1.27 1.27)
				)
			)
		)
		(property "Value" "SC1U16V3KX-5GP"
			(at 0 -2.8194 0)
			(unlocked yes)
			(layer "F.Fab")
			(hide yes)
			(effects
				(font
					(size 1.016 1.016)
					(thickness 0.1524)
				)
			)
		)
		(property "Device Type" "C603H36"
			(at 0 -4.3434 0)
			(unlocked yes)
			(layer "F.Fab")
			(hide yes)
			(effects
				(font
					(size 1.016 1.016)
					(thickness 0.1524)
				)
			)
		)
		(duplicate_pad_numbers_are_jumpers no)
		(fp_line
			(start 0.508 0)
			(end -0.508 0)
			(stroke
				(width 0.2032)
				(type default)
			)
			(layer "F.SilkS")
		)
		(fp_rect
			(start -0.5842 1.3335)
			(end 0.5842 -1.3335)
			(stroke
				(width 0)
				(type default)
			)
			(fill no)
			(layer "F.CrtYd")
		)
		(fp_rect
			(start -0.5842 1.3335)
			(end 0.5842 -1.3335)
			(stroke
				(width 0)
				(type default)
			)
			(fill no)
			(layer "F.Fab")
		)
		(pad "1" smd custom
			(at 0 -0.762)
			(size 0.2159 0.2159)
			(layers "F.Cu" "F.Mask" "F.Paste")
			(net "MB3_CM_UV_R")
			(options
				(clearance outline)
				(anchor circle)
			)
			(primitives
				(gr_poly
					(pts
						(arc
							(start -0.3302 -0.4318)
							(mid -0.402042 -0.402042)
							(end -0.4318 -0.3302)
						)
						(arc
							(start -0.4318 0.3302)
							(mid -0.402042 0.402042)
							(end -0.3302 0.4318)
						)
						(arc
							(start 0.3302 0.4318)
							(mid 0.402042 0.402042)
							(end 0.4318 0.3302)
						)
						(arc
							(start 0.4318 -0.3302)
							(mid 0.402042 -0.402042)
							(end 0.3302 -0.4318)
						)
					)
					(width 0)
					(fill yes)
				)
			)
		)
		(pad "2" smd custom
			(at 0 0.762)
			(size 0.2159 0.2159)
			(layers "F.Cu" "F.Mask" "F.Paste")
			(net "AGND_CURRENT_DPB")
			(options
				(clearance outline)
				(anchor circle)
			)
			(primitives
				(gr_poly
					(pts
						(arc
							(start -0.3302 -0.4318)
							(mid -0.402042 -0.402042)
							(end -0.4318 -0.3302)
						)
						(arc
							(start -0.4318 0.3302)
							(mid -0.402042 0.402042)
							(end -0.3302 0.4318)
						)
						(arc
							(start 0.3302 0.4318)
							(mid 0.402042 0.402042)
							(end 0.4318 0.3302)
						)
						(arc
							(start 0.4318 -0.3302)
							(mid 0.402042 -0.402042)
							(end 0.3302 -0.4318)
						)
					)
					(width 0)
					(fill yes)
				)
			)
		)
	)
	(footprint ""
		(layer "F.Cu")
		(at 445.0207 -62.143894 90)
		(property "Reference" "R912"
			(at 0 0 90)
			(layer "F.SilkS")
			(hide yes)
			(effects
				(font
					(size 1.27 1.27)
				)
			)
		)
		(property "Value" "10KR2F-2-GP"
			(at 0.064008 -3.993896 90)
			(unlocked yes)
			(layer "F.Fab")
			(hide yes)
			(effects
				(font
					(size 1.016 1.016)
					(thickness 0.1524)
				)
			)
		)
		(property "Device Type" "R402H16"
			(at 0.064008 -5.517896 90)
			(unlocked yes)
			(layer "F.Fab")
			(hide yes)
			(effects
				(font
					(size 1.016 1.016)
					(thickness 0.1524)
				)
			)
		)
		(duplicate_pad_numbers_are_jumpers no)
		(fp_line
			(start 0.508 -0.9398)
			(end -0.508 -0.9398)
			(stroke
				(width 0.1524)
				(type default)
			)
			(layer "F.SilkS")
		)
		(fp_line
			(start -0.508 -0.9398)
			(end -0.508 0.9398)
			(stroke
				(width 0.1524)
				(type default)
			)
			(layer "F.SilkS")
		)
		(fp_rect
			(start -0.508 0.9398)
			(end 0.508 -0.9398)
			(stroke
				(width 0)
				(type default)
			)
			(fill no)
			(layer "F.CrtYd")
		)
		(fp_rect
			(start -0.508 0.9398)
			(end 0.508 -0.9398)
			(stroke
				(width 0)
				(type default)
			)
			(fill no)
			(layer "F.Fab")
		)
		(pad "1" smd custom
			(at 0 -0.4445 90)
			(size 0.1397 0.1397)
			(layers "F.Cu" "F.Mask" "F.Paste")
			(net "P3V3_STBY_A")
			(options
				(clearance outline)
				(anchor circle)
			)
			(primitives
				(gr_poly
					(pts
						(arc
							(start -0.1778 -0.2794)
							(mid -0.249642 -0.249642)
							(end -0.2794 -0.1778)
						)
						(arc
							(start -0.2794 0.1778)
							(mid -0.249642 0.249642)
							(end -0.1778 0.2794)
						)
						(arc
							(start 0.1778 0.2794)
							(mid 0.249642 0.249642)
							(end 0.2794 0.1778)
						)
						(arc
							(start 0.2794 -0.1778)
							(mid 0.249642 -0.249642)
							(end 0.1778 -0.2794)
						)
					)
					(width 0)
					(fill yes)
				)
			)
		)
		(pad "2" smd custom
			(at 0 0.4445 90)
			(size 0.1397 0.1397)
			(layers "F.Cu" "F.Mask" "F.Paste")
			(net "HDD_PRSNT_34")
			(options
				(clearance outline)
				(anchor circle)
			)
			(primitives
				(gr_poly
					(pts
						(arc
							(start -0.1778 -0.2794)
							(mid -0.249642 -0.249642)
							(end -0.2794 -0.1778)
						)
						(arc
							(start -0.2794 0.1778)
							(mid -0.249642 0.249642)
							(end -0.1778 0.2794)
						)
						(arc
							(start 0.1778 0.2794)
							(mid 0.249642 0.249642)
							(end 0.2794 0.1778)
						)
						(arc
							(start 0.2794 -0.1778)
							(mid 0.249642 -0.249642)
							(end 0.1778 -0.2794)
						)
					)
					(width 0)
					(fill yes)
				)
			)
		)
	)
	(footprint ""
		(layer "F.Cu")
		(at 363.655102 -160.252918 -90)
		(property "Reference" "Q115"
			(at 0 0 270)
			(layer "F.SilkS")
			(hide yes)
			(effects
				(font
					(size 1.27 1.27)
				)
			)
		)
		(property "Value" "2N7002KDW-GP"
			(at -2.3622 -8.2042 270)
			(unlocked yes)
			(layer "F.Fab")
			(hide yes)
			(effects
				(font
					(size 1.016 1.016)
					(thickness 0.1524)
				)
			)
		)
		(property "Device Type" "SOT-363H44"
			(at -2.3622 -10.1092 270)
			(unlocked yes)
			(layer "F.Fab")
			(hide yes)
			(effects
				(font
					(size 1.016 1.016)
					(thickness 0.1524)
				)
			)
		)
		(duplicate_pad_numbers_are_jumpers no)
		(fp_line
			(start -1.4478 1.7018)
			(end 1.4478 1.7018)
			(stroke
				(width 0.1524)
				(type default)
			)
			(layer "F.SilkS")
		)
		(fp_line
			(start 1.4478 1.7018)
			(end 1.4478 -1.7018)
			(stroke
				(width 0.1524)
				(type default)
			)
			(layer "F.SilkS")
		)
		(fp_line
			(start -1.27 1.524)
			(end -1.27 0.6604)
			(stroke
				(width 0.4826)
				(type default)
			)
			(layer "F.SilkS")
		)
		(fp_line
			(start -1.4478 -1.7018)
			(end -1.4478 1.7018)
			(stroke
				(width 0.1524)
				(type default)
			)
			(layer "F.SilkS")
		)
		(fp_line
			(start 1.4478 -1.7018)
			(end -1.4478 -1.7018)
			(stroke
				(width 0.1524)
				(type default)
			)
			(layer "F.SilkS")
		)
		(fp_poly
			(pts
				(xy -1.524 -1.778) (xy 1.524 -1.778) (xy 1.524 1.778) (xy -1.524 1.778)
			)
			(stroke
				(width 0)
				(type default)
			)
			(fill no)
			(layer "F.CrtYd")
		)
		(fp_poly
			(pts
				(xy -1.524 -1.778) (xy 1.524 -1.778) (xy 1.524 1.778) (xy -1.524 1.778)
			)
			(stroke
				(width 0)
				(type default)
			)
			(fill no)
			(layer "F.Fab")
		)
		(pad "1" smd rect
			(at -0.65024 0.9398 270)
			(size 0.4064 1.016)
			(layers "F.Cu" "F.Mask" "F.Paste")
			(net "GND")
		)
		(pad "2" smd rect
			(at 0 0.9398 270)
			(size 0.4064 1.016)
			(layers "F.Cu" "F.Mask" "F.Paste")
			(net "SW_PWR_R_HDD19")
		)
		(pad "3" smd rect
			(at 0.65024 0.9398 270)
			(size 0.4064 1.016)
			(layers "F.Cu" "F.Mask" "F.Paste")
			(net "SW_HDD_P19")
		)
		(pad "4" smd rect
			(at 0.65024 -0.9398 270)
			(size 0.4064 1.016)
			(layers "F.Cu" "F.Mask" "F.Paste")
			(net "GND")
		)
		(pad "5" smd rect
			(at 0 -0.9398 270)
			(size 0.4064 1.016)
			(layers "F.Cu" "F.Mask" "F.Paste")
			(net "SW_HDD_G19")
		)
		(pad "6" smd rect
			(at -0.65024 -0.9398 270)
			(size 0.4064 1.016)
			(layers "F.Cu" "F.Mask" "F.Paste")
			(net "SW_HDD_R19")
		)
	)
	(footprint ""
		(layer "F.Cu")
		(at 7.333742 -291.042344 90)
		(property "Reference" "R553"
			(at 0 0 90)
			(layer "F.SilkS")
			(hide yes)
			(effects
				(font
					(size 1.27 1.27)
				)
			)
		)
		(property "Value" "4K7R2J-2-GP"
			(at 0.064008 -3.993896 90)
			(unlocked yes)
			(layer "F.Fab")
			(hide yes)
			(effects
				(font
					(size 1.016 1.016)
					(thickness 0.1524)
				)
			)
		)
		(property "Device Type" "R402H16"
			(at 0.064008 -5.517896 90)
			(unlocked yes)
			(layer "F.Fab")
			(hide yes)
			(effects
				(font
					(size 1.016 1.016)
					(thickness 0.1524)
				)
			)
		)
		(duplicate_pad_numbers_are_jumpers no)
		(fp_line
			(start 0.508 -0.9398)
			(end -0.508 -0.9398)
			(stroke
				(width 0.1524)
				(type default)
			)
			(layer "F.SilkS")
		)
		(fp_line
			(start -0.508 -0.9398)
			(end -0.508 0.9398)
			(stroke
				(width 0.1524)
				(type default)
			)
			(layer "F.SilkS")
		)
		(fp_rect
			(start -0.508 0.9398)
			(end 0.508 -0.9398)
			(stroke
				(width 0)
				(type default)
			)
			(fill no)
			(layer "F.CrtYd")
		)
		(fp_rect
			(start -0.508 0.9398)
			(end 0.508 -0.9398)
			(stroke
				(width 0)
				(type default)
			)
			(fill no)
			(layer "F.Fab")
		)
		(pad "1" smd custom
			(at 0 -0.4445 90)
			(size 0.1397 0.1397)
			(layers "F.Cu" "F.Mask" "F.Paste")
			(net "DRIVE_B_24_FLT_LED")
			(options
				(clearance outline)
				(anchor circle)
			)
			(primitives
				(gr_poly
					(pts
						(arc
							(start -0.1778 -0.2794)
							(mid -0.249642 -0.249642)
							(end -0.2794 -0.1778)
						)
						(arc
							(start -0.2794 0.1778)
							(mid -0.249642 0.249642)
							(end -0.1778 0.2794)
						)
						(arc
							(start 0.1778 0.2794)
							(mid 0.249642 0.249642)
							(end 0.2794 0.1778)
						)
						(arc
							(start 0.2794 -0.1778)
							(mid 0.249642 -0.249642)
							(end 0.1778 -0.2794)
						)
					)
					(width 0)
					(fill yes)
				)
			)
		)
		(pad "2" smd custom
			(at 0 0.4445 90)
			(size 0.1397 0.1397)
			(layers "F.Cu" "F.Mask" "F.Paste")
			(net "GND")
			(options
				(clearance outline)
				(anchor circle)
			)
			(primitives
				(gr_poly
					(pts
						(arc
							(start -0.1778 -0.2794)
							(mid -0.249642 -0.249642)
							(end -0.2794 -0.1778)
						)
						(arc
							(start -0.2794 0.1778)
							(mid -0.249642 0.249642)
							(end -0.1778 0.2794)
						)
						(arc
							(start 0.1778 0.2794)
							(mid 0.249642 0.249642)
							(end 0.2794 0.1778)
						)
						(arc
							(start 0.2794 -0.1778)
							(mid 0.249642 -0.249642)
							(end 0.1778 -0.2794)
						)
					)
					(width 0)
					(fill yes)
				)
			)
		)
	)
	(footprint ""
		(layer "F.Cu")
		(at 478.930462 -288.841942)
		(property "Reference" "R382"
			(at 0 0 0)
			(layer "F.SilkS")
			(hide yes)
			(effects
				(font
					(size 1.27 1.27)
				)
			)
		)
		(property "Value" "2R6F-GP"
			(at -0.0508 -4.8514 0)
			(unlocked yes)
			(layer "F.Fab")
			(hide yes)
			(effects
				(font
					(size 1.016 1.016)
					(thickness 0.1524)
				)
			)
		)
		(property "Device Type" "R1206H26"
			(at 0 -6.3754 0)
			(unlocked yes)
			(layer "F.Fab")
			(hide yes)
			(effects
				(font
					(size 1.016 1.016)
					(thickness 0.1524)
				)
			)
		)
		(duplicate_pad_numbers_are_jumpers no)
		(fp_line
			(start -1.016 -2.2352)
			(end 1.016 -2.2352)
			(stroke
				(width 0.1524)
				(type default)
			)
			(layer "F.SilkS")
		)
		(fp_line
			(start -1.016 2.2352)
			(end -1.016 -2.2352)
			(stroke
				(width 0.1524)
				(type default)
			)
			(layer "F.SilkS")
		)
		(fp_line
			(start 1.016 -2.2352)
			(end 1.016 2.2352)
			(stroke
				(width 0.1524)
				(type default)
			)
			(layer "F.SilkS")
		)
		(fp_line
			(start 1.016 2.2352)
			(end -1.016 2.2352)
			(stroke
				(width 0.1524)
				(type default)
			)
			(layer "F.SilkS")
		)
		(fp_rect
			(start -1.0922 2.3114)
			(end 1.0922 -2.3114)
			(stroke
				(width 0)
				(type default)
			)
			(fill no)
			(layer "F.CrtYd")
		)
		(fp_poly
			(pts
				(xy -1.0922 -2.3114) (xy 1.0922 -2.3114) (xy 1.0922 2.3114) (xy -1.0922 2.3114)
			)
			(stroke
				(width 0)
				(type default)
			)
			(fill no)
			(layer "F.Fab")
		)
		(pad "1" smd rect
			(at 0 -1.397)
			(size 1.651 1.27)
			(layers "F.Cu" "F.Mask" "F.Paste")
			(net "P5V_HDD11")
		)
		(pad "2" smd rect
			(at 0 1.397)
			(size 1.651 1.27)
			(layers "F.Cu" "F.Mask" "F.Paste")
			(net "5V_PRE_11")
		)
	)
	(footprint ""
		(layer "F.Cu")
		(at 357.100124 -172.909992 -90)
		(property "Reference" "HDDSAS19"
			(at 0 0 270)
			(layer "F.SilkS")
			(hide yes)
			(effects
				(font
					(size 1.27 1.27)
				)
			)
		)
		(property "Value" "SKT-SAS15P-14P-45-GP"
			(at -20.7645 -8.9789 270)
			(unlocked yes)
			(layer "F.Fab")
			(hide yes)
			(effects
				(font
					(size 1.016 1.016)
					(thickness 0.1524)
				)
			)
		)
		(property "Device Type" "10120818-001C-TRLF"
			(at -20.7645 -10.5029 270)
			(unlocked yes)
			(layer "F.Fab")
			(hide yes)
			(effects
				(font
					(size 1.016 1.016)
					(thickness 0.1524)
				)
			)
		)
		(duplicate_pad_numbers_are_jumpers no)
		(fp_line
			(start 1.651 4.2926)
			(end 1.651 3.0099)
			(stroke
				(width 0.1524)
				(type default)
			)
			(layer "F.SilkS")
		)
		(fp_line
			(start 8.509 4.2926)
			(end 1.651 4.2926)
			(stroke
				(width 0.1524)
				(type default)
			)
			(layer "F.SilkS")
		)
		(fp_line
			(start -23.4188 3.0099)
			(end -23.4188 -3.2512)
			(stroke
				(width 0.1524)
				(type default)
			)
			(layer "F.SilkS")
		)
		(fp_line
			(start 1.651 3.0099)
			(end -23.4188 3.0099)
			(stroke
				(width 0.1524)
				(type default)
			)
			(layer "F.SilkS")
		)
		(fp_line
			(start 8.509 3.0099)
			(end 8.509 4.2926)
			(stroke
				(width 0.1524)
				(type default)
			)
			(layer "F.SilkS")
		)
		(fp_line
			(start 23.4188 3.0099)
			(end 8.509 3.0099)
			(stroke
				(width 0.1524)
				(type default)
			)
			(layer "F.SilkS")
		)
		(fp_line
			(start -23.4188 -3.2512)
			(end 23.4188 -3.2512)
			(stroke
				(width 0.1524)
				(type default)
			)
			(layer "F.SilkS")
		)
		(fp_line
			(start 23.4188 -3.2512)
			(end 23.4188 3.0099)
			(stroke
				(width 0.1524)
				(type default)
			)
			(layer "F.SilkS")
		)
		(fp_line
			(start 15.5067 -3.3401)
			(end 16.2687 -3.3401)
			(stroke
				(width 0.3302)
				(type default)
			)
			(layer "F.SilkS")
		)
		(fp_poly
			(pts
				(xy 15.868904 -3.230372) (xy 16.503904 -3.865372) (xy 15.233904 -3.865372)
			)
			(stroke
				(width 0)
				(type default)
			)
			(fill yes)
			(layer "F.SilkS")
		)
		(fp_poly
			(pts
				(xy -22.8727 -2.7559) (xy 22.8727 -2.7559) (xy 22.8727 2.7559) (xy 8.255 2.7559) (xy 8.255 3.5179)
				(xy 1.905 3.5179) (xy 1.905 2.7559) (xy -22.8727 2.7559)
			)
			(stroke
				(width 0)
				(type default)
			)
			(fill no)
			(layer "F.CrtYd")
		)
		(fp_poly
			(pts
				(xy 1.397 4.5466) (xy 1.397 3.2639) (xy -23.6728 3.2639) (xy -23.6728 -3.5052) (xy 23.6728 -3.5052)
				(xy 23.6728 -0.00635) (xy 22.8727 -0.00635) (xy 22.8727 -2.7559) (xy -22.8727 -2.7559) (xy -22.8727 2.7559)
				(xy 1.905 2.7559) (xy 1.905 3.5179) (xy 8.255 3.5179) (xy 8.255 2.7559) (xy 22.8727 2.7559) (xy 22.8727 0.00635)
				(xy 23.6728 0.00635) (xy 23.6728 3.2639) (xy 8.763 3.2639) (xy 8.763 4.5466)
			)
			(stroke
				(width 0)
				(type default)
			)
			(fill no)
			(layer "F.CrtYd")
		)
		(fp_poly
			(pts
				(xy 1.397 4.5466) (xy 1.397 3.2639) (xy -23.6728 3.2639) (xy -23.6728 -3.5052) (xy 23.6728 -3.5052)
				(xy 23.6728 3.2639) (xy 8.763 3.2639) (xy 8.763 4.5466)
			)
			(stroke
				(width 0)
				(type default)
			)
			(fill no)
			(layer "F.Fab")
		)
		(pad "" np_thru_hole circle
			(at -18.874994 0 270)
			(size 0.254 0.254)
			(drill 1.3462)
			(layers "*.Cu" "*.Mask")
			(clearance 0.9017)
			(thermal_gap 0.9017)
		)
		(pad "" np_thru_hole circle
			(at 18.874994 0 270)
			(size 0.254 0.254)
			(drill 0.9398)
			(layers "*.Cu" "*.Mask")
			(clearance 0.6985)
			(thermal_gap 0.6985)
		)
		(pad "G1" smd rect
			(at 21.874988 0 270)
			(size 2.5908 2.5908)
			(layers "F.Cu" "F.Mask" "F.Paste")
			(net "GND")
		)
		(pad "G2" smd rect
			(at -21.874988 0 270)
			(size 2.5908 2.5908)
			(layers "F.Cu" "F.Mask" "F.Paste")
			(net "GND")
		)
		(pad "P1" smd rect
			(at 1.905 -1.82499 270)
			(size 0.6096 2.3622)
			(layers "F.Cu" "F.Mask" "F.Paste")
			(net "Net_2116")
		)
		(pad "P2" smd rect
			(at 0.635 -1.82499 270)
			(size 0.6096 2.3622)
			(layers "F.Cu" "F.Mask" "F.Paste")
			(net "Net_2117")
		)
		(pad "P3" smd rect
			(at -0.635 -1.82499 270)
			(size 0.6096 2.3622)
			(layers "F.Cu" "F.Mask" "F.Paste")
			(net "Net_2118")
		)
		(pad "P4" smd rect
			(at -1.905 -1.82499 270)
			(size 0.6096 2.3622)
			(layers "F.Cu" "F.Mask" "F.Paste")
			(net "GND")
		)
		(pad "P5" smd rect
			(at -3.175 -1.82499 270)
			(size 0.6096 2.3622)
			(layers "F.Cu" "F.Mask" "F.Paste")
			(net "HDD_PRSNT_19")
		)
		(pad "P6" smd rect
			(at -4.445 -1.82499 270)
			(size 0.6096 2.3622)
			(layers "F.Cu" "F.Mask" "F.Paste")
			(net "GND")
		)
		(pad "P7" smd rect
			(at -5.715 -1.82499 270)
			(size 0.6096 2.3622)
			(layers "F.Cu" "F.Mask" "F.Paste")
			(net "5V_PRE_19")
		)
		(pad "P8" smd rect
			(at -6.985 -1.82499 270)
			(size 0.6096 2.3622)
			(layers "F.Cu" "F.Mask" "F.Paste")
			(net "P5V_HDD19")
		)
		(pad "P9" smd rect
			(at -8.255 -1.82499 270)
			(size 0.6096 2.3622)
			(layers "F.Cu" "F.Mask" "F.Paste")
			(net "P5V_HDD19")
		)
		(pad "P10" smd rect
			(at -9.525 -1.82499 270)
			(size 0.6096 2.3622)
			(layers "F.Cu" "F.Mask" "F.Paste")
			(net "GND")
		)
		(pad "P11" smd rect
			(at -10.795 -1.82499 270)
			(size 0.6096 2.3622)
			(layers "F.Cu" "F.Mask" "F.Paste")
			(net "ACT_HDD_19")
		)
		(pad "P12" smd rect
			(at -12.065 -1.82499 270)
			(size 0.6096 2.3622)
			(layers "F.Cu" "F.Mask" "F.Paste")
			(net "GND")
		)
		(pad "P13" smd rect
			(at -13.335 -1.82499 270)
			(size 0.6096 2.3622)
			(layers "F.Cu" "F.Mask" "F.Paste")
			(net "12V_PRE_19")
		)
		(pad "P14" smd rect
			(at -14.605 -1.82499 270)
			(size 0.6096 2.3622)
			(layers "F.Cu" "F.Mask" "F.Paste")
			(net "P12V_HDD19")
		)
		(pad "P15" smd rect
			(at -15.875 -1.82499 270)
			(size 0.6096 2.3622)
			(layers "F.Cu" "F.Mask" "F.Paste")
			(net "P12V_HDD19")
		)
		(pad "S1" smd rect
			(at 15.875 -1.82499 270)
			(size 0.6096 2.3622)
			(layers "F.Cu" "F.Mask" "F.Paste")
			(net "GND")
		)
		(pad "S2" smd rect
			(at 14.605 -1.82499 270)
			(size 0.6096 2.3622)
			(layers "F.Cu" "F.Mask" "F.Paste")
			(net "SAS_HDD_RX_P19")
		)
		(pad "S3" smd rect
			(at 13.335 -1.82499 270)
			(size 0.6096 2.3622)
			(layers "F.Cu" "F.Mask" "F.Paste")
			(net "SAS_HDD_RX_N19")
		)
		(pad "S4" smd rect
			(at 12.065 -1.82499 270)
			(size 0.6096 2.3622)
			(layers "F.Cu" "F.Mask" "F.Paste")
			(net "GND")
		)
		(pad "S5" smd rect
			(at 10.795 -1.82499 270)
			(size 0.6096 2.3622)
			(layers "F.Cu" "F.Mask" "F.Paste")
			(net "PHY_DRV_A_TO_SCC_A_19_DN")
		)
		(pad "S6" smd rect
			(at 9.525 -1.82499 270)
			(size 0.6096 2.3622)
			(layers "F.Cu" "F.Mask" "F.Paste")
			(net "PHY_DRV_A_TO_SCC_A_19_DP")
		)
		(pad "S7" smd rect
			(at 8.255 -1.82499 270)
			(size 0.6096 2.3622)
			(layers "F.Cu" "F.Mask" "F.Paste")
			(net "GND")
		)
		(pad "S8" smd rect
			(at 7.480046 2.845054 270)
			(size 0.508 2.3622)
			(layers "F.Cu" "F.Mask" "F.Paste")
			(net "GND")
		)
		(pad "S9" smd rect
			(at 6.679946 2.845054 270)
			(size 0.508 2.3622)
			(layers "F.Cu" "F.Mask" "F.Paste")
			(net "Net_457")
		)
		(pad "S10" smd rect
			(at 5.8801 2.845054 270)
			(size 0.508 2.3622)
			(layers "F.Cu" "F.Mask" "F.Paste")
			(net "Net_349")
		)
		(pad "S11" smd rect
			(at 5.08 2.845054 270)
			(size 0.508 2.3622)
			(layers "F.Cu" "F.Mask" "F.Paste")
			(net "GND")
		)
		(pad "S12" smd rect
			(at 4.2799 2.845054 270)
			(size 0.508 2.3622)
			(layers "F.Cu" "F.Mask" "F.Paste")
			(net "Net_385")
		)
		(pad "S13" smd rect
			(at 3.480054 2.845054 270)
			(size 0.508 2.3622)
			(layers "F.Cu" "F.Mask" "F.Paste")
			(net "Net_421")
		)
		(pad "S14" smd rect
			(at 2.679954 2.845054 270)
			(size 0.508 2.3622)
			(layers "F.Cu" "F.Mask" "F.Paste")
			(net "GND")
		)
		(zone
			(layer "F.Cu")
			(hatch none 0.5)
			(connect_pads
				(clearance 0)
			)
			(min_thickness 0.25)
			(keepout
				(tracks not_allowed)
				(vias allowed)
				(pads allowed)
				(copperpour not_allowed)
				(footprints allowed)
			)
			(placement
				(enabled no)
				(sheetname "")
			)
			(fill
				(thermal_gap 0.5)
				(thermal_bridge_width 0.5)
				(island_removal_mode 0)
			)
			(polygon
				(pts
					(xy 360.757724 -189.648592) (xy 353.683824 -189.648592) (xy 353.683824 -196.582792) (xy 354.788724 -196.582792)
					(xy 354.788724 -192.467992) (xy 359.411524 -192.467992) (xy 359.411524 -196.582792) (xy 360.757724 -196.582792)
				)
			)
		)
		(zone
			(layer "F.Cu")
			(hatch none 0.5)
			(connect_pads
				(clearance 0)
			)
			(min_thickness 0.25)
			(keepout
				(tracks allowed)
				(vias not_allowed)
				(pads allowed)
				(copperpour not_allowed)
				(footprints allowed)
			)
			(placement
				(enabled no)
				(sheetname "")
			)
			(fill
				(thermal_gap 0.5)
				(thermal_bridge_width 0.5)
				(island_removal_mode 0)
			)
			(polygon
				(pts
					(xy 360.757724 -189.648592) (xy 353.683824 -189.648592) (xy 353.683824 -196.582792) (xy 354.788724 -196.582792)
					(xy 354.788724 -192.467992) (xy 359.411524 -192.467992) (xy 359.411524 -196.582792) (xy 360.757724 -196.582792)
				)
			)
		)
		(zone
			(layer "F.Cu")
			(hatch none 0.5)
			(connect_pads
				(clearance 0)
			)
			(min_thickness 0.25)
			(keepout
				(tracks allowed)
				(vias not_allowed)
				(pads allowed)
				(copperpour not_allowed)
				(footprints allowed)
			)
			(placement
				(enabled no)
				(sheetname "")
			)
			(fill
				(thermal_gap 0.5)
				(thermal_bridge_width 0.5)
				(island_removal_mode 0)
			)
			(polygon
				(pts
					(xy 360.757724 -156.171392) (xy 353.683824 -156.171392) (xy 353.683824 -149.237192) (xy 354.788724 -149.237192)
					(xy 354.788724 -153.351992) (xy 359.411524 -153.351992) (xy 359.411524 -149.237192) (xy 360.757724 -149.237192)
				)
			)
		)
		(zone
			(layer "F.Cu")
			(hatch none 0.5)
			(connect_pads
				(clearance 0)
			)
			(min_thickness 0.25)
			(keepout
				(tracks not_allowed)
				(vias allowed)
				(pads allowed)
				(copperpour not_allowed)
				(footprints allowed)
			)
			(placement
				(enabled no)
				(sheetname "")
			)
			(fill
				(thermal_gap 0.5)
				(thermal_bridge_width 0.5)
				(island_removal_mode 0)
			)
			(polygon
				(pts
					(xy 360.757724 -156.171392) (xy 353.683824 -156.171392) (xy 353.683824 -149.237192) (xy 354.788724 -149.237192)
					(xy 354.788724 -153.351992) (xy 359.411524 -153.351992) (xy 359.411524 -149.237192) (xy 360.757724 -149.237192)
				)
			)
		)
		(zone
			(layers "F.Cu" "B.Cu" "In1.Cu" "In2.Cu" "In3.Cu" "In4.Cu" "In5.Cu" "In6.Cu"
				"In7.Cu" "In8.Cu" "In9.Cu" "In10.Cu"
			)
			(hatch none 0.5)
			(connect_pads
				(clearance 0)
			)
			(min_thickness 0.25)
			(keepout
				(tracks not_allowed)
				(vias allowed)
				(pads allowed)
				(copperpour not_allowed)
				(footprints allowed)
			)
			(placement
				(enabled no)
				(sheetname "")
			)
			(fill
				(thermal_gap 0.5)
				(thermal_bridge_width 0.5)
				(island_removal_mode 0)
			)
			(polygon
				(pts
					(arc
						(start 357.874824 -154.034998)
						(mid 356.325424 -154.034998)
						(end 357.874824 -154.034998)
					)
				)
			)
		)
		(zone
			(layers "F.Cu" "B.Cu" "In1.Cu" "In2.Cu" "In3.Cu" "In4.Cu" "In5.Cu" "In6.Cu"
				"In7.Cu" "In8.Cu" "In9.Cu" "In10.Cu"
			)
			(hatch none 0.5)
			(connect_pads
				(clearance 0)
			)
			(min_thickness 0.25)
			(keepout
				(tracks not_allowed)
				(vias allowed)
				(pads allowed)
				(copperpour not_allowed)
				(footprints allowed)
			)
			(placement
				(enabled no)
				(sheetname "")
			)
			(fill
				(thermal_gap 0.5)
				(thermal_bridge_width 0.5)
				(island_removal_mode 0)
			)
			(polygon
				(pts
					(arc
						(start 358.078024 -191.784986)
						(mid 356.122224 -191.784986)
						(end 358.078024 -191.784986)
					)
				)
			)
		)
	)
	(footprint ""
		(layer "F.Cu")
		(at 363.909102 -180.826918 180)
		(property "Reference" "C288"
			(at 0 0 180)
			(layer "F.SilkS")
			(hide yes)
			(effects
				(font
					(size 1.27 1.27)
				)
			)
		)
		(property "Value" "SC10U16V6KX-2GP"
			(at -0.0762 -5.1308 180)
			(unlocked yes)
			(layer "F.Fab")
			(hide yes)
			(effects
				(font
					(size 1.016 1.016)
					(thickness 0.1524)
				)
			)
		)
		(property "Device Type" "C1206H71"
			(at -0.127 -6.6548 180)
			(unlocked yes)
			(layer "F.Fab")
			(hide yes)
			(effects
				(font
					(size 1.016 1.016)
					(thickness 0.1524)
				)
			)
		)
		(duplicate_pad_numbers_are_jumpers no)
		(fp_line
			(start 1.016 2.2352)
			(end -1.016 2.2352)
			(stroke
				(width 0.1524)
				(type default)
			)
			(layer "F.SilkS")
		)
		(fp_line
			(start 1.016 0.8382)
			(end 1.016 2.2352)
			(stroke
				(width 0.1524)
				(type default)
			)
			(layer "F.SilkS")
		)
		(fp_line
			(start 1.016 -2.2352)
			(end 1.016 -0.8382)
			(stroke
				(width 0.1524)
				(type default)
			)
			(layer "F.SilkS")
		)
		(fp_line
			(start -1.016 2.2352)
			(end -1.016 0.8382)
			(stroke
				(width 0.1524)
				(type default)
			)
			(layer "F.SilkS")
		)
		(fp_line
			(start -1.016 -0.8382)
			(end -1.016 -2.2352)
			(stroke
				(width 0.1524)
				(type default)
			)
			(layer "F.SilkS")
		)
		(fp_line
			(start -1.016 -2.2352)
			(end 1.016 -2.2352)
			(stroke
				(width 0.1524)
				(type default)
			)
			(layer "F.SilkS")
		)
		(fp_rect
			(start -1.0922 2.3114)
			(end 1.0922 -2.3114)
			(stroke
				(width 0)
				(type default)
			)
			(fill no)
			(layer "F.CrtYd")
		)
		(fp_poly
			(pts
				(xy 1.0922 -2.3114) (xy 1.0922 2.3114) (xy -1.0922 2.3114) (xy -1.0922 -2.3114)
			)
			(stroke
				(width 0)
				(type default)
			)
			(fill no)
			(layer "F.Fab")
		)
		(pad "1" smd rect
			(at 0 -1.397 180)
			(size 1.651 1.27)
			(layers "F.Cu" "F.Mask" "F.Paste")
			(net "P5V_HDD19")
		)
		(pad "2" smd rect
			(at 0 1.397 180)
			(size 1.651 1.27)
			(layers "F.Cu" "F.Mask" "F.Paste")
			(net "GND")
		)
	)
	(footprint ""
		(layer "F.Cu")
		(at 54.546246 -46.065694 -90)
		(property "Reference" "R713"
			(at 0 0 270)
			(layer "F.SilkS")
			(hide yes)
			(effects
				(font
					(size 1.27 1.27)
				)
			)
		)
		(property "Value" "1KR2F-3-GP"
			(at 0.064008 -3.993896 270)
			(unlocked yes)
			(layer "F.Fab")
			(hide yes)
			(effects
				(font
					(size 1.016 1.016)
					(thickness 0.1524)
				)
			)
		)
		(property "Device Type" "R402H16"
			(at 0.064008 -5.517896 270)
			(unlocked yes)
			(layer "F.Fab")
			(hide yes)
			(effects
				(font
					(size 1.016 1.016)
					(thickness 0.1524)
				)
			)
		)
		(duplicate_pad_numbers_are_jumpers no)
		(fp_line
			(start -0.508 -0.9398)
			(end -0.508 0.9398)
			(stroke
				(width 0.1524)
				(type default)
			)
			(layer "F.SilkS")
		)
		(fp_line
			(start 0.508 -0.9398)
			(end -0.508 -0.9398)
			(stroke
				(width 0.1524)
				(type default)
			)
			(layer "F.SilkS")
		)
		(fp_rect
			(start -0.508 0.9398)
			(end 0.508 -0.9398)
			(stroke
				(width 0)
				(type default)
			)
			(fill no)
			(layer "F.CrtYd")
		)
		(fp_rect
			(start -0.508 0.9398)
			(end 0.508 -0.9398)
			(stroke
				(width 0)
				(type default)
			)
			(fill no)
			(layer "F.Fab")
		)
		(pad "1" smd custom
			(at 0 -0.4445 270)
			(size 0.1397 0.1397)
			(layers "F.Cu" "F.Mask" "F.Paste")
			(net "P3V3_STBY_A")
			(options
				(clearance outline)
				(anchor circle)
			)
			(primitives
				(gr_poly
					(pts
						(arc
							(start -0.1778 -0.2794)
							(mid -0.249642 -0.249642)
							(end -0.2794 -0.1778)
						)
						(arc
							(start -0.2794 0.1778)
							(mid -0.249642 0.249642)
							(end -0.1778 0.2794)
						)
						(arc
							(start 0.1778 0.2794)
							(mid 0.249642 0.249642)
							(end 0.2794 0.1778)
						)
						(arc
							(start 0.2794 -0.1778)
							(mid 0.249642 -0.249642)
							(end 0.1778 -0.2794)
						)
					)
					(width 0)
					(fill yes)
				)
			)
		)
		(pad "2" smd custom
			(at 0 0.4445 270)
			(size 0.1397 0.1397)
			(layers "F.Cu" "F.Mask" "F.Paste")
			(net "SW_PWR_R_HDD25")
			(options
				(clearance outline)
				(anchor circle)
			)
			(primitives
				(gr_poly
					(pts
						(arc
							(start -0.1778 -0.2794)
							(mid -0.249642 -0.249642)
							(end -0.2794 -0.1778)
						)
						(arc
							(start -0.2794 0.1778)
							(mid -0.249642 0.249642)
							(end -0.1778 0.2794)
						)
						(arc
							(start 0.1778 0.2794)
							(mid 0.249642 0.249642)
							(end 0.2794 0.1778)
						)
						(arc
							(start 0.2794 -0.1778)
							(mid 0.249642 -0.249642)
							(end 0.1778 -0.2794)
						)
					)
					(width 0)
					(fill yes)
				)
			)
		)
	)
	(footprint ""
		(layer "F.Cu")
		(at 322.260468 -242.210844)
		(property "Reference" "R242"
			(at 0 0 0)
			(layer "F.SilkS")
			(hide yes)
			(effects
				(font
					(size 1.27 1.27)
				)
			)
		)
		(property "Value" "91R3F-1-GP"
			(at -0.0254 -2.5146 0)
			(unlocked yes)
			(layer "F.Fab")
			(hide yes)
			(effects
				(font
					(size 1.016 1.016)
					(thickness 0.1524)
				)
			)
		)
		(property "Device Type" "R603H22"
			(at -0.0254 -4.0386 0)
			(unlocked yes)
			(layer "F.Fab")
			(hide yes)
			(effects
				(font
					(size 1.016 1.016)
					(thickness 0.1524)
				)
			)
		)
		(duplicate_pad_numbers_are_jumpers no)
		(fp_line
			(start -0.4826 0)
			(end -0.2032 0)
			(stroke
				(width 0.2032)
				(type default)
			)
			(layer "F.SilkS")
		)
		(fp_line
			(start 0.2032 0)
			(end 0.4826 0)
			(stroke
				(width 0.2032)
				(type default)
			)
			(layer "F.SilkS")
		)
		(fp_rect
			(start -0.5842 1.3335)
			(end 0.5842 -1.3335)
			(stroke
				(width 0)
				(type default)
			)
			(fill no)
			(layer "F.CrtYd")
		)
		(fp_rect
			(start -0.5842 1.3335)
			(end 0.5842 -1.3335)
			(stroke
				(width 0)
				(type default)
			)
			(fill no)
			(layer "F.Fab")
		)
		(pad "1" smd custom
			(at 0 -0.762)
			(size 0.2159 0.2159)
			(layers "F.Cu" "F.Mask" "F.Paste")
			(net "P5V_A_3")
			(options
				(clearance outline)
				(anchor circle)
			)
			(primitives
				(gr_poly
					(pts
						(arc
							(start -0.3302 -0.4318)
							(mid -0.402042 -0.402042)
							(end -0.4318 -0.3302)
						)
						(arc
							(start -0.4318 0.3302)
							(mid -0.402042 0.402042)
							(end -0.3302 0.4318)
						)
						(arc
							(start 0.3302 0.4318)
							(mid 0.402042 0.402042)
							(end 0.4318 0.3302)
						)
						(arc
							(start 0.4318 -0.3302)
							(mid 0.402042 -0.402042)
							(end 0.3302 -0.4318)
						)
					)
					(width 0)
					(fill yes)
				)
			)
		)
		(pad "2" smd custom
			(at 0 0.762)
			(size 0.2159 0.2159)
			(layers "F.Cu" "F.Mask" "F.Paste")
			(net "DRV_ACT_6")
			(options
				(clearance outline)
				(anchor circle)
			)
			(primitives
				(gr_poly
					(pts
						(arc
							(start -0.3302 -0.4318)
							(mid -0.402042 -0.402042)
							(end -0.4318 -0.3302)
						)
						(arc
							(start -0.4318 0.3302)
							(mid -0.402042 0.402042)
							(end -0.3302 0.4318)
						)
						(arc
							(start 0.3302 0.4318)
							(mid 0.402042 0.402042)
							(end 0.4318 0.3302)
						)
						(arc
							(start 0.4318 -0.3302)
							(mid 0.402042 -0.402042)
							(end 0.3302 -0.4318)
						)
					)
					(width 0)
					(fill yes)
				)
			)
		)
	)
	(footprint ""
		(layer "F.Cu")
		(at 302.3108 -74.7776)
		(property "Reference" "R357"
			(at 0 0 0)
			(layer "F.SilkS")
			(hide yes)
			(effects
				(font
					(size 1.27 1.27)
				)
			)
		)
		(property "Value" "0R2J-2-GP"
			(at 0.064008 -3.993896 0)
			(unlocked yes)
			(layer "F.Fab")
			(hide yes)
			(effects
				(font
					(size 1.016 1.016)
					(thickness 0.1524)
				)
			)
		)
		(property "Device Type" "R402H16"
			(at 0.064008 -5.517896 0)
			(unlocked yes)
			(layer "F.Fab")
			(hide yes)
			(effects
				(font
					(size 1.016 1.016)
					(thickness 0.1524)
				)
			)
		)
		(duplicate_pad_numbers_are_jumpers no)
		(fp_line
			(start -0.508 -0.9398)
			(end -0.508 0.9398)
			(stroke
				(width 0.1524)
				(type default)
			)
			(layer "F.SilkS")
		)
		(fp_line
			(start 0.508 -0.9398)
			(end -0.508 -0.9398)
			(stroke
				(width 0.1524)
				(type default)
			)
			(layer "F.SilkS")
		)
		(fp_rect
			(start -0.508 0.9398)
			(end 0.508 -0.9398)
			(stroke
				(width 0)
				(type default)
			)
			(fill no)
			(layer "F.CrtYd")
		)
		(fp_rect
			(start -0.508 0.9398)
			(end 0.508 -0.9398)
			(stroke
				(width 0)
				(type default)
			)
			(fill no)
			(layer "F.Fab")
		)
		(pad "1" smd custom
			(at 0 -0.4445)
			(size 0.1397 0.1397)
			(layers "F.Cu" "F.Mask" "F.Paste")
			(net "SLOT1_SVR_ID0_GPIO0")
			(options
				(clearance outline)
				(anchor circle)
			)
			(primitives
				(gr_poly
					(pts
						(arc
							(start -0.1778 -0.2794)
							(mid -0.249642 -0.249642)
							(end -0.2794 -0.1778)
						)
						(arc
							(start -0.2794 0.1778)
							(mid -0.249642 0.249642)
							(end -0.1778 0.2794)
						)
						(arc
							(start 0.1778 0.2794)
							(mid 0.249642 0.249642)
							(end 0.2794 0.1778)
						)
						(arc
							(start 0.2794 -0.1778)
							(mid 0.249642 -0.249642)
							(end 0.1778 -0.2794)
						)
					)
					(width 0)
					(fill yes)
				)
			)
		)
		(pad "2" smd custom
			(at 0 0.4445)
			(size 0.1397 0.1397)
			(layers "F.Cu" "F.Mask" "F.Paste")
			(net "COMP_B_BMC_B_SPARE_0")
			(options
				(clearance outline)
				(anchor circle)
			)
			(primitives
				(gr_poly
					(pts
						(arc
							(start -0.1778 -0.2794)
							(mid -0.249642 -0.249642)
							(end -0.2794 -0.1778)
						)
						(arc
							(start -0.2794 0.1778)
							(mid -0.249642 0.249642)
							(end -0.1778 0.2794)
						)
						(arc
							(start 0.1778 0.2794)
							(mid 0.249642 0.249642)
							(end 0.2794 0.1778)
						)
						(arc
							(start 0.2794 -0.1778)
							(mid 0.249642 -0.249642)
							(end 0.1778 -0.2794)
						)
					)
					(width 0)
					(fill yes)
				)
			)
		)
	)
	(footprint ""
		(layer "F.Cu")
		(at 241.6048 -260.5532 180)
		(property "Reference" "R43"
			(at 0 0 180)
			(layer "F.SilkS")
			(hide yes)
			(effects
				(font
					(size 1.27 1.27)
				)
			)
		)
		(property "Value" "0R2J-2-GP"
			(at 0.064008 -3.993896 180)
			(unlocked yes)
			(layer "F.Fab")
			(hide yes)
			(effects
				(font
					(size 1.016 1.016)
					(thickness 0.1524)
				)
			)
		)
		(property "Device Type" "R402H16"
			(at 0.064008 -5.517896 180)
			(unlocked yes)
			(layer "F.Fab")
			(hide yes)
			(effects
				(font
					(size 1.016 1.016)
					(thickness 0.1524)
				)
			)
		)
		(duplicate_pad_numbers_are_jumpers no)
		(fp_line
			(start 0.508 -0.9398)
			(end -0.508 -0.9398)
			(stroke
				(width 0.1524)
				(type default)
			)
			(layer "F.SilkS")
		)
		(fp_line
			(start -0.508 -0.9398)
			(end -0.508 0.9398)
			(stroke
				(width 0.1524)
				(type default)
			)
			(layer "F.SilkS")
		)
		(fp_rect
			(start -0.508 0.9398)
			(end 0.508 -0.9398)
			(stroke
				(width 0)
				(type default)
			)
			(fill no)
			(layer "F.CrtYd")
		)
		(fp_rect
			(start -0.508 0.9398)
			(end 0.508 -0.9398)
			(stroke
				(width 0)
				(type default)
			)
			(fill no)
			(layer "F.Fab")
		)
		(pad "1" smd custom
			(at 0 -0.4445 180)
			(size 0.1397 0.1397)
			(layers "F.Cu" "F.Mask" "F.Paste")
			(net "IO_EXP5_SCL")
			(options
				(clearance outline)
				(anchor circle)
			)
			(primitives
				(gr_poly
					(pts
						(arc
							(start -0.1778 -0.2794)
							(mid -0.249642 -0.249642)
							(end -0.2794 -0.1778)
						)
						(arc
							(start -0.2794 0.1778)
							(mid -0.249642 0.249642)
							(end -0.1778 0.2794)
						)
						(arc
							(start 0.1778 0.2794)
							(mid 0.249642 0.249642)
							(end 0.2794 0.1778)
						)
						(arc
							(start 0.2794 -0.1778)
							(mid 0.249642 -0.249642)
							(end 0.1778 -0.2794)
						)
					)
					(width 0)
					(fill yes)
				)
			)
		)
		(pad "2" smd custom
			(at 0 0.4445 180)
			(size 0.1397 0.1397)
			(layers "F.Cu" "F.Mask" "F.Paste")
			(net "I2C_DRIVE_A_INS_SCL")
			(options
				(clearance outline)
				(anchor circle)
			)
			(primitives
				(gr_poly
					(pts
						(arc
							(start -0.1778 -0.2794)
							(mid -0.249642 -0.249642)
							(end -0.2794 -0.1778)
						)
						(arc
							(start -0.2794 0.1778)
							(mid -0.249642 0.249642)
							(end -0.1778 0.2794)
						)
						(arc
							(start 0.1778 0.2794)
							(mid 0.249642 0.249642)
							(end 0.2794 0.1778)
						)
						(arc
							(start 0.2794 -0.1778)
							(mid 0.249642 -0.249642)
							(end 0.1778 -0.2794)
						)
					)
					(width 0)
					(fill yes)
				)
			)
		)
	)
	(footprint ""
		(layer "F.Cu")
		(at 251.097542 -383.085848 180)
		(property "Reference" "R1140"
			(at 0 0 180)
			(layer "F.SilkS")
			(hide yes)
			(effects
				(font
					(size 1.27 1.27)
				)
			)
		)
		(property "Value" "100R2D-GP"
			(at 0.064008 -3.993896 180)
			(unlocked yes)
			(layer "F.Fab")
			(hide yes)
			(effects
				(font
					(size 1.016 1.016)
					(thickness 0.1524)
				)
			)
		)
		(property "Device Type" "R402H14"
			(at 0.064008 -5.517896 180)
			(unlocked yes)
			(layer "F.Fab")
			(hide yes)
			(effects
				(font
					(size 1.016 1.016)
					(thickness 0.1524)
				)
			)
		)
		(duplicate_pad_numbers_are_jumpers no)
		(fp_line
			(start 0.508 -0.9398)
			(end -0.508 -0.9398)
			(stroke
				(width 0.1524)
				(type default)
			)
			(layer "F.SilkS")
		)
		(fp_line
			(start -0.508 -0.9398)
			(end -0.508 0.9398)
			(stroke
				(width 0.1524)
				(type default)
			)
			(layer "F.SilkS")
		)
		(fp_rect
			(start -0.508 0.9398)
			(end 0.508 -0.9398)
			(stroke
				(width 0)
				(type default)
			)
			(fill no)
			(layer "F.CrtYd")
		)
		(fp_rect
			(start -0.508 0.9398)
			(end 0.508 -0.9398)
			(stroke
				(width 0)
				(type default)
			)
			(fill no)
			(layer "F.Fab")
		)
		(pad "1" smd custom
			(at 0 -0.4445 180)
			(size 0.1397 0.1397)
			(layers "F.Cu" "F.Mask" "F.Paste")
			(net "GND")
			(options
				(clearance outline)
				(anchor circle)
			)
			(primitives
				(gr_poly
					(pts
						(arc
							(start -0.1778 -0.2794)
							(mid -0.249642 -0.249642)
							(end -0.2794 -0.1778)
						)
						(arc
							(start -0.2794 0.1778)
							(mid -0.249642 0.249642)
							(end -0.1778 0.2794)
						)
						(arc
							(start 0.1778 0.2794)
							(mid 0.249642 0.249642)
							(end 0.2794 0.1778)
						)
						(arc
							(start 0.2794 -0.1778)
							(mid 0.249642 -0.249642)
							(end 0.1778 -0.2794)
						)
					)
					(width 0)
					(fill yes)
				)
			)
		)
		(pad "2" smd custom
			(at 0 0.4445 180)
			(size 0.1397 0.1397)
			(layers "F.Cu" "F.Mask" "F.Paste")
			(net "MB3_TEMP_E")
			(options
				(clearance outline)
				(anchor circle)
			)
			(primitives
				(gr_poly
					(pts
						(arc
							(start -0.1778 -0.2794)
							(mid -0.249642 -0.249642)
							(end -0.2794 -0.1778)
						)
						(arc
							(start -0.2794 0.1778)
							(mid -0.249642 0.249642)
							(end -0.1778 0.2794)
						)
						(arc
							(start 0.1778 0.2794)
							(mid 0.249642 0.249642)
							(end 0.2794 0.1778)
						)
						(arc
							(start 0.2794 -0.1778)
							(mid 0.249642 -0.249642)
							(end 0.1778 -0.2794)
						)
					)
					(width 0)
					(fill yes)
				)
			)
		)
	)
	(footprint ""
		(layer "F.Cu")
		(at 369.176554 -127.729234 180)
		(property "Reference" "Q283"
			(at 0 0 180)
			(layer "F.SilkS")
			(hide yes)
			(effects
				(font
					(size 1.27 1.27)
				)
			)
		)
		(property "Value" "SSM3K324R-GP"
			(at 0.127 -8.9662 180)
			(unlocked yes)
			(layer "F.Fab")
			(hide yes)
			(effects
				(font
					(size 1.016 1.016)
					(thickness 0.1524)
				)
			)
		)
		(property "Device Type" "SOT23DGS2D4H35"
			(at 0.127 -10.4902 180)
			(unlocked yes)
			(layer "F.Fab")
			(hide yes)
			(effects
				(font
					(size 1.016 1.016)
					(thickness 0.1524)
				)
			)
		)
		(duplicate_pad_numbers_are_jumpers no)
		(fp_line
			(start 1.651 1.778)
			(end 1.651 -1.778)
			(stroke
				(width 0.1524)
				(type default)
			)
			(layer "F.SilkS")
		)
		(fp_line
			(start 1.651 -1.778)
			(end -1.651 -1.778)
			(stroke
				(width 0.1524)
				(type default)
			)
			(layer "F.SilkS")
		)
		(fp_line
			(start -1.651 1.778)
			(end 1.651 1.778)
			(stroke
				(width 0.1524)
				(type default)
			)
			(layer "F.SilkS")
		)
		(fp_line
			(start -1.651 -1.778)
			(end -1.651 1.778)
			(stroke
				(width 0.1524)
				(type default)
			)
			(layer "F.SilkS")
		)
		(fp_poly
			(pts
				(xy -1.778 1.8796) (xy -1.778 -1.8796) (xy 1.778 -1.8796) (xy 1.778 1.8796)
			)
			(stroke
				(width 0)
				(type default)
			)
			(fill no)
			(layer "F.CrtYd")
		)
		(fp_poly
			(pts
				(xy -1.778 1.8796) (xy -1.778 -1.8796) (xy 1.778 -1.8796) (xy 1.778 1.8796)
			)
			(stroke
				(width 0)
				(type default)
			)
			(fill no)
			(layer "F.Fab")
		)
		(pad "D" smd custom
			(at 0 -0.9525 180)
			(size 0.1905 0.1905)
			(layers "F.Cu" "F.Mask" "F.Paste")
			(net "DRV_ACT_20_N")
			(options
				(clearance outline)
				(anchor circle)
			)
			(primitives
				(gr_poly
					(pts
						(arc
							(start -0.1778 0.5715)
							(mid -0.321484 0.511984)
							(end -0.381 0.3683)
						)
						(arc
							(start -0.381 -0.3683)
							(mid -0.321484 -0.511984)
							(end -0.1778 -0.5715)
						)
						(arc
							(start 0.1778 -0.5715)
							(mid 0.321484 -0.511984)
							(end 0.381 -0.3683)
						)
						(arc
							(start 0.381 0.3683)
							(mid 0.321484 0.511984)
							(end 0.1778 0.5715)
						)
					)
					(width 0)
					(fill yes)
				)
			)
		)
		(pad "G" smd custom
			(at -0.98425 0.9525 180)
			(size 0.1905 0.1905)
			(layers "F.Cu" "F.Mask" "F.Paste")
			(net "DRIVE_A_20_ACT")
			(options
				(clearance outline)
				(anchor circle)
			)
			(primitives
				(gr_poly
					(pts
						(arc
							(start -0.1778 0.5715)
							(mid -0.321484 0.511984)
							(end -0.381 0.3683)
						)
						(arc
							(start -0.381 -0.3683)
							(mid -0.321484 -0.511984)
							(end -0.1778 -0.5715)
						)
						(arc
							(start 0.1778 -0.5715)
							(mid 0.321484 -0.511984)
							(end 0.381 -0.3683)
						)
						(arc
							(start 0.381 0.3683)
							(mid 0.321484 0.511984)
							(end 0.1778 0.5715)
						)
					)
					(width 0)
					(fill yes)
				)
			)
		)
		(pad "S" smd custom
			(at 0.98425 0.9525 180)
			(size 0.1905 0.1905)
			(layers "F.Cu" "F.Mask" "F.Paste")
			(net "GND")
			(options
				(clearance outline)
				(anchor circle)
			)
			(primitives
				(gr_poly
					(pts
						(arc
							(start -0.1778 0.5715)
							(mid -0.321484 0.511984)
							(end -0.381 0.3683)
						)
						(arc
							(start -0.381 -0.3683)
							(mid -0.321484 -0.511984)
							(end -0.1778 -0.5715)
						)
						(arc
							(start 0.1778 -0.5715)
							(mid 0.321484 -0.511984)
							(end 0.381 -0.3683)
						)
						(arc
							(start 0.381 0.3683)
							(mid 0.321484 0.511984)
							(end 0.1778 0.5715)
						)
					)
					(width 0)
					(fill yes)
				)
			)
		)
	)
	(footprint ""
		(layer "F.Cu")
		(at 394.56995 -303.954942 180)
		(property "Reference" "C150"
			(at 0 0 180)
			(layer "F.SilkS")
			(hide yes)
			(effects
				(font
					(size 1.27 1.27)
				)
			)
		)
		(property "Value" "SC4D7U25V5KX-1-GP"
			(at -0.0762 -6.1214 180)
			(unlocked yes)
			(layer "F.Fab")
			(hide yes)
			(effects
				(font
					(size 1.016 1.016)
					(thickness 0.1524)
				)
			)
		)
		(property "Device Type" "C805H58"
			(at -0.0762 -8.1534 180)
			(unlocked yes)
			(layer "F.Fab")
			(hide yes)
			(effects
				(font
					(size 1.016 1.016)
					(thickness 0.1524)
				)
			)
		)
		(duplicate_pad_numbers_are_jumpers no)
		(fp_line
			(start 0.635 0)
			(end -0.635 0)
			(stroke
				(width 0.508)
				(type default)
			)
			(layer "F.SilkS")
		)
		(fp_rect
			(start -0.9652 1.778)
			(end 0.9652 -1.778)
			(stroke
				(width 0)
				(type default)
			)
			(fill no)
			(layer "F.CrtYd")
		)
		(fp_poly
			(pts
				(xy -0.9652 -1.778) (xy 0.9652 -1.778) (xy 0.9652 1.778) (xy -0.9652 1.778)
			)
			(stroke
				(width 0)
				(type default)
			)
			(fill no)
			(layer "F.Fab")
		)
		(pad "1" smd rect
			(at 0 -0.9652 180)
			(size 1.397 1.143)
			(layers "F.Cu" "F.Mask" "F.Paste")
			(net "P12V_HDD8")
		)
		(pad "2" smd rect
			(at 0 0.9652 180)
			(size 1.397 1.143)
			(layers "F.Cu" "F.Mask" "F.Paste")
			(net "GND")
		)
	)
	(footprint ""
		(layer "F.Cu")
		(at 11.106912 -127.808736 180)
		(property "Reference" "Q275"
			(at 0 0 180)
			(layer "F.SilkS")
			(hide yes)
			(effects
				(font
					(size 1.27 1.27)
				)
			)
		)
		(property "Value" "SSM3K324R-GP"
			(at 0.127 -8.9662 180)
			(unlocked yes)
			(layer "F.Fab")
			(hide yes)
			(effects
				(font
					(size 1.016 1.016)
					(thickness 0.1524)
				)
			)
		)
		(property "Device Type" "SOT23DGS2D4H35"
			(at 0.127 -10.4902 180)
			(unlocked yes)
			(layer "F.Fab")
			(hide yes)
			(effects
				(font
					(size 1.016 1.016)
					(thickness 0.1524)
				)
			)
		)
		(duplicate_pad_numbers_are_jumpers no)
		(fp_line
			(start 1.651 1.778)
			(end 1.651 -1.778)
			(stroke
				(width 0.1524)
				(type default)
			)
			(layer "F.SilkS")
		)
		(fp_line
			(start 1.651 -1.778)
			(end -1.651 -1.778)
			(stroke
				(width 0.1524)
				(type default)
			)
			(layer "F.SilkS")
		)
		(fp_line
			(start -1.651 1.778)
			(end 1.651 1.778)
			(stroke
				(width 0.1524)
				(type default)
			)
			(layer "F.SilkS")
		)
		(fp_line
			(start -1.651 -1.778)
			(end -1.651 1.778)
			(stroke
				(width 0.1524)
				(type default)
			)
			(layer "F.SilkS")
		)
		(fp_poly
			(pts
				(xy -1.778 1.8796) (xy -1.778 -1.8796) (xy 1.778 -1.8796) (xy 1.778 1.8796)
			)
			(stroke
				(width 0)
				(type default)
			)
			(fill no)
			(layer "F.CrtYd")
		)
		(fp_poly
			(pts
				(xy -1.778 1.8796) (xy -1.778 -1.8796) (xy 1.778 -1.8796) (xy 1.778 1.8796)
			)
			(stroke
				(width 0)
				(type default)
			)
			(fill no)
			(layer "F.Fab")
		)
		(pad "D" smd custom
			(at 0 -0.9525 180)
			(size 0.1905 0.1905)
			(layers "F.Cu" "F.Mask" "F.Paste")
			(net "DRV_ACT_12_N")
			(options
				(clearance outline)
				(anchor circle)
			)
			(primitives
				(gr_poly
					(pts
						(arc
							(start -0.1778 0.5715)
							(mid -0.321484 0.511984)
							(end -0.381 0.3683)
						)
						(arc
							(start -0.381 -0.3683)
							(mid -0.321484 -0.511984)
							(end -0.1778 -0.5715)
						)
						(arc
							(start 0.1778 -0.5715)
							(mid 0.321484 -0.511984)
							(end 0.381 -0.3683)
						)
						(arc
							(start 0.381 0.3683)
							(mid 0.321484 0.511984)
							(end 0.1778 0.5715)
						)
					)
					(width 0)
					(fill yes)
				)
			)
		)
		(pad "G" smd custom
			(at -0.98425 0.9525 180)
			(size 0.1905 0.1905)
			(layers "F.Cu" "F.Mask" "F.Paste")
			(net "DRIVE_A_12_ACT")
			(options
				(clearance outline)
				(anchor circle)
			)
			(primitives
				(gr_poly
					(pts
						(arc
							(start -0.1778 0.5715)
							(mid -0.321484 0.511984)
							(end -0.381 0.3683)
						)
						(arc
							(start -0.381 -0.3683)
							(mid -0.321484 -0.511984)
							(end -0.1778 -0.5715)
						)
						(arc
							(start 0.1778 -0.5715)
							(mid 0.321484 -0.511984)
							(end 0.381 -0.3683)
						)
						(arc
							(start 0.381 0.3683)
							(mid 0.321484 0.511984)
							(end 0.1778 0.5715)
						)
					)
					(width 0)
					(fill yes)
				)
			)
		)
		(pad "S" smd custom
			(at 0.98425 0.9525 180)
			(size 0.1905 0.1905)
			(layers "F.Cu" "F.Mask" "F.Paste")
			(net "GND")
			(options
				(clearance outline)
				(anchor circle)
			)
			(primitives
				(gr_poly
					(pts
						(arc
							(start -0.1778 0.5715)
							(mid -0.321484 0.511984)
							(end -0.381 0.3683)
						)
						(arc
							(start -0.381 -0.3683)
							(mid -0.321484 -0.511984)
							(end -0.1778 -0.5715)
						)
						(arc
							(start 0.1778 -0.5715)
							(mid 0.321484 -0.511984)
							(end 0.381 -0.3683)
						)
						(arc
							(start 0.381 0.3683)
							(mid 0.321484 0.511984)
							(end 0.1778 0.5715)
						)
					)
					(width 0)
					(fill yes)
				)
			)
		)
	)
	(footprint ""
		(layer "F.Cu")
		(at 234.5944 -231.3178)
		(property "Reference" "R65"
			(at 0 0 0)
			(layer "F.SilkS")
			(hide yes)
			(effects
				(font
					(size 1.27 1.27)
				)
			)
		)
		(property "Value" "0R2J-2-GP"
			(at 0.064008 -3.993896 0)
			(unlocked yes)
			(layer "F.Fab")
			(hide yes)
			(effects
				(font
					(size 1.016 1.016)
					(thickness 0.1524)
				)
			)
		)
		(property "Device Type" "R402H16"
			(at 0.064008 -5.517896 0)
			(unlocked yes)
			(layer "F.Fab")
			(hide yes)
			(effects
				(font
					(size 1.016 1.016)
					(thickness 0.1524)
				)
			)
		)
		(duplicate_pad_numbers_are_jumpers no)
		(fp_line
			(start -0.508 -0.9398)
			(end -0.508 0.9398)
			(stroke
				(width 0.1524)
				(type default)
			)
			(layer "F.SilkS")
		)
		(fp_line
			(start 0.508 -0.9398)
			(end -0.508 -0.9398)
			(stroke
				(width 0.1524)
				(type default)
			)
			(layer "F.SilkS")
		)
		(fp_rect
			(start -0.508 0.9398)
			(end 0.508 -0.9398)
			(stroke
				(width 0)
				(type default)
			)
			(fill no)
			(layer "F.CrtYd")
		)
		(fp_rect
			(start -0.508 0.9398)
			(end 0.508 -0.9398)
			(stroke
				(width 0)
				(type default)
			)
			(fill no)
			(layer "F.Fab")
		)
		(pad "1" smd custom
			(at 0 -0.4445)
			(size 0.1397 0.1397)
			(layers "F.Cu" "F.Mask" "F.Paste")
			(net "IO_EXP1_SCL")
			(options
				(clearance outline)
				(anchor circle)
			)
			(primitives
				(gr_poly
					(pts
						(arc
							(start -0.1778 -0.2794)
							(mid -0.249642 -0.249642)
							(end -0.2794 -0.1778)
						)
						(arc
							(start -0.2794 0.1778)
							(mid -0.249642 0.249642)
							(end -0.1778 0.2794)
						)
						(arc
							(start 0.1778 0.2794)
							(mid 0.249642 0.249642)
							(end 0.2794 0.1778)
						)
						(arc
							(start 0.2794 -0.1778)
							(mid 0.249642 -0.249642)
							(end 0.1778 -0.2794)
						)
					)
					(width 0)
					(fill yes)
				)
			)
		)
		(pad "2" smd custom
			(at 0 0.4445)
			(size 0.1397 0.1397)
			(layers "F.Cu" "F.Mask" "F.Paste")
			(net "I2C_DRIVE_A_PWR_SCL")
			(options
				(clearance outline)
				(anchor circle)
			)
			(primitives
				(gr_poly
					(pts
						(arc
							(start -0.1778 -0.2794)
							(mid -0.249642 -0.249642)
							(end -0.2794 -0.1778)
						)
						(arc
							(start -0.2794 0.1778)
							(mid -0.249642 0.249642)
							(end -0.1778 0.2794)
						)
						(arc
							(start 0.1778 0.2794)
							(mid 0.249642 0.249642)
							(end 0.2794 0.1778)
						)
						(arc
							(start 0.2794 -0.1778)
							(mid 0.249642 -0.249642)
							(end 0.1778 -0.2794)
						)
					)
					(width 0)
					(fill yes)
				)
			)
		)
	)
	(footprint ""
		(layer "F.Cu")
		(at 272.542 -354.104956 180)
		(property "Reference" "VIA39"
			(at 0 0 180)
			(layer "F.SilkS")
			(hide yes)
			(effects
				(font
					(size 1.27 1.27)
				)
			)
		)
		(property "Value" "100OHM-8L-1D6MM-L18L16-GP"
			(at -3.7211 -4.5085 180)
			(unlocked yes)
			(layer "F.Fab")
			(hide yes)
			(effects
				(font
					(size 1.016 1.016)
					(thickness 0.1524)
				)
			)
		)
		(property "Device Type" "VIA-PCIE-4P-394076"
			(at -3.7211 -6.0325 180)
			(unlocked yes)
			(layer "F.Fab")
			(hide yes)
			(effects
				(font
					(size 1.016 1.016)
					(thickness 0.1524)
				)
			)
		)
		(duplicate_pad_numbers_are_jumpers no)
		(fp_rect
			(start -1.9685 0.381)
			(end 1.9685 -0.381)
			(stroke
				(width 0)
				(type default)
			)
			(fill no)
			(layer "F.CrtYd")
		)
		(fp_rect
			(start -1.9685 0.381)
			(end 1.9685 -0.381)
			(stroke
				(width 0)
				(type default)
			)
			(fill no)
			(layer "F.Fab")
		)
		(pad "1" thru_hole circle
			(at -1.5875 0 180)
			(size 0.508 0.508)
			(drill 0.254)
			(layers "*.Cu" "*.Mask")
			(remove_unused_layers no)
			(net "GND")
			(clearance 0.127)
			(thermal_gap 0.127)
		)
		(pad "2" thru_hole circle
			(at -0.5715 0 180)
			(size 0.508 0.508)
			(drill 0.254)
			(layers "*.Cu" "*.Mask")
			(remove_unused_layers no)
			(net "PHY_SCC_A_TO_DRV_A_3_DP")
			(clearance 0.127)
			(thermal_gap 0.127)
		)
		(pad "3" thru_hole circle
			(at 0.5715 0 180)
			(size 0.508 0.508)
			(drill 0.254)
			(layers "*.Cu" "*.Mask")
			(remove_unused_layers no)
			(net "PHY_SCC_A_TO_DRV_A_3_DN")
			(clearance 0.127)
			(thermal_gap 0.127)
		)
		(pad "4" thru_hole circle
			(at 1.5875 0 180)
			(size 0.508 0.508)
			(drill 0.254)
			(layers "*.Cu" "*.Mask")
			(remove_unused_layers no)
			(net "GND")
			(clearance 0.127)
			(thermal_gap 0.127)
		)
	)
	(footprint ""
		(layer "F.Cu")
		(at 52.213002 -150.78075 -90)
		(property "Reference" "R1225"
			(at 0 0 270)
			(layer "F.SilkS")
			(hide yes)
			(effects
				(font
					(size 1.27 1.27)
				)
			)
		)
		(property "Value" "0R2J-2-GP"
			(at 0.064008 -3.993896 270)
			(unlocked yes)
			(layer "F.Fab")
			(hide yes)
			(effects
				(font
					(size 1.016 1.016)
					(thickness 0.1524)
				)
			)
		)
		(property "Device Type" "R402H16"
			(at 0.064008 -5.517896 270)
			(unlocked yes)
			(layer "F.Fab")
			(hide yes)
			(effects
				(font
					(size 1.016 1.016)
					(thickness 0.1524)
				)
			)
		)
		(duplicate_pad_numbers_are_jumpers no)
		(fp_line
			(start -0.508 -0.9398)
			(end -0.508 0.9398)
			(stroke
				(width 0.1524)
				(type default)
			)
			(layer "F.SilkS")
		)
		(fp_line
			(start 0.508 -0.9398)
			(end -0.508 -0.9398)
			(stroke
				(width 0.1524)
				(type default)
			)
			(layer "F.SilkS")
		)
		(fp_rect
			(start -0.508 0.9398)
			(end 0.508 -0.9398)
			(stroke
				(width 0)
				(type default)
			)
			(fill no)
			(layer "F.CrtYd")
		)
		(fp_rect
			(start -0.508 0.9398)
			(end 0.508 -0.9398)
			(stroke
				(width 0)
				(type default)
			)
			(fill no)
			(layer "F.Fab")
		)
		(pad "1" smd custom
			(at 0 -0.4445 270)
			(size 0.1397 0.1397)
			(layers "F.Cu" "F.Mask" "F.Paste")
			(net "P12V_A_PGOOD")
			(options
				(clearance outline)
				(anchor circle)
			)
			(primitives
				(gr_poly
					(pts
						(arc
							(start -0.1778 -0.2794)
							(mid -0.249642 -0.249642)
							(end -0.2794 -0.1778)
						)
						(arc
							(start -0.2794 0.1778)
							(mid -0.249642 0.249642)
							(end -0.1778 0.2794)
						)
						(arc
							(start 0.1778 0.2794)
							(mid 0.249642 0.249642)
							(end 0.2794 0.1778)
						)
						(arc
							(start 0.2794 -0.1778)
							(mid 0.249642 -0.249642)
							(end 0.1778 -0.2794)
						)
					)
					(width 0)
					(fill yes)
				)
			)
		)
		(pad "2" smd custom
			(at 0 0.4445 270)
			(size 0.1397 0.1397)
			(layers "F.Cu" "F.Mask" "F.Paste")
			(net "P5V_B_EN_R")
			(options
				(clearance outline)
				(anchor circle)
			)
			(primitives
				(gr_poly
					(pts
						(arc
							(start -0.1778 -0.2794)
							(mid -0.249642 -0.249642)
							(end -0.2794 -0.1778)
						)
						(arc
							(start -0.2794 0.1778)
							(mid -0.249642 0.249642)
							(end -0.1778 0.2794)
						)
						(arc
							(start 0.1778 0.2794)
							(mid 0.249642 0.249642)
							(end 0.2794 0.1778)
						)
						(arc
							(start 0.2794 -0.1778)
							(mid 0.249642 -0.249642)
							(end 0.1778 -0.2794)
						)
					)
					(width 0)
					(fill yes)
				)
			)
		)
	)
	(footprint ""
		(layer "F.Cu")
		(at 14.842998 -284.523942 90)
		(property "Reference" "C517"
			(at 0 0 90)
			(layer "F.SilkS")
			(hide yes)
			(effects
				(font
					(size 1.27 1.27)
				)
			)
		)
		(property "Value" "SCD033U25V2KX-GP"
			(at 1.1811 -2.7051 90)
			(unlocked yes)
			(layer "F.Fab")
			(hide yes)
			(effects
				(font
					(size 1.016 1.016)
					(thickness 0.1524)
				)
			)
		)
		(property "Device Type" "C402H22"
			(at 1.1811 -4.2291 90)
			(unlocked yes)
			(layer "F.Fab")
			(hide yes)
			(effects
				(font
					(size 1.016 1.016)
					(thickness 0.1524)
				)
			)
		)
		(duplicate_pad_numbers_are_jumpers no)
		(fp_rect
			(start -0.4318 0.9525)
			(end 0.4318 -0.9525)
			(stroke
				(width 0)
				(type default)
			)
			(fill no)
			(layer "F.CrtYd")
		)
		(fp_rect
			(start -0.4318 0.9525)
			(end 0.4318 -0.9525)
			(stroke
				(width 0)
				(type default)
			)
			(fill no)
			(layer "F.Fab")
		)
		(pad "1" smd custom
			(at 0 -0.4445 90)
			(size 0.1524 0.1524)
			(layers "F.Cu" "F.Mask" "F.Paste")
			(net "P12V_A")
			(options
				(clearance outline)
				(anchor circle)
			)
			(primitives
				(gr_poly
					(pts
						(arc
							(start 0.3048 -0.2032)
							(mid 0.275042 -0.275042)
							(end 0.2032 -0.3048)
						)
						(arc
							(start -0.2032 -0.3048)
							(mid -0.275042 -0.275042)
							(end -0.3048 -0.2032)
						)
						(arc
							(start -0.3048 0.2032)
							(mid -0.275042 0.275042)
							(end -0.2032 0.3048)
						)
						(arc
							(start 0.2032 0.3048)
							(mid 0.275042 0.275042)
							(end 0.3048 0.2032)
						)
					)
					(width 0)
					(fill yes)
				)
			)
		)
		(pad "2" smd custom
			(at 0 0.4445 90)
			(size 0.1524 0.1524)
			(layers "F.Cu" "F.Mask" "F.Paste")
			(net "SW_HDD_N0")
			(options
				(clearance outline)
				(anchor circle)
			)
			(primitives
				(gr_poly
					(pts
						(arc
							(start 0.3048 -0.2032)
							(mid 0.275042 -0.275042)
							(end 0.2032 -0.3048)
						)
						(arc
							(start -0.2032 -0.3048)
							(mid -0.275042 -0.275042)
							(end -0.3048 -0.2032)
						)
						(arc
							(start -0.3048 0.2032)
							(mid -0.275042 0.275042)
							(end -0.2032 0.3048)
						)
						(arc
							(start 0.2032 0.3048)
							(mid 0.275042 0.275042)
							(end 0.3048 0.2032)
						)
					)
					(width 0)
					(fill yes)
				)
			)
		)
	)
	(footprint ""
		(layer "F.Cu")
		(at 479.384614 -158.660592 -90)
		(property "Reference" "C338"
			(at 0 0 270)
			(layer "F.SilkS")
			(hide yes)
			(effects
				(font
					(size 1.27 1.27)
				)
			)
		)
		(property "Value" "SCD01U16V1KX-GP"
			(at -2.8321 -1.7399 270)
			(unlocked yes)
			(layer "F.Fab")
			(hide yes)
			(effects
				(font
					(size 1.016 1.016)
					(thickness 0.1524)
				)
			)
		)
		(property "Device Type" "C0201H13"
			(at -2.8321 -3.2639 270)
			(unlocked yes)
			(layer "F.Fab")
			(hide yes)
			(effects
				(font
					(size 1.016 1.016)
					(thickness 0.1524)
				)
			)
		)
		(duplicate_pad_numbers_are_jumpers no)
		(fp_rect
			(start -0.2794 0.6477)
			(end 0.2794 -0.6477)
			(stroke
				(width 0)
				(type default)
			)
			(fill no)
			(layer "F.CrtYd")
		)
		(fp_rect
			(start -0.2794 0.6477)
			(end 0.2794 -0.6477)
			(stroke
				(width 0)
				(type default)
			)
			(fill no)
			(layer "F.Fab")
		)
		(pad "1" smd custom
			(at 0 -0.2794 270)
			(size 0.0762 0.0762)
			(layers "F.Cu" "F.Mask" "F.Paste")
			(net "SAS_HDD_RX_P23")
			(options
				(clearance outline)
				(anchor circle)
			)
			(primitives
				(gr_poly
					(pts
						(arc
							(start 0.1524 -0.127)
							(mid 0.137521 -0.162921)
							(end 0.1016 -0.1778)
						)
						(arc
							(start -0.1016 -0.1778)
							(mid -0.137521 -0.162921)
							(end -0.1524 -0.127)
						)
						(arc
							(start -0.1524 0.127)
							(mid -0.137521 0.162921)
							(end -0.1016 0.1778)
						)
						(arc
							(start 0.1016 0.1778)
							(mid 0.137521 0.162921)
							(end 0.1524 0.127)
						)
					)
					(width 0)
					(fill yes)
				)
			)
		)
		(pad "2" smd custom
			(at 0 0.2794 270)
			(size 0.0762 0.0762)
			(layers "F.Cu" "F.Mask" "F.Paste")
			(net "PHY_SCC_A_TO_DRV_A_23_DP")
			(options
				(clearance outline)
				(anchor circle)
			)
			(primitives
				(gr_poly
					(pts
						(arc
							(start 0.1524 -0.127)
							(mid 0.137521 -0.162921)
							(end 0.1016 -0.1778)
						)
						(arc
							(start -0.1016 -0.1778)
							(mid -0.137521 -0.162921)
							(end -0.1524 -0.127)
						)
						(arc
							(start -0.1524 0.127)
							(mid -0.137521 0.162921)
							(end -0.1016 0.1778)
						)
						(arc
							(start 0.1016 0.1778)
							(mid 0.137521 0.162921)
							(end 0.1524 0.127)
						)
					)
					(width 0)
					(fill yes)
				)
			)
		)
	)
	(footprint ""
		(layer "F.Cu")
		(at 173.6725 -160.506918 90)
		(property "Reference" "R535"
			(at 0 0 90)
			(layer "F.SilkS")
			(hide yes)
			(effects
				(font
					(size 1.27 1.27)
				)
			)
		)
		(property "Value" "4K7R2J-2-GP"
			(at 0.064008 -3.993896 90)
			(unlocked yes)
			(layer "F.Fab")
			(hide yes)
			(effects
				(font
					(size 1.016 1.016)
					(thickness 0.1524)
				)
			)
		)
		(property "Device Type" "R402H16"
			(at 0.064008 -5.517896 90)
			(unlocked yes)
			(layer "F.Fab")
			(hide yes)
			(effects
				(font
					(size 1.016 1.016)
					(thickness 0.1524)
				)
			)
		)
		(duplicate_pad_numbers_are_jumpers no)
		(fp_line
			(start 0.508 -0.9398)
			(end -0.508 -0.9398)
			(stroke
				(width 0.1524)
				(type default)
			)
			(layer "F.SilkS")
		)
		(fp_line
			(start -0.508 -0.9398)
			(end -0.508 0.9398)
			(stroke
				(width 0.1524)
				(type default)
			)
			(layer "F.SilkS")
		)
		(fp_rect
			(start -0.508 0.9398)
			(end 0.508 -0.9398)
			(stroke
				(width 0)
				(type default)
			)
			(fill no)
			(layer "F.CrtYd")
		)
		(fp_rect
			(start -0.508 0.9398)
			(end 0.508 -0.9398)
			(stroke
				(width 0)
				(type default)
			)
			(fill no)
			(layer "F.Fab")
		)
		(pad "1" smd custom
			(at 0 -0.4445 90)
			(size 0.1397 0.1397)
			(layers "F.Cu" "F.Mask" "F.Paste")
			(net "P12V_A")
			(options
				(clearance outline)
				(anchor circle)
			)
			(primitives
				(gr_poly
					(pts
						(arc
							(start -0.1778 -0.2794)
							(mid -0.249642 -0.249642)
							(end -0.2794 -0.1778)
						)
						(arc
							(start -0.2794 0.1778)
							(mid -0.249642 0.249642)
							(end -0.1778 0.2794)
						)
						(arc
							(start 0.1778 0.2794)
							(mid 0.249642 0.249642)
							(end 0.2794 0.1778)
						)
						(arc
							(start 0.2794 -0.1778)
							(mid 0.249642 -0.249642)
							(end 0.1778 -0.2794)
						)
					)
					(width 0)
					(fill yes)
				)
			)
		)
		(pad "2" smd custom
			(at 0 0.4445 90)
			(size 0.1397 0.1397)
			(layers "F.Cu" "F.Mask" "F.Paste")
			(net "SW_HDD_R17")
			(options
				(clearance outline)
				(anchor circle)
			)
			(primitives
				(gr_poly
					(pts
						(arc
							(start -0.1778 -0.2794)
							(mid -0.249642 -0.249642)
							(end -0.2794 -0.1778)
						)
						(arc
							(start -0.2794 0.1778)
							(mid -0.249642 0.249642)
							(end -0.1778 0.2794)
						)
						(arc
							(start 0.1778 0.2794)
							(mid 0.249642 0.249642)
							(end 0.2794 0.1778)
						)
						(arc
							(start 0.2794 -0.1778)
							(mid 0.249642 -0.249642)
							(end 0.1778 -0.2794)
						)
					)
					(width 0)
					(fill yes)
				)
			)
		)
	)
	(footprint ""
		(layer "F.Cu")
		(at 378.864876 -127.254)
		(property "Reference" "R334"
			(at 0 0 0)
			(layer "F.SilkS")
			(hide yes)
			(effects
				(font
					(size 1.27 1.27)
				)
			)
		)
		(property "Value" "91R3F-1-GP"
			(at -0.0254 -2.5146 0)
			(unlocked yes)
			(layer "F.Fab")
			(hide yes)
			(effects
				(font
					(size 1.016 1.016)
					(thickness 0.1524)
				)
			)
		)
		(property "Device Type" "R603H22"
			(at -0.0254 -4.0386 0)
			(unlocked yes)
			(layer "F.Fab")
			(hide yes)
			(effects
				(font
					(size 1.016 1.016)
					(thickness 0.1524)
				)
			)
		)
		(duplicate_pad_numbers_are_jumpers no)
		(fp_line
			(start -0.4826 0)
			(end -0.2032 0)
			(stroke
				(width 0.2032)
				(type default)
			)
			(layer "F.SilkS")
		)
		(fp_line
			(start 0.2032 0)
			(end 0.4826 0)
			(stroke
				(width 0.2032)
				(type default)
			)
			(layer "F.SilkS")
		)
		(fp_rect
			(start -0.5842 1.3335)
			(end 0.5842 -1.3335)
			(stroke
				(width 0)
				(type default)
			)
			(fill no)
			(layer "F.CrtYd")
		)
		(fp_rect
			(start -0.5842 1.3335)
			(end 0.5842 -1.3335)
			(stroke
				(width 0)
				(type default)
			)
			(fill no)
			(layer "F.Fab")
		)
		(pad "1" smd custom
			(at 0 -0.762)
			(size 0.2159 0.2159)
			(layers "F.Cu" "F.Mask" "F.Paste")
			(net "P5V_A_3")
			(options
				(clearance outline)
				(anchor circle)
			)
			(primitives
				(gr_poly
					(pts
						(arc
							(start -0.3302 -0.4318)
							(mid -0.402042 -0.402042)
							(end -0.4318 -0.3302)
						)
						(arc
							(start -0.4318 0.3302)
							(mid -0.402042 0.402042)
							(end -0.3302 0.4318)
						)
						(arc
							(start 0.3302 0.4318)
							(mid 0.402042 0.402042)
							(end 0.4318 0.3302)
						)
						(arc
							(start 0.4318 -0.3302)
							(mid 0.402042 -0.402042)
							(end 0.3302 -0.4318)
						)
					)
					(width 0)
					(fill yes)
				)
			)
		)
		(pad "2" smd custom
			(at 0 0.762)
			(size 0.2159 0.2159)
			(layers "F.Cu" "F.Mask" "F.Paste")
			(net "DRV_ACT_20")
			(options
				(clearance outline)
				(anchor circle)
			)
			(primitives
				(gr_poly
					(pts
						(arc
							(start -0.3302 -0.4318)
							(mid -0.402042 -0.402042)
							(end -0.4318 -0.3302)
						)
						(arc
							(start -0.4318 0.3302)
							(mid -0.402042 0.402042)
							(end -0.3302 0.4318)
						)
						(arc
							(start 0.3302 0.4318)
							(mid 0.402042 0.402042)
							(end 0.4318 0.3302)
						)
						(arc
							(start 0.4318 -0.3302)
							(mid 0.402042 -0.402042)
							(end 0.3302 -0.4318)
						)
					)
					(width 0)
					(fill yes)
				)
			)
		)
	)
	(footprint ""
		(layer "F.Cu")
		(at 311.36463 -293.913814)
		(property "Reference" "Q257"
			(at 0 0 0)
			(layer "F.SilkS")
			(hide yes)
			(effects
				(font
					(size 1.27 1.27)
				)
			)
		)
		(property "Value" "2N7002K-2-GP"
			(at 0.127 -8.9662 0)
			(unlocked yes)
			(layer "F.Fab")
			(hide yes)
			(effects
				(font
					(size 1.016 1.016)
					(thickness 0.1524)
				)
			)
		)
		(property "Device Type" "SOT23DGS2D4H44"
			(at 0.127 -10.4902 0)
			(unlocked yes)
			(layer "F.Fab")
			(hide yes)
			(effects
				(font
					(size 1.016 1.016)
					(thickness 0.1524)
				)
			)
		)
		(duplicate_pad_numbers_are_jumpers no)
		(fp_line
			(start -1.651 -1.778)
			(end -1.651 1.778)
			(stroke
				(width 0.1524)
				(type default)
			)
			(layer "F.SilkS")
		)
		(fp_line
			(start -1.651 1.778)
			(end 1.651 1.778)
			(stroke
				(width 0.1524)
				(type default)
			)
			(layer "F.SilkS")
		)
		(fp_line
			(start 1.651 -1.778)
			(end -1.651 -1.778)
			(stroke
				(width 0.1524)
				(type default)
			)
			(layer "F.SilkS")
		)
		(fp_line
			(start 1.651 1.778)
			(end 1.651 -1.778)
			(stroke
				(width 0.1524)
				(type default)
			)
			(layer "F.SilkS")
		)
		(fp_poly
			(pts
				(xy -1.778 1.8796) (xy -1.778 -1.8796) (xy 1.778 -1.8796) (xy 1.778 1.8796)
			)
			(stroke
				(width 0)
				(type default)
			)
			(fill no)
			(layer "F.CrtYd")
		)
		(fp_poly
			(pts
				(xy -1.778 1.8796) (xy -1.778 -1.8796) (xy 1.778 -1.8796) (xy 1.778 1.8796)
			)
			(stroke
				(width 0)
				(type default)
			)
			(fill no)
			(layer "F.Fab")
		)
		(pad "D" smd custom
			(at 0 -0.9525)
			(size 0.1905 0.1905)
			(layers "F.Cu" "F.Mask" "F.Paste")
			(net "FLT_HDD30_N")
			(options
				(clearance outline)
				(anchor circle)
			)
			(primitives
				(gr_poly
					(pts
						(arc
							(start -0.1778 0.5715)
							(mid -0.321484 0.511984)
							(end -0.381 0.3683)
						)
						(arc
							(start -0.381 -0.3683)
							(mid -0.321484 -0.511984)
							(end -0.1778 -0.5715)
						)
						(arc
							(start 0.1778 -0.5715)
							(mid 0.321484 -0.511984)
							(end 0.381 -0.3683)
						)
						(arc
							(start 0.381 0.3683)
							(mid 0.321484 0.511984)
							(end 0.1778 0.5715)
						)
					)
					(width 0)
					(fill yes)
				)
			)
		)
		(pad "G" smd custom
			(at -0.98425 0.9525)
			(size 0.1905 0.1905)
			(layers "F.Cu" "F.Mask" "F.Paste")
			(net "DRIVE_B_30_FLT_LED")
			(options
				(clearance outline)
				(anchor circle)
			)
			(primitives
				(gr_poly
					(pts
						(arc
							(start -0.1778 0.5715)
							(mid -0.321484 0.511984)
							(end -0.381 0.3683)
						)
						(arc
							(start -0.381 -0.3683)
							(mid -0.321484 -0.511984)
							(end -0.1778 -0.5715)
						)
						(arc
							(start 0.1778 -0.5715)
							(mid 0.321484 -0.511984)
							(end 0.381 -0.3683)
						)
						(arc
							(start 0.381 0.3683)
							(mid 0.321484 0.511984)
							(end 0.1778 0.5715)
						)
					)
					(width 0)
					(fill yes)
				)
			)
		)
		(pad "S" smd custom
			(at 0.98425 0.9525)
			(size 0.1905 0.1905)
			(layers "F.Cu" "F.Mask" "F.Paste")
			(net "GND")
			(options
				(clearance outline)
				(anchor circle)
			)
			(primitives
				(gr_poly
					(pts
						(arc
							(start -0.1778 0.5715)
							(mid -0.321484 0.511984)
							(end -0.381 0.3683)
						)
						(arc
							(start -0.381 -0.3683)
							(mid -0.321484 -0.511984)
							(end -0.1778 -0.5715)
						)
						(arc
							(start 0.1778 -0.5715)
							(mid 0.321484 -0.511984)
							(end 0.381 -0.3683)
						)
						(arc
							(start 0.381 0.3683)
							(mid 0.321484 0.511984)
							(end 0.1778 0.5715)
						)
					)
					(width 0)
					(fill yes)
				)
			)
		)
	)
	(footprint ""
		(layer "F.Cu")
		(at 236.802676 -349.211392 180)
		(property "Reference" "R20"
			(at 0 0 180)
			(layer "F.SilkS")
			(hide yes)
			(effects
				(font
					(size 1.27 1.27)
				)
			)
		)
		(property "Value" "10KR2F-2-GP"
			(at 0.064008 -3.993896 180)
			(unlocked yes)
			(layer "F.Fab")
			(hide yes)
			(effects
				(font
					(size 1.016 1.016)
					(thickness 0.1524)
				)
			)
		)
		(property "Device Type" "R402H16"
			(at 0.064008 -5.517896 180)
			(unlocked yes)
			(layer "F.Fab")
			(hide yes)
			(effects
				(font
					(size 1.016 1.016)
					(thickness 0.1524)
				)
			)
		)
		(duplicate_pad_numbers_are_jumpers no)
		(fp_line
			(start 0.508 -0.9398)
			(end -0.508 -0.9398)
			(stroke
				(width 0.1524)
				(type default)
			)
			(layer "F.SilkS")
		)
		(fp_line
			(start -0.508 -0.9398)
			(end -0.508 0.9398)
			(stroke
				(width 0.1524)
				(type default)
			)
			(layer "F.SilkS")
		)
		(fp_rect
			(start -0.508 0.9398)
			(end 0.508 -0.9398)
			(stroke
				(width 0)
				(type default)
			)
			(fill no)
			(layer "F.CrtYd")
		)
		(fp_rect
			(start -0.508 0.9398)
			(end 0.508 -0.9398)
			(stroke
				(width 0)
				(type default)
			)
			(fill no)
			(layer "F.Fab")
		)
		(pad "1" smd custom
			(at 0 -0.4445 180)
			(size 0.1397 0.1397)
			(layers "F.Cu" "F.Mask" "F.Paste")
			(net "P3V3_SENSE")
			(options
				(clearance outline)
				(anchor circle)
			)
			(primitives
				(gr_poly
					(pts
						(arc
							(start -0.1778 -0.2794)
							(mid -0.249642 -0.249642)
							(end -0.2794 -0.1778)
						)
						(arc
							(start -0.2794 0.1778)
							(mid -0.249642 0.249642)
							(end -0.1778 0.2794)
						)
						(arc
							(start 0.1778 0.2794)
							(mid 0.249642 0.249642)
							(end 0.2794 0.1778)
						)
						(arc
							(start 0.2794 -0.1778)
							(mid 0.249642 -0.249642)
							(end 0.1778 -0.2794)
						)
					)
					(width 0)
					(fill yes)
				)
			)
		)
		(pad "2" smd custom
			(at 0 0.4445 180)
			(size 0.1397 0.1397)
			(layers "F.Cu" "F.Mask" "F.Paste")
			(net "GND")
			(options
				(clearance outline)
				(anchor circle)
			)
			(primitives
				(gr_poly
					(pts
						(arc
							(start -0.1778 -0.2794)
							(mid -0.249642 -0.249642)
							(end -0.2794 -0.1778)
						)
						(arc
							(start -0.2794 0.1778)
							(mid -0.249642 0.249642)
							(end -0.1778 0.2794)
						)
						(arc
							(start 0.1778 0.2794)
							(mid 0.249642 0.249642)
							(end 0.2794 0.1778)
						)
						(arc
							(start 0.2794 -0.1778)
							(mid 0.249642 -0.249642)
							(end 0.1778 -0.2794)
						)
					)
					(width 0)
					(fill yes)
				)
			)
		)
	)
	(footprint ""
		(layer "F.Cu")
		(at 158.708852 -162.749992 -90)
		(property "Reference" "VIA54"
			(at 0 0 270)
			(layer "F.SilkS")
			(hide yes)
			(effects
				(font
					(size 1.27 1.27)
				)
			)
		)
		(property "Value" "100OHM-8L-1D6MM-L18L16-GP"
			(at -3.7211 -4.5085 270)
			(unlocked yes)
			(layer "F.Fab")
			(hide yes)
			(effects
				(font
					(size 1.016 1.016)
					(thickness 0.1524)
				)
			)
		)
		(property "Device Type" "VIA-PCIE-4P-394076"
			(at -3.7211 -6.0325 270)
			(unlocked yes)
			(layer "F.Fab")
			(hide yes)
			(effects
				(font
					(size 1.016 1.016)
					(thickness 0.1524)
				)
			)
		)
		(duplicate_pad_numbers_are_jumpers no)
		(fp_rect
			(start -1.9685 0.381)
			(end 1.9685 -0.381)
			(stroke
				(width 0)
				(type default)
			)
			(fill no)
			(layer "F.CrtYd")
		)
		(fp_rect
			(start -1.9685 0.381)
			(end 1.9685 -0.381)
			(stroke
				(width 0)
				(type default)
			)
			(fill no)
			(layer "F.Fab")
		)
		(pad "1" thru_hole circle
			(at -1.5875 0 270)
			(size 0.508 0.508)
			(drill 0.254)
			(layers "*.Cu" "*.Mask")
			(remove_unused_layers no)
			(net "GND")
			(clearance 0.127)
			(thermal_gap 0.127)
		)
		(pad "2" thru_hole circle
			(at -0.5715 0 270)
			(size 0.508 0.508)
			(drill 0.254)
			(layers "*.Cu" "*.Mask")
			(remove_unused_layers no)
			(net "PHY_DRV_A_TO_SCC_A_16_DP")
			(clearance 0.127)
			(thermal_gap 0.127)
		)
		(pad "3" thru_hole circle
			(at 0.5715 0 270)
			(size 0.508 0.508)
			(drill 0.254)
			(layers "*.Cu" "*.Mask")
			(remove_unused_layers no)
			(net "PHY_DRV_A_TO_SCC_A_16_DN")
			(clearance 0.127)
			(thermal_gap 0.127)
		)
		(pad "4" thru_hole circle
			(at 1.5875 0 270)
			(size 0.508 0.508)
			(drill 0.254)
			(layers "*.Cu" "*.Mask")
			(remove_unused_layers no)
			(net "GND")
			(clearance 0.127)
			(thermal_gap 0.127)
		)
	)
	(footprint ""
		(layer "F.Cu")
		(at 51.599846 -61.000894 -90)
		(property "Reference" "C366"
			(at 0 0 270)
			(layer "F.SilkS")
			(hide yes)
			(effects
				(font
					(size 1.27 1.27)
				)
			)
		)
		(property "Value" "SC10U16V6KX-2GP"
			(at -0.0762 -5.1308 270)
			(unlocked yes)
			(layer "F.Fab")
			(hide yes)
			(effects
				(font
					(size 1.016 1.016)
					(thickness 0.1524)
				)
			)
		)
		(property "Device Type" "C1206H71"
			(at -0.127 -6.6548 270)
			(unlocked yes)
			(layer "F.Fab")
			(hide yes)
			(effects
				(font
					(size 1.016 1.016)
					(thickness 0.1524)
				)
			)
		)
		(duplicate_pad_numbers_are_jumpers no)
		(fp_line
			(start -1.016 2.2352)
			(end -1.016 0.8382)
			(stroke
				(width 0.1524)
				(type default)
			)
			(layer "F.SilkS")
		)
		(fp_line
			(start 1.016 2.2352)
			(end -1.016 2.2352)
			(stroke
				(width 0.1524)
				(type default)
			)
			(layer "F.SilkS")
		)
		(fp_line
			(start 1.016 0.8382)
			(end 1.016 2.2352)
			(stroke
				(width 0.1524)
				(type default)
			)
			(layer "F.SilkS")
		)
		(fp_line
			(start -1.016 -0.8382)
			(end -1.016 -2.2352)
			(stroke
				(width 0.1524)
				(type default)
			)
			(layer "F.SilkS")
		)
		(fp_line
			(start -1.016 -2.2352)
			(end 1.016 -2.2352)
			(stroke
				(width 0.1524)
				(type default)
			)
			(layer "F.SilkS")
		)
		(fp_line
			(start 1.016 -2.2352)
			(end 1.016 -0.8382)
			(stroke
				(width 0.1524)
				(type default)
			)
			(layer "F.SilkS")
		)
		(fp_rect
			(start -1.0922 2.3114)
			(end 1.0922 -2.3114)
			(stroke
				(width 0)
				(type default)
			)
			(fill no)
			(layer "F.CrtYd")
		)
		(fp_poly
			(pts
				(xy 1.0922 -2.3114) (xy 1.0922 2.3114) (xy -1.0922 2.3114) (xy -1.0922 -2.3114)
			)
			(stroke
				(width 0)
				(type default)
			)
			(fill no)
			(layer "F.Fab")
		)
		(pad "1" smd rect
			(at 0 -1.397 270)
			(size 1.651 1.27)
			(layers "F.Cu" "F.Mask" "F.Paste")
			(net "P5V_HDD25")
		)
		(pad "2" smd rect
			(at 0 1.397 270)
			(size 1.651 1.27)
			(layers "F.Cu" "F.Mask" "F.Paste")
			(net "GND")
		)
	)
	(footprint ""
		(layer "F.Cu")
		(at 338.709 -286.809942 -90)
		(property "Reference" "R283"
			(at 0 0 270)
			(layer "F.SilkS")
			(hide yes)
			(effects
				(font
					(size 1.27 1.27)
				)
			)
		)
		(property "Value" "300KR2F-GP"
			(at 0.064008 -3.993896 270)
			(unlocked yes)
			(layer "F.Fab")
			(hide yes)
			(effects
				(font
					(size 1.016 1.016)
					(thickness 0.1524)
				)
			)
		)
		(property "Device Type" "R402H16"
			(at 0.064008 -5.517896 270)
			(unlocked yes)
			(layer "F.Fab")
			(hide yes)
			(effects
				(font
					(size 1.016 1.016)
					(thickness 0.1524)
				)
			)
		)
		(duplicate_pad_numbers_are_jumpers no)
		(fp_line
			(start -0.508 -0.9398)
			(end -0.508 0.9398)
			(stroke
				(width 0.1524)
				(type default)
			)
			(layer "F.SilkS")
		)
		(fp_line
			(start 0.508 -0.9398)
			(end -0.508 -0.9398)
			(stroke
				(width 0.1524)
				(type default)
			)
			(layer "F.SilkS")
		)
		(fp_rect
			(start -0.508 0.9398)
			(end 0.508 -0.9398)
			(stroke
				(width 0)
				(type default)
			)
			(fill no)
			(layer "F.CrtYd")
		)
		(fp_rect
			(start -0.508 0.9398)
			(end 0.508 -0.9398)
			(stroke
				(width 0)
				(type default)
			)
			(fill no)
			(layer "F.Fab")
		)
		(pad "1" smd custom
			(at 0 -0.4445 270)
			(size 0.1397 0.1397)
			(layers "F.Cu" "F.Mask" "F.Paste")
			(net "SW_HDD_N6")
			(options
				(clearance outline)
				(anchor circle)
			)
			(primitives
				(gr_poly
					(pts
						(arc
							(start -0.1778 -0.2794)
							(mid -0.249642 -0.249642)
							(end -0.2794 -0.1778)
						)
						(arc
							(start -0.2794 0.1778)
							(mid -0.249642 0.249642)
							(end -0.1778 0.2794)
						)
						(arc
							(start 0.1778 0.2794)
							(mid 0.249642 0.249642)
							(end 0.2794 0.1778)
						)
						(arc
							(start 0.2794 -0.1778)
							(mid 0.249642 -0.249642)
							(end 0.1778 -0.2794)
						)
					)
					(width 0)
					(fill yes)
				)
			)
		)
		(pad "2" smd custom
			(at 0 0.4445 270)
			(size 0.1397 0.1397)
			(layers "F.Cu" "F.Mask" "F.Paste")
			(net "P12V_A")
			(options
				(clearance outline)
				(anchor circle)
			)
			(primitives
				(gr_poly
					(pts
						(arc
							(start -0.1778 -0.2794)
							(mid -0.249642 -0.249642)
							(end -0.2794 -0.1778)
						)
						(arc
							(start -0.2794 0.1778)
							(mid -0.249642 0.249642)
							(end -0.1778 0.2794)
						)
						(arc
							(start 0.1778 0.2794)
							(mid 0.249642 0.249642)
							(end 0.2794 0.1778)
						)
						(arc
							(start 0.2794 -0.1778)
							(mid 0.249642 -0.249642)
							(end 0.1778 -0.2794)
						)
					)
					(width 0)
					(fill yes)
				)
			)
		)
	)
	(footprint ""
		(layer "F.Cu")
		(at 221.021402 -213.881462)
		(property "Reference" "C68"
			(at 0 0 0)
			(layer "F.SilkS")
			(hide yes)
			(effects
				(font
					(size 1.27 1.27)
				)
			)
		)
		(property "Value" "SCD1U16V2KX-3GP"
			(at 1.1811 -2.7051 0)
			(unlocked yes)
			(layer "F.Fab")
			(hide yes)
			(effects
				(font
					(size 1.016 1.016)
					(thickness 0.1524)
				)
			)
		)
		(property "Device Type" "C402H22"
			(at 1.1811 -4.2291 0)
			(unlocked yes)
			(layer "F.Fab")
			(hide yes)
			(effects
				(font
					(size 1.016 1.016)
					(thickness 0.1524)
				)
			)
		)
		(duplicate_pad_numbers_are_jumpers no)
		(fp_rect
			(start -0.4318 0.9525)
			(end 0.4318 -0.9525)
			(stroke
				(width 0)
				(type default)
			)
			(fill no)
			(layer "F.CrtYd")
		)
		(fp_rect
			(start -0.4318 0.9525)
			(end 0.4318 -0.9525)
			(stroke
				(width 0)
				(type default)
			)
			(fill no)
			(layer "F.Fab")
		)
		(pad "1" smd custom
			(at 0 -0.4445)
			(size 0.1524 0.1524)
			(layers "F.Cu" "F.Mask" "F.Paste")
			(net "P3V3_STBY_A")
			(options
				(clearance outline)
				(anchor circle)
			)
			(primitives
				(gr_poly
					(pts
						(arc
							(start 0.3048 -0.2032)
							(mid 0.275042 -0.275042)
							(end 0.2032 -0.3048)
						)
						(arc
							(start -0.2032 -0.3048)
							(mid -0.275042 -0.275042)
							(end -0.3048 -0.2032)
						)
						(arc
							(start -0.3048 0.2032)
							(mid -0.275042 0.275042)
							(end -0.2032 0.3048)
						)
						(arc
							(start 0.2032 0.3048)
							(mid 0.275042 0.275042)
							(end 0.3048 0.2032)
						)
					)
					(width 0)
					(fill yes)
				)
			)
		)
		(pad "2" smd custom
			(at 0 0.4445)
			(size 0.1524 0.1524)
			(layers "F.Cu" "F.Mask" "F.Paste")
			(net "GND")
			(options
				(clearance outline)
				(anchor circle)
			)
			(primitives
				(gr_poly
					(pts
						(arc
							(start 0.3048 -0.2032)
							(mid 0.275042 -0.275042)
							(end 0.2032 -0.3048)
						)
						(arc
							(start -0.2032 -0.3048)
							(mid -0.275042 -0.275042)
							(end -0.3048 -0.2032)
						)
						(arc
							(start -0.3048 0.2032)
							(mid -0.275042 0.275042)
							(end -0.2032 0.3048)
						)
						(arc
							(start 0.2032 0.3048)
							(mid 0.275042 0.275042)
							(end 0.3048 0.2032)
						)
					)
					(width 0)
					(fill yes)
				)
			)
		)
	)
	(footprint ""
		(layer "F.Cu")
		(at 35.797998 -291.127942 90)
		(property "Reference" "C513"
			(at 0 0 90)
			(layer "F.SilkS")
			(hide yes)
			(effects
				(font
					(size 1.27 1.27)
				)
			)
		)
		(property "Value" "SCD01U50V2KX-1GP"
			(at 1.1811 -2.7051 90)
			(unlocked yes)
			(layer "F.Fab")
			(hide yes)
			(effects
				(font
					(size 1.016 1.016)
					(thickness 0.1524)
				)
			)
		)
		(property "Device Type" "C402H22"
			(at 1.1811 -4.2291 90)
			(unlocked yes)
			(layer "F.Fab")
			(hide yes)
			(effects
				(font
					(size 1.016 1.016)
					(thickness 0.1524)
				)
			)
		)
		(duplicate_pad_numbers_are_jumpers no)
		(fp_rect
			(start -0.4318 0.9525)
			(end 0.4318 -0.9525)
			(stroke
				(width 0)
				(type default)
			)
			(fill no)
			(layer "F.CrtYd")
		)
		(fp_rect
			(start -0.4318 0.9525)
			(end 0.4318 -0.9525)
			(stroke
				(width 0)
				(type default)
			)
			(fill no)
			(layer "F.Fab")
		)
		(pad "1" smd custom
			(at 0 -0.4445 90)
			(size 0.1524 0.1524)
			(layers "F.Cu" "F.Mask" "F.Paste")
			(net "HDD_PRSNT_0")
			(options
				(clearance outline)
				(anchor circle)
			)
			(primitives
				(gr_poly
					(pts
						(arc
							(start 0.3048 -0.2032)
							(mid 0.275042 -0.275042)
							(end 0.2032 -0.3048)
						)
						(arc
							(start -0.2032 -0.3048)
							(mid -0.275042 -0.275042)
							(end -0.3048 -0.2032)
						)
						(arc
							(start -0.3048 0.2032)
							(mid -0.275042 0.275042)
							(end -0.2032 0.3048)
						)
						(arc
							(start 0.2032 0.3048)
							(mid 0.275042 0.275042)
							(end 0.3048 0.2032)
						)
					)
					(width 0)
					(fill yes)
				)
			)
		)
		(pad "2" smd custom
			(at 0 0.4445 90)
			(size 0.1524 0.1524)
			(layers "F.Cu" "F.Mask" "F.Paste")
			(net "GND")
			(options
				(clearance outline)
				(anchor circle)
			)
			(primitives
				(gr_poly
					(pts
						(arc
							(start 0.3048 -0.2032)
							(mid 0.275042 -0.275042)
							(end 0.2032 -0.3048)
						)
						(arc
							(start -0.2032 -0.3048)
							(mid -0.275042 -0.275042)
							(end -0.3048 -0.2032)
						)
						(arc
							(start -0.3048 0.2032)
							(mid -0.275042 0.275042)
							(end -0.2032 0.3048)
						)
						(arc
							(start 0.2032 0.3048)
							(mid 0.275042 0.275042)
							(end 0.3048 0.2032)
						)
					)
					(width 0)
					(fill yes)
				)
			)
		)
	)
	(footprint ""
		(layer "F.Cu")
		(at 382.787398 -134.849362 180)
		(property "Reference" "R1295"
			(at 0 0 180)
			(layer "F.SilkS")
			(hide yes)
			(effects
				(font
					(size 1.27 1.27)
				)
			)
		)
		(property "Value" "3K3R3F-GP"
			(at -0.0254 -2.5146 180)
			(unlocked yes)
			(layer "F.Fab")
			(hide yes)
			(effects
				(font
					(size 1.016 1.016)
					(thickness 0.1524)
				)
			)
		)
		(property "Device Type" "R603H22"
			(at -0.0254 -4.0386 180)
			(unlocked yes)
			(layer "F.Fab")
			(hide yes)
			(effects
				(font
					(size 1.016 1.016)
					(thickness 0.1524)
				)
			)
		)
		(duplicate_pad_numbers_are_jumpers no)
		(fp_line
			(start 0.2032 0)
			(end 0.4826 0)
			(stroke
				(width 0.2032)
				(type default)
			)
			(layer "F.SilkS")
		)
		(fp_line
			(start -0.4826 0)
			(end -0.2032 0)
			(stroke
				(width 0.2032)
				(type default)
			)
			(layer "F.SilkS")
		)
		(fp_rect
			(start -0.5842 1.3335)
			(end 0.5842 -1.3335)
			(stroke
				(width 0)
				(type default)
			)
			(fill no)
			(layer "F.CrtYd")
		)
		(fp_rect
			(start -0.5842 1.3335)
			(end 0.5842 -1.3335)
			(stroke
				(width 0)
				(type default)
			)
			(fill no)
			(layer "F.Fab")
		)
		(pad "1" smd custom
			(at 0 -0.762 180)
			(size 0.2159 0.2159)
			(layers "F.Cu" "F.Mask" "F.Paste")
			(net "P12V_B")
			(options
				(clearance outline)
				(anchor circle)
			)
			(primitives
				(gr_poly
					(pts
						(arc
							(start -0.3302 -0.4318)
							(mid -0.402042 -0.402042)
							(end -0.4318 -0.3302)
						)
						(arc
							(start -0.4318 0.3302)
							(mid -0.402042 0.402042)
							(end -0.3302 0.4318)
						)
						(arc
							(start 0.3302 0.4318)
							(mid 0.402042 0.402042)
							(end 0.4318 0.3302)
						)
						(arc
							(start 0.4318 -0.3302)
							(mid 0.402042 -0.402042)
							(end 0.3302 -0.4318)
						)
					)
					(width 0)
					(fill yes)
				)
			)
		)
		(pad "2" smd custom
			(at 0 0.762 180)
			(size 0.2159 0.2159)
			(layers "F.Cu" "F.Mask" "F.Paste")
			(net "VCCP_B")
			(options
				(clearance outline)
				(anchor circle)
			)
			(primitives
				(gr_poly
					(pts
						(arc
							(start -0.3302 -0.4318)
							(mid -0.402042 -0.402042)
							(end -0.4318 -0.3302)
						)
						(arc
							(start -0.4318 0.3302)
							(mid -0.402042 0.402042)
							(end -0.3302 0.4318)
						)
						(arc
							(start 0.3302 0.4318)
							(mid 0.402042 0.402042)
							(end 0.4318 0.3302)
						)
						(arc
							(start 0.4318 -0.3302)
							(mid 0.402042 -0.402042)
							(end 0.3302 -0.4318)
						)
					)
					(width 0)
					(fill yes)
				)
			)
		)
	)
	(footprint ""
		(layer "F.Cu")
		(at 330.67498 -92.799916)
		(property "Reference" ""
			(at 0 0 0)
			(layer "F.SilkS")
			(hide yes)
			(effects
				(font
					(size 1.27 1.27)
				)
			)
		)
		(property "Value" "*"
			(at -8.398764 -8.057642 0)
			(unlocked yes)
			(layer "F.Fab")
			(hide yes)
			(effects
				(font
					(size 1.016 1.016)
					(thickness 0.1524)
				)
			)
		)
		(duplicate_pad_numbers_are_jumpers no)
		(fp_poly
			(pts
				(arc
					(start 7.3152 0)
					(mid 0 7.3152)
					(end -7.3152 0)
				)
				(arc
					(start -7.3152 -5.9944)
					(mid 0 -13.3096)
					(end 7.3152 -5.9944)
				)
			)
			(stroke
				(width 0)
				(type default)
			)
			(fill no)
			(layer "B.CrtYd")
		)
		(fp_poly
			(pts
				(arc
					(start 7.3152 0)
					(mid 0 7.3152)
					(end -7.3152 0)
				)
				(arc
					(start -7.3152 -5.9944)
					(mid 0 -13.3096)
					(end 7.3152 -5.9944)
				)
			)
			(stroke
				(width 0)
				(type default)
			)
			(fill no)
			(layer "F.CrtYd")
		)
		(fp_poly
			(pts
				(arc
					(start 7.3152 0)
					(mid 0 7.3152)
					(end -7.3152 0)
				)
				(arc
					(start -7.3152 -5.9944)
					(mid 0 -13.3096)
					(end 7.3152 -5.9944)
				)
			)
			(stroke
				(width 0)
				(type default)
			)
			(fill no)
			(layer "B.Fab")
		)
		(fp_poly
			(pts
				(arc
					(start 7.3152 0)
					(mid 0 7.3152)
					(end -7.3152 0)
				)
				(arc
					(start -7.3152 -5.9944)
					(mid 0 -13.3096)
					(end 7.3152 -5.9944)
				)
			)
			(stroke
				(width 0)
				(type default)
			)
			(fill no)
			(layer "F.Fab")
		)
		(pad "1" thru_hole oval
			(at 0 0)
			(size 14.0208 20.0152)
			(drill 0.0254
				(offset 0 -2.9972)
			)
			(layers "*.Cu" "*.Mask")
			(remove_unused_layers no)
			(net "Net_102")
			(clearance -1.002284)
			(thermal_gap 0.1524)
			(padstack
				(mode front_inner_back)
				(layer "Inner"
					(shape custom)
					(size 2.928012 2.928012)
					(options
						(anchor circle)
					)
					(primitives
						(gr_poly
							(pts
								(arc
									(start 4.571746 -2.084324)
									(mid 0.000333 7.430372)
									(end -4.571492 -2.084324)
								)
								(arc
									(start -4.571492 -2.084324)
									(mid -3.570296 -3.611977)
									(end -2.875026 -5.30098)
								)
								(arc
									(start -2.875026 -5.30098)
									(mid 0.000217 -7.43089)
									(end 2.87528 -5.30098)
								)
								(arc
									(start 2.87528 -5.30098)
									(mid 3.570511 -3.611956)
									(end 4.571746 -2.084324)
								)
							)
							(width 0)
							(fill yes)
						)
					)
					(clearance 0.1524)
				)
				(layer "B.Cu"
					(shape oval)
					(size 14.0208 20.0152)
					(offset 0 -2.9972)
					(clearance -1.002284)
				)
			)
		)
		(zone
			(layers "F.Cu" "B.Cu" "In1.Cu" "In2.Cu" "In3.Cu" "In4.Cu" "In5.Cu" "In6.Cu"
				"In7.Cu" "In8.Cu" "In9.Cu" "In10.Cu"
			)
			(hatch none 0.5)
			(connect_pads
				(clearance 0)
			)
			(min_thickness 0.25)
			(keepout
				(tracks not_allowed)
				(vias allowed)
				(pads allowed)
				(copperpour not_allowed)
				(footprints allowed)
			)
			(placement
				(enabled no)
				(sheetname "")
			)
			(fill
				(thermal_gap 0.5)
				(thermal_bridge_width 0.5)
				(island_removal_mode 0)
			)
			(polygon
				(pts
					(arc
						(start 323.66458 -98.794316)
						(mid 330.67498 -105.804716)
						(end 337.68538 -98.794316)
					)
					(arc
						(start 337.68538 -92.799916)
						(mid 330.67498 -85.789516)
						(end 323.66458 -92.799916)
					)
				)
			)
		)
	)
	(footprint ""
		(layer "F.Cu")
		(at 467.635336 -294.315134 180)
		(property "Reference" "R326"
			(at 0 0 180)
			(layer "F.SilkS")
			(hide yes)
			(effects
				(font
					(size 1.27 1.27)
				)
			)
		)
		(property "Value" "130R3F-GP"
			(at -0.0254 -2.5146 180)
			(unlocked yes)
			(layer "F.Fab")
			(hide yes)
			(effects
				(font
					(size 1.016 1.016)
					(thickness 0.1524)
				)
			)
		)
		(property "Device Type" "R603H22"
			(at -0.0254 -4.0386 180)
			(unlocked yes)
			(layer "F.Fab")
			(hide yes)
			(effects
				(font
					(size 1.016 1.016)
					(thickness 0.1524)
				)
			)
		)
		(duplicate_pad_numbers_are_jumpers no)
		(fp_line
			(start 0.2032 0)
			(end 0.4826 0)
			(stroke
				(width 0.2032)
				(type default)
			)
			(layer "F.SilkS")
		)
		(fp_line
			(start -0.4826 0)
			(end -0.2032 0)
			(stroke
				(width 0.2032)
				(type default)
			)
			(layer "F.SilkS")
		)
		(fp_rect
			(start -0.5842 1.3335)
			(end 0.5842 -1.3335)
			(stroke
				(width 0)
				(type default)
			)
			(fill no)
			(layer "F.CrtYd")
		)
		(fp_rect
			(start -0.5842 1.3335)
			(end 0.5842 -1.3335)
			(stroke
				(width 0)
				(type default)
			)
			(fill no)
			(layer "F.Fab")
		)
		(pad "1" smd custom
			(at 0 -0.762 180)
			(size 0.2159 0.2159)
			(layers "F.Cu" "F.Mask" "F.Paste")
			(net "P5V_B")
			(options
				(clearance outline)
				(anchor circle)
			)
			(primitives
				(gr_poly
					(pts
						(arc
							(start -0.3302 -0.4318)
							(mid -0.402042 -0.402042)
							(end -0.4318 -0.3302)
						)
						(arc
							(start -0.4318 0.3302)
							(mid -0.402042 0.402042)
							(end -0.3302 0.4318)
						)
						(arc
							(start 0.3302 0.4318)
							(mid 0.402042 0.402042)
							(end 0.4318 0.3302)
						)
						(arc
							(start 0.4318 -0.3302)
							(mid 0.402042 -0.402042)
							(end 0.3302 -0.4318)
						)
					)
					(width 0)
					(fill yes)
				)
			)
		)
		(pad "2" smd custom
			(at 0 0.762 180)
			(size 0.2159 0.2159)
			(layers "F.Cu" "F.Mask" "F.Paste")
			(net "FLT_HDD35")
			(options
				(clearance outline)
				(anchor circle)
			)
			(primitives
				(gr_poly
					(pts
						(arc
							(start -0.3302 -0.4318)
							(mid -0.402042 -0.402042)
							(end -0.4318 -0.3302)
						)
						(arc
							(start -0.4318 0.3302)
							(mid -0.402042 0.402042)
							(end -0.3302 0.4318)
						)
						(arc
							(start 0.3302 0.4318)
							(mid 0.402042 0.402042)
							(end 0.4318 0.3302)
						)
						(arc
							(start 0.4318 -0.3302)
							(mid 0.402042 -0.402042)
							(end 0.3302 -0.4318)
						)
					)
					(width 0)
					(fill yes)
				)
			)
		)
	)
	(footprint ""
		(layer "F.Cu")
		(at 159.324802 -92.799916)
		(property "Reference" ""
			(at 0 0 0)
			(layer "F.SilkS")
			(hide yes)
			(effects
				(font
					(size 1.27 1.27)
				)
			)
		)
		(property "Value" "*"
			(at -8.398764 -8.057642 0)
			(unlocked yes)
			(layer "F.Fab")
			(hide yes)
			(effects
				(font
					(size 1.016 1.016)
					(thickness 0.1524)
				)
			)
		)
		(duplicate_pad_numbers_are_jumpers no)
		(fp_poly
			(pts
				(arc
					(start 7.3152 0)
					(mid 0 7.3152)
					(end -7.3152 0)
				)
				(arc
					(start -7.3152 -5.9944)
					(mid 0 -13.3096)
					(end 7.3152 -5.9944)
				)
			)
			(stroke
				(width 0)
				(type default)
			)
			(fill no)
			(layer "B.CrtYd")
		)
		(fp_poly
			(pts
				(arc
					(start 7.3152 0)
					(mid 0 7.3152)
					(end -7.3152 0)
				)
				(arc
					(start -7.3152 -5.9944)
					(mid 0 -13.3096)
					(end 7.3152 -5.9944)
				)
			)
			(stroke
				(width 0)
				(type default)
			)
			(fill no)
			(layer "F.CrtYd")
		)
		(fp_poly
			(pts
				(arc
					(start 7.3152 0)
					(mid 0 7.3152)
					(end -7.3152 0)
				)
				(arc
					(start -7.3152 -5.9944)
					(mid 0 -13.3096)
					(end 7.3152 -5.9944)
				)
			)
			(stroke
				(width 0)
				(type default)
			)
			(fill no)
			(layer "B.Fab")
		)
		(fp_poly
			(pts
				(arc
					(start 7.3152 0)
					(mid 0 7.3152)
					(end -7.3152 0)
				)
				(arc
					(start -7.3152 -5.9944)
					(mid 0 -13.3096)
					(end 7.3152 -5.9944)
				)
			)
			(stroke
				(width 0)
				(type default)
			)
			(fill no)
			(layer "F.Fab")
		)
		(pad "1" thru_hole oval
			(at 0 0)
			(size 14.0208 20.0152)
			(drill 0.0254
				(offset 0 -2.9972)
			)
			(layers "*.Cu" "*.Mask")
			(remove_unused_layers no)
			(net "Net_26")
			(clearance -1.002284)
			(thermal_gap 0.1524)
			(padstack
				(mode front_inner_back)
				(layer "Inner"
					(shape custom)
					(size 2.928012 2.928012)
					(options
						(anchor circle)
					)
					(primitives
						(gr_poly
							(pts
								(arc
									(start 4.571746 -2.084324)
									(mid 0.000333 7.430372)
									(end -4.571492 -2.084324)
								)
								(arc
									(start -4.571492 -2.084324)
									(mid -3.570296 -3.611977)
									(end -2.875026 -5.30098)
								)
								(arc
									(start -2.875026 -5.30098)
									(mid 0.000217 -7.43089)
									(end 2.87528 -5.30098)
								)
								(arc
									(start 2.87528 -5.30098)
									(mid 3.570511 -3.611956)
									(end 4.571746 -2.084324)
								)
							)
							(width 0)
							(fill yes)
						)
					)
					(clearance 0.1524)
				)
				(layer "B.Cu"
					(shape oval)
					(size 14.0208 20.0152)
					(offset 0 -2.9972)
					(clearance -1.002284)
				)
			)
		)
		(zone
			(layers "F.Cu" "B.Cu" "In1.Cu" "In2.Cu" "In3.Cu" "In4.Cu" "In5.Cu" "In6.Cu"
				"In7.Cu" "In8.Cu" "In9.Cu" "In10.Cu"
			)
			(hatch none 0.5)
			(connect_pads
				(clearance 0)
			)
			(min_thickness 0.25)
			(keepout
				(tracks not_allowed)
				(vias allowed)
				(pads allowed)
				(copperpour not_allowed)
				(footprints allowed)
			)
			(placement
				(enabled no)
				(sheetname "")
			)
			(fill
				(thermal_gap 0.5)
				(thermal_bridge_width 0.5)
				(island_removal_mode 0)
			)
			(polygon
				(pts
					(arc
						(start 152.314402 -98.794316)
						(mid 159.324802 -105.804716)
						(end 166.335202 -98.794316)
					)
					(arc
						(start 166.335202 -92.799916)
						(mid 159.324802 -85.789516)
						(end 152.314402 -92.799916)
					)
				)
			)
		)
	)
	(footprint ""
		(layer "F.Cu")
		(at 180.7464 -163.554918 90)
		(property "Reference" "R533"
			(at 0 0 90)
			(layer "F.SilkS")
			(hide yes)
			(effects
				(font
					(size 1.27 1.27)
				)
			)
		)
		(property "Value" "4K7R2J-2-GP"
			(at 0.064008 -3.993896 90)
			(unlocked yes)
			(layer "F.Fab")
			(hide yes)
			(effects
				(font
					(size 1.016 1.016)
					(thickness 0.1524)
				)
			)
		)
		(property "Device Type" "R402H16"
			(at 0.064008 -5.517896 90)
			(unlocked yes)
			(layer "F.Fab")
			(hide yes)
			(effects
				(font
					(size 1.016 1.016)
					(thickness 0.1524)
				)
			)
		)
		(duplicate_pad_numbers_are_jumpers no)
		(fp_line
			(start 0.508 -0.9398)
			(end -0.508 -0.9398)
			(stroke
				(width 0.1524)
				(type default)
			)
			(layer "F.SilkS")
		)
		(fp_line
			(start -0.508 -0.9398)
			(end -0.508 0.9398)
			(stroke
				(width 0.1524)
				(type default)
			)
			(layer "F.SilkS")
		)
		(fp_rect
			(start -0.508 0.9398)
			(end 0.508 -0.9398)
			(stroke
				(width 0)
				(type default)
			)
			(fill no)
			(layer "F.CrtYd")
		)
		(fp_rect
			(start -0.508 0.9398)
			(end 0.508 -0.9398)
			(stroke
				(width 0)
				(type default)
			)
			(fill no)
			(layer "F.Fab")
		)
		(pad "1" smd custom
			(at 0 -0.4445 90)
			(size 0.1397 0.1397)
			(layers "F.Cu" "F.Mask" "F.Paste")
			(net "SW_PWR_R_HDD17")
			(options
				(clearance outline)
				(anchor circle)
			)
			(primitives
				(gr_poly
					(pts
						(arc
							(start -0.1778 -0.2794)
							(mid -0.249642 -0.249642)
							(end -0.2794 -0.1778)
						)
						(arc
							(start -0.2794 0.1778)
							(mid -0.249642 0.249642)
							(end -0.1778 0.2794)
						)
						(arc
							(start 0.1778 0.2794)
							(mid 0.249642 0.249642)
							(end 0.2794 0.1778)
						)
						(arc
							(start 0.2794 -0.1778)
							(mid 0.249642 -0.249642)
							(end 0.1778 -0.2794)
						)
					)
					(width 0)
					(fill yes)
				)
			)
		)
		(pad "2" smd custom
			(at 0 0.4445 90)
			(size 0.1397 0.1397)
			(layers "F.Cu" "F.Mask" "F.Paste")
			(net "GND")
			(options
				(clearance outline)
				(anchor circle)
			)
			(primitives
				(gr_poly
					(pts
						(arc
							(start -0.1778 -0.2794)
							(mid -0.249642 -0.249642)
							(end -0.2794 -0.1778)
						)
						(arc
							(start -0.2794 0.1778)
							(mid -0.249642 0.249642)
							(end -0.1778 0.2794)
						)
						(arc
							(start 0.1778 0.2794)
							(mid 0.249642 0.249642)
							(end 0.2794 0.1778)
						)
						(arc
							(start 0.2794 -0.1778)
							(mid 0.249642 -0.249642)
							(end 0.1778 -0.2794)
						)
					)
					(width 0)
					(fill yes)
				)
			)
		)
	)
	(footprint ""
		(layer "F.Cu")
		(at 258.5212 -290.195 180)
		(property "Reference" "R3"
			(at 0 0 180)
			(layer "F.SilkS")
			(hide yes)
			(effects
				(font
					(size 1.27 1.27)
				)
			)
		)
		(property "Value" "4K7R2F-GP"
			(at 0.064008 -3.993896 180)
			(unlocked yes)
			(layer "F.Fab")
			(hide yes)
			(effects
				(font
					(size 1.016 1.016)
					(thickness 0.1524)
				)
			)
		)
		(property "Device Type" "R402H16"
			(at 0.064008 -5.517896 180)
			(unlocked yes)
			(layer "F.Fab")
			(hide yes)
			(effects
				(font
					(size 1.016 1.016)
					(thickness 0.1524)
				)
			)
		)
		(duplicate_pad_numbers_are_jumpers no)
		(fp_line
			(start 0.508 -0.9398)
			(end -0.508 -0.9398)
			(stroke
				(width 0.1524)
				(type default)
			)
			(layer "F.SilkS")
		)
		(fp_line
			(start -0.508 -0.9398)
			(end -0.508 0.9398)
			(stroke
				(width 0.1524)
				(type default)
			)
			(layer "F.SilkS")
		)
		(fp_rect
			(start -0.508 0.9398)
			(end 0.508 -0.9398)
			(stroke
				(width 0)
				(type default)
			)
			(fill no)
			(layer "F.CrtYd")
		)
		(fp_rect
			(start -0.508 0.9398)
			(end 0.508 -0.9398)
			(stroke
				(width 0)
				(type default)
			)
			(fill no)
			(layer "F.Fab")
		)
		(pad "1" smd custom
			(at 0 -0.4445 180)
			(size 0.1397 0.1397)
			(layers "F.Cu" "F.Mask" "F.Paste")
			(net "P3V3_STBY_A")
			(options
				(clearance outline)
				(anchor circle)
			)
			(primitives
				(gr_poly
					(pts
						(arc
							(start -0.1778 -0.2794)
							(mid -0.249642 -0.249642)
							(end -0.2794 -0.1778)
						)
						(arc
							(start -0.2794 0.1778)
							(mid -0.249642 0.249642)
							(end -0.1778 0.2794)
						)
						(arc
							(start 0.1778 0.2794)
							(mid 0.249642 0.249642)
							(end 0.2794 0.1778)
						)
						(arc
							(start 0.2794 -0.1778)
							(mid 0.249642 -0.249642)
							(end 0.1778 -0.2794)
						)
					)
					(width 0)
					(fill yes)
				)
			)
		)
		(pad "2" smd custom
			(at 0 0.4445 180)
			(size 0.1397 0.1397)
			(layers "F.Cu" "F.Mask" "F.Paste")
			(net "EEPROM_A2")
			(options
				(clearance outline)
				(anchor circle)
			)
			(primitives
				(gr_poly
					(pts
						(arc
							(start -0.1778 -0.2794)
							(mid -0.249642 -0.249642)
							(end -0.2794 -0.1778)
						)
						(arc
							(start -0.2794 0.1778)
							(mid -0.249642 0.249642)
							(end -0.1778 0.2794)
						)
						(arc
							(start 0.1778 0.2794)
							(mid 0.249642 0.249642)
							(end 0.2794 0.1778)
						)
						(arc
							(start 0.2794 -0.1778)
							(mid 0.249642 -0.249642)
							(end 0.1778 -0.2794)
						)
					)
					(width 0)
					(fill yes)
				)
			)
		)
	)
	(footprint ""
		(layer "F.Cu")
		(at 83.784948 -285.285942 180)
		(property "Reference" "Q12"
			(at 0 0 180)
			(layer "F.SilkS")
			(hide yes)
			(effects
				(font
					(size 1.27 1.27)
				)
			)
		)
		(property "Value" "AO4406AL-GP"
			(at -3.707384 -1.5367 180)
			(unlocked yes)
			(layer "F.Fab")
			(hide yes)
			(effects
				(font
					(size 1.016 1.016)
					(thickness 0.1524)
				)
			)
		)
		(property "Device Type" "SOIC8H69"
			(at -3.707384 -3.0607 180)
			(unlocked yes)
			(layer "F.Fab")
			(hide yes)
			(effects
				(font
					(size 1.016 1.016)
					(thickness 0.1524)
				)
			)
		)
		(duplicate_pad_numbers_are_jumpers no)
		(fp_line
			(start 2.1336 1.4224)
			(end 2.1336 -1.4224)
			(stroke
				(width 0.1524)
				(type default)
			)
			(layer "F.SilkS")
		)
		(fp_line
			(start 2.1336 -1.4224)
			(end -2.7432 -1.4224)
			(stroke
				(width 0.1524)
				(type default)
			)
			(layer "F.SilkS")
		)
		(fp_line
			(start -2.1844 -0.0508)
			(end -2.7178 0.508)
			(stroke
				(width 0.1524)
				(type default)
			)
			(layer "F.SilkS")
		)
		(fp_line
			(start -2.6289 3.4417)
			(end -2.6289 1.4732)
			(stroke
				(width 0.381)
				(type default)
			)
			(layer "F.SilkS")
		)
		(fp_line
			(start -2.7178 -0.508)
			(end -2.1844 -0.0508)
			(stroke
				(width 0.1524)
				(type default)
			)
			(layer "F.SilkS")
		)
		(fp_line
			(start -2.7432 1.4224)
			(end 2.1336 1.4224)
			(stroke
				(width 0.1524)
				(type default)
			)
			(layer "F.SilkS")
		)
		(fp_line
			(start -2.7432 1.4224)
			(end -2.6416 1.4224)
			(stroke
				(width 0.1524)
				(type default)
			)
			(layer "F.SilkS")
		)
		(fp_line
			(start -2.7432 -1.4224)
			(end -2.7432 1.4224)
			(stroke
				(width 0.1524)
				(type default)
			)
			(layer "F.SilkS")
		)
		(fp_poly
			(pts
				(xy -2.2098 -1.4224) (xy -2.2098 1.4224) (xy 2.2098 1.4224) (xy 2.2098 -1.4224)
			)
			(stroke
				(width 0)
				(type default)
			)
			(fill yes)
			(layer "F.SilkS")
		)
		(fp_rect
			(start -2.450084 2.999994)
			(end 2.450084 -2.999994)
			(stroke
				(width 0)
				(type default)
			)
			(fill no)
			(layer "F.CrtYd")
		)
		(fp_poly
			(pts
				(xy -2.8194 3.6322) (xy -2.8194 -3.6322) (xy 2.8194 -3.6322) (xy 2.8194 1.18364) (xy 2.450084 1.18364)
				(xy 2.450084 -2.999994) (xy -2.450084 -2.999994) (xy -2.450084 2.999994) (xy 2.450084 2.999994)
				(xy 2.450084 1.18618) (xy 2.8194 1.18618) (xy 2.8194 3.6322)
			)
			(stroke
				(width 0)
				(type default)
			)
			(fill no)
			(layer "F.CrtYd")
		)
		(fp_rect
			(start -2.8194 3.6322)
			(end 2.8194 -3.6322)
			(stroke
				(width 0)
				(type default)
			)
			(fill no)
			(layer "F.Fab")
		)
		(pad "1" smd rect
			(at -1.905 2.54 180)
			(size 0.635 1.651)
			(layers "F.Cu" "F.Mask" "F.Paste")
			(net "P5V_HDD2")
		)
		(pad "2" smd rect
			(at -0.635 2.54 180)
			(size 0.635 1.651)
			(layers "F.Cu" "F.Mask" "F.Paste")
			(net "P5V_HDD2")
		)
		(pad "3" smd rect
			(at 0.635 2.54 180)
			(size 0.635 1.651)
			(layers "F.Cu" "F.Mask" "F.Paste")
			(net "P5V_HDD2")
		)
		(pad "4" smd rect
			(at 1.905 2.54 180)
			(size 0.635 1.651)
			(layers "F.Cu" "F.Mask" "F.Paste")
			(net "SW_HDD_P2")
		)
		(pad "5" smd rect
			(at 1.905 -2.54 180)
			(size 0.635 1.651)
			(layers "F.Cu" "F.Mask" "F.Paste")
			(net "P5V_A_1")
		)
		(pad "6" smd rect
			(at 0.635 -2.54 180)
			(size 0.635 1.651)
			(layers "F.Cu" "F.Mask" "F.Paste")
			(net "P5V_A_1")
		)
		(pad "7" smd rect
			(at -0.635 -2.54 180)
			(size 0.635 1.651)
			(layers "F.Cu" "F.Mask" "F.Paste")
			(net "P5V_A_1")
		)
		(pad "8" smd rect
			(at -1.905 -2.54 180)
			(size 0.635 1.651)
			(layers "F.Cu" "F.Mask" "F.Paste")
			(net "P5V_A_1")
		)
	)
	(footprint ""
		(layer "F.Cu")
		(at 222.619316 -116.728748 -90)
		(property "Reference" "R157"
			(at 0 0 270)
			(layer "F.SilkS")
			(hide yes)
			(effects
				(font
					(size 1.27 1.27)
				)
			)
		)
		(property "Value" "0R2J-2-GP"
			(at 0.064008 -3.993896 270)
			(unlocked yes)
			(layer "F.Fab")
			(hide yes)
			(effects
				(font
					(size 1.016 1.016)
					(thickness 0.1524)
				)
			)
		)
		(property "Device Type" "R402H16"
			(at 0.064008 -5.517896 270)
			(unlocked yes)
			(layer "F.Fab")
			(hide yes)
			(effects
				(font
					(size 1.016 1.016)
					(thickness 0.1524)
				)
			)
		)
		(duplicate_pad_numbers_are_jumpers no)
		(fp_line
			(start -0.508 -0.9398)
			(end -0.508 0.9398)
			(stroke
				(width 0.1524)
				(type default)
			)
			(layer "F.SilkS")
		)
		(fp_line
			(start 0.508 -0.9398)
			(end -0.508 -0.9398)
			(stroke
				(width 0.1524)
				(type default)
			)
			(layer "F.SilkS")
		)
		(fp_rect
			(start -0.508 0.9398)
			(end 0.508 -0.9398)
			(stroke
				(width 0)
				(type default)
			)
			(fill no)
			(layer "F.CrtYd")
		)
		(fp_rect
			(start -0.508 0.9398)
			(end 0.508 -0.9398)
			(stroke
				(width 0)
				(type default)
			)
			(fill no)
			(layer "F.Fab")
		)
		(pad "1" smd custom
			(at 0 -0.4445 270)
			(size 0.1397 0.1397)
			(layers "F.Cu" "F.Mask" "F.Paste")
			(net "SLOT3_SVR_ID0_GPIO3")
			(options
				(clearance outline)
				(anchor circle)
			)
			(primitives
				(gr_poly
					(pts
						(arc
							(start -0.1778 -0.2794)
							(mid -0.249642 -0.249642)
							(end -0.2794 -0.1778)
						)
						(arc
							(start -0.2794 0.1778)
							(mid -0.249642 0.249642)
							(end -0.1778 0.2794)
						)
						(arc
							(start 0.1778 0.2794)
							(mid 0.249642 0.249642)
							(end 0.2794 0.1778)
						)
						(arc
							(start 0.2794 -0.1778)
							(mid 0.249642 -0.249642)
							(end 0.1778 -0.2794)
						)
					)
					(width 0)
					(fill yes)
				)
			)
		)
		(pad "2" smd custom
			(at 0 0.4445 270)
			(size 0.1397 0.1397)
			(layers "F.Cu" "F.Mask" "F.Paste")
			(net "COMP_A_TO_BMC_A_RESET_N")
			(options
				(clearance outline)
				(anchor circle)
			)
			(primitives
				(gr_poly
					(pts
						(arc
							(start -0.1778 -0.2794)
							(mid -0.249642 -0.249642)
							(end -0.2794 -0.1778)
						)
						(arc
							(start -0.2794 0.1778)
							(mid -0.249642 0.249642)
							(end -0.1778 0.2794)
						)
						(arc
							(start 0.1778 0.2794)
							(mid 0.249642 0.249642)
							(end 0.2794 0.1778)
						)
						(arc
							(start 0.2794 -0.1778)
							(mid 0.249642 -0.249642)
							(end 0.1778 -0.2794)
						)
					)
					(width 0)
					(fill yes)
				)
			)
		)
	)
	(footprint ""
		(layer "F.Cu")
		(at 246.992902 -393.107164)
		(property "Reference" "R1171"
			(at 0 0 0)
			(layer "F.SilkS")
			(hide yes)
			(effects
				(font
					(size 1.27 1.27)
				)
			)
		)
		(property "Value" "5K1R2F-3-GP"
			(at 0.064008 -3.993896 0)
			(unlocked yes)
			(layer "F.Fab")
			(hide yes)
			(effects
				(font
					(size 1.016 1.016)
					(thickness 0.1524)
				)
			)
		)
		(property "Device Type" "R402H16"
			(at 0.064008 -5.517896 0)
			(unlocked yes)
			(layer "F.Fab")
			(hide yes)
			(effects
				(font
					(size 1.016 1.016)
					(thickness 0.1524)
				)
			)
		)
		(duplicate_pad_numbers_are_jumpers no)
		(fp_line
			(start -0.508 -0.9398)
			(end -0.508 0.9398)
			(stroke
				(width 0.1524)
				(type default)
			)
			(layer "F.SilkS")
		)
		(fp_line
			(start 0.508 -0.9398)
			(end -0.508 -0.9398)
			(stroke
				(width 0.1524)
				(type default)
			)
			(layer "F.SilkS")
		)
		(fp_rect
			(start -0.508 0.9398)
			(end 0.508 -0.9398)
			(stroke
				(width 0)
				(type default)
			)
			(fill no)
			(layer "F.CrtYd")
		)
		(fp_rect
			(start -0.508 0.9398)
			(end 0.508 -0.9398)
			(stroke
				(width 0)
				(type default)
			)
			(fill no)
			(layer "F.Fab")
		)
		(pad "1" smd custom
			(at 0 -0.4445)
			(size 0.1397 0.1397)
			(layers "F.Cu" "F.Mask" "F.Paste")
			(net "MB3_CM_UV_R")
			(options
				(clearance outline)
				(anchor circle)
			)
			(primitives
				(gr_poly
					(pts
						(arc
							(start -0.1778 -0.2794)
							(mid -0.249642 -0.249642)
							(end -0.2794 -0.1778)
						)
						(arc
							(start -0.2794 0.1778)
							(mid -0.249642 0.249642)
							(end -0.1778 0.2794)
						)
						(arc
							(start 0.1778 0.2794)
							(mid 0.249642 0.249642)
							(end 0.2794 0.1778)
						)
						(arc
							(start 0.2794 -0.1778)
							(mid 0.249642 -0.249642)
							(end 0.1778 -0.2794)
						)
					)
					(width 0)
					(fill yes)
				)
			)
		)
		(pad "2" smd custom
			(at 0 0.4445)
			(size 0.1397 0.1397)
			(layers "F.Cu" "F.Mask" "F.Paste")
			(net "AGND_CURRENT_DPB")
			(options
				(clearance outline)
				(anchor circle)
			)
			(primitives
				(gr_poly
					(pts
						(arc
							(start -0.1778 -0.2794)
							(mid -0.249642 -0.249642)
							(end -0.2794 -0.1778)
						)
						(arc
							(start -0.2794 0.1778)
							(mid -0.249642 0.249642)
							(end -0.1778 0.2794)
						)
						(arc
							(start 0.1778 0.2794)
							(mid 0.249642 0.249642)
							(end 0.2794 0.1778)
						)
						(arc
							(start 0.2794 -0.1778)
							(mid 0.249642 -0.249642)
							(end 0.1778 -0.2794)
						)
					)
					(width 0)
					(fill yes)
				)
			)
		)
	)
	(footprint ""
		(layer "F.Cu")
		(at 158.663386 -44.219368 90)
		(property "Reference" "C402"
			(at 0 0 90)
			(layer "F.SilkS")
			(hide yes)
			(effects
				(font
					(size 1.27 1.27)
				)
			)
		)
		(property "Value" "SCD01U16V1KX-GP"
			(at -2.8321 -1.7399 90)
			(unlocked yes)
			(layer "F.Fab")
			(hide yes)
			(effects
				(font
					(size 1.016 1.016)
					(thickness 0.1524)
				)
			)
		)
		(property "Device Type" "C0201H13"
			(at -2.8321 -3.2639 90)
			(unlocked yes)
			(layer "F.Fab")
			(hide yes)
			(effects
				(font
					(size 1.016 1.016)
					(thickness 0.1524)
				)
			)
		)
		(duplicate_pad_numbers_are_jumpers no)
		(fp_rect
			(start -0.2794 0.6477)
			(end 0.2794 -0.6477)
			(stroke
				(width 0)
				(type default)
			)
			(fill no)
			(layer "F.CrtYd")
		)
		(fp_rect
			(start -0.2794 0.6477)
			(end 0.2794 -0.6477)
			(stroke
				(width 0)
				(type default)
			)
			(fill no)
			(layer "F.Fab")
		)
		(pad "1" smd custom
			(at 0 -0.2794 90)
			(size 0.0762 0.0762)
			(layers "F.Cu" "F.Mask" "F.Paste")
			(net "SAS_HDD_RX_N28")
			(options
				(clearance outline)
				(anchor circle)
			)
			(primitives
				(gr_poly
					(pts
						(arc
							(start 0.1524 -0.127)
							(mid 0.137521 -0.162921)
							(end 0.1016 -0.1778)
						)
						(arc
							(start -0.1016 -0.1778)
							(mid -0.137521 -0.162921)
							(end -0.1524 -0.127)
						)
						(arc
							(start -0.1524 0.127)
							(mid -0.137521 0.162921)
							(end -0.1016 0.1778)
						)
						(arc
							(start 0.1016 0.1778)
							(mid 0.137521 0.162921)
							(end 0.1524 0.127)
						)
					)
					(width 0)
					(fill yes)
				)
			)
		)
		(pad "2" smd custom
			(at 0 0.2794 90)
			(size 0.0762 0.0762)
			(layers "F.Cu" "F.Mask" "F.Paste")
			(net "PHY_SCC_A_TO_DRV_A_28_DN")
			(options
				(clearance outline)
				(anchor circle)
			)
			(primitives
				(gr_poly
					(pts
						(arc
							(start 0.1524 -0.127)
							(mid 0.137521 -0.162921)
							(end 0.1016 -0.1778)
						)
						(arc
							(start -0.1016 -0.1778)
							(mid -0.137521 -0.162921)
							(end -0.1524 -0.127)
						)
						(arc
							(start -0.1524 0.127)
							(mid -0.137521 0.162921)
							(end -0.1016 0.1778)
						)
						(arc
							(start 0.1016 0.1778)
							(mid 0.137521 0.162921)
							(end 0.1524 0.127)
						)
					)
					(width 0)
					(fill yes)
				)
			)
		)
	)
	(footprint ""
		(layer "F.Cu")
		(at 38.05682 -188.915294)
		(property "Reference" "Q224"
			(at 0 0 0)
			(layer "F.SilkS")
			(hide yes)
			(effects
				(font
					(size 1.27 1.27)
				)
			)
		)
		(property "Value" "2N7002K-2-GP"
			(at 0.127 -8.9662 0)
			(unlocked yes)
			(layer "F.Fab")
			(hide yes)
			(effects
				(font
					(size 1.016 1.016)
					(thickness 0.1524)
				)
			)
		)
		(property "Device Type" "SOT23DGS2D4H44"
			(at 0.127 -10.4902 0)
			(unlocked yes)
			(layer "F.Fab")
			(hide yes)
			(effects
				(font
					(size 1.016 1.016)
					(thickness 0.1524)
				)
			)
		)
		(duplicate_pad_numbers_are_jumpers no)
		(fp_line
			(start -1.651 -1.778)
			(end -1.651 1.778)
			(stroke
				(width 0.1524)
				(type default)
			)
			(layer "F.SilkS")
		)
		(fp_line
			(start -1.651 1.778)
			(end 1.651 1.778)
			(stroke
				(width 0.1524)
				(type default)
			)
			(layer "F.SilkS")
		)
		(fp_line
			(start 1.651 -1.778)
			(end -1.651 -1.778)
			(stroke
				(width 0.1524)
				(type default)
			)
			(layer "F.SilkS")
		)
		(fp_line
			(start 1.651 1.778)
			(end 1.651 -1.778)
			(stroke
				(width 0.1524)
				(type default)
			)
			(layer "F.SilkS")
		)
		(fp_poly
			(pts
				(xy -1.778 1.8796) (xy -1.778 -1.8796) (xy 1.778 -1.8796) (xy 1.778 1.8796)
			)
			(stroke
				(width 0)
				(type default)
			)
			(fill no)
			(layer "F.CrtYd")
		)
		(fp_poly
			(pts
				(xy -1.778 1.8796) (xy -1.778 -1.8796) (xy 1.778 -1.8796) (xy 1.778 1.8796)
			)
			(stroke
				(width 0)
				(type default)
			)
			(fill no)
			(layer "F.Fab")
		)
		(pad "D" smd custom
			(at 0 -0.9525)
			(size 0.1905 0.1905)
			(layers "F.Cu" "F.Mask" "F.Paste")
			(net "FLT_HDD1_N")
			(options
				(clearance outline)
				(anchor circle)
			)
			(primitives
				(gr_poly
					(pts
						(arc
							(start -0.1778 0.5715)
							(mid -0.321484 0.511984)
							(end -0.381 0.3683)
						)
						(arc
							(start -0.381 -0.3683)
							(mid -0.321484 -0.511984)
							(end -0.1778 -0.5715)
						)
						(arc
							(start 0.1778 -0.5715)
							(mid 0.321484 -0.511984)
							(end 0.381 -0.3683)
						)
						(arc
							(start 0.381 0.3683)
							(mid 0.321484 0.511984)
							(end 0.1778 0.5715)
						)
					)
					(width 0)
					(fill yes)
				)
			)
		)
		(pad "G" smd custom
			(at -0.98425 0.9525)
			(size 0.1905 0.1905)
			(layers "F.Cu" "F.Mask" "F.Paste")
			(net "DRIVE_A_1_FLT_LED")
			(options
				(clearance outline)
				(anchor circle)
			)
			(primitives
				(gr_poly
					(pts
						(arc
							(start -0.1778 0.5715)
							(mid -0.321484 0.511984)
							(end -0.381 0.3683)
						)
						(arc
							(start -0.381 -0.3683)
							(mid -0.321484 -0.511984)
							(end -0.1778 -0.5715)
						)
						(arc
							(start 0.1778 -0.5715)
							(mid 0.321484 -0.511984)
							(end 0.381 -0.3683)
						)
						(arc
							(start 0.381 0.3683)
							(mid 0.321484 0.511984)
							(end 0.1778 0.5715)
						)
					)
					(width 0)
					(fill yes)
				)
			)
		)
		(pad "S" smd custom
			(at 0.98425 0.9525)
			(size 0.1905 0.1905)
			(layers "F.Cu" "F.Mask" "F.Paste")
			(net "GND")
			(options
				(clearance outline)
				(anchor circle)
			)
			(primitives
				(gr_poly
					(pts
						(arc
							(start -0.1778 0.5715)
							(mid -0.321484 0.511984)
							(end -0.381 0.3683)
						)
						(arc
							(start -0.381 -0.3683)
							(mid -0.321484 -0.511984)
							(end -0.1778 -0.5715)
						)
						(arc
							(start 0.1778 -0.5715)
							(mid 0.321484 -0.511984)
							(end 0.381 -0.3683)
						)
						(arc
							(start 0.381 0.3683)
							(mid 0.321484 0.511984)
							(end 0.1778 0.5715)
						)
					)
					(width 0)
					(fill yes)
				)
			)
		)
	)
	(footprint ""
		(layer "F.Cu")
		(at 176.657 -294.683942 90)
		(property "Reference" "R248"
			(at 0 0 90)
			(layer "F.SilkS")
			(hide yes)
			(effects
				(font
					(size 1.27 1.27)
				)
			)
		)
		(property "Value" "2R6F-GP"
			(at -0.0508 -4.8514 90)
			(unlocked yes)
			(layer "F.Fab")
			(hide yes)
			(effects
				(font
					(size 1.016 1.016)
					(thickness 0.1524)
				)
			)
		)
		(property "Device Type" "R1206H26"
			(at 0 -6.3754 90)
			(unlocked yes)
			(layer "F.Fab")
			(hide yes)
			(effects
				(font
					(size 1.016 1.016)
					(thickness 0.1524)
				)
			)
		)
		(duplicate_pad_numbers_are_jumpers no)
		(fp_line
			(start 1.016 -2.2352)
			(end 1.016 2.2352)
			(stroke
				(width 0.1524)
				(type default)
			)
			(layer "F.SilkS")
		)
		(fp_line
			(start -1.016 -2.2352)
			(end 1.016 -2.2352)
			(stroke
				(width 0.1524)
				(type default)
			)
			(layer "F.SilkS")
		)
		(fp_line
			(start 1.016 2.2352)
			(end -1.016 2.2352)
			(stroke
				(width 0.1524)
				(type default)
			)
			(layer "F.SilkS")
		)
		(fp_line
			(start -1.016 2.2352)
			(end -1.016 -2.2352)
			(stroke
				(width 0.1524)
				(type default)
			)
			(layer "F.SilkS")
		)
		(fp_rect
			(start -1.0922 2.3114)
			(end 1.0922 -2.3114)
			(stroke
				(width 0)
				(type default)
			)
			(fill no)
			(layer "F.CrtYd")
		)
		(fp_poly
			(pts
				(xy -1.0922 -2.3114) (xy 1.0922 -2.3114) (xy 1.0922 2.3114) (xy -1.0922 2.3114)
			)
			(stroke
				(width 0)
				(type default)
			)
			(fill no)
			(layer "F.Fab")
		)
		(pad "1" smd rect
			(at 0 -1.397 90)
			(size 1.651 1.27)
			(layers "F.Cu" "F.Mask" "F.Paste")
			(net "P12V_HDD5")
		)
		(pad "2" smd rect
			(at 0 1.397 90)
			(size 1.651 1.27)
			(layers "F.Cu" "F.Mask" "F.Paste")
			(net "12V_PRE_5")
		)
	)
	(footprint ""
		(layer "F.Cu")
		(at 44.1198 -141.1986 90)
		(property "Reference" "C614"
			(at 0 0 90)
			(layer "F.SilkS")
			(hide yes)
			(effects
				(font
					(size 1.27 1.27)
				)
			)
		)
		(property "Value" "SC10U16V5KX-7-GP-U"
			(at -0.0762 -6.1214 90)
			(unlocked yes)
			(layer "F.Fab")
			(hide yes)
			(effects
				(font
					(size 1.016 1.016)
					(thickness 0.1524)
				)
			)
		)
		(property "Device Type" "C805H58"
			(at -0.0762 -8.1534 90)
			(unlocked yes)
			(layer "F.Fab")
			(hide yes)
			(effects
				(font
					(size 1.016 1.016)
					(thickness 0.1524)
				)
			)
		)
		(duplicate_pad_numbers_are_jumpers no)
		(fp_line
			(start 0.635 0)
			(end -0.635 0)
			(stroke
				(width 0.508)
				(type default)
			)
			(layer "F.SilkS")
		)
		(fp_rect
			(start -0.9652 1.778)
			(end 0.9652 -1.778)
			(stroke
				(width 0)
				(type default)
			)
			(fill no)
			(layer "F.CrtYd")
		)
		(fp_poly
			(pts
				(xy -0.9652 -1.778) (xy 0.9652 -1.778) (xy 0.9652 1.778) (xy -0.9652 1.778)
			)
			(stroke
				(width 0)
				(type default)
			)
			(fill no)
			(layer "F.Fab")
		)
		(pad "1" smd rect
			(at 0 -0.9652 90)
			(size 1.397 1.143)
			(layers "F.Cu" "F.Mask" "F.Paste")
			(net "P12V_A_VIN_U21")
		)
		(pad "2" smd rect
			(at 0 0.9652 90)
			(size 1.397 1.143)
			(layers "F.Cu" "F.Mask" "F.Paste")
			(net "GND")
		)
	)
	(footprint ""
		(layer "F.Cu")
		(at 141.042898 -169.523918 90)
		(property "Reference" "C257"
			(at 0 0 90)
			(layer "F.SilkS")
			(hide yes)
			(effects
				(font
					(size 1.27 1.27)
				)
			)
		)
		(property "Value" "SCD033U25V2KX-GP"
			(at 1.1811 -2.7051 90)
			(unlocked yes)
			(layer "F.Fab")
			(hide yes)
			(effects
				(font
					(size 1.016 1.016)
					(thickness 0.1524)
				)
			)
		)
		(property "Device Type" "C402H22"
			(at 1.1811 -4.2291 90)
			(unlocked yes)
			(layer "F.Fab")
			(hide yes)
			(effects
				(font
					(size 1.016 1.016)
					(thickness 0.1524)
				)
			)
		)
		(duplicate_pad_numbers_are_jumpers no)
		(fp_rect
			(start -0.4318 0.9525)
			(end 0.4318 -0.9525)
			(stroke
				(width 0)
				(type default)
			)
			(fill no)
			(layer "F.CrtYd")
		)
		(fp_rect
			(start -0.4318 0.9525)
			(end 0.4318 -0.9525)
			(stroke
				(width 0)
				(type default)
			)
			(fill no)
			(layer "F.Fab")
		)
		(pad "1" smd custom
			(at 0 -0.4445 90)
			(size 0.1524 0.1524)
			(layers "F.Cu" "F.Mask" "F.Paste")
			(net "P12V_A")
			(options
				(clearance outline)
				(anchor circle)
			)
			(primitives
				(gr_poly
					(pts
						(arc
							(start 0.3048 -0.2032)
							(mid 0.275042 -0.275042)
							(end 0.2032 -0.3048)
						)
						(arc
							(start -0.2032 -0.3048)
							(mid -0.275042 -0.275042)
							(end -0.3048 -0.2032)
						)
						(arc
							(start -0.3048 0.2032)
							(mid -0.275042 0.275042)
							(end -0.2032 0.3048)
						)
						(arc
							(start 0.2032 0.3048)
							(mid 0.275042 0.275042)
							(end 0.3048 0.2032)
						)
					)
					(width 0)
					(fill yes)
				)
			)
		)
		(pad "2" smd custom
			(at 0 0.4445 90)
			(size 0.1524 0.1524)
			(layers "F.Cu" "F.Mask" "F.Paste")
			(net "SW_HDD_N16")
			(options
				(clearance outline)
				(anchor circle)
			)
			(primitives
				(gr_poly
					(pts
						(arc
							(start 0.3048 -0.2032)
							(mid 0.275042 -0.275042)
							(end 0.2032 -0.3048)
						)
						(arc
							(start -0.2032 -0.3048)
							(mid -0.275042 -0.275042)
							(end -0.3048 -0.2032)
						)
						(arc
							(start -0.3048 0.2032)
							(mid -0.275042 0.275042)
							(end -0.2032 0.3048)
						)
						(arc
							(start 0.2032 0.3048)
							(mid 0.275042 0.275042)
							(end 0.3048 0.2032)
						)
					)
					(width 0)
					(fill yes)
				)
			)
		)
	)
	(footprint ""
		(layer "F.Cu")
		(at 164.279326 -303.88306)
		(property "Reference" "Q256"
			(at 0 0 0)
			(layer "F.SilkS")
			(hide yes)
			(effects
				(font
					(size 1.27 1.27)
				)
			)
		)
		(property "Value" "2N7002K-2-GP"
			(at 0.127 -8.9662 0)
			(unlocked yes)
			(layer "F.Fab")
			(hide yes)
			(effects
				(font
					(size 1.016 1.016)
					(thickness 0.1524)
				)
			)
		)
		(property "Device Type" "SOT23DGS2D4H44"
			(at 0.127 -10.4902 0)
			(unlocked yes)
			(layer "F.Fab")
			(hide yes)
			(effects
				(font
					(size 1.016 1.016)
					(thickness 0.1524)
				)
			)
		)
		(duplicate_pad_numbers_are_jumpers no)
		(fp_line
			(start -1.651 -1.778)
			(end -1.651 1.778)
			(stroke
				(width 0.1524)
				(type default)
			)
			(layer "F.SilkS")
		)
		(fp_line
			(start -1.651 1.778)
			(end 1.651 1.778)
			(stroke
				(width 0.1524)
				(type default)
			)
			(layer "F.SilkS")
		)
		(fp_line
			(start 1.651 -1.778)
			(end -1.651 -1.778)
			(stroke
				(width 0.1524)
				(type default)
			)
			(layer "F.SilkS")
		)
		(fp_line
			(start 1.651 1.778)
			(end 1.651 -1.778)
			(stroke
				(width 0.1524)
				(type default)
			)
			(layer "F.SilkS")
		)
		(fp_poly
			(pts
				(xy -1.778 1.8796) (xy -1.778 -1.8796) (xy 1.778 -1.8796) (xy 1.778 1.8796)
			)
			(stroke
				(width 0)
				(type default)
			)
			(fill no)
			(layer "F.CrtYd")
		)
		(fp_poly
			(pts
				(xy -1.778 1.8796) (xy -1.778 -1.8796) (xy 1.778 -1.8796) (xy 1.778 1.8796)
			)
			(stroke
				(width 0)
				(type default)
			)
			(fill no)
			(layer "F.Fab")
		)
		(pad "D" smd custom
			(at 0 -0.9525)
			(size 0.1905 0.1905)
			(layers "F.Cu" "F.Mask" "F.Paste")
			(net "FLT_HDD29_N")
			(options
				(clearance outline)
				(anchor circle)
			)
			(primitives
				(gr_poly
					(pts
						(arc
							(start -0.1778 0.5715)
							(mid -0.321484 0.511984)
							(end -0.381 0.3683)
						)
						(arc
							(start -0.381 -0.3683)
							(mid -0.321484 -0.511984)
							(end -0.1778 -0.5715)
						)
						(arc
							(start 0.1778 -0.5715)
							(mid 0.321484 -0.511984)
							(end 0.381 -0.3683)
						)
						(arc
							(start 0.381 0.3683)
							(mid 0.321484 0.511984)
							(end 0.1778 0.5715)
						)
					)
					(width 0)
					(fill yes)
				)
			)
		)
		(pad "G" smd custom
			(at -0.98425 0.9525)
			(size 0.1905 0.1905)
			(layers "F.Cu" "F.Mask" "F.Paste")
			(net "DRIVE_B_29_FLT_LED")
			(options
				(clearance outline)
				(anchor circle)
			)
			(primitives
				(gr_poly
					(pts
						(arc
							(start -0.1778 0.5715)
							(mid -0.321484 0.511984)
							(end -0.381 0.3683)
						)
						(arc
							(start -0.381 -0.3683)
							(mid -0.321484 -0.511984)
							(end -0.1778 -0.5715)
						)
						(arc
							(start 0.1778 -0.5715)
							(mid 0.321484 -0.511984)
							(end 0.381 -0.3683)
						)
						(arc
							(start 0.381 0.3683)
							(mid 0.321484 0.511984)
							(end 0.1778 0.5715)
						)
					)
					(width 0)
					(fill yes)
				)
			)
		)
		(pad "S" smd custom
			(at 0.98425 0.9525)
			(size 0.1905 0.1905)
			(layers "F.Cu" "F.Mask" "F.Paste")
			(net "GND")
			(options
				(clearance outline)
				(anchor circle)
			)
			(primitives
				(gr_poly
					(pts
						(arc
							(start -0.1778 0.5715)
							(mid -0.321484 0.511984)
							(end -0.381 0.3683)
						)
						(arc
							(start -0.381 -0.3683)
							(mid -0.321484 -0.511984)
							(end -0.1778 -0.5715)
						)
						(arc
							(start 0.1778 -0.5715)
							(mid 0.321484 -0.511984)
							(end 0.381 -0.3683)
						)
						(arc
							(start 0.381 0.3683)
							(mid 0.321484 0.511984)
							(end 0.1778 0.5715)
						)
					)
					(width 0)
					(fill yes)
				)
			)
		)
	)
	(footprint ""
		(layer "F.Cu")
		(at 79.974948 -276.649942 180)
		(property "Reference" "D2"
			(at 0 0 180)
			(layer "F.SilkS")
			(hide yes)
			(effects
				(font
					(size 1.27 1.27)
				)
			)
		)
		(property "Value" "RB551V30-GP"
			(at 0 -6.7818 180)
			(unlocked yes)
			(layer "F.Fab")
			(hide yes)
			(effects
				(font
					(size 1.016 1.016)
					(thickness 0.1524)
				)
			)
		)
		(property "Device Type" "SOD323AKH38"
			(at 0 -8.6868 180)
			(unlocked yes)
			(layer "F.Fab")
			(hide yes)
			(effects
				(font
					(size 1.016 1.016)
					(thickness 0.1524)
				)
			)
		)
		(duplicate_pad_numbers_are_jumpers no)
		(fp_line
			(start 0.889 2.159)
			(end -0.889 2.159)
			(stroke
				(width 0.1524)
				(type default)
			)
			(layer "F.SilkS")
		)
		(fp_line
			(start 0.889 -1.9304)
			(end 0.889 2.159)
			(stroke
				(width 0.1524)
				(type default)
			)
			(layer "F.SilkS")
		)
		(fp_line
			(start 0.762 2.0574)
			(end -0.762 2.0574)
			(stroke
				(width 0.508)
				(type default)
			)
			(layer "F.SilkS")
		)
		(fp_line
			(start -0.889 2.159)
			(end -0.889 -1.9304)
			(stroke
				(width 0.1524)
				(type default)
			)
			(layer "F.SilkS")
		)
		(fp_line
			(start -0.889 -1.9304)
			(end 0.889 -1.9304)
			(stroke
				(width 0.1524)
				(type default)
			)
			(layer "F.SilkS")
		)
		(fp_rect
			(start -1.016 2.3114)
			(end 1.016 -2.0066)
			(stroke
				(width 0)
				(type default)
			)
			(fill no)
			(layer "F.CrtYd")
		)
		(fp_poly
			(pts
				(xy -1.016 -2.0066) (xy 1.016 -2.0066) (xy 1.016 2.3114) (xy -1.016 2.3114)
			)
			(stroke
				(width 0)
				(type default)
			)
			(fill no)
			(layer "F.Fab")
		)
		(pad "A" smd rect
			(at 0 -1.143 180)
			(size 0.5588 1.016)
			(layers "F.Cu" "F.Mask" "F.Paste")
			(net "SW_HDD_R2")
		)
		(pad "K" smd rect
			(at 0 1.143 180)
			(size 0.5588 1.016)
			(layers "F.Cu" "F.Mask" "F.Paste")
			(net "SW_HDD_N2")
		)
	)
	(footprint ""
		(layer "F.Cu")
		(at 205.232254 -14.313916)
		(property "Reference" "TC17"
			(at 0 0 0)
			(layer "F.SilkS")
			(hide yes)
			(effects
				(font
					(size 1.27 1.27)
				)
			)
		)
		(property "Value" "SE270U16VM-8-GP"
			(at -4.5974 -2.54 0)
			(unlocked yes)
			(layer "F.Fab")
			(hide yes)
			(effects
				(font
					(size 1.016 1.016)
					(thickness 0.1524)
				)
			)
		)
		(property "Device Type" "SE361416H394"
			(at -4.5974 -4.064 0)
			(unlocked yes)
			(layer "F.Fab")
			(hide yes)
			(effects
				(font
					(size 1.016 1.016)
					(thickness 0.1524)
				)
			)
		)
		(duplicate_pad_numbers_are_jumpers no)
		(fp_line
			(start -3.556 -3.4163)
			(end -2.3622 -4.6101)
			(stroke
				(width 0.1524)
				(type default)
			)
			(layer "F.SilkS")
		)
		(fp_line
			(start -3.556 4.6101)
			(end -3.556 -3.4163)
			(stroke
				(width 0.1524)
				(type default)
			)
			(layer "F.SilkS")
		)
		(fp_line
			(start -2.3622 -4.6101)
			(end 2.3622 -4.6101)
			(stroke
				(width 0.1524)
				(type default)
			)
			(layer "F.SilkS")
		)
		(fp_line
			(start 2.3622 -4.6101)
			(end 3.556 -3.4163)
			(stroke
				(width 0.1524)
				(type default)
			)
			(layer "F.SilkS")
		)
		(fp_line
			(start 3.556 -3.4163)
			(end 3.556 4.6101)
			(stroke
				(width 0.1524)
				(type default)
			)
			(layer "F.SilkS")
		)
		(fp_line
			(start 3.556 4.6101)
			(end -3.556 4.6101)
			(stroke
				(width 0.1524)
				(type default)
			)
			(layer "F.SilkS")
		)
		(fp_rect
			(start -3.302 3.6449)
			(end 3.302 -3.6449)
			(stroke
				(width 0)
				(type default)
			)
			(fill no)
			(layer "F.CrtYd")
		)
		(fp_poly
			(pts
				(xy 3.81 4.6863) (xy 3.81 -3.4925) (xy 3.302 -3.4925) (xy 3.302 3.6449) (xy -3.302 3.6449) (xy -3.302 -3.6449)
				(xy 3.302 -3.6449) (xy 3.302 -3.5052) (xy 3.81 -3.5052) (xy 3.81 -4.6863) (xy -3.81 -4.6863) (xy -3.81 4.6863)
			)
			(stroke
				(width 0)
				(type default)
			)
			(fill no)
			(layer "F.CrtYd")
		)
		(fp_rect
			(start -3.81 4.6863)
			(end 3.81 -4.6863)
			(stroke
				(width 0)
				(type default)
			)
			(fill no)
			(layer "F.Fab")
		)
		(pad "1" smd rect
			(at 0 -2.574036)
			(size 1.4224 3.556)
			(layers "F.Cu" "F.Mask" "F.Paste")
			(net "P12V_A")
		)
		(pad "2" smd rect
			(at 0 2.574036)
			(size 1.4224 3.556)
			(layers "F.Cu" "F.Mask" "F.Paste")
			(net "GND")
		)
	)
	(footprint ""
		(layer "F.Cu")
		(at 48.297846 -282.060142 -90)
		(property "Reference" "C61"
			(at 0 0 270)
			(layer "F.SilkS")
			(hide yes)
			(effects
				(font
					(size 1.27 1.27)
				)
			)
		)
		(property "Value" "SCD033U25V2KX-GP"
			(at 1.1811 -2.7051 270)
			(unlocked yes)
			(layer "F.Fab")
			(hide yes)
			(effects
				(font
					(size 1.016 1.016)
					(thickness 0.1524)
				)
			)
		)
		(property "Device Type" "C402H22"
			(at 1.1811 -4.2291 270)
			(unlocked yes)
			(layer "F.Fab")
			(hide yes)
			(effects
				(font
					(size 1.016 1.016)
					(thickness 0.1524)
				)
			)
		)
		(duplicate_pad_numbers_are_jumpers no)
		(fp_rect
			(start -0.4318 0.9525)
			(end 0.4318 -0.9525)
			(stroke
				(width 0)
				(type default)
			)
			(fill no)
			(layer "F.CrtYd")
		)
		(fp_rect
			(start -0.4318 0.9525)
			(end 0.4318 -0.9525)
			(stroke
				(width 0)
				(type default)
			)
			(fill no)
			(layer "F.Fab")
		)
		(pad "1" smd custom
			(at 0 -0.4445 270)
			(size 0.1524 0.1524)
			(layers "F.Cu" "F.Mask" "F.Paste")
			(net "SW_HDD_P1")
			(options
				(clearance outline)
				(anchor circle)
			)
			(primitives
				(gr_poly
					(pts
						(arc
							(start 0.3048 -0.2032)
							(mid 0.275042 -0.275042)
							(end 0.2032 -0.3048)
						)
						(arc
							(start -0.2032 -0.3048)
							(mid -0.275042 -0.275042)
							(end -0.3048 -0.2032)
						)
						(arc
							(start -0.3048 0.2032)
							(mid -0.275042 0.275042)
							(end -0.2032 0.3048)
						)
						(arc
							(start 0.2032 0.3048)
							(mid 0.275042 0.275042)
							(end 0.3048 0.2032)
						)
					)
					(width 0)
					(fill yes)
				)
			)
		)
		(pad "2" smd custom
			(at 0 0.4445 270)
			(size 0.1524 0.1524)
			(layers "F.Cu" "F.Mask" "F.Paste")
			(net "GND")
			(options
				(clearance outline)
				(anchor circle)
			)
			(primitives
				(gr_poly
					(pts
						(arc
							(start 0.3048 -0.2032)
							(mid 0.275042 -0.275042)
							(end 0.2032 -0.3048)
						)
						(arc
							(start -0.2032 -0.3048)
							(mid -0.275042 -0.275042)
							(end -0.3048 -0.2032)
						)
						(arc
							(start -0.3048 0.2032)
							(mid -0.275042 0.275042)
							(end -0.2032 0.3048)
						)
						(arc
							(start 0.2032 0.3048)
							(mid 0.275042 0.275042)
							(end 0.3048 0.2032)
						)
					)
					(width 0)
					(fill yes)
				)
			)
		)
	)
	(footprint ""
		(layer "F.Cu")
		(at 405.9936 -282.702 180)
		(property "Reference" "C153"
			(at 0 0 180)
			(layer "F.SilkS")
			(hide yes)
			(effects
				(font
					(size 1.27 1.27)
				)
			)
		)
		(property "Value" "SCD033U25V2KX-GP"
			(at 1.1811 -2.7051 180)
			(unlocked yes)
			(layer "F.Fab")
			(hide yes)
			(effects
				(font
					(size 1.016 1.016)
					(thickness 0.1524)
				)
			)
		)
		(property "Device Type" "C402H22"
			(at 1.1811 -4.2291 180)
			(unlocked yes)
			(layer "F.Fab")
			(hide yes)
			(effects
				(font
					(size 1.016 1.016)
					(thickness 0.1524)
				)
			)
		)
		(duplicate_pad_numbers_are_jumpers no)
		(fp_rect
			(start -0.4318 0.9525)
			(end 0.4318 -0.9525)
			(stroke
				(width 0)
				(type default)
			)
			(fill no)
			(layer "F.CrtYd")
		)
		(fp_rect
			(start -0.4318 0.9525)
			(end 0.4318 -0.9525)
			(stroke
				(width 0)
				(type default)
			)
			(fill no)
			(layer "F.Fab")
		)
		(pad "1" smd custom
			(at 0 -0.4445 180)
			(size 0.1524 0.1524)
			(layers "F.Cu" "F.Mask" "F.Paste")
			(net "P12V_A")
			(options
				(clearance outline)
				(anchor circle)
			)
			(primitives
				(gr_poly
					(pts
						(arc
							(start 0.3048 -0.2032)
							(mid 0.275042 -0.275042)
							(end 0.2032 -0.3048)
						)
						(arc
							(start -0.2032 -0.3048)
							(mid -0.275042 -0.275042)
							(end -0.3048 -0.2032)
						)
						(arc
							(start -0.3048 0.2032)
							(mid -0.275042 0.275042)
							(end -0.2032 0.3048)
						)
						(arc
							(start 0.2032 0.3048)
							(mid 0.275042 0.275042)
							(end 0.3048 0.2032)
						)
					)
					(width 0)
					(fill yes)
				)
			)
		)
		(pad "2" smd custom
			(at 0 0.4445 180)
			(size 0.1524 0.1524)
			(layers "F.Cu" "F.Mask" "F.Paste")
			(net "SW_HDD_N8")
			(options
				(clearance outline)
				(anchor circle)
			)
			(primitives
				(gr_poly
					(pts
						(arc
							(start 0.3048 -0.2032)
							(mid 0.275042 -0.275042)
							(end 0.2032 -0.3048)
						)
						(arc
							(start -0.2032 -0.3048)
							(mid -0.275042 -0.275042)
							(end -0.3048 -0.2032)
						)
						(arc
							(start -0.3048 0.2032)
							(mid -0.275042 0.275042)
							(end -0.2032 0.3048)
						)
						(arc
							(start 0.2032 0.3048)
							(mid 0.275042 0.275042)
							(end 0.3048 0.2032)
						)
					)
					(width 0)
					(fill yes)
				)
			)
		)
	)
	(footprint ""
		(layer "F.Cu")
		(at 401.80895 -56.809894 -90)
		(property "Reference" "R880"
			(at 0 0 270)
			(layer "F.SilkS")
			(hide yes)
			(effects
				(font
					(size 1.27 1.27)
				)
			)
		)
		(property "Value" "300KR2F-GP"
			(at 0.064008 -3.993896 270)
			(unlocked yes)
			(layer "F.Fab")
			(hide yes)
			(effects
				(font
					(size 1.016 1.016)
					(thickness 0.1524)
				)
			)
		)
		(property "Device Type" "R402H16"
			(at 0.064008 -5.517896 270)
			(unlocked yes)
			(layer "F.Fab")
			(hide yes)
			(effects
				(font
					(size 1.016 1.016)
					(thickness 0.1524)
				)
			)
		)
		(duplicate_pad_numbers_are_jumpers no)
		(fp_line
			(start -0.508 -0.9398)
			(end -0.508 0.9398)
			(stroke
				(width 0.1524)
				(type default)
			)
			(layer "F.SilkS")
		)
		(fp_line
			(start 0.508 -0.9398)
			(end -0.508 -0.9398)
			(stroke
				(width 0.1524)
				(type default)
			)
			(layer "F.SilkS")
		)
		(fp_rect
			(start -0.508 0.9398)
			(end 0.508 -0.9398)
			(stroke
				(width 0)
				(type default)
			)
			(fill no)
			(layer "F.CrtYd")
		)
		(fp_rect
			(start -0.508 0.9398)
			(end 0.508 -0.9398)
			(stroke
				(width 0)
				(type default)
			)
			(fill no)
			(layer "F.Fab")
		)
		(pad "1" smd custom
			(at 0 -0.4445 270)
			(size 0.1397 0.1397)
			(layers "F.Cu" "F.Mask" "F.Paste")
			(net "SW_HDD_N32")
			(options
				(clearance outline)
				(anchor circle)
			)
			(primitives
				(gr_poly
					(pts
						(arc
							(start -0.1778 -0.2794)
							(mid -0.249642 -0.249642)
							(end -0.2794 -0.1778)
						)
						(arc
							(start -0.2794 0.1778)
							(mid -0.249642 0.249642)
							(end -0.1778 0.2794)
						)
						(arc
							(start 0.1778 0.2794)
							(mid 0.249642 0.249642)
							(end 0.2794 0.1778)
						)
						(arc
							(start 0.2794 -0.1778)
							(mid 0.249642 -0.249642)
							(end 0.1778 -0.2794)
						)
					)
					(width 0)
					(fill yes)
				)
			)
		)
		(pad "2" smd custom
			(at 0 0.4445 270)
			(size 0.1397 0.1397)
			(layers "F.Cu" "F.Mask" "F.Paste")
			(net "P12V_A")
			(options
				(clearance outline)
				(anchor circle)
			)
			(primitives
				(gr_poly
					(pts
						(arc
							(start -0.1778 -0.2794)
							(mid -0.249642 -0.249642)
							(end -0.2794 -0.1778)
						)
						(arc
							(start -0.2794 0.1778)
							(mid -0.249642 0.249642)
							(end -0.1778 0.2794)
						)
						(arc
							(start 0.1778 0.2794)
							(mid 0.249642 0.249642)
							(end 0.2794 0.1778)
						)
						(arc
							(start 0.2794 -0.1778)
							(mid 0.249642 -0.249642)
							(end 0.1778 -0.2794)
						)
					)
					(width 0)
					(fill yes)
				)
			)
		)
	)
	(footprint ""
		(layer "F.Cu")
		(at 236.024928 -234.6071 180)
		(property "Reference" "C22"
			(at 0 0 180)
			(layer "F.SilkS")
			(hide yes)
			(effects
				(font
					(size 1.27 1.27)
				)
			)
		)
		(property "Value" "SCD1U16V2KX-3GP"
			(at 1.1811 -2.7051 180)
			(unlocked yes)
			(layer "F.Fab")
			(hide yes)
			(effects
				(font
					(size 1.016 1.016)
					(thickness 0.1524)
				)
			)
		)
		(property "Device Type" "C402H22"
			(at 1.1811 -4.2291 180)
			(unlocked yes)
			(layer "F.Fab")
			(hide yes)
			(effects
				(font
					(size 1.016 1.016)
					(thickness 0.1524)
				)
			)
		)
		(duplicate_pad_numbers_are_jumpers no)
		(fp_rect
			(start -0.4318 0.9525)
			(end 0.4318 -0.9525)
			(stroke
				(width 0)
				(type default)
			)
			(fill no)
			(layer "F.CrtYd")
		)
		(fp_rect
			(start -0.4318 0.9525)
			(end 0.4318 -0.9525)
			(stroke
				(width 0)
				(type default)
			)
			(fill no)
			(layer "F.Fab")
		)
		(pad "1" smd custom
			(at 0 -0.4445 180)
			(size 0.1524 0.1524)
			(layers "F.Cu" "F.Mask" "F.Paste")
			(net "GPIO_VCC_U7")
			(options
				(clearance outline)
				(anchor circle)
			)
			(primitives
				(gr_poly
					(pts
						(arc
							(start 0.3048 -0.2032)
							(mid 0.275042 -0.275042)
							(end 0.2032 -0.3048)
						)
						(arc
							(start -0.2032 -0.3048)
							(mid -0.275042 -0.275042)
							(end -0.3048 -0.2032)
						)
						(arc
							(start -0.3048 0.2032)
							(mid -0.275042 0.275042)
							(end -0.2032 0.3048)
						)
						(arc
							(start 0.2032 0.3048)
							(mid 0.275042 0.275042)
							(end 0.3048 0.2032)
						)
					)
					(width 0)
					(fill yes)
				)
			)
		)
		(pad "2" smd custom
			(at 0 0.4445 180)
			(size 0.1524 0.1524)
			(layers "F.Cu" "F.Mask" "F.Paste")
			(net "GND")
			(options
				(clearance outline)
				(anchor circle)
			)
			(primitives
				(gr_poly
					(pts
						(arc
							(start 0.3048 -0.2032)
							(mid 0.275042 -0.275042)
							(end 0.2032 -0.3048)
						)
						(arc
							(start -0.2032 -0.3048)
							(mid -0.275042 -0.275042)
							(end -0.3048 -0.2032)
						)
						(arc
							(start -0.3048 0.2032)
							(mid -0.275042 0.275042)
							(end -0.2032 0.3048)
						)
						(arc
							(start 0.2032 0.3048)
							(mid 0.275042 0.275042)
							(end 0.3048 0.2032)
						)
					)
					(width 0)
					(fill yes)
				)
			)
		)
	)
	(footprint ""
		(layer "F.Cu")
		(at 333.502 -303.954942 180)
		(property "Reference" "C123"
			(at 0 0 180)
			(layer "F.SilkS")
			(hide yes)
			(effects
				(font
					(size 1.27 1.27)
				)
			)
		)
		(property "Value" "SC4D7U25V5KX-1-GP"
			(at -0.0762 -6.1214 180)
			(unlocked yes)
			(layer "F.Fab")
			(hide yes)
			(effects
				(font
					(size 1.016 1.016)
					(thickness 0.1524)
				)
			)
		)
		(property "Device Type" "C805H58"
			(at -0.0762 -8.1534 180)
			(unlocked yes)
			(layer "F.Fab")
			(hide yes)
			(effects
				(font
					(size 1.016 1.016)
					(thickness 0.1524)
				)
			)
		)
		(duplicate_pad_numbers_are_jumpers no)
		(fp_line
			(start 0.635 0)
			(end -0.635 0)
			(stroke
				(width 0.508)
				(type default)
			)
			(layer "F.SilkS")
		)
		(fp_rect
			(start -0.9652 1.778)
			(end 0.9652 -1.778)
			(stroke
				(width 0)
				(type default)
			)
			(fill no)
			(layer "F.CrtYd")
		)
		(fp_poly
			(pts
				(xy -0.9652 -1.778) (xy 0.9652 -1.778) (xy 0.9652 1.778) (xy -0.9652 1.778)
			)
			(stroke
				(width 0)
				(type default)
			)
			(fill no)
			(layer "F.Fab")
		)
		(pad "1" smd rect
			(at 0 -0.9652 180)
			(size 1.397 1.143)
			(layers "F.Cu" "F.Mask" "F.Paste")
			(net "P12V_HDD6")
		)
		(pad "2" smd rect
			(at 0 0.9652 180)
			(size 1.397 1.143)
			(layers "F.Cu" "F.Mask" "F.Paste")
			(net "GND")
		)
	)
	(footprint ""
		(layer "F.Cu")
		(at 459.7019 -303.954942 180)
		(property "Reference" "C175"
			(at 0 0 180)
			(layer "F.SilkS")
			(hide yes)
			(effects
				(font
					(size 1.27 1.27)
				)
			)
		)
		(property "Value" "SC4D7U25V5KX-1-GP"
			(at -0.0762 -6.1214 180)
			(unlocked yes)
			(layer "F.Fab")
			(hide yes)
			(effects
				(font
					(size 1.016 1.016)
					(thickness 0.1524)
				)
			)
		)
		(property "Device Type" "C805H58"
			(at -0.0762 -8.1534 180)
			(unlocked yes)
			(layer "F.Fab")
			(hide yes)
			(effects
				(font
					(size 1.016 1.016)
					(thickness 0.1524)
				)
			)
		)
		(duplicate_pad_numbers_are_jumpers no)
		(fp_line
			(start 0.635 0)
			(end -0.635 0)
			(stroke
				(width 0.508)
				(type default)
			)
			(layer "F.SilkS")
		)
		(fp_rect
			(start -0.9652 1.778)
			(end 0.9652 -1.778)
			(stroke
				(width 0)
				(type default)
			)
			(fill no)
			(layer "F.CrtYd")
		)
		(fp_poly
			(pts
				(xy -0.9652 -1.778) (xy 0.9652 -1.778) (xy 0.9652 1.778) (xy -0.9652 1.778)
			)
			(stroke
				(width 0)
				(type default)
			)
			(fill no)
			(layer "F.Fab")
		)
		(pad "1" smd rect
			(at 0 -0.9652 180)
			(size 1.397 1.143)
			(layers "F.Cu" "F.Mask" "F.Paste")
			(net "P12V_HDD10")
		)
		(pad "2" smd rect
			(at 0 0.9652 180)
			(size 1.397 1.143)
			(layers "F.Cu" "F.Mask" "F.Paste")
			(net "GND")
		)
	)
	(footprint ""
		(layer "F.Cu")
		(at 67.093846 -68.747894)
		(property "Reference" "TP127"
			(at 0 0 0)
			(layer "F.SilkS")
			(hide yes)
			(effects
				(font
					(size 1.27 1.27)
				)
			)
		)
		(property "Value" "TPAD32-GP"
			(at -0.0508 -1.6764 0)
			(unlocked yes)
			(layer "F.Fab")
			(hide yes)
			(effects
				(font
					(size 1.016 1.016)
					(thickness 0.1524)
				)
			)
		)
		(property "Device Type" "TPAD32"
			(at -0.0508 -3.2004 0)
			(unlocked yes)
			(layer "F.Fab")
			(hide yes)
			(effects
				(font
					(size 1.016 1.016)
					(thickness 0.1524)
				)
			)
		)
		(duplicate_pad_numbers_are_jumpers no)
		(fp_poly
			(pts
				(arc
					(start 0.4064 0)
					(mid -0.4064 0)
					(end 0.4064 0)
				)
			)
			(stroke
				(width 0)
				(type default)
			)
			(fill no)
			(layer "F.CrtYd")
		)
		(fp_poly
			(pts
				(arc
					(start 0.7112 0)
					(mid -0.7112 0)
					(end 0.7112 0)
				)
			)
			(stroke
				(width 0)
				(type default)
			)
			(fill no)
			(layer "F.Fab")
		)
		(pad "1" smd circle
			(at 0 0)
			(size 0.8128 0.8128)
			(layers "F.Cu" "F.Mask" "F.Paste")
			(net "ACT_HDD_25")
		)
	)
	(footprint ""
		(layer "F.Cu")
		(at 33.325054 -92.799916)
		(property "Reference" ""
			(at 0 0 0)
			(layer "F.SilkS")
			(hide yes)
			(effects
				(font
					(size 1.27 1.27)
				)
			)
		)
		(property "Value" "*"
			(at -8.398764 -8.057642 0)
			(unlocked yes)
			(layer "F.Fab")
			(hide yes)
			(effects
				(font
					(size 1.016 1.016)
					(thickness 0.1524)
				)
			)
		)
		(duplicate_pad_numbers_are_jumpers no)
		(fp_poly
			(pts
				(arc
					(start 7.3152 0)
					(mid 0 7.3152)
					(end -7.3152 0)
				)
				(arc
					(start -7.3152 -5.9944)
					(mid 0 -13.3096)
					(end 7.3152 -5.9944)
				)
			)
			(stroke
				(width 0)
				(type default)
			)
			(fill no)
			(layer "B.CrtYd")
		)
		(fp_poly
			(pts
				(arc
					(start 7.3152 0)
					(mid 0 7.3152)
					(end -7.3152 0)
				)
				(arc
					(start -7.3152 -5.9944)
					(mid 0 -13.3096)
					(end 7.3152 -5.9944)
				)
			)
			(stroke
				(width 0)
				(type default)
			)
			(fill no)
			(layer "F.CrtYd")
		)
		(fp_poly
			(pts
				(arc
					(start 7.3152 0)
					(mid 0 7.3152)
					(end -7.3152 0)
				)
				(arc
					(start -7.3152 -5.9944)
					(mid 0 -13.3096)
					(end 7.3152 -5.9944)
				)
			)
			(stroke
				(width 0)
				(type default)
			)
			(fill no)
			(layer "B.Fab")
		)
		(fp_poly
			(pts
				(arc
					(start 7.3152 0)
					(mid 0 7.3152)
					(end -7.3152 0)
				)
				(arc
					(start -7.3152 -5.9944)
					(mid 0 -13.3096)
					(end 7.3152 -5.9944)
				)
			)
			(stroke
				(width 0)
				(type default)
			)
			(fill no)
			(layer "F.Fab")
		)
		(pad "1" thru_hole oval
			(at 0 0)
			(size 14.0208 20.0152)
			(drill 0.0254
				(offset 0 -2.9972)
			)
			(layers "*.Cu" "*.Mask")
			(remove_unused_layers no)
			(net "Net_28")
			(clearance -1.002284)
			(thermal_gap 0.1524)
			(padstack
				(mode front_inner_back)
				(layer "Inner"
					(shape custom)
					(size 2.928012 2.928012)
					(options
						(anchor circle)
					)
					(primitives
						(gr_poly
							(pts
								(arc
									(start 4.571746 -2.084324)
									(mid 0.000333 7.430372)
									(end -4.571492 -2.084324)
								)
								(arc
									(start -4.571492 -2.084324)
									(mid -3.570296 -3.611977)
									(end -2.875026 -5.30098)
								)
								(arc
									(start -2.875026 -5.30098)
									(mid 0.000217 -7.43089)
									(end 2.87528 -5.30098)
								)
								(arc
									(start 2.87528 -5.30098)
									(mid 3.570511 -3.611956)
									(end 4.571746 -2.084324)
								)
							)
							(width 0)
							(fill yes)
						)
					)
					(clearance 0.1524)
				)
				(layer "B.Cu"
					(shape oval)
					(size 14.0208 20.0152)
					(offset 0 -2.9972)
					(clearance -1.002284)
				)
			)
		)
		(zone
			(layers "F.Cu" "B.Cu" "In1.Cu" "In2.Cu" "In3.Cu" "In4.Cu" "In5.Cu" "In6.Cu"
				"In7.Cu" "In8.Cu" "In9.Cu" "In10.Cu"
			)
			(hatch none 0.5)
			(connect_pads
				(clearance 0)
			)
			(min_thickness 0.25)
			(keepout
				(tracks not_allowed)
				(vias allowed)
				(pads allowed)
				(copperpour not_allowed)
				(footprints allowed)
			)
			(placement
				(enabled no)
				(sheetname "")
			)
			(fill
				(thermal_gap 0.5)
				(thermal_bridge_width 0.5)
				(island_removal_mode 0)
			)
			(polygon
				(pts
					(arc
						(start 26.314654 -98.794316)
						(mid 33.325054 -105.804716)
						(end 40.335454 -98.794316)
					)
					(arc
						(start 40.335454 -92.799916)
						(mid 33.325054 -85.789516)
						(end 26.314654 -92.799916)
					)
				)
			)
		)
	)
	(footprint ""
		(layer "F.Cu")
		(at 42.992802 -145.72615 -90)
		(property "Reference" "R1238"
			(at 0 0 270)
			(layer "F.SilkS")
			(hide yes)
			(effects
				(font
					(size 1.27 1.27)
				)
			)
		)
		(property "Value" "309KR2F-GP"
			(at 0.064008 -3.993896 270)
			(unlocked yes)
			(layer "F.Fab")
			(hide yes)
			(effects
				(font
					(size 1.016 1.016)
					(thickness 0.1524)
				)
			)
		)
		(property "Device Type" "R402H16"
			(at 0.064008 -5.517896 270)
			(unlocked yes)
			(layer "F.Fab")
			(hide yes)
			(effects
				(font
					(size 1.016 1.016)
					(thickness 0.1524)
				)
			)
		)
		(duplicate_pad_numbers_are_jumpers no)
		(fp_line
			(start -0.508 -0.9398)
			(end -0.508 0.9398)
			(stroke
				(width 0.1524)
				(type default)
			)
			(layer "F.SilkS")
		)
		(fp_line
			(start 0.508 -0.9398)
			(end -0.508 -0.9398)
			(stroke
				(width 0.1524)
				(type default)
			)
			(layer "F.SilkS")
		)
		(fp_rect
			(start -0.508 0.9398)
			(end 0.508 -0.9398)
			(stroke
				(width 0)
				(type default)
			)
			(fill no)
			(layer "F.CrtYd")
		)
		(fp_rect
			(start -0.508 0.9398)
			(end 0.508 -0.9398)
			(stroke
				(width 0)
				(type default)
			)
			(fill no)
			(layer "F.Fab")
		)
		(pad "1" smd custom
			(at 0 -0.4445 270)
			(size 0.1397 0.1397)
			(layers "F.Cu" "F.Mask" "F.Paste")
			(net "P5V_B_RF")
			(options
				(clearance outline)
				(anchor circle)
			)
			(primitives
				(gr_poly
					(pts
						(arc
							(start -0.1778 -0.2794)
							(mid -0.249642 -0.249642)
							(end -0.2794 -0.1778)
						)
						(arc
							(start -0.2794 0.1778)
							(mid -0.249642 0.249642)
							(end -0.1778 0.2794)
						)
						(arc
							(start 0.1778 0.2794)
							(mid 0.249642 0.249642)
							(end 0.2794 0.1778)
						)
						(arc
							(start 0.2794 -0.1778)
							(mid 0.249642 -0.249642)
							(end 0.1778 -0.2794)
						)
					)
					(width 0)
					(fill yes)
				)
			)
		)
		(pad "2" smd custom
			(at 0 0.4445 270)
			(size 0.1397 0.1397)
			(layers "F.Cu" "F.Mask" "F.Paste")
			(net "P5V_B_VREG")
			(options
				(clearance outline)
				(anchor circle)
			)
			(primitives
				(gr_poly
					(pts
						(arc
							(start -0.1778 -0.2794)
							(mid -0.249642 -0.249642)
							(end -0.2794 -0.1778)
						)
						(arc
							(start -0.2794 0.1778)
							(mid -0.249642 0.249642)
							(end -0.1778 0.2794)
						)
						(arc
							(start 0.1778 0.2794)
							(mid 0.249642 0.249642)
							(end 0.2794 0.1778)
						)
						(arc
							(start 0.2794 -0.1778)
							(mid 0.249642 -0.249642)
							(end 0.1778 -0.2794)
						)
					)
					(width 0)
					(fill yes)
				)
			)
		)
	)
	(footprint ""
		(layer "F.Cu")
		(at 478.282 -163.068)
		(property "Reference" "C345"
			(at 0 0 0)
			(layer "F.SilkS")
			(hide yes)
			(effects
				(font
					(size 1.27 1.27)
				)
			)
		)
		(property "Value" "SCD01U50V2KX-1GP"
			(at 1.1811 -2.7051 0)
			(unlocked yes)
			(layer "F.Fab")
			(hide yes)
			(effects
				(font
					(size 1.016 1.016)
					(thickness 0.1524)
				)
			)
		)
		(property "Device Type" "C402H22"
			(at 1.1811 -4.2291 0)
			(unlocked yes)
			(layer "F.Fab")
			(hide yes)
			(effects
				(font
					(size 1.016 1.016)
					(thickness 0.1524)
				)
			)
		)
		(duplicate_pad_numbers_are_jumpers no)
		(fp_rect
			(start -0.4318 0.9525)
			(end 0.4318 -0.9525)
			(stroke
				(width 0)
				(type default)
			)
			(fill no)
			(layer "F.CrtYd")
		)
		(fp_rect
			(start -0.4318 0.9525)
			(end 0.4318 -0.9525)
			(stroke
				(width 0)
				(type default)
			)
			(fill no)
			(layer "F.Fab")
		)
		(pad "1" smd custom
			(at 0 -0.4445)
			(size 0.1524 0.1524)
			(layers "F.Cu" "F.Mask" "F.Paste")
			(net "HDD_PRSNT_23")
			(options
				(clearance outline)
				(anchor circle)
			)
			(primitives
				(gr_poly
					(pts
						(arc
							(start 0.3048 -0.2032)
							(mid 0.275042 -0.275042)
							(end 0.2032 -0.3048)
						)
						(arc
							(start -0.2032 -0.3048)
							(mid -0.275042 -0.275042)
							(end -0.3048 -0.2032)
						)
						(arc
							(start -0.3048 0.2032)
							(mid -0.275042 0.275042)
							(end -0.2032 0.3048)
						)
						(arc
							(start 0.2032 0.3048)
							(mid 0.275042 0.275042)
							(end 0.3048 0.2032)
						)
					)
					(width 0)
					(fill yes)
				)
			)
		)
		(pad "2" smd custom
			(at 0 0.4445)
			(size 0.1524 0.1524)
			(layers "F.Cu" "F.Mask" "F.Paste")
			(net "GND")
			(options
				(clearance outline)
				(anchor circle)
			)
			(primitives
				(gr_poly
					(pts
						(arc
							(start 0.3048 -0.2032)
							(mid 0.275042 -0.275042)
							(end 0.2032 -0.3048)
						)
						(arc
							(start -0.2032 -0.3048)
							(mid -0.275042 -0.275042)
							(end -0.3048 -0.2032)
						)
						(arc
							(start -0.3048 0.2032)
							(mid -0.275042 0.275042)
							(end -0.2032 0.3048)
						)
						(arc
							(start 0.2032 0.3048)
							(mid 0.275042 0.275042)
							(end 0.3048 0.2032)
						)
					)
					(width 0)
					(fill yes)
				)
			)
		)
	)
	(footprint ""
		(layer "F.Cu")
		(at 337.291934 -21.45157 180)
		(property "Reference" "R99"
			(at 0 0 180)
			(layer "F.SilkS")
			(hide yes)
			(effects
				(font
					(size 1.27 1.27)
				)
			)
		)
		(property "Value" "4K7R2F-GP"
			(at 0.064008 -3.993896 180)
			(unlocked yes)
			(layer "F.Fab")
			(hide yes)
			(effects
				(font
					(size 1.016 1.016)
					(thickness 0.1524)
				)
			)
		)
		(property "Device Type" "R402H16"
			(at 0.064008 -5.517896 180)
			(unlocked yes)
			(layer "F.Fab")
			(hide yes)
			(effects
				(font
					(size 1.016 1.016)
					(thickness 0.1524)
				)
			)
		)
		(duplicate_pad_numbers_are_jumpers no)
		(fp_line
			(start 0.508 -0.9398)
			(end -0.508 -0.9398)
			(stroke
				(width 0.1524)
				(type default)
			)
			(layer "F.SilkS")
		)
		(fp_line
			(start -0.508 -0.9398)
			(end -0.508 0.9398)
			(stroke
				(width 0.1524)
				(type default)
			)
			(layer "F.SilkS")
		)
		(fp_rect
			(start -0.508 0.9398)
			(end 0.508 -0.9398)
			(stroke
				(width 0)
				(type default)
			)
			(fill no)
			(layer "F.CrtYd")
		)
		(fp_rect
			(start -0.508 0.9398)
			(end 0.508 -0.9398)
			(stroke
				(width 0)
				(type default)
			)
			(fill no)
			(layer "F.Fab")
		)
		(pad "1" smd custom
			(at 0 -0.4445 180)
			(size 0.1397 0.1397)
			(layers "F.Cu" "F.Mask" "F.Paste")
			(net "P3V3_STBY_B")
			(options
				(clearance outline)
				(anchor circle)
			)
			(primitives
				(gr_poly
					(pts
						(arc
							(start -0.1778 -0.2794)
							(mid -0.249642 -0.249642)
							(end -0.2794 -0.1778)
						)
						(arc
							(start -0.2794 0.1778)
							(mid -0.249642 0.249642)
							(end -0.1778 0.2794)
						)
						(arc
							(start 0.1778 0.2794)
							(mid 0.249642 0.249642)
							(end 0.2794 0.1778)
						)
						(arc
							(start 0.2794 -0.1778)
							(mid 0.249642 -0.249642)
							(end 0.1778 -0.2794)
						)
					)
					(width 0)
					(fill yes)
				)
			)
		)
		(pad "2" smd custom
			(at 0 0.4445 180)
			(size 0.1397 0.1397)
			(layers "F.Cu" "F.Mask" "F.Paste")
			(net "IO_EXP11_A2")
			(options
				(clearance outline)
				(anchor circle)
			)
			(primitives
				(gr_poly
					(pts
						(arc
							(start -0.1778 -0.2794)
							(mid -0.249642 -0.249642)
							(end -0.2794 -0.1778)
						)
						(arc
							(start -0.2794 0.1778)
							(mid -0.249642 0.249642)
							(end -0.1778 0.2794)
						)
						(arc
							(start 0.1778 0.2794)
							(mid 0.249642 0.249642)
							(end 0.2794 0.1778)
						)
						(arc
							(start 0.2794 -0.1778)
							(mid 0.249642 -0.249642)
							(end 0.1778 -0.2794)
						)
					)
					(width 0)
					(fill yes)
				)
			)
		)
	)
	(footprint ""
		(layer "F.Cu")
		(at 32.508952 -47.749968 -90)
		(property "Reference" "VIA58"
			(at 0 0 270)
			(layer "F.SilkS")
			(hide yes)
			(effects
				(font
					(size 1.27 1.27)
				)
			)
		)
		(property "Value" "100OHM-8L-1D6MM-L18L16-GP"
			(at -3.7211 -4.5085 270)
			(unlocked yes)
			(layer "F.Fab")
			(hide yes)
			(effects
				(font
					(size 1.016 1.016)
					(thickness 0.1524)
				)
			)
		)
		(property "Device Type" "VIA-PCIE-4P-394076"
			(at -3.7211 -6.0325 270)
			(unlocked yes)
			(layer "F.Fab")
			(hide yes)
			(effects
				(font
					(size 1.016 1.016)
					(thickness 0.1524)
				)
			)
		)
		(duplicate_pad_numbers_are_jumpers no)
		(fp_rect
			(start -1.9685 0.381)
			(end 1.9685 -0.381)
			(stroke
				(width 0)
				(type default)
			)
			(fill no)
			(layer "F.CrtYd")
		)
		(fp_rect
			(start -1.9685 0.381)
			(end 1.9685 -0.381)
			(stroke
				(width 0)
				(type default)
			)
			(fill no)
			(layer "F.Fab")
		)
		(pad "1" thru_hole circle
			(at -1.5875 0 270)
			(size 0.508 0.508)
			(drill 0.254)
			(layers "*.Cu" "*.Mask")
			(remove_unused_layers no)
			(net "GND")
			(clearance 0.127)
			(thermal_gap 0.127)
		)
		(pad "2" thru_hole circle
			(at -0.5715 0 270)
			(size 0.508 0.508)
			(drill 0.254)
			(layers "*.Cu" "*.Mask")
			(remove_unused_layers no)
			(net "PHY_DRV_A_TO_SCC_A_24_DP")
			(clearance 0.127)
			(thermal_gap 0.127)
		)
		(pad "3" thru_hole circle
			(at 0.5715 0 270)
			(size 0.508 0.508)
			(drill 0.254)
			(layers "*.Cu" "*.Mask")
			(remove_unused_layers no)
			(net "PHY_DRV_A_TO_SCC_A_24_DN")
			(clearance 0.127)
			(thermal_gap 0.127)
		)
		(pad "4" thru_hole circle
			(at 1.5875 0 270)
			(size 0.508 0.508)
			(drill 0.254)
			(layers "*.Cu" "*.Mask")
			(remove_unused_layers no)
			(net "GND")
			(clearance 0.127)
			(thermal_gap 0.127)
		)
	)
	(footprint ""
		(layer "F.Cu")
		(at 259.300472 10.1854 90)
		(property "Reference" "R610"
			(at 0 0 90)
			(layer "F.SilkS")
			(hide yes)
			(effects
				(font
					(size 1.27 1.27)
				)
			)
		)
		(property "Value" "10KR2F-2-GP"
			(at 0.064008 -3.993896 90)
			(unlocked yes)
			(layer "F.Fab")
			(hide yes)
			(effects
				(font
					(size 1.016 1.016)
					(thickness 0.1524)
				)
			)
		)
		(property "Device Type" "R402H16"
			(at 0.064008 -5.517896 90)
			(unlocked yes)
			(layer "F.Fab")
			(hide yes)
			(effects
				(font
					(size 1.016 1.016)
					(thickness 0.1524)
				)
			)
		)
		(duplicate_pad_numbers_are_jumpers no)
		(fp_line
			(start 0.508 -0.9398)
			(end -0.508 -0.9398)
			(stroke
				(width 0.1524)
				(type default)
			)
			(layer "F.SilkS")
		)
		(fp_line
			(start -0.508 -0.9398)
			(end -0.508 0.9398)
			(stroke
				(width 0.1524)
				(type default)
			)
			(layer "F.SilkS")
		)
		(fp_rect
			(start -0.508 0.9398)
			(end 0.508 -0.9398)
			(stroke
				(width 0)
				(type default)
			)
			(fill no)
			(layer "F.CrtYd")
		)
		(fp_rect
			(start -0.508 0.9398)
			(end 0.508 -0.9398)
			(stroke
				(width 0)
				(type default)
			)
			(fill no)
			(layer "F.Fab")
		)
		(pad "1" smd custom
			(at 0 -0.4445 90)
			(size 0.1397 0.1397)
			(layers "F.Cu" "F.Mask" "F.Paste")
			(net "IOM_A_FAULT_LED")
			(options
				(clearance outline)
				(anchor circle)
			)
			(primitives
				(gr_poly
					(pts
						(arc
							(start -0.1778 -0.2794)
							(mid -0.249642 -0.249642)
							(end -0.2794 -0.1778)
						)
						(arc
							(start -0.2794 0.1778)
							(mid -0.249642 0.249642)
							(end -0.1778 0.2794)
						)
						(arc
							(start 0.1778 0.2794)
							(mid 0.249642 0.249642)
							(end 0.2794 0.1778)
						)
						(arc
							(start 0.2794 -0.1778)
							(mid 0.249642 -0.249642)
							(end 0.1778 -0.2794)
						)
					)
					(width 0)
					(fill yes)
				)
			)
		)
		(pad "2" smd custom
			(at 0 0.4445 90)
			(size 0.1397 0.1397)
			(layers "F.Cu" "F.Mask" "F.Paste")
			(net "GND")
			(options
				(clearance outline)
				(anchor circle)
			)
			(primitives
				(gr_poly
					(pts
						(arc
							(start -0.1778 -0.2794)
							(mid -0.249642 -0.249642)
							(end -0.2794 -0.1778)
						)
						(arc
							(start -0.2794 0.1778)
							(mid -0.249642 0.249642)
							(end -0.1778 0.2794)
						)
						(arc
							(start 0.1778 0.2794)
							(mid 0.249642 0.249642)
							(end 0.2794 0.1778)
						)
						(arc
							(start 0.2794 -0.1778)
							(mid 0.249642 -0.249642)
							(end 0.1778 -0.2794)
						)
					)
					(width 0)
					(fill yes)
				)
			)
		)
	)
	(footprint ""
		(layer "F.Cu")
		(at 175.848518 -28.635452 90)
		(property "Reference" "C81"
			(at 0 0 90)
			(layer "F.SilkS")
			(hide yes)
			(effects
				(font
					(size 1.27 1.27)
				)
			)
		)
		(property "Value" "SCD1U16V2KX-3GP"
			(at 1.1811 -2.7051 90)
			(unlocked yes)
			(layer "F.Fab")
			(hide yes)
			(effects
				(font
					(size 1.016 1.016)
					(thickness 0.1524)
				)
			)
		)
		(property "Device Type" "C402H22"
			(at 1.1811 -4.2291 90)
			(unlocked yes)
			(layer "F.Fab")
			(hide yes)
			(effects
				(font
					(size 1.016 1.016)
					(thickness 0.1524)
				)
			)
		)
		(duplicate_pad_numbers_are_jumpers no)
		(fp_rect
			(start -0.4318 0.9525)
			(end 0.4318 -0.9525)
			(stroke
				(width 0)
				(type default)
			)
			(fill no)
			(layer "F.CrtYd")
		)
		(fp_rect
			(start -0.4318 0.9525)
			(end 0.4318 -0.9525)
			(stroke
				(width 0)
				(type default)
			)
			(fill no)
			(layer "F.Fab")
		)
		(pad "1" smd custom
			(at 0 -0.4445 90)
			(size 0.1524 0.1524)
			(layers "F.Cu" "F.Mask" "F.Paste")
			(net "P3V3_STBY_A")
			(options
				(clearance outline)
				(anchor circle)
			)
			(primitives
				(gr_poly
					(pts
						(arc
							(start 0.3048 -0.2032)
							(mid 0.275042 -0.275042)
							(end 0.2032 -0.3048)
						)
						(arc
							(start -0.2032 -0.3048)
							(mid -0.275042 -0.275042)
							(end -0.3048 -0.2032)
						)
						(arc
							(start -0.3048 0.2032)
							(mid -0.275042 0.275042)
							(end -0.2032 0.3048)
						)
						(arc
							(start 0.2032 0.3048)
							(mid 0.275042 0.275042)
							(end 0.3048 0.2032)
						)
					)
					(width 0)
					(fill yes)
				)
			)
		)
		(pad "2" smd custom
			(at 0 0.4445 90)
			(size 0.1524 0.1524)
			(layers "F.Cu" "F.Mask" "F.Paste")
			(net "GND")
			(options
				(clearance outline)
				(anchor circle)
			)
			(primitives
				(gr_poly
					(pts
						(arc
							(start 0.3048 -0.2032)
							(mid 0.275042 -0.275042)
							(end 0.2032 -0.3048)
						)
						(arc
							(start -0.2032 -0.3048)
							(mid -0.275042 -0.275042)
							(end -0.3048 -0.2032)
						)
						(arc
							(start -0.3048 0.2032)
							(mid -0.275042 0.275042)
							(end -0.2032 0.3048)
						)
						(arc
							(start 0.2032 0.3048)
							(mid 0.275042 0.275042)
							(end 0.3048 0.2032)
						)
					)
					(width 0)
					(fill yes)
				)
			)
		)
	)
	(footprint ""
		(layer "F.Cu")
		(at 263.81837 -29.811726)
		(property "Reference" "TC18"
			(at 0 0 0)
			(layer "F.SilkS")
			(hide yes)
			(effects
				(font
					(size 1.27 1.27)
				)
			)
		)
		(property "Value" "SE270U16VM-8-GP"
			(at -4.5974 -2.54 0)
			(unlocked yes)
			(layer "F.Fab")
			(hide yes)
			(effects
				(font
					(size 1.016 1.016)
					(thickness 0.1524)
				)
			)
		)
		(property "Device Type" "SE361416H394"
			(at -4.5974 -4.064 0)
			(unlocked yes)
			(layer "F.Fab")
			(hide yes)
			(effects
				(font
					(size 1.016 1.016)
					(thickness 0.1524)
				)
			)
		)
		(duplicate_pad_numbers_are_jumpers no)
		(fp_line
			(start -3.556 -3.4163)
			(end -2.3622 -4.6101)
			(stroke
				(width 0.1524)
				(type default)
			)
			(layer "F.SilkS")
		)
		(fp_line
			(start -3.556 4.6101)
			(end -3.556 -3.4163)
			(stroke
				(width 0.1524)
				(type default)
			)
			(layer "F.SilkS")
		)
		(fp_line
			(start -2.3622 -4.6101)
			(end 2.3622 -4.6101)
			(stroke
				(width 0.1524)
				(type default)
			)
			(layer "F.SilkS")
		)
		(fp_line
			(start 2.3622 -4.6101)
			(end 3.556 -3.4163)
			(stroke
				(width 0.1524)
				(type default)
			)
			(layer "F.SilkS")
		)
		(fp_line
			(start 3.556 -3.4163)
			(end 3.556 4.6101)
			(stroke
				(width 0.1524)
				(type default)
			)
			(layer "F.SilkS")
		)
		(fp_line
			(start 3.556 4.6101)
			(end -3.556 4.6101)
			(stroke
				(width 0.1524)
				(type default)
			)
			(layer "F.SilkS")
		)
		(fp_rect
			(start -3.302 3.6449)
			(end 3.302 -3.6449)
			(stroke
				(width 0)
				(type default)
			)
			(fill no)
			(layer "F.CrtYd")
		)
		(fp_poly
			(pts
				(xy 3.81 4.6863) (xy 3.81 -3.4925) (xy 3.302 -3.4925) (xy 3.302 3.6449) (xy -3.302 3.6449) (xy -3.302 -3.6449)
				(xy 3.302 -3.6449) (xy 3.302 -3.5052) (xy 3.81 -3.5052) (xy 3.81 -4.6863) (xy -3.81 -4.6863) (xy -3.81 4.6863)
			)
			(stroke
				(width 0)
				(type default)
			)
			(fill no)
			(layer "F.CrtYd")
		)
		(fp_rect
			(start -3.81 4.6863)
			(end 3.81 -4.6863)
			(stroke
				(width 0)
				(type default)
			)
			(fill no)
			(layer "F.Fab")
		)
		(pad "1" smd rect
			(at 0 -2.574036)
			(size 1.4224 3.556)
			(layers "F.Cu" "F.Mask" "F.Paste")
			(net "P12V_A")
		)
		(pad "2" smd rect
			(at 0 2.574036)
			(size 1.4224 3.556)
			(layers "F.Cu" "F.Mask" "F.Paste")
			(net "GND")
		)
	)
	(footprint ""
		(layer "F.Cu")
		(at 118.890796 -74.462894 180)
		(property "Reference" "C398"
			(at 0 0 180)
			(layer "F.SilkS")
			(hide yes)
			(effects
				(font
					(size 1.27 1.27)
				)
			)
		)
		(property "Value" "SC1U25V3KX-GP"
			(at 0 -2.8194 180)
			(unlocked yes)
			(layer "F.Fab")
			(hide yes)
			(effects
				(font
					(size 1.016 1.016)
					(thickness 0.1524)
				)
			)
		)
		(property "Device Type" "C603H36"
			(at 0 -4.3434 180)
			(unlocked yes)
			(layer "F.Fab")
			(hide yes)
			(effects
				(font
					(size 1.016 1.016)
					(thickness 0.1524)
				)
			)
		)
		(duplicate_pad_numbers_are_jumpers no)
		(fp_line
			(start 0.508 0)
			(end -0.508 0)
			(stroke
				(width 0.2032)
				(type default)
			)
			(layer "F.SilkS")
		)
		(fp_rect
			(start -0.5842 1.3335)
			(end 0.5842 -1.3335)
			(stroke
				(width 0)
				(type default)
			)
			(fill no)
			(layer "F.CrtYd")
		)
		(fp_rect
			(start -0.5842 1.3335)
			(end 0.5842 -1.3335)
			(stroke
				(width 0)
				(type default)
			)
			(fill no)
			(layer "F.Fab")
		)
		(pad "1" smd custom
			(at 0 -0.762 180)
			(size 0.2159 0.2159)
			(layers "F.Cu" "F.Mask" "F.Paste")
			(net "P12V_HDD27")
			(options
				(clearance outline)
				(anchor circle)
			)
			(primitives
				(gr_poly
					(pts
						(arc
							(start -0.3302 -0.4318)
							(mid -0.402042 -0.402042)
							(end -0.4318 -0.3302)
						)
						(arc
							(start -0.4318 0.3302)
							(mid -0.402042 0.402042)
							(end -0.3302 0.4318)
						)
						(arc
							(start 0.3302 0.4318)
							(mid 0.402042 0.402042)
							(end 0.4318 0.3302)
						)
						(arc
							(start 0.4318 -0.3302)
							(mid 0.402042 -0.402042)
							(end 0.3302 -0.4318)
						)
					)
					(width 0)
					(fill yes)
				)
			)
		)
		(pad "2" smd custom
			(at 0 0.762 180)
			(size 0.2159 0.2159)
			(layers "F.Cu" "F.Mask" "F.Paste")
			(net "GND")
			(options
				(clearance outline)
				(anchor circle)
			)
			(primitives
				(gr_poly
					(pts
						(arc
							(start -0.3302 -0.4318)
							(mid -0.402042 -0.402042)
							(end -0.4318 -0.3302)
						)
						(arc
							(start -0.4318 0.3302)
							(mid -0.402042 0.402042)
							(end -0.3302 0.4318)
						)
						(arc
							(start 0.3302 0.4318)
							(mid 0.402042 0.402042)
							(end 0.4318 0.3302)
						)
						(arc
							(start 0.4318 -0.3302)
							(mid 0.402042 -0.402042)
							(end 0.3302 -0.4318)
						)
					)
					(width 0)
					(fill yes)
				)
			)
		)
	)
	(footprint ""
		(layer "F.Cu")
		(at 144.977866 -137.879074)
		(property "Reference" "U23"
			(at 0 0 0)
			(layer "F.SilkS")
			(hide yes)
			(effects
				(font
					(size 1.27 1.27)
				)
			)
		)
		(property "Value" "ADM1278-2ACPZ-RL-1-GP"
			(at -4.7625 -7.4422 0)
			(unlocked yes)
			(layer "F.Fab")
			(hide yes)
			(effects
				(font
					(size 1.016 1.016)
					(thickness 0.1524)
				)
			)
		)
		(property "Device Type" "QFN32-G3D45-UH32"
			(at -4.7625 -8.9662 0)
			(unlocked yes)
			(layer "F.Fab")
			(hide yes)
			(effects
				(font
					(size 1.016 1.016)
					(thickness 0.1524)
				)
			)
		)
		(duplicate_pad_numbers_are_jumpers no)
		(fp_line
			(start -4.0513 -1.24968)
			(end -3.2893 -1.24968)
			(stroke
				(width 0.1524)
				(type default)
			)
			(layer "F.SilkS")
		)
		(fp_line
			(start -3.7973 1.24968)
			(end -3.2893 1.24968)
			(stroke
				(width 0.1524)
				(type default)
			)
			(layer "F.SilkS")
		)
		(fp_line
			(start -3.5179 -3.5179)
			(end -2.2479 -3.5179)
			(stroke
				(width 0.1524)
				(type default)
			)
			(layer "F.SilkS")
		)
		(fp_line
			(start -3.5179 -2.2479)
			(end -3.5179 -3.5179)
			(stroke
				(width 0.1524)
				(type default)
			)
			(layer "F.SilkS")
		)
		(fp_line
			(start -3.5179 2.2479)
			(end -3.5179 3.5179)
			(stroke
				(width 0.1524)
				(type default)
			)
			(layer "F.SilkS")
		)
		(fp_line
			(start -3.5179 3.5179)
			(end -2.2479 3.5179)
			(stroke
				(width 0.1524)
				(type default)
			)
			(layer "F.SilkS")
		)
		(fp_line
			(start -0.250698 -3.7973)
			(end -0.250698 -3.2893)
			(stroke
				(width 0.1524)
				(type default)
			)
			(layer "F.SilkS")
		)
		(fp_line
			(start -0.250698 4.0513)
			(end -0.250698 3.2893)
			(stroke
				(width 0.1524)
				(type default)
			)
			(layer "F.SilkS")
		)
		(fp_line
			(start 3.5179 2.2479)
			(end 3.5179 3.5179)
			(stroke
				(width 0.1524)
				(type default)
			)
			(layer "F.SilkS")
		)
		(fp_line
			(start 3.5179 3.5179)
			(end 2.2479 3.5179)
			(stroke
				(width 0.1524)
				(type default)
			)
			(layer "F.SilkS")
		)
		(fp_line
			(start 3.7973 1.749552)
			(end 3.2893 1.749552)
			(stroke
				(width 0.1524)
				(type default)
			)
			(layer "F.SilkS")
		)
		(fp_line
			(start 4.0513 -0.749808)
			(end 3.2893 -0.749808)
			(stroke
				(width 0.1524)
				(type default)
			)
			(layer "F.SilkS")
		)
		(fp_poly
			(pts
				(xy 2.2479 -3.5179) (xy 3.5179 -2.2479) (xy 3.5179 -3.5179)
			)
			(stroke
				(width 0)
				(type default)
			)
			(fill yes)
			(layer "F.SilkS")
		)
		(fp_rect
			(start -2.5019 2.5019)
			(end 2.5019 -2.5019)
			(stroke
				(width 0)
				(type default)
			)
			(fill no)
			(layer "F.CrtYd")
		)
		(fp_poly
			(pts
				(xy -3.5179 3.5179) (xy -3.5179 -3.5179) (xy 3.5179 -3.5179) (xy 3.5179 3.5179) (xy -2.49682 3.5179)
				(xy -2.49682 2.5019) (xy 2.5019 2.5019) (xy 2.5019 -2.5019) (xy -2.5019 -2.5019) (xy -2.5019 3.5179)
			)
			(stroke
				(width 0)
				(type default)
			)
			(fill no)
			(layer "F.CrtYd")
		)
		(fp_rect
			(start -3.5179 3.5179)
			(end 3.5179 -3.5179)
			(stroke
				(width 0)
				(type default)
			)
			(fill no)
			(layer "F.Fab")
		)
		(pad "1" smd rect
			(at 1.75006 -2.5527)
			(size 0.3048 0.9144)
			(layers "F.Cu" "F.Mask" "F.Paste")
			(net "MB0_PSET_R")
		)
		(pad "2" smd rect
			(at 1.249934 -2.4765)
			(size 0.3048 1.0668)
			(layers "F.Cu" "F.Mask" "F.Paste")
			(net "MB0_VCAP_R")
		)
		(pad "3" smd rect
			(at 0.750062 -2.4765)
			(size 0.3048 1.0668)
			(layers "F.Cu" "F.Mask" "F.Paste")
			(net "MB0_ISET_R")
		)
		(pad "4" smd rect
			(at 0.249936 -2.4765)
			(size 0.3048 1.0668)
			(layers "F.Cu" "F.Mask" "F.Paste")
			(net "MB0_ISTART_R")
		)
		(pad "5" smd rect
			(at -0.249936 -2.4765)
			(size 0.3048 1.0668)
			(layers "F.Cu" "F.Mask" "F.Paste")
			(net "MB0_TIME_R")
		)
		(pad "6" smd rect
			(at -0.750062 -2.4765)
			(size 0.3048 1.0668)
			(layers "F.Cu" "F.Mask" "F.Paste")
			(net "Net_1360")
		)
		(pad "7" smd rect
			(at -1.249934 -2.4765)
			(size 0.3048 1.0668)
			(layers "F.Cu" "F.Mask" "F.Paste")
			(net "MB0_CM_ADR1_R")
		)
		(pad "8" smd rect
			(at -1.75006 -2.5527)
			(size 0.3048 0.9144)
			(layers "F.Cu" "F.Mask" "F.Paste")
			(net "MB0_CM_ADR2_R")
		)
		(pad "9" smd rect
			(at -2.5527 -1.75006)
			(size 0.9144 0.3048)
			(layers "F.Cu" "F.Mask" "F.Paste")
			(net "MB0_SPISS_PD")
		)
		(pad "10" smd rect
			(at -2.4765 -1.249934)
			(size 1.0668 0.3048)
			(layers "F.Cu" "F.Mask" "F.Paste")
			(net "Net_1364")
		)
		(pad "11" smd rect
			(at -2.4765 -0.750062)
			(size 1.0668 0.3048)
			(layers "F.Cu" "F.Mask" "F.Paste")
			(net "Net_1363")
		)
		(pad "12" smd rect
			(at -2.4765 -0.249936)
			(size 1.0668 0.3048)
			(layers "F.Cu" "F.Mask" "F.Paste")
			(net "MB0_HS_ENABLE")
		)
		(pad "13" smd rect
			(at -2.4765 0.249936)
			(size 1.0668 0.3048)
			(layers "F.Cu" "F.Mask" "F.Paste")
			(net "Net_1362")
		)
		(pad "14" smd rect
			(at -2.4765 0.750062)
			(size 1.0668 0.3048)
			(layers "F.Cu" "F.Mask" "F.Paste")
			(net "Net_1361")
		)
		(pad "15" smd rect
			(at -2.4765 1.249934)
			(size 1.0668 0.3048)
			(layers "F.Cu" "F.Mask" "F.Paste")
			(net "MB0_SDA_R")
		)
		(pad "16" smd rect
			(at -2.5527 1.75006)
			(size 0.9144 0.3048)
			(layers "F.Cu" "F.Mask" "F.Paste")
			(net "MB0_SCL_R")
		)
		(pad "17" smd rect
			(at -1.75006 2.5527)
			(size 0.3048 0.9144)
			(layers "F.Cu" "F.Mask" "F.Paste")
			(net "MB0_RETRY_R")
		)
		(pad "18" smd rect
			(at -1.249934 2.4765)
			(size 0.3048 1.0668)
			(layers "F.Cu" "F.Mask" "F.Paste")
			(net "COMP_A_PGOOD")
		)
		(pad "19" smd rect
			(at -0.750062 2.4765)
			(size 0.3048 1.0668)
			(layers "F.Cu" "F.Mask" "F.Paste")
			(net "Net_1365")
		)
		(pad "20" smd rect
			(at -0.249936 2.4765)
			(size 0.3048 1.0668)
			(layers "F.Cu" "F.Mask" "F.Paste")
			(net "MB0_CM_VOUT_R")
		)
		(pad "21" smd rect
			(at 0.249936 2.4765)
			(size 0.3048 1.0668)
			(layers "F.Cu" "F.Mask" "F.Paste")
			(net "MB0_P12V_PWGIN_R")
		)
		(pad "22" smd rect
			(at 0.750062 2.4765)
			(size 0.3048 1.0668)
			(layers "F.Cu" "F.Mask" "F.Paste")
			(net "AGND_CURRENT_MONOA")
		)
		(pad "23" smd rect
			(at 1.249934 2.4765)
			(size 0.3048 1.0668)
			(layers "F.Cu" "F.Mask" "F.Paste")
			(net "GND")
		)
		(pad "24" smd rect
			(at 1.75006 2.5527)
			(size 0.3048 0.9144)
			(layers "F.Cu" "F.Mask" "F.Paste")
			(net "MB0_CM_GATE")
		)
		(pad "25" smd rect
			(at 2.5527 1.75006)
			(size 0.9144 0.3048)
			(layers "F.Cu" "F.Mask" "F.Paste")
			(net "MB0_TEMP")
		)
		(pad "26" smd rect
			(at 2.4765 1.249934)
			(size 1.0668 0.3048)
			(layers "F.Cu" "F.Mask" "F.Paste")
			(net "MB0_CM_SENSE_N")
		)
		(pad "27" smd rect
			(at 2.4765 0.750062)
			(size 1.0668 0.3048)
			(layers "F.Cu" "F.Mask" "F.Paste")
			(net "MB0_HS_SENSE_N")
		)
		(pad "28" smd rect
			(at 2.4765 0.249936)
			(size 1.0668 0.3048)
			(layers "F.Cu" "F.Mask" "F.Paste")
			(net "MB0_HS_SENSE_P")
		)
		(pad "29" smd rect
			(at 2.4765 -0.249936)
			(size 1.0668 0.3048)
			(layers "F.Cu" "F.Mask" "F.Paste")
			(net "MB0_CM_SENSE_P")
		)
		(pad "30" smd rect
			(at 2.4765 -0.750062)
			(size 1.0668 0.3048)
			(layers "F.Cu" "F.Mask" "F.Paste")
			(net "MB0_P12V_HS")
		)
		(pad "31" smd rect
			(at 2.4765 -1.249934)
			(size 1.0668 0.3048)
			(layers "F.Cu" "F.Mask" "F.Paste")
			(net "MB0_CM_UV_R")
		)
		(pad "32" smd rect
			(at 2.5527 -1.75006)
			(size 0.9144 0.3048)
			(layers "F.Cu" "F.Mask" "F.Paste")
			(net "MB0_CM_OV_R")
		)
		(pad "33" smd rect
			(at 0 0)
			(size 3.4544 3.4544)
			(layers "F.Cu" "F.Mask" "F.Paste")
			(net "AGND_CURRENT_MONOA")
		)
	)
	(footprint ""
		(layer "F.Cu")
		(at 424.469052 -74.335894 180)
		(property "Reference" "C476"
			(at 0 0 180)
			(layer "F.SilkS")
			(hide yes)
			(effects
				(font
					(size 1.27 1.27)
				)
			)
		)
		(property "Value" "SC1U25V3KX-GP"
			(at 0 -2.8194 180)
			(unlocked yes)
			(layer "F.Fab")
			(hide yes)
			(effects
				(font
					(size 1.016 1.016)
					(thickness 0.1524)
				)
			)
		)
		(property "Device Type" "C603H36"
			(at 0 -4.3434 180)
			(unlocked yes)
			(layer "F.Fab")
			(hide yes)
			(effects
				(font
					(size 1.016 1.016)
					(thickness 0.1524)
				)
			)
		)
		(duplicate_pad_numbers_are_jumpers no)
		(fp_line
			(start 0.508 0)
			(end -0.508 0)
			(stroke
				(width 0.2032)
				(type default)
			)
			(layer "F.SilkS")
		)
		(fp_rect
			(start -0.5842 1.3335)
			(end 0.5842 -1.3335)
			(stroke
				(width 0)
				(type default)
			)
			(fill no)
			(layer "F.CrtYd")
		)
		(fp_rect
			(start -0.5842 1.3335)
			(end 0.5842 -1.3335)
			(stroke
				(width 0)
				(type default)
			)
			(fill no)
			(layer "F.Fab")
		)
		(pad "1" smd custom
			(at 0 -0.762 180)
			(size 0.2159 0.2159)
			(layers "F.Cu" "F.Mask" "F.Paste")
			(net "P12V_HDD33")
			(options
				(clearance outline)
				(anchor circle)
			)
			(primitives
				(gr_poly
					(pts
						(arc
							(start -0.3302 -0.4318)
							(mid -0.402042 -0.402042)
							(end -0.4318 -0.3302)
						)
						(arc
							(start -0.4318 0.3302)
							(mid -0.402042 0.402042)
							(end -0.3302 0.4318)
						)
						(arc
							(start 0.3302 0.4318)
							(mid 0.402042 0.402042)
							(end 0.4318 0.3302)
						)
						(arc
							(start 0.4318 -0.3302)
							(mid 0.402042 -0.402042)
							(end 0.3302 -0.4318)
						)
					)
					(width 0)
					(fill yes)
				)
			)
		)
		(pad "2" smd custom
			(at 0 0.762 180)
			(size 0.2159 0.2159)
			(layers "F.Cu" "F.Mask" "F.Paste")
			(net "GND")
			(options
				(clearance outline)
				(anchor circle)
			)
			(primitives
				(gr_poly
					(pts
						(arc
							(start -0.3302 -0.4318)
							(mid -0.402042 -0.402042)
							(end -0.4318 -0.3302)
						)
						(arc
							(start -0.4318 0.3302)
							(mid -0.402042 0.402042)
							(end -0.3302 0.4318)
						)
						(arc
							(start 0.3302 0.4318)
							(mid 0.402042 0.402042)
							(end 0.4318 0.3302)
						)
						(arc
							(start 0.4318 -0.3302)
							(mid 0.402042 -0.402042)
							(end 0.3302 -0.4318)
						)
					)
					(width 0)
					(fill yes)
				)
			)
		)
	)
	(footprint ""
		(layer "F.Cu")
		(at 50.456846 -64.683894 90)
		(property "Reference" "R706"
			(at 0 0 90)
			(layer "F.SilkS")
			(hide yes)
			(effects
				(font
					(size 1.27 1.27)
				)
			)
		)
		(property "Value" "2R6F-GP"
			(at -0.0508 -4.8514 90)
			(unlocked yes)
			(layer "F.Fab")
			(hide yes)
			(effects
				(font
					(size 1.016 1.016)
					(thickness 0.1524)
				)
			)
		)
		(property "Device Type" "R1206H26"
			(at 0 -6.3754 90)
			(unlocked yes)
			(layer "F.Fab")
			(hide yes)
			(effects
				(font
					(size 1.016 1.016)
					(thickness 0.1524)
				)
			)
		)
		(duplicate_pad_numbers_are_jumpers no)
		(fp_line
			(start 1.016 -2.2352)
			(end 1.016 2.2352)
			(stroke
				(width 0.1524)
				(type default)
			)
			(layer "F.SilkS")
		)
		(fp_line
			(start -1.016 -2.2352)
			(end 1.016 -2.2352)
			(stroke
				(width 0.1524)
				(type default)
			)
			(layer "F.SilkS")
		)
		(fp_line
			(start 1.016 2.2352)
			(end -1.016 2.2352)
			(stroke
				(width 0.1524)
				(type default)
			)
			(layer "F.SilkS")
		)
		(fp_line
			(start -1.016 2.2352)
			(end -1.016 -2.2352)
			(stroke
				(width 0.1524)
				(type default)
			)
			(layer "F.SilkS")
		)
		(fp_rect
			(start -1.0922 2.3114)
			(end 1.0922 -2.3114)
			(stroke
				(width 0)
				(type default)
			)
			(fill no)
			(layer "F.CrtYd")
		)
		(fp_poly
			(pts
				(xy -1.0922 -2.3114) (xy 1.0922 -2.3114) (xy 1.0922 2.3114) (xy -1.0922 2.3114)
			)
			(stroke
				(width 0)
				(type default)
			)
			(fill no)
			(layer "F.Fab")
		)
		(pad "1" smd rect
			(at 0 -1.397 90)
			(size 1.651 1.27)
			(layers "F.Cu" "F.Mask" "F.Paste")
			(net "P12V_HDD25")
		)
		(pad "2" smd rect
			(at 0 1.397 90)
			(size 1.651 1.27)
			(layers "F.Cu" "F.Mask" "F.Paste")
			(net "12V_PRE_25")
		)
	)
	(footprint ""
		(layer "F.Cu")
		(at 318.389 -65.064894 -90)
		(property "Reference" "R824"
			(at 0 0 270)
			(layer "F.SilkS")
			(hide yes)
			(effects
				(font
					(size 1.27 1.27)
				)
			)
		)
		(property "Value" "220R3F-1-GP"
			(at -0.0254 -2.5146 270)
			(unlocked yes)
			(layer "F.Fab")
			(hide yes)
			(effects
				(font
					(size 1.016 1.016)
					(thickness 0.1524)
				)
			)
		)
		(property "Device Type" "R603H22"
			(at -0.0254 -4.0386 270)
			(unlocked yes)
			(layer "F.Fab")
			(hide yes)
			(effects
				(font
					(size 1.016 1.016)
					(thickness 0.1524)
				)
			)
		)
		(duplicate_pad_numbers_are_jumpers no)
		(fp_line
			(start -0.4826 0)
			(end -0.2032 0)
			(stroke
				(width 0.2032)
				(type default)
			)
			(layer "F.SilkS")
		)
		(fp_line
			(start 0.2032 0)
			(end 0.4826 0)
			(stroke
				(width 0.2032)
				(type default)
			)
			(layer "F.SilkS")
		)
		(fp_rect
			(start -0.5842 1.3335)
			(end 0.5842 -1.3335)
			(stroke
				(width 0)
				(type default)
			)
			(fill no)
			(layer "F.CrtYd")
		)
		(fp_rect
			(start -0.5842 1.3335)
			(end 0.5842 -1.3335)
			(stroke
				(width 0)
				(type default)
			)
			(fill no)
			(layer "F.Fab")
		)
		(pad "1" smd custom
			(at 0 -0.762 270)
			(size 0.2159 0.2159)
			(layers "F.Cu" "F.Mask" "F.Paste")
			(net "HDD_PRSNT_30")
			(options
				(clearance outline)
				(anchor circle)
			)
			(primitives
				(gr_poly
					(pts
						(arc
							(start -0.3302 -0.4318)
							(mid -0.402042 -0.402042)
							(end -0.4318 -0.3302)
						)
						(arc
							(start -0.4318 0.3302)
							(mid -0.402042 0.402042)
							(end -0.3302 0.4318)
						)
						(arc
							(start 0.3302 0.4318)
							(mid 0.402042 0.402042)
							(end 0.4318 0.3302)
						)
						(arc
							(start 0.4318 -0.3302)
							(mid 0.402042 -0.402042)
							(end 0.3302 -0.4318)
						)
					)
					(width 0)
					(fill yes)
				)
			)
		)
		(pad "2" smd custom
			(at 0 0.762 270)
			(size 0.2159 0.2159)
			(layers "F.Cu" "F.Mask" "F.Paste")
			(net "DRIVE_A_30_INS")
			(options
				(clearance outline)
				(anchor circle)
			)
			(primitives
				(gr_poly
					(pts
						(arc
							(start -0.3302 -0.4318)
							(mid -0.402042 -0.402042)
							(end -0.4318 -0.3302)
						)
						(arc
							(start -0.4318 0.3302)
							(mid -0.402042 0.402042)
							(end -0.3302 0.4318)
						)
						(arc
							(start 0.3302 0.4318)
							(mid 0.402042 0.402042)
							(end 0.4318 0.3302)
						)
						(arc
							(start 0.4318 -0.3302)
							(mid 0.402042 -0.402042)
							(end 0.3302 -0.4318)
						)
					)
					(width 0)
					(fill yes)
				)
			)
		)
	)
	(footprint ""
		(layer "F.Cu")
		(at 457.6699 -303.954942 180)
		(property "Reference" "C174"
			(at 0 0 180)
			(layer "F.SilkS")
			(hide yes)
			(effects
				(font
					(size 1.27 1.27)
				)
			)
		)
		(property "Value" "SC4D7U25V5KX-1-GP"
			(at -0.0762 -6.1214 180)
			(unlocked yes)
			(layer "F.Fab")
			(hide yes)
			(effects
				(font
					(size 1.016 1.016)
					(thickness 0.1524)
				)
			)
		)
		(property "Device Type" "C805H58"
			(at -0.0762 -8.1534 180)
			(unlocked yes)
			(layer "F.Fab")
			(hide yes)
			(effects
				(font
					(size 1.016 1.016)
					(thickness 0.1524)
				)
			)
		)
		(duplicate_pad_numbers_are_jumpers no)
		(fp_line
			(start 0.635 0)
			(end -0.635 0)
			(stroke
				(width 0.508)
				(type default)
			)
			(layer "F.SilkS")
		)
		(fp_rect
			(start -0.9652 1.778)
			(end 0.9652 -1.778)
			(stroke
				(width 0)
				(type default)
			)
			(fill no)
			(layer "F.CrtYd")
		)
		(fp_poly
			(pts
				(xy -0.9652 -1.778) (xy 0.9652 -1.778) (xy 0.9652 1.778) (xy -0.9652 1.778)
			)
			(stroke
				(width 0)
				(type default)
			)
			(fill no)
			(layer "F.Fab")
		)
		(pad "1" smd rect
			(at 0 -0.9652 180)
			(size 1.397 1.143)
			(layers "F.Cu" "F.Mask" "F.Paste")
			(net "P12V_HDD10")
		)
		(pad "2" smd rect
			(at 0 0.9652 180)
			(size 1.397 1.143)
			(layers "F.Cu" "F.Mask" "F.Paste")
			(net "GND")
		)
	)
	(footprint ""
		(layer "F.Cu")
		(at 255.389634 -6.741922 90)
		(property "Reference" "TP214"
			(at 0 0 90)
			(layer "F.SilkS")
			(hide yes)
			(effects
				(font
					(size 1.27 1.27)
				)
			)
		)
		(property "Value" "TPAD32-GP"
			(at -0.0508 -1.6764 90)
			(unlocked yes)
			(layer "F.Fab")
			(hide yes)
			(effects
				(font
					(size 1.016 1.016)
					(thickness 0.1524)
				)
			)
		)
		(property "Device Type" "TPAD32"
			(at -0.0508 -3.2004 90)
			(unlocked yes)
			(layer "F.Fab")
			(hide yes)
			(effects
				(font
					(size 1.016 1.016)
					(thickness 0.1524)
				)
			)
		)
		(duplicate_pad_numbers_are_jumpers no)
		(fp_poly
			(pts
				(arc
					(start 0 0.4064)
					(mid 0 -0.4064)
					(end 0 0.4064)
				)
			)
			(stroke
				(width 0)
				(type default)
			)
			(fill no)
			(layer "F.CrtYd")
		)
		(fp_poly
			(pts
				(arc
					(start 0 0.7112)
					(mid 0 -0.7112)
					(end 0 0.7112)
				)
			)
			(stroke
				(width 0)
				(type default)
			)
			(fill no)
			(layer "F.Fab")
		)
		(pad "1" smd circle
			(at 0 0 90)
			(size 0.8128 0.8128)
			(layers "F.Cu" "F.Mask" "F.Paste")
			(net "TP_COMP_A_NCSI_TXD0")
		)
	)
	(footprint ""
		(layer "F.Cu")
		(at 228.419152 -390.33704)
		(property "Reference" "Q9"
			(at 0 0 0)
			(layer "F.SilkS")
			(hide yes)
			(effects
				(font
					(size 1.27 1.27)
				)
			)
		)
		(property "Value" "MMBT3904TT1G-GP"
			(at 0 -9.7282 0)
			(unlocked yes)
			(layer "F.Fab")
			(hide yes)
			(effects
				(font
					(size 1.016 1.016)
					(thickness 0.1524)
				)
			)
		)
		(property "Device Type" "SC75CBE1D6H36"
			(at 0 -11.6332 0)
			(unlocked yes)
			(layer "F.Fab")
			(hide yes)
			(effects
				(font
					(size 1.016 1.016)
					(thickness 0.1524)
				)
			)
		)
		(duplicate_pad_numbers_are_jumpers no)
		(fp_line
			(start -0.9652 -1.3716)
			(end -0.9652 1.3716)
			(stroke
				(width 0.1524)
				(type default)
			)
			(layer "F.SilkS")
		)
		(fp_line
			(start -0.9652 1.3716)
			(end 0.9652 1.3716)
			(stroke
				(width 0.1524)
				(type default)
			)
			(layer "F.SilkS")
		)
		(fp_line
			(start 0.9652 -1.3716)
			(end -0.9652 -1.3716)
			(stroke
				(width 0.1524)
				(type default)
			)
			(layer "F.SilkS")
		)
		(fp_line
			(start 0.9652 1.3716)
			(end 0.9652 -1.3716)
			(stroke
				(width 0.1524)
				(type default)
			)
			(layer "F.SilkS")
		)
		(fp_rect
			(start -1.0414 1.4478)
			(end 1.0414 -1.4478)
			(stroke
				(width 0)
				(type default)
			)
			(fill no)
			(layer "F.CrtYd")
		)
		(fp_poly
			(pts
				(xy -1.0414 -1.4478) (xy 1.0414 -1.4478) (xy 1.0414 1.4478) (xy -1.0414 1.4478)
			)
			(stroke
				(width 0)
				(type default)
			)
			(fill no)
			(layer "F.Fab")
		)
		(pad "B" smd custom
			(at -0.508 0.7112)
			(size 0.127 0.127)
			(layers "F.Cu" "F.Mask" "F.Paste")
			(net "VCCP_IN")
			(options
				(clearance outline)
				(anchor circle)
			)
			(primitives
				(gr_poly
					(pts
						(arc
							(start -0.044958 0.4572)
							(mid -0.192463 0.399794)
							(end -0.254 0.254)
						)
						(xy -0.254 -0.254)
						(arc
							(start -0.253746 -0.254)
							(mid -0.192968 -0.398936)
							(end -0.04699 -0.4572)
						)
						(arc
							(start 0.04699 -0.4572)
							(mid 0.192989 -0.398958)
							(end 0.253746 -0.254)
						)
						(xy 0.254 -0.254)
						(arc
							(start 0.254 0.254)
							(mid 0.192404 0.399734)
							(end 0.044958 0.4572)
						)
					)
					(width 0)
					(fill yes)
				)
			)
		)
		(pad "C" smd custom
			(at 0 -0.7112)
			(size 0.127 0.127)
			(layers "F.Cu" "F.Mask" "F.Paste")
			(net "P12V_IN")
			(options
				(clearance outline)
				(anchor circle)
			)
			(primitives
				(gr_poly
					(pts
						(arc
							(start -0.044958 0.4572)
							(mid -0.192463 0.399794)
							(end -0.254 0.254)
						)
						(xy -0.254 -0.254)
						(arc
							(start -0.253746 -0.254)
							(mid -0.192968 -0.398936)
							(end -0.04699 -0.4572)
						)
						(arc
							(start 0.04699 -0.4572)
							(mid 0.192989 -0.398958)
							(end 0.253746 -0.254)
						)
						(xy 0.254 -0.254)
						(arc
							(start 0.254 0.254)
							(mid 0.192404 0.399734)
							(end 0.044958 0.4572)
						)
					)
					(width 0)
					(fill yes)
				)
			)
		)
		(pad "E" smd custom
			(at 0.508 0.7112)
			(size 0.127 0.127)
			(layers "F.Cu" "F.Mask" "F.Paste")
			(net "P3V3_IN_BIAS")
			(options
				(clearance outline)
				(anchor circle)
			)
			(primitives
				(gr_poly
					(pts
						(arc
							(start -0.044958 0.4572)
							(mid -0.192463 0.399794)
							(end -0.254 0.254)
						)
						(xy -0.254 -0.254)
						(arc
							(start -0.253746 -0.254)
							(mid -0.192968 -0.398936)
							(end -0.04699 -0.4572)
						)
						(arc
							(start 0.04699 -0.4572)
							(mid 0.192989 -0.398958)
							(end 0.253746 -0.254)
						)
						(xy 0.254 -0.254)
						(arc
							(start 0.254 0.254)
							(mid 0.192404 0.399734)
							(end 0.044958 0.4572)
						)
					)
					(width 0)
					(fill yes)
				)
			)
		)
	)
	(footprint ""
		(layer "F.Cu")
		(at 55.486046 -186.287918)
		(property "Reference" "C214"
			(at 0 0 0)
			(layer "F.SilkS")
			(hide yes)
			(effects
				(font
					(size 1.27 1.27)
				)
			)
		)
		(property "Value" "SC4D7U25V5KX-1-GP"
			(at -0.0762 -6.1214 0)
			(unlocked yes)
			(layer "F.Fab")
			(hide yes)
			(effects
				(font
					(size 1.016 1.016)
					(thickness 0.1524)
				)
			)
		)
		(property "Device Type" "C805H58"
			(at -0.0762 -8.1534 0)
			(unlocked yes)
			(layer "F.Fab")
			(hide yes)
			(effects
				(font
					(size 1.016 1.016)
					(thickness 0.1524)
				)
			)
		)
		(duplicate_pad_numbers_are_jumpers no)
		(fp_line
			(start 0.635 0)
			(end -0.635 0)
			(stroke
				(width 0.508)
				(type default)
			)
			(layer "F.SilkS")
		)
		(fp_rect
			(start -0.9652 1.778)
			(end 0.9652 -1.778)
			(stroke
				(width 0)
				(type default)
			)
			(fill no)
			(layer "F.CrtYd")
		)
		(fp_poly
			(pts
				(xy -0.9652 -1.778) (xy 0.9652 -1.778) (xy 0.9652 1.778) (xy -0.9652 1.778)
			)
			(stroke
				(width 0)
				(type default)
			)
			(fill no)
			(layer "F.Fab")
		)
		(pad "1" smd rect
			(at 0 -0.9652)
			(size 1.397 1.143)
			(layers "F.Cu" "F.Mask" "F.Paste")
			(net "P12V_HDD13")
		)
		(pad "2" smd rect
			(at 0 0.9652)
			(size 1.397 1.143)
			(layers "F.Cu" "F.Mask" "F.Paste")
			(net "GND")
		)
	)
	(footprint ""
		(layer "F.Cu")
		(at 271.19707 -8.936228 180)
		(property "Reference" "TP193"
			(at 0 0 180)
			(layer "F.SilkS")
			(hide yes)
			(effects
				(font
					(size 1.27 1.27)
				)
			)
		)
		(property "Value" "TPAD32-GP"
			(at -0.0508 -1.6764 180)
			(unlocked yes)
			(layer "F.Fab")
			(hide yes)
			(effects
				(font
					(size 1.016 1.016)
					(thickness 0.1524)
				)
			)
		)
		(property "Device Type" "TPAD32"
			(at -0.0508 -3.2004 180)
			(unlocked yes)
			(layer "F.Fab")
			(hide yes)
			(effects
				(font
					(size 1.016 1.016)
					(thickness 0.1524)
				)
			)
		)
		(duplicate_pad_numbers_are_jumpers no)
		(fp_poly
			(pts
				(arc
					(start -0.4064 0)
					(mid 0.4064 0)
					(end -0.4064 0)
				)
			)
			(stroke
				(width 0)
				(type default)
			)
			(fill no)
			(layer "F.CrtYd")
		)
		(fp_poly
			(pts
				(arc
					(start -0.7112 0)
					(mid 0.7112 0)
					(end -0.7112 0)
				)
			)
			(stroke
				(width 0)
				(type default)
			)
			(fill no)
			(layer "F.Fab")
		)
		(pad "1" smd circle
			(at 0 0 180)
			(size 0.8128 0.8128)
			(layers "F.Cu" "F.Mask" "F.Paste")
			(net "TP_COMP_B_NCSI_RXD0")
		)
	)
	(footprint ""
		(layer "F.Cu")
		(at 444.1952 -250.825 90)
		(property "Reference" "C632"
			(at 0 0 90)
			(layer "F.SilkS")
			(hide yes)
			(effects
				(font
					(size 1.27 1.27)
				)
			)
		)
		(property "Value" "SC10U16V5KX-7-GP-U"
			(at -0.0762 -6.1214 90)
			(unlocked yes)
			(layer "F.Fab")
			(hide yes)
			(effects
				(font
					(size 1.016 1.016)
					(thickness 0.1524)
				)
			)
		)
		(property "Device Type" "C805H58"
			(at -0.0762 -8.1534 90)
			(unlocked yes)
			(layer "F.Fab")
			(hide yes)
			(effects
				(font
					(size 1.016 1.016)
					(thickness 0.1524)
				)
			)
		)
		(duplicate_pad_numbers_are_jumpers no)
		(fp_line
			(start 0.635 0)
			(end -0.635 0)
			(stroke
				(width 0.508)
				(type default)
			)
			(layer "F.SilkS")
		)
		(fp_rect
			(start -0.9652 1.778)
			(end 0.9652 -1.778)
			(stroke
				(width 0)
				(type default)
			)
			(fill no)
			(layer "F.CrtYd")
		)
		(fp_poly
			(pts
				(xy -0.9652 -1.778) (xy 0.9652 -1.778) (xy 0.9652 1.778) (xy -0.9652 1.778)
			)
			(stroke
				(width 0)
				(type default)
			)
			(fill no)
			(layer "F.Fab")
		)
		(pad "1" smd rect
			(at 0 -0.9652 90)
			(size 1.397 1.143)
			(layers "F.Cu" "F.Mask" "F.Paste")
			(net "P12V_A_VIN_U22")
		)
		(pad "2" smd rect
			(at 0 0.9652 90)
			(size 1.397 1.143)
			(layers "F.Cu" "F.Mask" "F.Paste")
			(net "GND")
		)
	)
	(footprint ""
		(layer "F.Cu")
		(at 109.356652 -127.779272 180)
		(property "Reference" "Q242"
			(at 0 0 180)
			(layer "F.SilkS")
			(hide yes)
			(effects
				(font
					(size 1.27 1.27)
				)
			)
		)
		(property "Value" "2N7002K-2-GP"
			(at 0.127 -8.9662 180)
			(unlocked yes)
			(layer "F.Fab")
			(hide yes)
			(effects
				(font
					(size 1.016 1.016)
					(thickness 0.1524)
				)
			)
		)
		(property "Device Type" "SOT23DGS2D4H44"
			(at 0.127 -10.4902 180)
			(unlocked yes)
			(layer "F.Fab")
			(hide yes)
			(effects
				(font
					(size 1.016 1.016)
					(thickness 0.1524)
				)
			)
		)
		(duplicate_pad_numbers_are_jumpers no)
		(fp_line
			(start 1.651 1.778)
			(end 1.651 -1.778)
			(stroke
				(width 0.1524)
				(type default)
			)
			(layer "F.SilkS")
		)
		(fp_line
			(start 1.651 -1.778)
			(end -1.651 -1.778)
			(stroke
				(width 0.1524)
				(type default)
			)
			(layer "F.SilkS")
		)
		(fp_line
			(start -1.651 1.778)
			(end 1.651 1.778)
			(stroke
				(width 0.1524)
				(type default)
			)
			(layer "F.SilkS")
		)
		(fp_line
			(start -1.651 -1.778)
			(end -1.651 1.778)
			(stroke
				(width 0.1524)
				(type default)
			)
			(layer "F.SilkS")
		)
		(fp_poly
			(pts
				(xy -1.778 1.8796) (xy -1.778 -1.8796) (xy 1.778 -1.8796) (xy 1.778 1.8796)
			)
			(stroke
				(width 0)
				(type default)
			)
			(fill no)
			(layer "F.CrtYd")
		)
		(fp_poly
			(pts
				(xy -1.778 1.8796) (xy -1.778 -1.8796) (xy 1.778 -1.8796) (xy 1.778 1.8796)
			)
			(stroke
				(width 0)
				(type default)
			)
			(fill no)
			(layer "F.Fab")
		)
		(pad "D" smd custom
			(at 0 -0.9525 180)
			(size 0.1905 0.1905)
			(layers "F.Cu" "F.Mask" "F.Paste")
			(net "FLT_HDD15_N")
			(options
				(clearance outline)
				(anchor circle)
			)
			(primitives
				(gr_poly
					(pts
						(arc
							(start -0.1778 0.5715)
							(mid -0.321484 0.511984)
							(end -0.381 0.3683)
						)
						(arc
							(start -0.381 -0.3683)
							(mid -0.321484 -0.511984)
							(end -0.1778 -0.5715)
						)
						(arc
							(start 0.1778 -0.5715)
							(mid 0.321484 -0.511984)
							(end 0.381 -0.3683)
						)
						(arc
							(start 0.381 0.3683)
							(mid 0.321484 0.511984)
							(end 0.1778 0.5715)
						)
					)
					(width 0)
					(fill yes)
				)
			)
		)
		(pad "G" smd custom
			(at -0.98425 0.9525 180)
			(size 0.1905 0.1905)
			(layers "F.Cu" "F.Mask" "F.Paste")
			(net "DRIVE_A_15_FLT_LED")
			(options
				(clearance outline)
				(anchor circle)
			)
			(primitives
				(gr_poly
					(pts
						(arc
							(start -0.1778 0.5715)
							(mid -0.321484 0.511984)
							(end -0.381 0.3683)
						)
						(arc
							(start -0.381 -0.3683)
							(mid -0.321484 -0.511984)
							(end -0.1778 -0.5715)
						)
						(arc
							(start 0.1778 -0.5715)
							(mid 0.321484 -0.511984)
							(end 0.381 -0.3683)
						)
						(arc
							(start 0.381 0.3683)
							(mid 0.321484 0.511984)
							(end 0.1778 0.5715)
						)
					)
					(width 0)
					(fill yes)
				)
			)
		)
		(pad "S" smd custom
			(at 0.98425 0.9525 180)
			(size 0.1905 0.1905)
			(layers "F.Cu" "F.Mask" "F.Paste")
			(net "GND")
			(options
				(clearance outline)
				(anchor circle)
			)
			(primitives
				(gr_poly
					(pts
						(arc
							(start -0.1778 0.5715)
							(mid -0.321484 0.511984)
							(end -0.381 0.3683)
						)
						(arc
							(start -0.381 -0.3683)
							(mid -0.321484 -0.511984)
							(end -0.1778 -0.5715)
						)
						(arc
							(start 0.1778 -0.5715)
							(mid 0.321484 -0.511984)
							(end 0.381 -0.3683)
						)
						(arc
							(start 0.381 0.3683)
							(mid 0.321484 0.511984)
							(end 0.1778 0.5715)
						)
					)
					(width 0)
					(fill yes)
				)
			)
		)
	)
	(footprint ""
		(layer "F.Cu")
		(at 393.674854 -322.799964)
		(property "Reference" ""
			(at 0 0 0)
			(layer "F.SilkS")
			(hide yes)
			(effects
				(font
					(size 1.27 1.27)
				)
			)
		)
		(property "Value" "*"
			(at -8.398764 -8.057642 0)
			(unlocked yes)
			(layer "F.Fab")
			(hide yes)
			(effects
				(font
					(size 1.016 1.016)
					(thickness 0.1524)
				)
			)
		)
		(duplicate_pad_numbers_are_jumpers no)
		(fp_poly
			(pts
				(arc
					(start 7.3152 0)
					(mid 0 7.3152)
					(end -7.3152 0)
				)
				(arc
					(start -7.3152 -5.9944)
					(mid 0 -13.3096)
					(end 7.3152 -5.9944)
				)
			)
			(stroke
				(width 0)
				(type default)
			)
			(fill no)
			(layer "B.CrtYd")
		)
		(fp_poly
			(pts
				(arc
					(start 7.3152 0)
					(mid 0 7.3152)
					(end -7.3152 0)
				)
				(arc
					(start -7.3152 -5.9944)
					(mid 0 -13.3096)
					(end 7.3152 -5.9944)
				)
			)
			(stroke
				(width 0)
				(type default)
			)
			(fill no)
			(layer "F.CrtYd")
		)
		(fp_poly
			(pts
				(arc
					(start 7.3152 0)
					(mid 0 7.3152)
					(end -7.3152 0)
				)
				(arc
					(start -7.3152 -5.9944)
					(mid 0 -13.3096)
					(end 7.3152 -5.9944)
				)
			)
			(stroke
				(width 0)
				(type default)
			)
			(fill no)
			(layer "B.Fab")
		)
		(fp_poly
			(pts
				(arc
					(start 7.3152 0)
					(mid 0 7.3152)
					(end -7.3152 0)
				)
				(arc
					(start -7.3152 -5.9944)
					(mid 0 -13.3096)
					(end 7.3152 -5.9944)
				)
			)
			(stroke
				(width 0)
				(type default)
			)
			(fill no)
			(layer "F.Fab")
		)
		(pad "1" thru_hole oval
			(at 0 0)
			(size 14.0208 20.0152)
			(drill 0.0254
				(offset 0 -2.9972)
			)
			(layers "*.Cu" "*.Mask")
			(remove_unused_layers no)
			(net "Net_96")
			(clearance -1.002284)
			(thermal_gap 0.1524)
			(padstack
				(mode front_inner_back)
				(layer "Inner"
					(shape custom)
					(size 2.928012 2.928012)
					(options
						(anchor circle)
					)
					(primitives
						(gr_poly
							(pts
								(arc
									(start 4.571746 -2.084324)
									(mid 0.000333 7.430372)
									(end -4.571492 -2.084324)
								)
								(arc
									(start -4.571492 -2.084324)
									(mid -3.570296 -3.611977)
									(end -2.875026 -5.30098)
								)
								(arc
									(start -2.875026 -5.30098)
									(mid 0.000217 -7.43089)
									(end 2.87528 -5.30098)
								)
								(arc
									(start 2.87528 -5.30098)
									(mid 3.570511 -3.611956)
									(end 4.571746 -2.084324)
								)
							)
							(width 0)
							(fill yes)
						)
					)
					(clearance 0.1524)
				)
				(layer "B.Cu"
					(shape oval)
					(size 14.0208 20.0152)
					(offset 0 -2.9972)
					(clearance -1.002284)
				)
			)
		)
		(zone
			(layers "F.Cu" "B.Cu" "In1.Cu" "In2.Cu" "In3.Cu" "In4.Cu" "In5.Cu" "In6.Cu"
				"In7.Cu" "In8.Cu" "In9.Cu" "In10.Cu"
			)
			(hatch none 0.5)
			(connect_pads
				(clearance 0)
			)
			(min_thickness 0.25)
			(keepout
				(tracks not_allowed)
				(vias allowed)
				(pads allowed)
				(copperpour not_allowed)
				(footprints allowed)
			)
			(placement
				(enabled no)
				(sheetname "")
			)
			(fill
				(thermal_gap 0.5)
				(thermal_bridge_width 0.5)
				(island_removal_mode 0)
			)
			(polygon
				(pts
					(arc
						(start 386.664454 -328.794364)
						(mid 393.674854 -335.804764)
						(end 400.685254 -328.794364)
					)
					(arc
						(start 400.685254 -322.799964)
						(mid 393.674854 -315.789564)
						(end 386.664454 -322.799964)
					)
				)
			)
		)
	)
	(footprint ""
		(layer "F.Cu")
		(at 370.259102 -287.851342 90)
		(property "Reference" "C140"
			(at 0 0 90)
			(layer "F.SilkS")
			(hide yes)
			(effects
				(font
					(size 1.27 1.27)
				)
			)
		)
		(property "Value" "SCD033U25V2KX-GP"
			(at 1.1811 -2.7051 90)
			(unlocked yes)
			(layer "F.Fab")
			(hide yes)
			(effects
				(font
					(size 1.016 1.016)
					(thickness 0.1524)
				)
			)
		)
		(property "Device Type" "C402H22"
			(at 1.1811 -4.2291 90)
			(unlocked yes)
			(layer "F.Fab")
			(hide yes)
			(effects
				(font
					(size 1.016 1.016)
					(thickness 0.1524)
				)
			)
		)
		(duplicate_pad_numbers_are_jumpers no)
		(fp_rect
			(start -0.4318 0.9525)
			(end 0.4318 -0.9525)
			(stroke
				(width 0)
				(type default)
			)
			(fill no)
			(layer "F.CrtYd")
		)
		(fp_rect
			(start -0.4318 0.9525)
			(end 0.4318 -0.9525)
			(stroke
				(width 0)
				(type default)
			)
			(fill no)
			(layer "F.Fab")
		)
		(pad "1" smd custom
			(at 0 -0.4445 90)
			(size 0.1524 0.1524)
			(layers "F.Cu" "F.Mask" "F.Paste")
			(net "P12V_A")
			(options
				(clearance outline)
				(anchor circle)
			)
			(primitives
				(gr_poly
					(pts
						(arc
							(start 0.3048 -0.2032)
							(mid 0.275042 -0.275042)
							(end 0.2032 -0.3048)
						)
						(arc
							(start -0.2032 -0.3048)
							(mid -0.275042 -0.275042)
							(end -0.3048 -0.2032)
						)
						(arc
							(start -0.3048 0.2032)
							(mid -0.275042 0.275042)
							(end -0.2032 0.3048)
						)
						(arc
							(start 0.2032 0.3048)
							(mid 0.275042 0.275042)
							(end 0.3048 0.2032)
						)
					)
					(width 0)
					(fill yes)
				)
			)
		)
		(pad "2" smd custom
			(at 0 0.4445 90)
			(size 0.1524 0.1524)
			(layers "F.Cu" "F.Mask" "F.Paste")
			(net "SW_HDD_N7")
			(options
				(clearance outline)
				(anchor circle)
			)
			(primitives
				(gr_poly
					(pts
						(arc
							(start 0.3048 -0.2032)
							(mid 0.275042 -0.275042)
							(end 0.2032 -0.3048)
						)
						(arc
							(start -0.2032 -0.3048)
							(mid -0.275042 -0.275042)
							(end -0.3048 -0.2032)
						)
						(arc
							(start -0.3048 0.2032)
							(mid -0.275042 0.275042)
							(end -0.2032 0.3048)
						)
						(arc
							(start 0.2032 0.3048)
							(mid 0.275042 0.275042)
							(end 0.3048 0.2032)
						)
					)
					(width 0)
					(fill yes)
				)
			)
		)
	)
	(footprint ""
		(layer "F.Cu")
		(at 363.020102 -188.954918 180)
		(property "Reference" "C291"
			(at 0 0 180)
			(layer "F.SilkS")
			(hide yes)
			(effects
				(font
					(size 1.27 1.27)
				)
			)
		)
		(property "Value" "SC4D7U25V5KX-1-GP"
			(at -0.0762 -6.1214 180)
			(unlocked yes)
			(layer "F.Fab")
			(hide yes)
			(effects
				(font
					(size 1.016 1.016)
					(thickness 0.1524)
				)
			)
		)
		(property "Device Type" "C805H58"
			(at -0.0762 -8.1534 180)
			(unlocked yes)
			(layer "F.Fab")
			(hide yes)
			(effects
				(font
					(size 1.016 1.016)
					(thickness 0.1524)
				)
			)
		)
		(duplicate_pad_numbers_are_jumpers no)
		(fp_line
			(start 0.635 0)
			(end -0.635 0)
			(stroke
				(width 0.508)
				(type default)
			)
			(layer "F.SilkS")
		)
		(fp_rect
			(start -0.9652 1.778)
			(end 0.9652 -1.778)
			(stroke
				(width 0)
				(type default)
			)
			(fill no)
			(layer "F.CrtYd")
		)
		(fp_poly
			(pts
				(xy -0.9652 -1.778) (xy 0.9652 -1.778) (xy 0.9652 1.778) (xy -0.9652 1.778)
			)
			(stroke
				(width 0)
				(type default)
			)
			(fill no)
			(layer "F.Fab")
		)
		(pad "1" smd rect
			(at 0 -0.9652 180)
			(size 1.397 1.143)
			(layers "F.Cu" "F.Mask" "F.Paste")
			(net "P12V_HDD19")
		)
		(pad "2" smd rect
			(at 0 0.9652 180)
			(size 1.397 1.143)
			(layers "F.Cu" "F.Mask" "F.Paste")
			(net "GND")
		)
	)
	(footprint ""
		(layer "F.Cu")
		(at 253.603506 -261.324598 180)
		(property "Reference" "R59"
			(at 0 0 180)
			(layer "F.SilkS")
			(hide yes)
			(effects
				(font
					(size 1.27 1.27)
				)
			)
		)
		(property "Value" "0R2J-2-GP"
			(at 0.064008 -3.993896 180)
			(unlocked yes)
			(layer "F.Fab")
			(hide yes)
			(effects
				(font
					(size 1.016 1.016)
					(thickness 0.1524)
				)
			)
		)
		(property "Device Type" "R402H16"
			(at 0.064008 -5.517896 180)
			(unlocked yes)
			(layer "F.Fab")
			(hide yes)
			(effects
				(font
					(size 1.016 1.016)
					(thickness 0.1524)
				)
			)
		)
		(duplicate_pad_numbers_are_jumpers no)
		(fp_line
			(start 0.508 -0.9398)
			(end -0.508 -0.9398)
			(stroke
				(width 0.1524)
				(type default)
			)
			(layer "F.SilkS")
		)
		(fp_line
			(start -0.508 -0.9398)
			(end -0.508 0.9398)
			(stroke
				(width 0.1524)
				(type default)
			)
			(layer "F.SilkS")
		)
		(fp_rect
			(start -0.508 0.9398)
			(end 0.508 -0.9398)
			(stroke
				(width 0)
				(type default)
			)
			(fill no)
			(layer "F.CrtYd")
		)
		(fp_rect
			(start -0.508 0.9398)
			(end 0.508 -0.9398)
			(stroke
				(width 0)
				(type default)
			)
			(fill no)
			(layer "F.Fab")
		)
		(pad "1" smd custom
			(at 0 -0.4445 180)
			(size 0.1397 0.1397)
			(layers "F.Cu" "F.Mask" "F.Paste")
			(net "IO_EXP6_SDA")
			(options
				(clearance outline)
				(anchor circle)
			)
			(primitives
				(gr_poly
					(pts
						(arc
							(start -0.1778 -0.2794)
							(mid -0.249642 -0.249642)
							(end -0.2794 -0.1778)
						)
						(arc
							(start -0.2794 0.1778)
							(mid -0.249642 0.249642)
							(end -0.1778 0.2794)
						)
						(arc
							(start 0.1778 0.2794)
							(mid 0.249642 0.249642)
							(end 0.2794 0.1778)
						)
						(arc
							(start 0.2794 -0.1778)
							(mid 0.249642 -0.249642)
							(end 0.1778 -0.2794)
						)
					)
					(width 0)
					(fill yes)
				)
			)
		)
		(pad "2" smd custom
			(at 0 0.4445 180)
			(size 0.1397 0.1397)
			(layers "F.Cu" "F.Mask" "F.Paste")
			(net "I2C_DRIVE_A_INS_SDA")
			(options
				(clearance outline)
				(anchor circle)
			)
			(primitives
				(gr_poly
					(pts
						(arc
							(start -0.1778 -0.2794)
							(mid -0.249642 -0.249642)
							(end -0.2794 -0.1778)
						)
						(arc
							(start -0.2794 0.1778)
							(mid -0.249642 0.249642)
							(end -0.1778 0.2794)
						)
						(arc
							(start 0.1778 0.2794)
							(mid 0.249642 0.249642)
							(end 0.2794 0.1778)
						)
						(arc
							(start 0.2794 -0.1778)
							(mid 0.249642 -0.249642)
							(end 0.1778 -0.2794)
						)
					)
					(width 0)
					(fill yes)
				)
			)
		)
	)
	(footprint ""
		(layer "F.Cu")
		(at 210.898232 -9.492488 90)
		(property "Reference" "C42"
			(at 0 0 90)
			(layer "F.SilkS")
			(hide yes)
			(effects
				(font
					(size 1.27 1.27)
				)
			)
		)
		(property "Value" "SC1U16V3KX-5GP"
			(at 0 -2.8194 90)
			(unlocked yes)
			(layer "F.Fab")
			(hide yes)
			(effects
				(font
					(size 1.016 1.016)
					(thickness 0.1524)
				)
			)
		)
		(property "Device Type" "C603H36"
			(at 0 -4.3434 90)
			(unlocked yes)
			(layer "F.Fab")
			(hide yes)
			(effects
				(font
					(size 1.016 1.016)
					(thickness 0.1524)
				)
			)
		)
		(duplicate_pad_numbers_are_jumpers no)
		(fp_line
			(start 0.508 0)
			(end -0.508 0)
			(stroke
				(width 0.2032)
				(type default)
			)
			(layer "F.SilkS")
		)
		(fp_rect
			(start -0.5842 1.3335)
			(end 0.5842 -1.3335)
			(stroke
				(width 0)
				(type default)
			)
			(fill no)
			(layer "F.CrtYd")
		)
		(fp_rect
			(start -0.5842 1.3335)
			(end 0.5842 -1.3335)
			(stroke
				(width 0)
				(type default)
			)
			(fill no)
			(layer "F.Fab")
		)
		(pad "1" smd custom
			(at 0 -0.762 90)
			(size 0.2159 0.2159)
			(layers "F.Cu" "F.Mask" "F.Paste")
			(net "P5V_A_2")
			(options
				(clearance outline)
				(anchor circle)
			)
			(primitives
				(gr_poly
					(pts
						(arc
							(start -0.3302 -0.4318)
							(mid -0.402042 -0.402042)
							(end -0.4318 -0.3302)
						)
						(arc
							(start -0.4318 0.3302)
							(mid -0.402042 0.402042)
							(end -0.3302 0.4318)
						)
						(arc
							(start 0.3302 0.4318)
							(mid 0.402042 0.402042)
							(end 0.4318 0.3302)
						)
						(arc
							(start 0.4318 -0.3302)
							(mid 0.402042 -0.402042)
							(end 0.3302 -0.4318)
						)
					)
					(width 0)
					(fill yes)
				)
			)
		)
		(pad "2" smd custom
			(at 0 0.762 90)
			(size 0.2159 0.2159)
			(layers "F.Cu" "F.Mask" "F.Paste")
			(net "GND")
			(options
				(clearance outline)
				(anchor circle)
			)
			(primitives
				(gr_poly
					(pts
						(arc
							(start -0.3302 -0.4318)
							(mid -0.402042 -0.402042)
							(end -0.4318 -0.3302)
						)
						(arc
							(start -0.4318 0.3302)
							(mid -0.402042 0.402042)
							(end -0.3302 0.4318)
						)
						(arc
							(start 0.3302 0.4318)
							(mid 0.402042 0.402042)
							(end 0.4318 0.3302)
						)
						(arc
							(start 0.4318 -0.3302)
							(mid 0.402042 -0.402042)
							(end 0.3302 -0.4318)
						)
					)
					(width 0)
					(fill yes)
				)
			)
		)
	)
	(footprint ""
		(layer "F.Cu")
		(at 172.5422 -45.608494 90)
		(property "Reference" "R811"
			(at 0 0 90)
			(layer "F.SilkS")
			(hide yes)
			(effects
				(font
					(size 1.27 1.27)
				)
			)
		)
		(property "Value" "4K7R2J-2-GP"
			(at 0.064008 -3.993896 90)
			(unlocked yes)
			(layer "F.Fab")
			(hide yes)
			(effects
				(font
					(size 1.016 1.016)
					(thickness 0.1524)
				)
			)
		)
		(property "Device Type" "R402H16"
			(at 0.064008 -5.517896 90)
			(unlocked yes)
			(layer "F.Fab")
			(hide yes)
			(effects
				(font
					(size 1.016 1.016)
					(thickness 0.1524)
				)
			)
		)
		(duplicate_pad_numbers_are_jumpers no)
		(fp_line
			(start 0.508 -0.9398)
			(end -0.508 -0.9398)
			(stroke
				(width 0.1524)
				(type default)
			)
			(layer "F.SilkS")
		)
		(fp_line
			(start -0.508 -0.9398)
			(end -0.508 0.9398)
			(stroke
				(width 0.1524)
				(type default)
			)
			(layer "F.SilkS")
		)
		(fp_rect
			(start -0.508 0.9398)
			(end 0.508 -0.9398)
			(stroke
				(width 0)
				(type default)
			)
			(fill no)
			(layer "F.CrtYd")
		)
		(fp_rect
			(start -0.508 0.9398)
			(end 0.508 -0.9398)
			(stroke
				(width 0)
				(type default)
			)
			(fill no)
			(layer "F.Fab")
		)
		(pad "1" smd custom
			(at 0 -0.4445 90)
			(size 0.1397 0.1397)
			(layers "F.Cu" "F.Mask" "F.Paste")
			(net "P12V_A")
			(options
				(clearance outline)
				(anchor circle)
			)
			(primitives
				(gr_poly
					(pts
						(arc
							(start -0.1778 -0.2794)
							(mid -0.249642 -0.249642)
							(end -0.2794 -0.1778)
						)
						(arc
							(start -0.2794 0.1778)
							(mid -0.249642 0.249642)
							(end -0.1778 0.2794)
						)
						(arc
							(start 0.1778 0.2794)
							(mid 0.249642 0.249642)
							(end 0.2794 0.1778)
						)
						(arc
							(start 0.2794 -0.1778)
							(mid 0.249642 -0.249642)
							(end 0.1778 -0.2794)
						)
					)
					(width 0)
					(fill yes)
				)
			)
		)
		(pad "2" smd custom
			(at 0 0.4445 90)
			(size 0.1397 0.1397)
			(layers "F.Cu" "F.Mask" "F.Paste")
			(net "SW_HDD_R29")
			(options
				(clearance outline)
				(anchor circle)
			)
			(primitives
				(gr_poly
					(pts
						(arc
							(start -0.1778 -0.2794)
							(mid -0.249642 -0.249642)
							(end -0.2794 -0.1778)
						)
						(arc
							(start -0.2794 0.1778)
							(mid -0.249642 0.249642)
							(end -0.1778 0.2794)
						)
						(arc
							(start 0.1778 0.2794)
							(mid 0.249642 0.249642)
							(end 0.2794 0.1778)
						)
						(arc
							(start 0.2794 -0.1778)
							(mid 0.249642 -0.249642)
							(end 0.1778 -0.2794)
						)
					)
					(width 0)
					(fill yes)
				)
			)
		)
	)
	(footprint ""
		(layer "F.Cu")
		(at 412.912052 -177.169318 90)
		(property "Reference" "R613"
			(at 0 0 90)
			(layer "F.SilkS")
			(hide yes)
			(effects
				(font
					(size 1.27 1.27)
				)
			)
		)
		(property "Value" "10KR2F-2-GP"
			(at 0.064008 -3.993896 90)
			(unlocked yes)
			(layer "F.Fab")
			(hide yes)
			(effects
				(font
					(size 1.016 1.016)
					(thickness 0.1524)
				)
			)
		)
		(property "Device Type" "R402H16"
			(at 0.064008 -5.517896 90)
			(unlocked yes)
			(layer "F.Fab")
			(hide yes)
			(effects
				(font
					(size 1.016 1.016)
					(thickness 0.1524)
				)
			)
		)
		(duplicate_pad_numbers_are_jumpers no)
		(fp_line
			(start 0.508 -0.9398)
			(end -0.508 -0.9398)
			(stroke
				(width 0.1524)
				(type default)
			)
			(layer "F.SilkS")
		)
		(fp_line
			(start -0.508 -0.9398)
			(end -0.508 0.9398)
			(stroke
				(width 0.1524)
				(type default)
			)
			(layer "F.SilkS")
		)
		(fp_rect
			(start -0.508 0.9398)
			(end 0.508 -0.9398)
			(stroke
				(width 0)
				(type default)
			)
			(fill no)
			(layer "F.CrtYd")
		)
		(fp_rect
			(start -0.508 0.9398)
			(end 0.508 -0.9398)
			(stroke
				(width 0)
				(type default)
			)
			(fill no)
			(layer "F.Fab")
		)
		(pad "1" smd custom
			(at 0 -0.4445 90)
			(size 0.1397 0.1397)
			(layers "F.Cu" "F.Mask" "F.Paste")
			(net "P3V3_STBY_A")
			(options
				(clearance outline)
				(anchor circle)
			)
			(primitives
				(gr_poly
					(pts
						(arc
							(start -0.1778 -0.2794)
							(mid -0.249642 -0.249642)
							(end -0.2794 -0.1778)
						)
						(arc
							(start -0.2794 0.1778)
							(mid -0.249642 0.249642)
							(end -0.1778 0.2794)
						)
						(arc
							(start 0.1778 0.2794)
							(mid 0.249642 0.249642)
							(end 0.2794 0.1778)
						)
						(arc
							(start 0.2794 -0.1778)
							(mid 0.249642 -0.249642)
							(end 0.1778 -0.2794)
						)
					)
					(width 0)
					(fill yes)
				)
			)
		)
		(pad "2" smd custom
			(at 0 0.4445 90)
			(size 0.1397 0.1397)
			(layers "F.Cu" "F.Mask" "F.Paste")
			(net "HDD_PRSNT_21")
			(options
				(clearance outline)
				(anchor circle)
			)
			(primitives
				(gr_poly
					(pts
						(arc
							(start -0.1778 -0.2794)
							(mid -0.249642 -0.249642)
							(end -0.2794 -0.1778)
						)
						(arc
							(start -0.2794 0.1778)
							(mid -0.249642 0.249642)
							(end -0.1778 0.2794)
						)
						(arc
							(start 0.1778 0.2794)
							(mid 0.249642 0.249642)
							(end 0.2794 0.1778)
						)
						(arc
							(start 0.2794 -0.1778)
							(mid 0.249642 -0.249642)
							(end 0.1778 -0.2794)
						)
					)
					(width 0)
					(fill yes)
				)
			)
		)
	)
	(footprint ""
		(layer "F.Cu")
		(at 272.542 -352.305112 180)
		(property "Reference" "VIA41"
			(at 0 0 180)
			(layer "F.SilkS")
			(hide yes)
			(effects
				(font
					(size 1.27 1.27)
				)
			)
		)
		(property "Value" "100OHM-8L-1D6MM-L18L16-GP"
			(at -3.7211 -4.5085 180)
			(unlocked yes)
			(layer "F.Fab")
			(hide yes)
			(effects
				(font
					(size 1.016 1.016)
					(thickness 0.1524)
				)
			)
		)
		(property "Device Type" "VIA-PCIE-4P-394076"
			(at -3.7211 -6.0325 180)
			(unlocked yes)
			(layer "F.Fab")
			(hide yes)
			(effects
				(font
					(size 1.016 1.016)
					(thickness 0.1524)
				)
			)
		)
		(duplicate_pad_numbers_are_jumpers no)
		(fp_rect
			(start -1.9685 0.381)
			(end 1.9685 -0.381)
			(stroke
				(width 0)
				(type default)
			)
			(fill no)
			(layer "F.CrtYd")
		)
		(fp_rect
			(start -1.9685 0.381)
			(end 1.9685 -0.381)
			(stroke
				(width 0)
				(type default)
			)
			(fill no)
			(layer "F.Fab")
		)
		(pad "1" thru_hole circle
			(at -1.5875 0 180)
			(size 0.508 0.508)
			(drill 0.254)
			(layers "*.Cu" "*.Mask")
			(remove_unused_layers no)
			(net "GND")
			(clearance 0.127)
			(thermal_gap 0.127)
		)
		(pad "2" thru_hole circle
			(at -0.5715 0 180)
			(size 0.508 0.508)
			(drill 0.254)
			(layers "*.Cu" "*.Mask")
			(remove_unused_layers no)
			(net "PHY_SCC_A_TO_DRV_A_4_DP")
			(clearance 0.127)
			(thermal_gap 0.127)
		)
		(pad "3" thru_hole circle
			(at 0.5715 0 180)
			(size 0.508 0.508)
			(drill 0.254)
			(layers "*.Cu" "*.Mask")
			(remove_unused_layers no)
			(net "PHY_SCC_A_TO_DRV_A_4_DN")
			(clearance 0.127)
			(thermal_gap 0.127)
		)
		(pad "4" thru_hole circle
			(at 1.5875 0 180)
			(size 0.508 0.508)
			(drill 0.254)
			(layers "*.Cu" "*.Mask")
			(remove_unused_layers no)
			(net "GND")
			(clearance 0.127)
			(thermal_gap 0.127)
		)
	)
	(footprint ""
		(layer "F.Cu")
		(at 384.734562 -159.219392 -90)
		(property "Reference" "C298"
			(at 0 0 270)
			(layer "F.SilkS")
			(hide yes)
			(effects
				(font
					(size 1.27 1.27)
				)
			)
		)
		(property "Value" "SCD01U16V1KX-GP"
			(at -2.8321 -1.7399 270)
			(unlocked yes)
			(layer "F.Fab")
			(hide yes)
			(effects
				(font
					(size 1.016 1.016)
					(thickness 0.1524)
				)
			)
		)
		(property "Device Type" "C0201H13"
			(at -2.8321 -3.2639 270)
			(unlocked yes)
			(layer "F.Fab")
			(hide yes)
			(effects
				(font
					(size 1.016 1.016)
					(thickness 0.1524)
				)
			)
		)
		(duplicate_pad_numbers_are_jumpers no)
		(fp_rect
			(start -0.2794 0.6477)
			(end 0.2794 -0.6477)
			(stroke
				(width 0)
				(type default)
			)
			(fill no)
			(layer "F.CrtYd")
		)
		(fp_rect
			(start -0.2794 0.6477)
			(end 0.2794 -0.6477)
			(stroke
				(width 0)
				(type default)
			)
			(fill no)
			(layer "F.Fab")
		)
		(pad "1" smd custom
			(at 0 -0.2794 270)
			(size 0.0762 0.0762)
			(layers "F.Cu" "F.Mask" "F.Paste")
			(net "SAS_HDD_RX_N20")
			(options
				(clearance outline)
				(anchor circle)
			)
			(primitives
				(gr_poly
					(pts
						(arc
							(start 0.1524 -0.127)
							(mid 0.137521 -0.162921)
							(end 0.1016 -0.1778)
						)
						(arc
							(start -0.1016 -0.1778)
							(mid -0.137521 -0.162921)
							(end -0.1524 -0.127)
						)
						(arc
							(start -0.1524 0.127)
							(mid -0.137521 0.162921)
							(end -0.1016 0.1778)
						)
						(arc
							(start 0.1016 0.1778)
							(mid 0.137521 0.162921)
							(end 0.1524 0.127)
						)
					)
					(width 0)
					(fill yes)
				)
			)
		)
		(pad "2" smd custom
			(at 0 0.2794 270)
			(size 0.0762 0.0762)
			(layers "F.Cu" "F.Mask" "F.Paste")
			(net "PHY_SCC_A_TO_DRV_A_20_DN")
			(options
				(clearance outline)
				(anchor circle)
			)
			(primitives
				(gr_poly
					(pts
						(arc
							(start 0.1524 -0.127)
							(mid 0.137521 -0.162921)
							(end 0.1016 -0.1778)
						)
						(arc
							(start -0.1016 -0.1778)
							(mid -0.137521 -0.162921)
							(end -0.1524 -0.127)
						)
						(arc
							(start -0.1524 0.127)
							(mid -0.137521 0.162921)
							(end -0.1016 0.1778)
						)
						(arc
							(start 0.1016 0.1778)
							(mid 0.137521 0.162921)
							(end 0.1524 0.127)
						)
					)
					(width 0)
					(fill yes)
				)
			)
		)
	)
	(footprint ""
		(layer "F.Cu")
		(at 51.980846 -278.554942 180)
		(property "Reference" "Q7"
			(at 0 0 180)
			(layer "F.SilkS")
			(hide yes)
			(effects
				(font
					(size 1.27 1.27)
				)
			)
		)
		(property "Value" "2N7002KDW-GP"
			(at -2.3622 -8.2042 180)
			(unlocked yes)
			(layer "F.Fab")
			(hide yes)
			(effects
				(font
					(size 1.016 1.016)
					(thickness 0.1524)
				)
			)
		)
		(property "Device Type" "SOT-363H44"
			(at -2.3622 -10.1092 180)
			(unlocked yes)
			(layer "F.Fab")
			(hide yes)
			(effects
				(font
					(size 1.016 1.016)
					(thickness 0.1524)
				)
			)
		)
		(duplicate_pad_numbers_are_jumpers no)
		(fp_line
			(start 1.4478 1.7018)
			(end 1.4478 -1.7018)
			(stroke
				(width 0.1524)
				(type default)
			)
			(layer "F.SilkS")
		)
		(fp_line
			(start 1.4478 -1.7018)
			(end -1.4478 -1.7018)
			(stroke
				(width 0.1524)
				(type default)
			)
			(layer "F.SilkS")
		)
		(fp_line
			(start -1.27 1.524)
			(end -1.27 0.6604)
			(stroke
				(width 0.4826)
				(type default)
			)
			(layer "F.SilkS")
		)
		(fp_line
			(start -1.4478 1.7018)
			(end 1.4478 1.7018)
			(stroke
				(width 0.1524)
				(type default)
			)
			(layer "F.SilkS")
		)
		(fp_line
			(start -1.4478 -1.7018)
			(end -1.4478 1.7018)
			(stroke
				(width 0.1524)
				(type default)
			)
			(layer "F.SilkS")
		)
		(fp_poly
			(pts
				(xy -1.524 -1.778) (xy 1.524 -1.778) (xy 1.524 1.778) (xy -1.524 1.778)
			)
			(stroke
				(width 0)
				(type default)
			)
			(fill no)
			(layer "F.CrtYd")
		)
		(fp_poly
			(pts
				(xy -1.524 -1.778) (xy 1.524 -1.778) (xy 1.524 1.778) (xy -1.524 1.778)
			)
			(stroke
				(width 0)
				(type default)
			)
			(fill no)
			(layer "F.Fab")
		)
		(pad "1" smd rect
			(at -0.65024 0.9398 180)
			(size 0.4064 1.016)
			(layers "F.Cu" "F.Mask" "F.Paste")
			(net "GND")
		)
		(pad "2" smd rect
			(at 0 0.9398 180)
			(size 0.4064 1.016)
			(layers "F.Cu" "F.Mask" "F.Paste")
			(net "SW_PWR_R_HDD1")
		)
		(pad "3" smd rect
			(at 0.65024 0.9398 180)
			(size 0.4064 1.016)
			(layers "F.Cu" "F.Mask" "F.Paste")
			(net "SW_HDD_P1")
		)
		(pad "4" smd rect
			(at 0.65024 -0.9398 180)
			(size 0.4064 1.016)
			(layers "F.Cu" "F.Mask" "F.Paste")
			(net "GND")
		)
		(pad "5" smd rect
			(at 0 -0.9398 180)
			(size 0.4064 1.016)
			(layers "F.Cu" "F.Mask" "F.Paste")
			(net "SW_HDD_G1")
		)
		(pad "6" smd rect
			(at -0.65024 -0.9398 180)
			(size 0.4064 1.016)
			(layers "F.Cu" "F.Mask" "F.Paste")
			(net "SW_HDD_R1")
		)
	)
	(footprint ""
		(layer "F.Cu")
		(at 272.542 -337.90509 180)
		(property "Reference" "VIA45"
			(at 0 0 180)
			(layer "F.SilkS")
			(hide yes)
			(effects
				(font
					(size 1.27 1.27)
				)
			)
		)
		(property "Value" "100OHM-8L-1D6MM-L18L16-GP"
			(at -3.7211 -4.5085 180)
			(unlocked yes)
			(layer "F.Fab")
			(hide yes)
			(effects
				(font
					(size 1.016 1.016)
					(thickness 0.1524)
				)
			)
		)
		(property "Device Type" "VIA-PCIE-4P-394076"
			(at -3.7211 -6.0325 180)
			(unlocked yes)
			(layer "F.Fab")
			(hide yes)
			(effects
				(font
					(size 1.016 1.016)
					(thickness 0.1524)
				)
			)
		)
		(duplicate_pad_numbers_are_jumpers no)
		(fp_rect
			(start -1.9685 0.381)
			(end 1.9685 -0.381)
			(stroke
				(width 0)
				(type default)
			)
			(fill no)
			(layer "F.CrtYd")
		)
		(fp_rect
			(start -1.9685 0.381)
			(end 1.9685 -0.381)
			(stroke
				(width 0)
				(type default)
			)
			(fill no)
			(layer "F.Fab")
		)
		(pad "1" thru_hole circle
			(at -1.5875 0 180)
			(size 0.508 0.508)
			(drill 0.254)
			(layers "*.Cu" "*.Mask")
			(remove_unused_layers no)
			(net "GND")
			(clearance 0.127)
			(thermal_gap 0.127)
		)
		(pad "2" thru_hole circle
			(at -0.5715 0 180)
			(size 0.508 0.508)
			(drill 0.254)
			(layers "*.Cu" "*.Mask")
			(remove_unused_layers no)
			(net "PHY_SCC_A_TO_DRV_A_12_DP")
			(clearance 0.127)
			(thermal_gap 0.127)
		)
		(pad "3" thru_hole circle
			(at 0.5715 0 180)
			(size 0.508 0.508)
			(drill 0.254)
			(layers "*.Cu" "*.Mask")
			(remove_unused_layers no)
			(net "PHY_SCC_A_TO_DRV_A_12_DN")
			(clearance 0.127)
			(thermal_gap 0.127)
		)
		(pad "4" thru_hole circle
			(at 1.5875 0 180)
			(size 0.508 0.508)
			(drill 0.254)
			(layers "*.Cu" "*.Mask")
			(remove_unused_layers no)
			(net "GND")
			(clearance 0.127)
			(thermal_gap 0.127)
		)
	)
	(footprint ""
		(layer "F.Cu")
		(at 456.048872 -189.380876 180)
		(property "Reference" "C333"
			(at 0 0 180)
			(layer "F.SilkS")
			(hide yes)
			(effects
				(font
					(size 1.27 1.27)
				)
			)
		)
		(property "Value" "SC1U25V3KX-GP"
			(at 0 -2.8194 180)
			(unlocked yes)
			(layer "F.Fab")
			(hide yes)
			(effects
				(font
					(size 1.016 1.016)
					(thickness 0.1524)
				)
			)
		)
		(property "Device Type" "C603H36"
			(at 0 -4.3434 180)
			(unlocked yes)
			(layer "F.Fab")
			(hide yes)
			(effects
				(font
					(size 1.016 1.016)
					(thickness 0.1524)
				)
			)
		)
		(duplicate_pad_numbers_are_jumpers no)
		(fp_line
			(start 0.508 0)
			(end -0.508 0)
			(stroke
				(width 0.2032)
				(type default)
			)
			(layer "F.SilkS")
		)
		(fp_rect
			(start -0.5842 1.3335)
			(end 0.5842 -1.3335)
			(stroke
				(width 0)
				(type default)
			)
			(fill no)
			(layer "F.CrtYd")
		)
		(fp_rect
			(start -0.5842 1.3335)
			(end 0.5842 -1.3335)
			(stroke
				(width 0)
				(type default)
			)
			(fill no)
			(layer "F.Fab")
		)
		(pad "1" smd custom
			(at 0 -0.762 180)
			(size 0.2159 0.2159)
			(layers "F.Cu" "F.Mask" "F.Paste")
			(net "P12V_HDD22")
			(options
				(clearance outline)
				(anchor circle)
			)
			(primitives
				(gr_poly
					(pts
						(arc
							(start -0.3302 -0.4318)
							(mid -0.402042 -0.402042)
							(end -0.4318 -0.3302)
						)
						(arc
							(start -0.4318 0.3302)
							(mid -0.402042 0.402042)
							(end -0.3302 0.4318)
						)
						(arc
							(start 0.3302 0.4318)
							(mid 0.402042 0.402042)
							(end 0.4318 0.3302)
						)
						(arc
							(start 0.4318 -0.3302)
							(mid 0.402042 -0.402042)
							(end 0.3302 -0.4318)
						)
					)
					(width 0)
					(fill yes)
				)
			)
		)
		(pad "2" smd custom
			(at 0 0.762 180)
			(size 0.2159 0.2159)
			(layers "F.Cu" "F.Mask" "F.Paste")
			(net "GND")
			(options
				(clearance outline)
				(anchor circle)
			)
			(primitives
				(gr_poly
					(pts
						(arc
							(start -0.3302 -0.4318)
							(mid -0.402042 -0.402042)
							(end -0.4318 -0.3302)
						)
						(arc
							(start -0.4318 0.3302)
							(mid -0.402042 0.402042)
							(end -0.3302 0.4318)
						)
						(arc
							(start 0.3302 0.4318)
							(mid 0.402042 0.402042)
							(end 0.4318 0.3302)
						)
						(arc
							(start 0.4318 -0.3302)
							(mid 0.402042 -0.402042)
							(end 0.3302 -0.4318)
						)
					)
					(width 0)
					(fill yes)
				)
			)
		)
	)
	(footprint ""
		(layer "F.Cu")
		(at 117.2718 -294.6908 90)
		(property "Reference" "R202"
			(at 0 0 90)
			(layer "F.SilkS")
			(hide yes)
			(effects
				(font
					(size 1.27 1.27)
				)
			)
		)
		(property "Value" "2R6F-GP"
			(at -0.0508 -4.8514 90)
			(unlocked yes)
			(layer "F.Fab")
			(hide yes)
			(effects
				(font
					(size 1.016 1.016)
					(thickness 0.1524)
				)
			)
		)
		(property "Device Type" "R1206H26"
			(at 0 -6.3754 90)
			(unlocked yes)
			(layer "F.Fab")
			(hide yes)
			(effects
				(font
					(size 1.016 1.016)
					(thickness 0.1524)
				)
			)
		)
		(duplicate_pad_numbers_are_jumpers no)
		(fp_line
			(start 1.016 -2.2352)
			(end 1.016 2.2352)
			(stroke
				(width 0.1524)
				(type default)
			)
			(layer "F.SilkS")
		)
		(fp_line
			(start -1.016 -2.2352)
			(end 1.016 -2.2352)
			(stroke
				(width 0.1524)
				(type default)
			)
			(layer "F.SilkS")
		)
		(fp_line
			(start 1.016 2.2352)
			(end -1.016 2.2352)
			(stroke
				(width 0.1524)
				(type default)
			)
			(layer "F.SilkS")
		)
		(fp_line
			(start -1.016 2.2352)
			(end -1.016 -2.2352)
			(stroke
				(width 0.1524)
				(type default)
			)
			(layer "F.SilkS")
		)
		(fp_rect
			(start -1.0922 2.3114)
			(end 1.0922 -2.3114)
			(stroke
				(width 0)
				(type default)
			)
			(fill no)
			(layer "F.CrtYd")
		)
		(fp_poly
			(pts
				(xy -1.0922 -2.3114) (xy 1.0922 -2.3114) (xy 1.0922 2.3114) (xy -1.0922 2.3114)
			)
			(stroke
				(width 0)
				(type default)
			)
			(fill no)
			(layer "F.Fab")
		)
		(pad "1" smd rect
			(at 0 -1.397 90)
			(size 1.651 1.27)
			(layers "F.Cu" "F.Mask" "F.Paste")
			(net "P12V_HDD3")
		)
		(pad "2" smd rect
			(at 0 1.397 90)
			(size 1.651 1.27)
			(layers "F.Cu" "F.Mask" "F.Paste")
			(net "12V_PRE_3")
		)
	)
	(footprint ""
		(layer "F.Cu")
		(at 329.819 -66.842894 180)
		(property "Reference" "C430"
			(at 0 0 180)
			(layer "F.SilkS")
			(hide yes)
			(effects
				(font
					(size 1.27 1.27)
				)
			)
		)
		(property "Value" "SC1U16V3KX-5GP"
			(at 0 -2.8194 180)
			(unlocked yes)
			(layer "F.Fab")
			(hide yes)
			(effects
				(font
					(size 1.016 1.016)
					(thickness 0.1524)
				)
			)
		)
		(property "Device Type" "C603H36"
			(at 0 -4.3434 180)
			(unlocked yes)
			(layer "F.Fab")
			(hide yes)
			(effects
				(font
					(size 1.016 1.016)
					(thickness 0.1524)
				)
			)
		)
		(duplicate_pad_numbers_are_jumpers no)
		(fp_line
			(start 0.508 0)
			(end -0.508 0)
			(stroke
				(width 0.2032)
				(type default)
			)
			(layer "F.SilkS")
		)
		(fp_rect
			(start -0.5842 1.3335)
			(end 0.5842 -1.3335)
			(stroke
				(width 0)
				(type default)
			)
			(fill no)
			(layer "F.CrtYd")
		)
		(fp_rect
			(start -0.5842 1.3335)
			(end 0.5842 -1.3335)
			(stroke
				(width 0)
				(type default)
			)
			(fill no)
			(layer "F.Fab")
		)
		(pad "1" smd custom
			(at 0 -0.762 180)
			(size 0.2159 0.2159)
			(layers "F.Cu" "F.Mask" "F.Paste")
			(net "P5V_HDD30")
			(options
				(clearance outline)
				(anchor circle)
			)
			(primitives
				(gr_poly
					(pts
						(arc
							(start -0.3302 -0.4318)
							(mid -0.402042 -0.402042)
							(end -0.4318 -0.3302)
						)
						(arc
							(start -0.4318 0.3302)
							(mid -0.402042 0.402042)
							(end -0.3302 0.4318)
						)
						(arc
							(start 0.3302 0.4318)
							(mid 0.402042 0.402042)
							(end 0.4318 0.3302)
						)
						(arc
							(start 0.4318 -0.3302)
							(mid 0.402042 -0.402042)
							(end 0.3302 -0.4318)
						)
					)
					(width 0)
					(fill yes)
				)
			)
		)
		(pad "2" smd custom
			(at 0 0.762 180)
			(size 0.2159 0.2159)
			(layers "F.Cu" "F.Mask" "F.Paste")
			(net "GND")
			(options
				(clearance outline)
				(anchor circle)
			)
			(primitives
				(gr_poly
					(pts
						(arc
							(start -0.3302 -0.4318)
							(mid -0.402042 -0.402042)
							(end -0.4318 -0.3302)
						)
						(arc
							(start -0.4318 0.3302)
							(mid -0.402042 0.402042)
							(end -0.3302 0.4318)
						)
						(arc
							(start 0.3302 0.4318)
							(mid 0.402042 0.402042)
							(end 0.4318 0.3302)
						)
						(arc
							(start 0.4318 -0.3302)
							(mid 0.402042 -0.402042)
							(end 0.3302 -0.4318)
						)
					)
					(width 0)
					(fill yes)
				)
			)
		)
	)
	(footprint ""
		(layer "F.Cu")
		(at 254.557276 -248.87936 180)
		(property "Reference" "R61"
			(at 0 0 180)
			(layer "F.SilkS")
			(hide yes)
			(effects
				(font
					(size 1.27 1.27)
				)
			)
		)
		(property "Value" "4K7R2F-GP"
			(at 0.064008 -3.993896 180)
			(unlocked yes)
			(layer "F.Fab")
			(hide yes)
			(effects
				(font
					(size 1.016 1.016)
					(thickness 0.1524)
				)
			)
		)
		(property "Device Type" "R402H16"
			(at 0.064008 -5.517896 180)
			(unlocked yes)
			(layer "F.Fab")
			(hide yes)
			(effects
				(font
					(size 1.016 1.016)
					(thickness 0.1524)
				)
			)
		)
		(duplicate_pad_numbers_are_jumpers no)
		(fp_line
			(start 0.508 -0.9398)
			(end -0.508 -0.9398)
			(stroke
				(width 0.1524)
				(type default)
			)
			(layer "F.SilkS")
		)
		(fp_line
			(start -0.508 -0.9398)
			(end -0.508 0.9398)
			(stroke
				(width 0.1524)
				(type default)
			)
			(layer "F.SilkS")
		)
		(fp_rect
			(start -0.508 0.9398)
			(end 0.508 -0.9398)
			(stroke
				(width 0)
				(type default)
			)
			(fill no)
			(layer "F.CrtYd")
		)
		(fp_rect
			(start -0.508 0.9398)
			(end 0.508 -0.9398)
			(stroke
				(width 0)
				(type default)
			)
			(fill no)
			(layer "F.Fab")
		)
		(pad "1" smd custom
			(at 0 -0.4445 180)
			(size 0.1397 0.1397)
			(layers "F.Cu" "F.Mask" "F.Paste")
			(net "P3V3_STBY_A")
			(options
				(clearance outline)
				(anchor circle)
			)
			(primitives
				(gr_poly
					(pts
						(arc
							(start -0.1778 -0.2794)
							(mid -0.249642 -0.249642)
							(end -0.2794 -0.1778)
						)
						(arc
							(start -0.2794 0.1778)
							(mid -0.249642 0.249642)
							(end -0.1778 0.2794)
						)
						(arc
							(start 0.1778 0.2794)
							(mid 0.249642 0.249642)
							(end 0.2794 0.1778)
						)
						(arc
							(start 0.2794 -0.1778)
							(mid 0.249642 -0.249642)
							(end 0.1778 -0.2794)
						)
					)
					(width 0)
					(fill yes)
				)
			)
		)
		(pad "2" smd custom
			(at 0 0.4445 180)
			(size 0.1397 0.1397)
			(layers "F.Cu" "F.Mask" "F.Paste")
			(net "IO_EXP6_A1")
			(options
				(clearance outline)
				(anchor circle)
			)
			(primitives
				(gr_poly
					(pts
						(arc
							(start -0.1778 -0.2794)
							(mid -0.249642 -0.249642)
							(end -0.2794 -0.1778)
						)
						(arc
							(start -0.2794 0.1778)
							(mid -0.249642 0.249642)
							(end -0.1778 0.2794)
						)
						(arc
							(start 0.1778 0.2794)
							(mid 0.249642 0.249642)
							(end 0.2794 0.1778)
						)
						(arc
							(start 0.2794 -0.1778)
							(mid 0.249642 -0.249642)
							(end 0.1778 -0.2794)
						)
					)
					(width 0)
					(fill yes)
				)
			)
		)
	)
	(footprint ""
		(layer "F.Cu")
		(at 133.852158 -130.271012 -90)
		(property "Reference" "R519"
			(at 0 0 270)
			(layer "F.SilkS")
			(hide yes)
			(effects
				(font
					(size 1.27 1.27)
				)
			)
		)
		(property "Value" "4K7R2J-2-GP"
			(at 0.064008 -3.993896 270)
			(unlocked yes)
			(layer "F.Fab")
			(hide yes)
			(effects
				(font
					(size 1.016 1.016)
					(thickness 0.1524)
				)
			)
		)
		(property "Device Type" "R402H16"
			(at 0.064008 -5.517896 270)
			(unlocked yes)
			(layer "F.Fab")
			(hide yes)
			(effects
				(font
					(size 1.016 1.016)
					(thickness 0.1524)
				)
			)
		)
		(duplicate_pad_numbers_are_jumpers no)
		(fp_line
			(start -0.508 -0.9398)
			(end -0.508 0.9398)
			(stroke
				(width 0.1524)
				(type default)
			)
			(layer "F.SilkS")
		)
		(fp_line
			(start 0.508 -0.9398)
			(end -0.508 -0.9398)
			(stroke
				(width 0.1524)
				(type default)
			)
			(layer "F.SilkS")
		)
		(fp_rect
			(start -0.508 0.9398)
			(end 0.508 -0.9398)
			(stroke
				(width 0)
				(type default)
			)
			(fill no)
			(layer "F.CrtYd")
		)
		(fp_rect
			(start -0.508 0.9398)
			(end 0.508 -0.9398)
			(stroke
				(width 0)
				(type default)
			)
			(fill no)
			(layer "F.Fab")
		)
		(pad "1" smd custom
			(at 0 -0.4445 270)
			(size 0.1397 0.1397)
			(layers "F.Cu" "F.Mask" "F.Paste")
			(net "DRIVE_A_16_FLT_LED")
			(options
				(clearance outline)
				(anchor circle)
			)
			(primitives
				(gr_poly
					(pts
						(arc
							(start -0.1778 -0.2794)
							(mid -0.249642 -0.249642)
							(end -0.2794 -0.1778)
						)
						(arc
							(start -0.2794 0.1778)
							(mid -0.249642 0.249642)
							(end -0.1778 0.2794)
						)
						(arc
							(start 0.1778 0.2794)
							(mid 0.249642 0.249642)
							(end 0.2794 0.1778)
						)
						(arc
							(start 0.2794 -0.1778)
							(mid 0.249642 -0.249642)
							(end 0.1778 -0.2794)
						)
					)
					(width 0)
					(fill yes)
				)
			)
		)
		(pad "2" smd custom
			(at 0 0.4445 270)
			(size 0.1397 0.1397)
			(layers "F.Cu" "F.Mask" "F.Paste")
			(net "GND")
			(options
				(clearance outline)
				(anchor circle)
			)
			(primitives
				(gr_poly
					(pts
						(arc
							(start -0.1778 -0.2794)
							(mid -0.249642 -0.249642)
							(end -0.2794 -0.1778)
						)
						(arc
							(start -0.2794 0.1778)
							(mid -0.249642 0.249642)
							(end -0.1778 0.2794)
						)
						(arc
							(start 0.1778 0.2794)
							(mid 0.249642 0.249642)
							(end 0.2794 0.1778)
						)
						(arc
							(start 0.2794 -0.1778)
							(mid 0.249642 -0.249642)
							(end 0.1778 -0.2794)
						)
					)
					(width 0)
					(fill yes)
				)
			)
		)
	)
	(footprint ""
		(layer "F.Cu")
		(at 259.969 -272.288)
		(property "Reference" "R104"
			(at 0 0 0)
			(layer "F.SilkS")
			(hide yes)
			(effects
				(font
					(size 1.27 1.27)
				)
			)
		)
		(property "Value" "4K7R2F-GP"
			(at 0.064008 -3.993896 0)
			(unlocked yes)
			(layer "F.Fab")
			(hide yes)
			(effects
				(font
					(size 1.016 1.016)
					(thickness 0.1524)
				)
			)
		)
		(property "Device Type" "R402H16"
			(at 0.064008 -5.517896 0)
			(unlocked yes)
			(layer "F.Fab")
			(hide yes)
			(effects
				(font
					(size 1.016 1.016)
					(thickness 0.1524)
				)
			)
		)
		(duplicate_pad_numbers_are_jumpers no)
		(fp_line
			(start -0.508 -0.9398)
			(end -0.508 0.9398)
			(stroke
				(width 0.1524)
				(type default)
			)
			(layer "F.SilkS")
		)
		(fp_line
			(start 0.508 -0.9398)
			(end -0.508 -0.9398)
			(stroke
				(width 0.1524)
				(type default)
			)
			(layer "F.SilkS")
		)
		(fp_rect
			(start -0.508 0.9398)
			(end 0.508 -0.9398)
			(stroke
				(width 0)
				(type default)
			)
			(fill no)
			(layer "F.CrtYd")
		)
		(fp_rect
			(start -0.508 0.9398)
			(end 0.508 -0.9398)
			(stroke
				(width 0)
				(type default)
			)
			(fill no)
			(layer "F.Fab")
		)
		(pad "1" smd custom
			(at 0 -0.4445)
			(size 0.1397 0.1397)
			(layers "F.Cu" "F.Mask" "F.Paste")
			(net "IO_EXP0_INT_N")
			(options
				(clearance outline)
				(anchor circle)
			)
			(primitives
				(gr_poly
					(pts
						(arc
							(start -0.1778 -0.2794)
							(mid -0.249642 -0.249642)
							(end -0.2794 -0.1778)
						)
						(arc
							(start -0.2794 0.1778)
							(mid -0.249642 0.249642)
							(end -0.1778 0.2794)
						)
						(arc
							(start 0.1778 0.2794)
							(mid 0.249642 0.249642)
							(end 0.2794 0.1778)
						)
						(arc
							(start 0.2794 -0.1778)
							(mid 0.249642 -0.249642)
							(end 0.1778 -0.2794)
						)
					)
					(width 0)
					(fill yes)
				)
			)
		)
		(pad "2" smd custom
			(at 0 0.4445)
			(size 0.1397 0.1397)
			(layers "F.Cu" "F.Mask" "F.Paste")
			(net "P3V3_STBY_A")
			(options
				(clearance outline)
				(anchor circle)
			)
			(primitives
				(gr_poly
					(pts
						(arc
							(start -0.1778 -0.2794)
							(mid -0.249642 -0.249642)
							(end -0.2794 -0.1778)
						)
						(arc
							(start -0.2794 0.1778)
							(mid -0.249642 0.249642)
							(end -0.1778 0.2794)
						)
						(arc
							(start 0.1778 0.2794)
							(mid 0.249642 0.249642)
							(end 0.2794 0.1778)
						)
						(arc
							(start 0.2794 -0.1778)
							(mid 0.249642 -0.249642)
							(end 0.1778 -0.2794)
						)
					)
					(width 0)
					(fill yes)
				)
			)
		)
	)
	(footprint ""
		(layer "F.Cu")
		(at 335.7626 -45.735494 180)
		(property "Reference" "R837"
			(at 0 0 180)
			(layer "F.SilkS")
			(hide yes)
			(effects
				(font
					(size 1.27 1.27)
				)
			)
		)
		(property "Value" "0R2J-2-GP"
			(at 0.064008 -3.993896 180)
			(unlocked yes)
			(layer "F.Fab")
			(hide yes)
			(effects
				(font
					(size 1.016 1.016)
					(thickness 0.1524)
				)
			)
		)
		(property "Device Type" "R402H16"
			(at 0.064008 -5.517896 180)
			(unlocked yes)
			(layer "F.Fab")
			(hide yes)
			(effects
				(font
					(size 1.016 1.016)
					(thickness 0.1524)
				)
			)
		)
		(duplicate_pad_numbers_are_jumpers no)
		(fp_line
			(start 0.508 -0.9398)
			(end -0.508 -0.9398)
			(stroke
				(width 0.1524)
				(type default)
			)
			(layer "F.SilkS")
		)
		(fp_line
			(start -0.508 -0.9398)
			(end -0.508 0.9398)
			(stroke
				(width 0.1524)
				(type default)
			)
			(layer "F.SilkS")
		)
		(fp_rect
			(start -0.508 0.9398)
			(end 0.508 -0.9398)
			(stroke
				(width 0)
				(type default)
			)
			(fill no)
			(layer "F.CrtYd")
		)
		(fp_rect
			(start -0.508 0.9398)
			(end 0.508 -0.9398)
			(stroke
				(width 0)
				(type default)
			)
			(fill no)
			(layer "F.Fab")
		)
		(pad "1" smd custom
			(at 0 -0.4445 180)
			(size 0.1397 0.1397)
			(layers "F.Cu" "F.Mask" "F.Paste")
			(net "SW_HDD_G30")
			(options
				(clearance outline)
				(anchor circle)
			)
			(primitives
				(gr_poly
					(pts
						(arc
							(start -0.1778 -0.2794)
							(mid -0.249642 -0.249642)
							(end -0.2794 -0.1778)
						)
						(arc
							(start -0.2794 0.1778)
							(mid -0.249642 0.249642)
							(end -0.1778 0.2794)
						)
						(arc
							(start 0.1778 0.2794)
							(mid 0.249642 0.249642)
							(end 0.2794 0.1778)
						)
						(arc
							(start 0.2794 -0.1778)
							(mid 0.249642 -0.249642)
							(end 0.1778 -0.2794)
						)
					)
					(width 0)
					(fill yes)
				)
			)
		)
		(pad "2" smd custom
			(at 0 0.4445 180)
			(size 0.1397 0.1397)
			(layers "F.Cu" "F.Mask" "F.Paste")
			(net "SW_HDD_R30")
			(options
				(clearance outline)
				(anchor circle)
			)
			(primitives
				(gr_poly
					(pts
						(arc
							(start -0.1778 -0.2794)
							(mid -0.249642 -0.249642)
							(end -0.2794 -0.1778)
						)
						(arc
							(start -0.2794 0.1778)
							(mid -0.249642 0.249642)
							(end -0.1778 0.2794)
						)
						(arc
							(start 0.1778 0.2794)
							(mid 0.249642 0.249642)
							(end 0.2794 0.1778)
						)
						(arc
							(start 0.2794 -0.1778)
							(mid 0.249642 -0.249642)
							(end 0.1778 -0.2794)
						)
					)
					(width 0)
					(fill yes)
				)
			)
		)
	)
	(footprint ""
		(layer "F.Cu")
		(at 54.295802 -150.67915)
		(property "Reference" "TP257"
			(at 0 0 0)
			(layer "F.SilkS")
			(hide yes)
			(effects
				(font
					(size 1.27 1.27)
				)
			)
		)
		(property "Value" "TPAD32-GP"
			(at -0.0508 -1.6764 0)
			(unlocked yes)
			(layer "F.Fab")
			(hide yes)
			(effects
				(font
					(size 1.016 1.016)
					(thickness 0.1524)
				)
			)
		)
		(property "Device Type" "TPAD32"
			(at -0.0508 -3.2004 0)
			(unlocked yes)
			(layer "F.Fab")
			(hide yes)
			(effects
				(font
					(size 1.016 1.016)
					(thickness 0.1524)
				)
			)
		)
		(duplicate_pad_numbers_are_jumpers no)
		(fp_poly
			(pts
				(arc
					(start 0.4064 0)
					(mid -0.4064 0)
					(end 0.4064 0)
				)
			)
			(stroke
				(width 0)
				(type default)
			)
			(fill no)
			(layer "F.CrtYd")
		)
		(fp_poly
			(pts
				(arc
					(start 0.7112 0)
					(mid -0.7112 0)
					(end 0.7112 0)
				)
			)
			(stroke
				(width 0)
				(type default)
			)
			(fill no)
			(layer "F.Fab")
		)
		(pad "1" smd circle
			(at 0 0)
			(size 0.8128 0.8128)
			(layers "F.Cu" "F.Mask" "F.Paste")
			(net "P5V_A_2_PGOOD")
		)
	)
	(footprint ""
		(layer "F.Cu")
		(at 48.374046 -53.101494 -90)
		(property "Reference" "C373"
			(at 0 0 270)
			(layer "F.SilkS")
			(hide yes)
			(effects
				(font
					(size 1.27 1.27)
				)
			)
		)
		(property "Value" "SCD033U25V2KX-GP"
			(at 1.1811 -2.7051 270)
			(unlocked yes)
			(layer "F.Fab")
			(hide yes)
			(effects
				(font
					(size 1.016 1.016)
					(thickness 0.1524)
				)
			)
		)
		(property "Device Type" "C402H22"
			(at 1.1811 -4.2291 270)
			(unlocked yes)
			(layer "F.Fab")
			(hide yes)
			(effects
				(font
					(size 1.016 1.016)
					(thickness 0.1524)
				)
			)
		)
		(duplicate_pad_numbers_are_jumpers no)
		(fp_rect
			(start -0.4318 0.9525)
			(end 0.4318 -0.9525)
			(stroke
				(width 0)
				(type default)
			)
			(fill no)
			(layer "F.CrtYd")
		)
		(fp_rect
			(start -0.4318 0.9525)
			(end 0.4318 -0.9525)
			(stroke
				(width 0)
				(type default)
			)
			(fill no)
			(layer "F.Fab")
		)
		(pad "1" smd custom
			(at 0 -0.4445 270)
			(size 0.1524 0.1524)
			(layers "F.Cu" "F.Mask" "F.Paste")
			(net "SW_HDD_P25")
			(options
				(clearance outline)
				(anchor circle)
			)
			(primitives
				(gr_poly
					(pts
						(arc
							(start 0.3048 -0.2032)
							(mid 0.275042 -0.275042)
							(end 0.2032 -0.3048)
						)
						(arc
							(start -0.2032 -0.3048)
							(mid -0.275042 -0.275042)
							(end -0.3048 -0.2032)
						)
						(arc
							(start -0.3048 0.2032)
							(mid -0.275042 0.275042)
							(end -0.2032 0.3048)
						)
						(arc
							(start 0.2032 0.3048)
							(mid 0.275042 0.275042)
							(end 0.3048 0.2032)
						)
					)
					(width 0)
					(fill yes)
				)
			)
		)
		(pad "2" smd custom
			(at 0 0.4445 270)
			(size 0.1524 0.1524)
			(layers "F.Cu" "F.Mask" "F.Paste")
			(net "GND")
			(options
				(clearance outline)
				(anchor circle)
			)
			(primitives
				(gr_poly
					(pts
						(arc
							(start 0.3048 -0.2032)
							(mid 0.275042 -0.275042)
							(end 0.2032 -0.3048)
						)
						(arc
							(start -0.2032 -0.3048)
							(mid -0.275042 -0.275042)
							(end -0.3048 -0.2032)
						)
						(arc
							(start -0.3048 0.2032)
							(mid -0.275042 0.275042)
							(end -0.2032 0.3048)
						)
						(arc
							(start 0.2032 0.3048)
							(mid 0.275042 0.275042)
							(end 0.3048 0.2032)
						)
					)
					(width 0)
					(fill yes)
				)
			)
		)
	)
	(footprint ""
		(layer "F.Cu")
		(at 166.324788 -9.19988)
		(property "Reference" ""
			(at 0 0 0)
			(layer "F.SilkS")
			(hide yes)
			(effects
				(font
					(size 1.27 1.27)
				)
			)
		)
		(property "Value" "*"
			(at -6.1214 1.4351 0)
			(unlocked yes)
			(layer "F.Fab")
			(hide yes)
			(effects
				(font
					(size 1.016 1.016)
					(thickness 0.1524)
				)
			)
		)
		(duplicate_pad_numbers_are_jumpers no)
		(fp_poly
			(pts
				(arc
					(start 5.0673 0)
					(mid -5.0673 0)
					(end 5.0673 0)
				)
			)
			(stroke
				(width 0)
				(type default)
			)
			(fill no)
			(layer "B.CrtYd")
		)
		(fp_poly
			(pts
				(arc
					(start 5.0673 0)
					(mid -5.0673 0)
					(end 5.0673 0)
				)
			)
			(stroke
				(width 0)
				(type default)
			)
			(fill no)
			(layer "F.CrtYd")
		)
		(fp_poly
			(pts
				(arc
					(start 5.0673 0)
					(mid -5.0673 0)
					(end 5.0673 0)
				)
			)
			(stroke
				(width 0)
				(type default)
			)
			(fill no)
			(layer "B.Fab")
		)
		(fp_poly
			(pts
				(arc
					(start 5.0673 0)
					(mid -5.0673 0)
					(end 5.0673 0)
				)
			)
			(stroke
				(width 0)
				(type default)
			)
			(fill no)
			(layer "F.Fab")
		)
		(pad "1" thru_hole circle
			(at 0 0)
			(size 9.525 9.525)
			(drill 5.715)
			(layers "*.Cu" "*.Mask")
			(remove_unused_layers no)
			(net "Net_30")
			(clearance -1.397)
			(thermal_gap 0.3048)
			(padstack
				(mode front_inner_back)
				(layer "Inner"
					(shape circle)
					(size 6.1214 6.1214)
					(clearance 0.3048)
				)
				(layer "B.Cu"
					(shape circle)
					(size 9.525 9.525)
					(clearance -1.397)
				)
			)
		)
		(zone
			(layers "F.Cu" "B.Cu" "In1.Cu" "In2.Cu" "In3.Cu" "In4.Cu" "In5.Cu" "In6.Cu"
				"In7.Cu" "In8.Cu" "In9.Cu" "In10.Cu"
			)
			(hatch none 0.5)
			(connect_pads
				(clearance 0)
			)
			(min_thickness 0.25)
			(keepout
				(tracks not_allowed)
				(vias allowed)
				(pads allowed)
				(copperpour not_allowed)
				(footprints allowed)
			)
			(placement
				(enabled no)
				(sheetname "")
			)
			(fill
				(thermal_gap 0.5)
				(thermal_bridge_width 0.5)
				(island_removal_mode 0)
			)
			(polygon
				(pts
					(arc
						(start 171.087288 -9.19988)
						(mid 161.562288 -9.19988)
						(end 171.087288 -9.19988)
					)
				)
			)
		)
	)
	(footprint ""
		(layer "F.Cu")
		(at 479.384614 -159.219392 -90)
		(property "Reference" "C337"
			(at 0 0 270)
			(layer "F.SilkS")
			(hide yes)
			(effects
				(font
					(size 1.27 1.27)
				)
			)
		)
		(property "Value" "SCD01U16V1KX-GP"
			(at -2.8321 -1.7399 270)
			(unlocked yes)
			(layer "F.Fab")
			(hide yes)
			(effects
				(font
					(size 1.016 1.016)
					(thickness 0.1524)
				)
			)
		)
		(property "Device Type" "C0201H13"
			(at -2.8321 -3.2639 270)
			(unlocked yes)
			(layer "F.Fab")
			(hide yes)
			(effects
				(font
					(size 1.016 1.016)
					(thickness 0.1524)
				)
			)
		)
		(duplicate_pad_numbers_are_jumpers no)
		(fp_rect
			(start -0.2794 0.6477)
			(end 0.2794 -0.6477)
			(stroke
				(width 0)
				(type default)
			)
			(fill no)
			(layer "F.CrtYd")
		)
		(fp_rect
			(start -0.2794 0.6477)
			(end 0.2794 -0.6477)
			(stroke
				(width 0)
				(type default)
			)
			(fill no)
			(layer "F.Fab")
		)
		(pad "1" smd custom
			(at 0 -0.2794 270)
			(size 0.0762 0.0762)
			(layers "F.Cu" "F.Mask" "F.Paste")
			(net "SAS_HDD_RX_N23")
			(options
				(clearance outline)
				(anchor circle)
			)
			(primitives
				(gr_poly
					(pts
						(arc
							(start 0.1524 -0.127)
							(mid 0.137521 -0.162921)
							(end 0.1016 -0.1778)
						)
						(arc
							(start -0.1016 -0.1778)
							(mid -0.137521 -0.162921)
							(end -0.1524 -0.127)
						)
						(arc
							(start -0.1524 0.127)
							(mid -0.137521 0.162921)
							(end -0.1016 0.1778)
						)
						(arc
							(start 0.1016 0.1778)
							(mid 0.137521 0.162921)
							(end 0.1524 0.127)
						)
					)
					(width 0)
					(fill yes)
				)
			)
		)
		(pad "2" smd custom
			(at 0 0.2794 270)
			(size 0.0762 0.0762)
			(layers "F.Cu" "F.Mask" "F.Paste")
			(net "PHY_SCC_A_TO_DRV_A_23_DN")
			(options
				(clearance outline)
				(anchor circle)
			)
			(primitives
				(gr_poly
					(pts
						(arc
							(start 0.1524 -0.127)
							(mid 0.137521 -0.162921)
							(end 0.1016 -0.1778)
						)
						(arc
							(start -0.1016 -0.1778)
							(mid -0.137521 -0.162921)
							(end -0.1524 -0.127)
						)
						(arc
							(start -0.1524 0.127)
							(mid -0.137521 0.162921)
							(end -0.1016 0.1778)
						)
						(arc
							(start 0.1016 0.1778)
							(mid 0.137521 0.162921)
							(end 0.1524 0.127)
						)
					)
					(width 0)
					(fill yes)
				)
			)
		)
	)
	(footprint ""
		(layer "F.Cu")
		(at 243.332 -395.9098 180)
		(property "Reference" "C589"
			(at 0 0 180)
			(layer "F.SilkS")
			(hide yes)
			(effects
				(font
					(size 1.27 1.27)
				)
			)
		)
		(property "Value" "SCD1U25V2KX-2-GP"
			(at 1.1811 -2.7051 180)
			(unlocked yes)
			(layer "F.Fab")
			(hide yes)
			(effects
				(font
					(size 1.016 1.016)
					(thickness 0.1524)
				)
			)
		)
		(property "Device Type" "C402H22"
			(at 1.1811 -4.2291 180)
			(unlocked yes)
			(layer "F.Fab")
			(hide yes)
			(effects
				(font
					(size 1.016 1.016)
					(thickness 0.1524)
				)
			)
		)
		(duplicate_pad_numbers_are_jumpers no)
		(fp_rect
			(start -0.4318 0.9525)
			(end 0.4318 -0.9525)
			(stroke
				(width 0)
				(type default)
			)
			(fill no)
			(layer "F.CrtYd")
		)
		(fp_rect
			(start -0.4318 0.9525)
			(end 0.4318 -0.9525)
			(stroke
				(width 0)
				(type default)
			)
			(fill no)
			(layer "F.Fab")
		)
		(pad "1" smd custom
			(at 0 -0.4445 180)
			(size 0.1524 0.1524)
			(layers "F.Cu" "F.Mask" "F.Paste")
			(net "MB3_PSET_R")
			(options
				(clearance outline)
				(anchor circle)
			)
			(primitives
				(gr_poly
					(pts
						(arc
							(start 0.3048 -0.2032)
							(mid 0.275042 -0.275042)
							(end 0.2032 -0.3048)
						)
						(arc
							(start -0.2032 -0.3048)
							(mid -0.275042 -0.275042)
							(end -0.3048 -0.2032)
						)
						(arc
							(start -0.3048 0.2032)
							(mid -0.275042 0.275042)
							(end -0.2032 0.3048)
						)
						(arc
							(start 0.2032 0.3048)
							(mid 0.275042 0.275042)
							(end 0.3048 0.2032)
						)
					)
					(width 0)
					(fill yes)
				)
			)
		)
		(pad "2" smd custom
			(at 0 0.4445 180)
			(size 0.1524 0.1524)
			(layers "F.Cu" "F.Mask" "F.Paste")
			(net "AGND_CURRENT_DPB")
			(options
				(clearance outline)
				(anchor circle)
			)
			(primitives
				(gr_poly
					(pts
						(arc
							(start 0.3048 -0.2032)
							(mid 0.275042 -0.275042)
							(end 0.2032 -0.3048)
						)
						(arc
							(start -0.2032 -0.3048)
							(mid -0.275042 -0.275042)
							(end -0.3048 -0.2032)
						)
						(arc
							(start -0.3048 0.2032)
							(mid -0.275042 0.275042)
							(end -0.2032 0.3048)
						)
						(arc
							(start 0.2032 0.3048)
							(mid 0.275042 0.275042)
							(end 0.3048 0.2032)
						)
					)
					(width 0)
					(fill yes)
				)
			)
		)
	)
	(footprint ""
		(layer "F.Cu")
		(at 59.749944 -172.909992 -90)
		(property "Reference" "HDDSAS13"
			(at 0 0 270)
			(layer "F.SilkS")
			(hide yes)
			(effects
				(font
					(size 1.27 1.27)
				)
			)
		)
		(property "Value" "SKT-SAS15P-14P-45-GP"
			(at -20.7645 -8.9789 270)
			(unlocked yes)
			(layer "F.Fab")
			(hide yes)
			(effects
				(font
					(size 1.016 1.016)
					(thickness 0.1524)
				)
			)
		)
		(property "Device Type" "10120818-001C-TRLF"
			(at -20.7645 -10.5029 270)
			(unlocked yes)
			(layer "F.Fab")
			(hide yes)
			(effects
				(font
					(size 1.016 1.016)
					(thickness 0.1524)
				)
			)
		)
		(duplicate_pad_numbers_are_jumpers no)
		(fp_line
			(start 1.651 4.2926)
			(end 1.651 3.0099)
			(stroke
				(width 0.1524)
				(type default)
			)
			(layer "F.SilkS")
		)
		(fp_line
			(start 8.509 4.2926)
			(end 1.651 4.2926)
			(stroke
				(width 0.1524)
				(type default)
			)
			(layer "F.SilkS")
		)
		(fp_line
			(start -23.4188 3.0099)
			(end -23.4188 -3.2512)
			(stroke
				(width 0.1524)
				(type default)
			)
			(layer "F.SilkS")
		)
		(fp_line
			(start 1.651 3.0099)
			(end -23.4188 3.0099)
			(stroke
				(width 0.1524)
				(type default)
			)
			(layer "F.SilkS")
		)
		(fp_line
			(start 8.509 3.0099)
			(end 8.509 4.2926)
			(stroke
				(width 0.1524)
				(type default)
			)
			(layer "F.SilkS")
		)
		(fp_line
			(start 23.4188 3.0099)
			(end 8.509 3.0099)
			(stroke
				(width 0.1524)
				(type default)
			)
			(layer "F.SilkS")
		)
		(fp_line
			(start -23.4188 -3.2512)
			(end 23.4188 -3.2512)
			(stroke
				(width 0.1524)
				(type default)
			)
			(layer "F.SilkS")
		)
		(fp_line
			(start 23.4188 -3.2512)
			(end 23.4188 3.0099)
			(stroke
				(width 0.1524)
				(type default)
			)
			(layer "F.SilkS")
		)
		(fp_line
			(start 15.5067 -3.3401)
			(end 16.2687 -3.3401)
			(stroke
				(width 0.3302)
				(type default)
			)
			(layer "F.SilkS")
		)
		(fp_poly
			(pts
				(xy 15.868904 -3.230372) (xy 16.503904 -3.865372) (xy 15.233904 -3.865372)
			)
			(stroke
				(width 0)
				(type default)
			)
			(fill yes)
			(layer "F.SilkS")
		)
		(fp_poly
			(pts
				(xy -22.8727 -2.7559) (xy 22.8727 -2.7559) (xy 22.8727 2.7559) (xy 8.255 2.7559) (xy 8.255 3.5179)
				(xy 1.905 3.5179) (xy 1.905 2.7559) (xy -22.8727 2.7559)
			)
			(stroke
				(width 0)
				(type default)
			)
			(fill no)
			(layer "F.CrtYd")
		)
		(fp_poly
			(pts
				(xy 1.397 4.5466) (xy 1.397 3.2639) (xy -23.6728 3.2639) (xy -23.6728 -3.5052) (xy 23.6728 -3.5052)
				(xy 23.6728 -0.00635) (xy 22.8727 -0.00635) (xy 22.8727 -2.7559) (xy -22.8727 -2.7559) (xy -22.8727 2.7559)
				(xy 1.905 2.7559) (xy 1.905 3.5179) (xy 8.255 3.5179) (xy 8.255 2.7559) (xy 22.8727 2.7559) (xy 22.8727 0.00635)
				(xy 23.6728 0.00635) (xy 23.6728 3.2639) (xy 8.763 3.2639) (xy 8.763 4.5466)
			)
			(stroke
				(width 0)
				(type default)
			)
			(fill no)
			(layer "F.CrtYd")
		)
		(fp_poly
			(pts
				(xy 1.397 4.5466) (xy 1.397 3.2639) (xy -23.6728 3.2639) (xy -23.6728 -3.5052) (xy 23.6728 -3.5052)
				(xy 23.6728 3.2639) (xy 8.763 3.2639) (xy 8.763 4.5466)
			)
			(stroke
				(width 0)
				(type default)
			)
			(fill no)
			(layer "F.Fab")
		)
		(pad "" np_thru_hole circle
			(at -18.874994 0 270)
			(size 0.254 0.254)
			(drill 1.3462)
			(layers "*.Cu" "*.Mask")
			(clearance 0.9017)
			(thermal_gap 0.9017)
		)
		(pad "" np_thru_hole circle
			(at 18.874994 0 270)
			(size 0.254 0.254)
			(drill 0.9398)
			(layers "*.Cu" "*.Mask")
			(clearance 0.6985)
			(thermal_gap 0.6985)
		)
		(pad "G1" smd rect
			(at 21.874988 0 270)
			(size 2.5908 2.5908)
			(layers "F.Cu" "F.Mask" "F.Paste")
			(net "GND")
		)
		(pad "G2" smd rect
			(at -21.874988 0 270)
			(size 2.5908 2.5908)
			(layers "F.Cu" "F.Mask" "F.Paste")
			(net "GND")
		)
		(pad "P1" smd rect
			(at 1.905 -1.82499 270)
			(size 0.6096 2.3622)
			(layers "F.Cu" "F.Mask" "F.Paste")
			(net "Net_2151")
		)
		(pad "P2" smd rect
			(at 0.635 -1.82499 270)
			(size 0.6096 2.3622)
			(layers "F.Cu" "F.Mask" "F.Paste")
			(net "Net_2152")
		)
		(pad "P3" smd rect
			(at -0.635 -1.82499 270)
			(size 0.6096 2.3622)
			(layers "F.Cu" "F.Mask" "F.Paste")
			(net "Net_2153")
		)
		(pad "P4" smd rect
			(at -1.905 -1.82499 270)
			(size 0.6096 2.3622)
			(layers "F.Cu" "F.Mask" "F.Paste")
			(net "GND")
		)
		(pad "P5" smd rect
			(at -3.175 -1.82499 270)
			(size 0.6096 2.3622)
			(layers "F.Cu" "F.Mask" "F.Paste")
			(net "HDD_PRSNT_13")
		)
		(pad "P6" smd rect
			(at -4.445 -1.82499 270)
			(size 0.6096 2.3622)
			(layers "F.Cu" "F.Mask" "F.Paste")
			(net "GND")
		)
		(pad "P7" smd rect
			(at -5.715 -1.82499 270)
			(size 0.6096 2.3622)
			(layers "F.Cu" "F.Mask" "F.Paste")
			(net "5V_PRE_13")
		)
		(pad "P8" smd rect
			(at -6.985 -1.82499 270)
			(size 0.6096 2.3622)
			(layers "F.Cu" "F.Mask" "F.Paste")
			(net "P5V_HDD13")
		)
		(pad "P9" smd rect
			(at -8.255 -1.82499 270)
			(size 0.6096 2.3622)
			(layers "F.Cu" "F.Mask" "F.Paste")
			(net "P5V_HDD13")
		)
		(pad "P10" smd rect
			(at -9.525 -1.82499 270)
			(size 0.6096 2.3622)
			(layers "F.Cu" "F.Mask" "F.Paste")
			(net "GND")
		)
		(pad "P11" smd rect
			(at -10.795 -1.82499 270)
			(size 0.6096 2.3622)
			(layers "F.Cu" "F.Mask" "F.Paste")
			(net "ACT_HDD_13")
		)
		(pad "P12" smd rect
			(at -12.065 -1.82499 270)
			(size 0.6096 2.3622)
			(layers "F.Cu" "F.Mask" "F.Paste")
			(net "GND")
		)
		(pad "P13" smd rect
			(at -13.335 -1.82499 270)
			(size 0.6096 2.3622)
			(layers "F.Cu" "F.Mask" "F.Paste")
			(net "12V_PRE_13")
		)
		(pad "P14" smd rect
			(at -14.605 -1.82499 270)
			(size 0.6096 2.3622)
			(layers "F.Cu" "F.Mask" "F.Paste")
			(net "P12V_HDD13")
		)
		(pad "P15" smd rect
			(at -15.875 -1.82499 270)
			(size 0.6096 2.3622)
			(layers "F.Cu" "F.Mask" "F.Paste")
			(net "P12V_HDD13")
		)
		(pad "S1" smd rect
			(at 15.875 -1.82499 270)
			(size 0.6096 2.3622)
			(layers "F.Cu" "F.Mask" "F.Paste")
			(net "GND")
		)
		(pad "S2" smd rect
			(at 14.605 -1.82499 270)
			(size 0.6096 2.3622)
			(layers "F.Cu" "F.Mask" "F.Paste")
			(net "SAS_HDD_RX_P13")
		)
		(pad "S3" smd rect
			(at 13.335 -1.82499 270)
			(size 0.6096 2.3622)
			(layers "F.Cu" "F.Mask" "F.Paste")
			(net "SAS_HDD_RX_N13")
		)
		(pad "S4" smd rect
			(at 12.065 -1.82499 270)
			(size 0.6096 2.3622)
			(layers "F.Cu" "F.Mask" "F.Paste")
			(net "GND")
		)
		(pad "S5" smd rect
			(at 10.795 -1.82499 270)
			(size 0.6096 2.3622)
			(layers "F.Cu" "F.Mask" "F.Paste")
			(net "PHY_DRV_A_TO_SCC_A_13_DN")
		)
		(pad "S6" smd rect
			(at 9.525 -1.82499 270)
			(size 0.6096 2.3622)
			(layers "F.Cu" "F.Mask" "F.Paste")
			(net "PHY_DRV_A_TO_SCC_A_13_DP")
		)
		(pad "S7" smd rect
			(at 8.255 -1.82499 270)
			(size 0.6096 2.3622)
			(layers "F.Cu" "F.Mask" "F.Paste")
			(net "GND")
		)
		(pad "S8" smd rect
			(at 7.480046 2.845054 270)
			(size 0.508 2.3622)
			(layers "F.Cu" "F.Mask" "F.Paste")
			(net "GND")
		)
		(pad "S9" smd rect
			(at 6.679946 2.845054 270)
			(size 0.508 2.3622)
			(layers "F.Cu" "F.Mask" "F.Paste")
			(net "Net_450")
		)
		(pad "S10" smd rect
			(at 5.8801 2.845054 270)
			(size 0.508 2.3622)
			(layers "F.Cu" "F.Mask" "F.Paste")
			(net "Net_342")
		)
		(pad "S11" smd rect
			(at 5.08 2.845054 270)
			(size 0.508 2.3622)
			(layers "F.Cu" "F.Mask" "F.Paste")
			(net "GND")
		)
		(pad "S12" smd rect
			(at 4.2799 2.845054 270)
			(size 0.508 2.3622)
			(layers "F.Cu" "F.Mask" "F.Paste")
			(net "Net_378")
		)
		(pad "S13" smd rect
			(at 3.480054 2.845054 270)
			(size 0.508 2.3622)
			(layers "F.Cu" "F.Mask" "F.Paste")
			(net "Net_414")
		)
		(pad "S14" smd rect
			(at 2.679954 2.845054 270)
			(size 0.508 2.3622)
			(layers "F.Cu" "F.Mask" "F.Paste")
			(net "GND")
		)
		(zone
			(layer "F.Cu")
			(hatch none 0.5)
			(connect_pads
				(clearance 0)
			)
			(min_thickness 0.25)
			(keepout
				(tracks allowed)
				(vias not_allowed)
				(pads allowed)
				(copperpour not_allowed)
				(footprints allowed)
			)
			(placement
				(enabled no)
				(sheetname "")
			)
			(fill
				(thermal_gap 0.5)
				(thermal_bridge_width 0.5)
				(island_removal_mode 0)
			)
			(polygon
				(pts
					(xy 63.407544 -189.648592) (xy 56.333644 -189.648592) (xy 56.333644 -196.582792) (xy 57.438544 -196.582792)
					(xy 57.438544 -192.467992) (xy 62.061344 -192.467992) (xy 62.061344 -196.582792) (xy 63.407544 -196.582792)
				)
			)
		)
		(zone
			(layer "F.Cu")
			(hatch none 0.5)
			(connect_pads
				(clearance 0)
			)
			(min_thickness 0.25)
			(keepout
				(tracks not_allowed)
				(vias allowed)
				(pads allowed)
				(copperpour not_allowed)
				(footprints allowed)
			)
			(placement
				(enabled no)
				(sheetname "")
			)
			(fill
				(thermal_gap 0.5)
				(thermal_bridge_width 0.5)
				(island_removal_mode 0)
			)
			(polygon
				(pts
					(xy 63.407544 -189.648592) (xy 56.333644 -189.648592) (xy 56.333644 -196.582792) (xy 57.438544 -196.582792)
					(xy 57.438544 -192.467992) (xy 62.061344 -192.467992) (xy 62.061344 -196.582792) (xy 63.407544 -196.582792)
				)
			)
		)
		(zone
			(layer "F.Cu")
			(hatch none 0.5)
			(connect_pads
				(clearance 0)
			)
			(min_thickness 0.25)
			(keepout
				(tracks allowed)
				(vias not_allowed)
				(pads allowed)
				(copperpour not_allowed)
				(footprints allowed)
			)
			(placement
				(enabled no)
				(sheetname "")
			)
			(fill
				(thermal_gap 0.5)
				(thermal_bridge_width 0.5)
				(island_removal_mode 0)
			)
			(polygon
				(pts
					(xy 63.407544 -156.171392) (xy 56.333644 -156.171392) (xy 56.333644 -149.237192) (xy 57.438544 -149.237192)
					(xy 57.438544 -153.351992) (xy 62.061344 -153.351992) (xy 62.061344 -149.237192) (xy 63.407544 -149.237192)
				)
			)
		)
		(zone
			(layer "F.Cu")
			(hatch none 0.5)
			(connect_pads
				(clearance 0)
			)
			(min_thickness 0.25)
			(keepout
				(tracks not_allowed)
				(vias allowed)
				(pads allowed)
				(copperpour not_allowed)
				(footprints allowed)
			)
			(placement
				(enabled no)
				(sheetname "")
			)
			(fill
				(thermal_gap 0.5)
				(thermal_bridge_width 0.5)
				(island_removal_mode 0)
			)
			(polygon
				(pts
					(xy 63.407544 -156.171392) (xy 56.333644 -156.171392) (xy 56.333644 -149.237192) (xy 57.438544 -149.237192)
					(xy 57.438544 -153.351992) (xy 62.061344 -153.351992) (xy 62.061344 -149.237192) (xy 63.407544 -149.237192)
				)
			)
		)
		(zone
			(layers "F.Cu" "B.Cu" "In1.Cu" "In2.Cu" "In3.Cu" "In4.Cu" "In5.Cu" "In6.Cu"
				"In7.Cu" "In8.Cu" "In9.Cu" "In10.Cu"
			)
			(hatch none 0.5)
			(connect_pads
				(clearance 0)
			)
			(min_thickness 0.25)
			(keepout
				(tracks not_allowed)
				(vias allowed)
				(pads allowed)
				(copperpour not_allowed)
				(footprints allowed)
			)
			(placement
				(enabled no)
				(sheetname "")
			)
			(fill
				(thermal_gap 0.5)
				(thermal_bridge_width 0.5)
				(island_removal_mode 0)
			)
			(polygon
				(pts
					(arc
						(start 60.524644 -154.034998)
						(mid 58.975244 -154.034998)
						(end 60.524644 -154.034998)
					)
				)
			)
		)
		(zone
			(layers "F.Cu" "B.Cu" "In1.Cu" "In2.Cu" "In3.Cu" "In4.Cu" "In5.Cu" "In6.Cu"
				"In7.Cu" "In8.Cu" "In9.Cu" "In10.Cu"
			)
			(hatch none 0.5)
			(connect_pads
				(clearance 0)
			)
			(min_thickness 0.25)
			(keepout
				(tracks not_allowed)
				(vias allowed)
				(pads allowed)
				(copperpour not_allowed)
				(footprints allowed)
			)
			(placement
				(enabled no)
				(sheetname "")
			)
			(fill
				(thermal_gap 0.5)
				(thermal_bridge_width 0.5)
				(island_removal_mode 0)
			)
			(polygon
				(pts
					(arc
						(start 60.727844 -191.784986)
						(mid 58.772044 -191.784986)
						(end 60.727844 -191.784986)
					)
				)
			)
		)
	)
	(footprint ""
		(layer "F.Cu")
		(at 91.300046 -172.909992 -90)
		(property "Reference" "HDDSAS14"
			(at 0 0 270)
			(layer "F.SilkS")
			(hide yes)
			(effects
				(font
					(size 1.27 1.27)
				)
			)
		)
		(property "Value" "SKT-SAS15P-14P-45-GP"
			(at -20.7645 -8.9789 270)
			(unlocked yes)
			(layer "F.Fab")
			(hide yes)
			(effects
				(font
					(size 1.016 1.016)
					(thickness 0.1524)
				)
			)
		)
		(property "Device Type" "10120818-001C-TRLF"
			(at -20.7645 -10.5029 270)
			(unlocked yes)
			(layer "F.Fab")
			(hide yes)
			(effects
				(font
					(size 1.016 1.016)
					(thickness 0.1524)
				)
			)
		)
		(duplicate_pad_numbers_are_jumpers no)
		(fp_line
			(start 1.651 4.2926)
			(end 1.651 3.0099)
			(stroke
				(width 0.1524)
				(type default)
			)
			(layer "F.SilkS")
		)
		(fp_line
			(start 8.509 4.2926)
			(end 1.651 4.2926)
			(stroke
				(width 0.1524)
				(type default)
			)
			(layer "F.SilkS")
		)
		(fp_line
			(start -23.4188 3.0099)
			(end -23.4188 -3.2512)
			(stroke
				(width 0.1524)
				(type default)
			)
			(layer "F.SilkS")
		)
		(fp_line
			(start 1.651 3.0099)
			(end -23.4188 3.0099)
			(stroke
				(width 0.1524)
				(type default)
			)
			(layer "F.SilkS")
		)
		(fp_line
			(start 8.509 3.0099)
			(end 8.509 4.2926)
			(stroke
				(width 0.1524)
				(type default)
			)
			(layer "F.SilkS")
		)
		(fp_line
			(start 23.4188 3.0099)
			(end 8.509 3.0099)
			(stroke
				(width 0.1524)
				(type default)
			)
			(layer "F.SilkS")
		)
		(fp_line
			(start -23.4188 -3.2512)
			(end 23.4188 -3.2512)
			(stroke
				(width 0.1524)
				(type default)
			)
			(layer "F.SilkS")
		)
		(fp_line
			(start 23.4188 -3.2512)
			(end 23.4188 3.0099)
			(stroke
				(width 0.1524)
				(type default)
			)
			(layer "F.SilkS")
		)
		(fp_line
			(start 15.5067 -3.3401)
			(end 16.2687 -3.3401)
			(stroke
				(width 0.3302)
				(type default)
			)
			(layer "F.SilkS")
		)
		(fp_poly
			(pts
				(xy 15.868904 -3.230372) (xy 16.503904 -3.865372) (xy 15.233904 -3.865372)
			)
			(stroke
				(width 0)
				(type default)
			)
			(fill yes)
			(layer "F.SilkS")
		)
		(fp_poly
			(pts
				(xy -22.8727 -2.7559) (xy 22.8727 -2.7559) (xy 22.8727 2.7559) (xy 8.255 2.7559) (xy 8.255 3.5179)
				(xy 1.905 3.5179) (xy 1.905 2.7559) (xy -22.8727 2.7559)
			)
			(stroke
				(width 0)
				(type default)
			)
			(fill no)
			(layer "F.CrtYd")
		)
		(fp_poly
			(pts
				(xy 1.397 4.5466) (xy 1.397 3.2639) (xy -23.6728 3.2639) (xy -23.6728 -3.5052) (xy 23.6728 -3.5052)
				(xy 23.6728 -0.00635) (xy 22.8727 -0.00635) (xy 22.8727 -2.7559) (xy -22.8727 -2.7559) (xy -22.8727 2.7559)
				(xy 1.905 2.7559) (xy 1.905 3.5179) (xy 8.255 3.5179) (xy 8.255 2.7559) (xy 22.8727 2.7559) (xy 22.8727 0.00635)
				(xy 23.6728 0.00635) (xy 23.6728 3.2639) (xy 8.763 3.2639) (xy 8.763 4.5466)
			)
			(stroke
				(width 0)
				(type default)
			)
			(fill no)
			(layer "F.CrtYd")
		)
		(fp_poly
			(pts
				(xy 1.397 4.5466) (xy 1.397 3.2639) (xy -23.6728 3.2639) (xy -23.6728 -3.5052) (xy 23.6728 -3.5052)
				(xy 23.6728 3.2639) (xy 8.763 3.2639) (xy 8.763 4.5466)
			)
			(stroke
				(width 0)
				(type default)
			)
			(fill no)
			(layer "F.Fab")
		)
		(pad "" np_thru_hole circle
			(at -18.874994 0 270)
			(size 0.254 0.254)
			(drill 1.3462)
			(layers "*.Cu" "*.Mask")
			(clearance 0.9017)
			(thermal_gap 0.9017)
		)
		(pad "" np_thru_hole circle
			(at 18.874994 0 270)
			(size 0.254 0.254)
			(drill 0.9398)
			(layers "*.Cu" "*.Mask")
			(clearance 0.6985)
			(thermal_gap 0.6985)
		)
		(pad "G1" smd rect
			(at 21.874988 0 270)
			(size 2.5908 2.5908)
			(layers "F.Cu" "F.Mask" "F.Paste")
			(net "GND")
		)
		(pad "G2" smd rect
			(at -21.874988 0 270)
			(size 2.5908 2.5908)
			(layers "F.Cu" "F.Mask" "F.Paste")
			(net "GND")
		)
		(pad "P1" smd rect
			(at 1.905 -1.82499 270)
			(size 0.6096 2.3622)
			(layers "F.Cu" "F.Mask" "F.Paste")
			(net "Net_2146")
		)
		(pad "P2" smd rect
			(at 0.635 -1.82499 270)
			(size 0.6096 2.3622)
			(layers "F.Cu" "F.Mask" "F.Paste")
			(net "Net_2147")
		)
		(pad "P3" smd rect
			(at -0.635 -1.82499 270)
			(size 0.6096 2.3622)
			(layers "F.Cu" "F.Mask" "F.Paste")
			(net "Net_2148")
		)
		(pad "P4" smd rect
			(at -1.905 -1.82499 270)
			(size 0.6096 2.3622)
			(layers "F.Cu" "F.Mask" "F.Paste")
			(net "GND")
		)
		(pad "P5" smd rect
			(at -3.175 -1.82499 270)
			(size 0.6096 2.3622)
			(layers "F.Cu" "F.Mask" "F.Paste")
			(net "HDD_PRSNT_14")
		)
		(pad "P6" smd rect
			(at -4.445 -1.82499 270)
			(size 0.6096 2.3622)
			(layers "F.Cu" "F.Mask" "F.Paste")
			(net "GND")
		)
		(pad "P7" smd rect
			(at -5.715 -1.82499 270)
			(size 0.6096 2.3622)
			(layers "F.Cu" "F.Mask" "F.Paste")
			(net "5V_PRE_14")
		)
		(pad "P8" smd rect
			(at -6.985 -1.82499 270)
			(size 0.6096 2.3622)
			(layers "F.Cu" "F.Mask" "F.Paste")
			(net "P5V_HDD14")
		)
		(pad "P9" smd rect
			(at -8.255 -1.82499 270)
			(size 0.6096 2.3622)
			(layers "F.Cu" "F.Mask" "F.Paste")
			(net "P5V_HDD14")
		)
		(pad "P10" smd rect
			(at -9.525 -1.82499 270)
			(size 0.6096 2.3622)
			(layers "F.Cu" "F.Mask" "F.Paste")
			(net "GND")
		)
		(pad "P11" smd rect
			(at -10.795 -1.82499 270)
			(size 0.6096 2.3622)
			(layers "F.Cu" "F.Mask" "F.Paste")
			(net "ACT_HDD_14")
		)
		(pad "P12" smd rect
			(at -12.065 -1.82499 270)
			(size 0.6096 2.3622)
			(layers "F.Cu" "F.Mask" "F.Paste")
			(net "GND")
		)
		(pad "P13" smd rect
			(at -13.335 -1.82499 270)
			(size 0.6096 2.3622)
			(layers "F.Cu" "F.Mask" "F.Paste")
			(net "12V_PRE_14")
		)
		(pad "P14" smd rect
			(at -14.605 -1.82499 270)
			(size 0.6096 2.3622)
			(layers "F.Cu" "F.Mask" "F.Paste")
			(net "P12V_HDD14")
		)
		(pad "P15" smd rect
			(at -15.875 -1.82499 270)
			(size 0.6096 2.3622)
			(layers "F.Cu" "F.Mask" "F.Paste")
			(net "P12V_HDD14")
		)
		(pad "S1" smd rect
			(at 15.875 -1.82499 270)
			(size 0.6096 2.3622)
			(layers "F.Cu" "F.Mask" "F.Paste")
			(net "GND")
		)
		(pad "S2" smd rect
			(at 14.605 -1.82499 270)
			(size 0.6096 2.3622)
			(layers "F.Cu" "F.Mask" "F.Paste")
			(net "SAS_HDD_RX_P14")
		)
		(pad "S3" smd rect
			(at 13.335 -1.82499 270)
			(size 0.6096 2.3622)
			(layers "F.Cu" "F.Mask" "F.Paste")
			(net "SAS_HDD_RX_N14")
		)
		(pad "S4" smd rect
			(at 12.065 -1.82499 270)
			(size 0.6096 2.3622)
			(layers "F.Cu" "F.Mask" "F.Paste")
			(net "GND")
		)
		(pad "S5" smd rect
			(at 10.795 -1.82499 270)
			(size 0.6096 2.3622)
			(layers "F.Cu" "F.Mask" "F.Paste")
			(net "PHY_DRV_A_TO_SCC_A_14_DN")
		)
		(pad "S6" smd rect
			(at 9.525 -1.82499 270)
			(size 0.6096 2.3622)
			(layers "F.Cu" "F.Mask" "F.Paste")
			(net "PHY_DRV_A_TO_SCC_A_14_DP")
		)
		(pad "S7" smd rect
			(at 8.255 -1.82499 270)
			(size 0.6096 2.3622)
			(layers "F.Cu" "F.Mask" "F.Paste")
			(net "GND")
		)
		(pad "S8" smd rect
			(at 7.480046 2.845054 270)
			(size 0.508 2.3622)
			(layers "F.Cu" "F.Mask" "F.Paste")
			(net "GND")
		)
		(pad "S9" smd rect
			(at 6.679946 2.845054 270)
			(size 0.508 2.3622)
			(layers "F.Cu" "F.Mask" "F.Paste")
			(net "Net_451")
		)
		(pad "S10" smd rect
			(at 5.8801 2.845054 270)
			(size 0.508 2.3622)
			(layers "F.Cu" "F.Mask" "F.Paste")
			(net "Net_343")
		)
		(pad "S11" smd rect
			(at 5.08 2.845054 270)
			(size 0.508 2.3622)
			(layers "F.Cu" "F.Mask" "F.Paste")
			(net "GND")
		)
		(pad "S12" smd rect
			(at 4.2799 2.845054 270)
			(size 0.508 2.3622)
			(layers "F.Cu" "F.Mask" "F.Paste")
			(net "Net_379")
		)
		(pad "S13" smd rect
			(at 3.480054 2.845054 270)
			(size 0.508 2.3622)
			(layers "F.Cu" "F.Mask" "F.Paste")
			(net "Net_415")
		)
		(pad "S14" smd rect
			(at 2.679954 2.845054 270)
			(size 0.508 2.3622)
			(layers "F.Cu" "F.Mask" "F.Paste")
			(net "GND")
		)
		(zone
			(layer "F.Cu")
			(hatch none 0.5)
			(connect_pads
				(clearance 0)
			)
			(min_thickness 0.25)
			(keepout
				(tracks allowed)
				(vias not_allowed)
				(pads allowed)
				(copperpour not_allowed)
				(footprints allowed)
			)
			(placement
				(enabled no)
				(sheetname "")
			)
			(fill
				(thermal_gap 0.5)
				(thermal_bridge_width 0.5)
				(island_removal_mode 0)
			)
			(polygon
				(pts
					(xy 94.957646 -189.648592) (xy 87.883746 -189.648592) (xy 87.883746 -196.582792) (xy 88.988646 -196.582792)
					(xy 88.988646 -192.467992) (xy 93.611446 -192.467992) (xy 93.611446 -196.582792) (xy 94.957646 -196.582792)
				)
			)
		)
		(zone
			(layer "F.Cu")
			(hatch none 0.5)
			(connect_pads
				(clearance 0)
			)
			(min_thickness 0.25)
			(keepout
				(tracks not_allowed)
				(vias allowed)
				(pads allowed)
				(copperpour not_allowed)
				(footprints allowed)
			)
			(placement
				(enabled no)
				(sheetname "")
			)
			(fill
				(thermal_gap 0.5)
				(thermal_bridge_width 0.5)
				(island_removal_mode 0)
			)
			(polygon
				(pts
					(xy 94.957646 -189.648592) (xy 87.883746 -189.648592) (xy 87.883746 -196.582792) (xy 88.988646 -196.582792)
					(xy 88.988646 -192.467992) (xy 93.611446 -192.467992) (xy 93.611446 -196.582792) (xy 94.957646 -196.582792)
				)
			)
		)
		(zone
			(layer "F.Cu")
			(hatch none 0.5)
			(connect_pads
				(clearance 0)
			)
			(min_thickness 0.25)
			(keepout
				(tracks allowed)
				(vias not_allowed)
				(pads allowed)
				(copperpour not_allowed)
				(footprints allowed)
			)
			(placement
				(enabled no)
				(sheetname "")
			)
			(fill
				(thermal_gap 0.5)
				(thermal_bridge_width 0.5)
				(island_removal_mode 0)
			)
			(polygon
				(pts
					(xy 94.957646 -156.171392) (xy 87.883746 -156.171392) (xy 87.883746 -149.237192) (xy 88.988646 -149.237192)
					(xy 88.988646 -153.351992) (xy 93.611446 -153.351992) (xy 93.611446 -149.237192) (xy 94.957646 -149.237192)
				)
			)
		)
		(zone
			(layer "F.Cu")
			(hatch none 0.5)
			(connect_pads
				(clearance 0)
			)
			(min_thickness 0.25)
			(keepout
				(tracks not_allowed)
				(vias allowed)
				(pads allowed)
				(copperpour not_allowed)
				(footprints allowed)
			)
			(placement
				(enabled no)
				(sheetname "")
			)
			(fill
				(thermal_gap 0.5)
				(thermal_bridge_width 0.5)
				(island_removal_mode 0)
			)
			(polygon
				(pts
					(xy 94.957646 -156.171392) (xy 87.883746 -156.171392) (xy 87.883746 -149.237192) (xy 88.988646 -149.237192)
					(xy 88.988646 -153.351992) (xy 93.611446 -153.351992) (xy 93.611446 -149.237192) (xy 94.957646 -149.237192)
				)
			)
		)
		(zone
			(layers "F.Cu" "B.Cu" "In1.Cu" "In2.Cu" "In3.Cu" "In4.Cu" "In5.Cu" "In6.Cu"
				"In7.Cu" "In8.Cu" "In9.Cu" "In10.Cu"
			)
			(hatch none 0.5)
			(connect_pads
				(clearance 0)
			)
			(min_thickness 0.25)
			(keepout
				(tracks not_allowed)
				(vias allowed)
				(pads allowed)
				(copperpour not_allowed)
				(footprints allowed)
			)
			(placement
				(enabled no)
				(sheetname "")
			)
			(fill
				(thermal_gap 0.5)
				(thermal_bridge_width 0.5)
				(island_removal_mode 0)
			)
			(polygon
				(pts
					(arc
						(start 92.074746 -154.034998)
						(mid 90.525346 -154.034998)
						(end 92.074746 -154.034998)
					)
				)
			)
		)
		(zone
			(layers "F.Cu" "B.Cu" "In1.Cu" "In2.Cu" "In3.Cu" "In4.Cu" "In5.Cu" "In6.Cu"
				"In7.Cu" "In8.Cu" "In9.Cu" "In10.Cu"
			)
			(hatch none 0.5)
			(connect_pads
				(clearance 0)
			)
			(min_thickness 0.25)
			(keepout
				(tracks not_allowed)
				(vias allowed)
				(pads allowed)
				(copperpour not_allowed)
				(footprints allowed)
			)
			(placement
				(enabled no)
				(sheetname "")
			)
			(fill
				(thermal_gap 0.5)
				(thermal_bridge_width 0.5)
				(island_removal_mode 0)
			)
			(polygon
				(pts
					(arc
						(start 92.277946 -191.784986)
						(mid 90.322146 -191.784986)
						(end 92.277946 -191.784986)
					)
				)
			)
		)
	)
	(footprint ""
		(layer "F.Cu")
		(at 112.388142 -272.726404 180)
		(property "Reference" "R211"
			(at 0 0 180)
			(layer "F.SilkS")
			(hide yes)
			(effects
				(font
					(size 1.27 1.27)
				)
			)
		)
		(property "Value" "0R2J-2-GP"
			(at 0.064008 -3.993896 180)
			(unlocked yes)
			(layer "F.Fab")
			(hide yes)
			(effects
				(font
					(size 1.016 1.016)
					(thickness 0.1524)
				)
			)
		)
		(property "Device Type" "R402H16"
			(at 0.064008 -5.517896 180)
			(unlocked yes)
			(layer "F.Fab")
			(hide yes)
			(effects
				(font
					(size 1.016 1.016)
					(thickness 0.1524)
				)
			)
		)
		(duplicate_pad_numbers_are_jumpers no)
		(fp_line
			(start 0.508 -0.9398)
			(end -0.508 -0.9398)
			(stroke
				(width 0.1524)
				(type default)
			)
			(layer "F.SilkS")
		)
		(fp_line
			(start -0.508 -0.9398)
			(end -0.508 0.9398)
			(stroke
				(width 0.1524)
				(type default)
			)
			(layer "F.SilkS")
		)
		(fp_rect
			(start -0.508 0.9398)
			(end 0.508 -0.9398)
			(stroke
				(width 0)
				(type default)
			)
			(fill no)
			(layer "F.CrtYd")
		)
		(fp_rect
			(start -0.508 0.9398)
			(end 0.508 -0.9398)
			(stroke
				(width 0)
				(type default)
			)
			(fill no)
			(layer "F.Fab")
		)
		(pad "1" smd custom
			(at 0 -0.4445 180)
			(size 0.1397 0.1397)
			(layers "F.Cu" "F.Mask" "F.Paste")
			(net "DRIVE_A_3_PWR")
			(options
				(clearance outline)
				(anchor circle)
			)
			(primitives
				(gr_poly
					(pts
						(arc
							(start -0.1778 -0.2794)
							(mid -0.249642 -0.249642)
							(end -0.2794 -0.1778)
						)
						(arc
							(start -0.2794 0.1778)
							(mid -0.249642 0.249642)
							(end -0.1778 0.2794)
						)
						(arc
							(start 0.1778 0.2794)
							(mid 0.249642 0.249642)
							(end 0.2794 0.1778)
						)
						(arc
							(start 0.2794 -0.1778)
							(mid 0.249642 -0.249642)
							(end 0.1778 -0.2794)
						)
					)
					(width 0)
					(fill yes)
				)
			)
		)
		(pad "2" smd custom
			(at 0 0.4445 180)
			(size 0.1397 0.1397)
			(layers "F.Cu" "F.Mask" "F.Paste")
			(net "SW_PWR_R_HDD3")
			(options
				(clearance outline)
				(anchor circle)
			)
			(primitives
				(gr_poly
					(pts
						(arc
							(start -0.1778 -0.2794)
							(mid -0.249642 -0.249642)
							(end -0.2794 -0.1778)
						)
						(arc
							(start -0.2794 0.1778)
							(mid -0.249642 0.249642)
							(end -0.1778 0.2794)
						)
						(arc
							(start 0.1778 0.2794)
							(mid 0.249642 0.249642)
							(end 0.2794 0.1778)
						)
						(arc
							(start 0.2794 -0.1778)
							(mid 0.249642 -0.249642)
							(end 0.1778 -0.2794)
						)
					)
					(width 0)
					(fill yes)
				)
			)
		)
	)
	(footprint ""
		(layer "F.Cu")
		(at 221.0054 -177.0634)
		(property "Reference" "C134"
			(at 0 0 0)
			(layer "F.SilkS")
			(hide yes)
			(effects
				(font
					(size 1.27 1.27)
				)
			)
		)
		(property "Value" "SC22U25V6KX-2-GP-U"
			(at -2.860802 -5.279644 0)
			(unlocked yes)
			(layer "F.Fab")
			(hide yes)
			(effects
				(font
					(size 1.016 1.016)
					(thickness 0.1524)
				)
			)
		)
		(property "Device Type" "C1206-TO0D3H75"
			(at -2.860802 -6.803644 0)
			(unlocked yes)
			(layer "F.Fab")
			(hide yes)
			(effects
				(font
					(size 1.016 1.016)
					(thickness 0.1524)
				)
			)
		)
		(duplicate_pad_numbers_are_jumpers no)
		(fp_line
			(start -1.3081 -2.3749)
			(end 1.3081 -2.3749)
			(stroke
				(width 0.1524)
				(type default)
			)
			(layer "F.SilkS")
		)
		(fp_line
			(start -1.3081 2.3749)
			(end -1.3081 -2.3749)
			(stroke
				(width 0.1524)
				(type default)
			)
			(layer "F.SilkS")
		)
		(fp_line
			(start 1.3081 -2.3749)
			(end 1.3081 2.3749)
			(stroke
				(width 0.1524)
				(type default)
			)
			(layer "F.SilkS")
		)
		(fp_line
			(start 1.3081 2.3749)
			(end -1.3081 2.3749)
			(stroke
				(width 0.1524)
				(type default)
			)
			(layer "F.SilkS")
		)
		(fp_rect
			(start -0.8001 1.6002)
			(end 0.8001 -1.6002)
			(stroke
				(width 0)
				(type default)
			)
			(fill no)
			(layer "F.CrtYd")
		)
		(fp_poly
			(pts
				(xy -1.5621 2.4511) (xy -1.5621 1.6002) (xy 0.8001 1.6002) (xy 0.8001 -1.6002) (xy -0.8001 -1.6002)
				(xy -0.8001 1.5875) (xy -1.5621 1.5875) (xy -1.5621 -2.4511) (xy 1.5621 -2.4511) (xy 1.5621 2.4511)
			)
			(stroke
				(width 0)
				(type default)
			)
			(fill no)
			(layer "F.CrtYd")
		)
		(fp_rect
			(start -1.5621 2.4511)
			(end 1.5621 -2.4511)
			(stroke
				(width 0)
				(type default)
			)
			(fill no)
			(layer "F.Fab")
		)
		(pad "1" smd rect
			(at 0 -1.392936)
			(size 2.1082 1.4478)
			(layers "F.Cu" "F.Mask" "F.Paste")
			(net "P12V_A_COMP")
		)
		(pad "2" smd rect
			(at 0 1.392936)
			(size 2.1082 1.4478)
			(layers "F.Cu" "F.Mask" "F.Paste")
			(net "GND")
		)
	)
	(footprint ""
		(layer "F.Cu")
		(at 133.89483 -142.61338)
		(property "Reference" "Q6"
			(at 0 0 0)
			(layer "F.SilkS")
			(hide yes)
			(effects
				(font
					(size 1.27 1.27)
				)
			)
		)
		(property "Value" "MMBT3904TT1G-GP"
			(at 0 -9.7282 0)
			(unlocked yes)
			(layer "F.Fab")
			(hide yes)
			(effects
				(font
					(size 1.016 1.016)
					(thickness 0.1524)
				)
			)
		)
		(property "Device Type" "SC75CBE1D6H36"
			(at 0 -11.6332 0)
			(unlocked yes)
			(layer "F.Fab")
			(hide yes)
			(effects
				(font
					(size 1.016 1.016)
					(thickness 0.1524)
				)
			)
		)
		(duplicate_pad_numbers_are_jumpers no)
		(fp_line
			(start -0.9652 -1.3716)
			(end -0.9652 1.3716)
			(stroke
				(width 0.1524)
				(type default)
			)
			(layer "F.SilkS")
		)
		(fp_line
			(start -0.9652 1.3716)
			(end 0.9652 1.3716)
			(stroke
				(width 0.1524)
				(type default)
			)
			(layer "F.SilkS")
		)
		(fp_line
			(start 0.9652 -1.3716)
			(end -0.9652 -1.3716)
			(stroke
				(width 0.1524)
				(type default)
			)
			(layer "F.SilkS")
		)
		(fp_line
			(start 0.9652 1.3716)
			(end 0.9652 -1.3716)
			(stroke
				(width 0.1524)
				(type default)
			)
			(layer "F.SilkS")
		)
		(fp_rect
			(start -1.0414 1.4478)
			(end 1.0414 -1.4478)
			(stroke
				(width 0)
				(type default)
			)
			(fill no)
			(layer "F.CrtYd")
		)
		(fp_poly
			(pts
				(xy -1.0414 -1.4478) (xy 1.0414 -1.4478) (xy 1.0414 1.4478) (xy -1.0414 1.4478)
			)
			(stroke
				(width 0)
				(type default)
			)
			(fill no)
			(layer "F.Fab")
		)
		(pad "B" smd custom
			(at -0.508 0.7112)
			(size 0.127 0.127)
			(layers "F.Cu" "F.Mask" "F.Paste")
			(net "VCCP_A")
			(options
				(clearance outline)
				(anchor circle)
			)
			(primitives
				(gr_poly
					(pts
						(arc
							(start -0.044958 0.4572)
							(mid -0.192463 0.399794)
							(end -0.254 0.254)
						)
						(xy -0.254 -0.254)
						(arc
							(start -0.253746 -0.254)
							(mid -0.192968 -0.398936)
							(end -0.04699 -0.4572)
						)
						(arc
							(start 0.04699 -0.4572)
							(mid 0.192989 -0.398958)
							(end 0.253746 -0.254)
						)
						(xy 0.254 -0.254)
						(arc
							(start 0.254 0.254)
							(mid 0.192404 0.399734)
							(end 0.044958 0.4572)
						)
					)
					(width 0)
					(fill yes)
				)
			)
		)
		(pad "C" smd custom
			(at 0 -0.7112)
			(size 0.127 0.127)
			(layers "F.Cu" "F.Mask" "F.Paste")
			(net "P12V_A")
			(options
				(clearance outline)
				(anchor circle)
			)
			(primitives
				(gr_poly
					(pts
						(arc
							(start -0.044958 0.4572)
							(mid -0.192463 0.399794)
							(end -0.254 0.254)
						)
						(xy -0.254 -0.254)
						(arc
							(start -0.253746 -0.254)
							(mid -0.192968 -0.398936)
							(end -0.04699 -0.4572)
						)
						(arc
							(start 0.04699 -0.4572)
							(mid 0.192989 -0.398958)
							(end 0.253746 -0.254)
						)
						(xy 0.254 -0.254)
						(arc
							(start 0.254 0.254)
							(mid 0.192404 0.399734)
							(end 0.044958 0.4572)
						)
					)
					(width 0)
					(fill yes)
				)
			)
		)
		(pad "E" smd custom
			(at 0.508 0.7112)
			(size 0.127 0.127)
			(layers "F.Cu" "F.Mask" "F.Paste")
			(net "P3V3_A_BIAS")
			(options
				(clearance outline)
				(anchor circle)
			)
			(primitives
				(gr_poly
					(pts
						(arc
							(start -0.044958 0.4572)
							(mid -0.192463 0.399794)
							(end -0.254 0.254)
						)
						(xy -0.254 -0.254)
						(arc
							(start -0.253746 -0.254)
							(mid -0.192968 -0.398936)
							(end -0.04699 -0.4572)
						)
						(arc
							(start 0.04699 -0.4572)
							(mid 0.192989 -0.398958)
							(end 0.253746 -0.254)
						)
						(xy 0.254 -0.254)
						(arc
							(start 0.254 0.254)
							(mid 0.192404 0.399734)
							(end 0.044958 0.4572)
						)
					)
					(width 0)
					(fill yes)
				)
			)
		)
	)
	(footprint ""
		(layer "F.Cu")
		(at 239.300004 -14.85011 90)
		(property "Reference" "MONO2"
			(at 0 0 90)
			(layer "F.SilkS")
			(hide yes)
			(effects
				(font
					(size 1.27 1.27)
				)
			)
		)
		(property "Value" "AMP-CONN164-4R-1-GP"
			(at -25.705054 -1.203706 90)
			(unlocked yes)
			(layer "F.Fab")
			(hide yes)
			(effects
				(font
					(size 1.016 1.016)
					(thickness 0.1524)
				)
			)
		)
		(property "Device Type" "PREFIT-164P-890091-1H441"
			(at -25.705054 -2.727706 90)
			(unlocked yes)
			(layer "F.Fab")
			(hide yes)
			(effects
				(font
					(size 1.016 1.016)
					(thickness 0.1524)
				)
			)
		)
		(duplicate_pad_numbers_are_jumpers no)
		(fp_line
			(start 74.5998 -4.1656)
			(end 74.5998 5.4102)
			(stroke
				(width 0.1524)
				(type default)
			)
			(layer "F.SilkS")
		)
		(fp_line
			(start -14.9098 -4.1656)
			(end 74.5998 -4.1656)
			(stroke
				(width 0.1524)
				(type default)
			)
			(layer "F.SilkS")
		)
		(fp_line
			(start 74.5998 5.4102)
			(end -14.9098 5.4102)
			(stroke
				(width 0.1524)
				(type default)
			)
			(layer "F.SilkS")
		)
		(fp_line
			(start -14.9098 5.4102)
			(end -14.9098 -4.1656)
			(stroke
				(width 0.1524)
				(type default)
			)
			(layer "F.SilkS")
		)
		(fp_poly
			(pts
				(xy -14.9098 5.4102) (xy -14.9098 -4.1656) (xy 74.5998 -4.1656) (xy 74.5998 -3.98653) (xy -13.5636 -3.98653)
				(xy -13.5636 3.98653) (xy 23.4442 3.98653) (xy 23.4442 5.3086) (xy 33.8074 5.3086) (xy 33.8074 3.98653)
				(xy 74.5998 3.98653) (xy 74.5998 5.4102)
			)
			(stroke
				(width 0)
				(type default)
			)
			(fill yes)
			(layer "F.SilkS")
		)
		(fp_poly
			(pts
				(arc
					(start -13.1826 -2.99593)
					(mid -13.4366 -3.24993)
					(end -13.1826 -3.50393)
				)
				(arc
					(start -12.6746 -3.50393)
					(mid -12.4206 -3.24993)
					(end -12.6746 -2.99593)
				)
			)
			(stroke
				(width 0)
				(type default)
			)
			(fill yes)
			(layer "F.SilkS")
		)
		(fp_poly
			(pts
				(arc
					(start -13.1826 -0.995934)
					(mid -13.4366 -1.249934)
					(end -13.1826 -1.503934)
				)
				(arc
					(start -12.6746 -1.503934)
					(mid -12.4206 -1.249934)
					(end -12.6746 -0.995934)
				)
			)
			(stroke
				(width 0)
				(type default)
			)
			(fill yes)
			(layer "F.SilkS")
		)
		(fp_poly
			(pts
				(arc
					(start -13.1826 1.503934)
					(mid -13.4366 1.249934)
					(end -13.1826 0.995934)
				)
				(arc
					(start -12.6746 0.995934)
					(mid -12.4206 1.249934)
					(end -12.6746 1.503934)
				)
			)
			(stroke
				(width 0)
				(type default)
			)
			(fill yes)
			(layer "F.SilkS")
		)
		(fp_poly
			(pts
				(arc
					(start -13.1826 3.50393)
					(mid -13.4366 3.24993)
					(end -13.1826 2.99593)
				)
				(arc
					(start -12.6746 2.99593)
					(mid -12.4206 3.24993)
					(end -12.6746 3.50393)
				)
			)
			(stroke
				(width 0)
				(type default)
			)
			(fill yes)
			(layer "F.SilkS")
		)
		(fp_rect
			(start -17.1958 8.7884)
			(end 76.8858 -8.7884)
			(stroke
				(width 0)
				(type default)
			)
			(fill no)
			(layer "B.CrtYd")
		)
		(fp_rect
			(start -14.6558 5.1562)
			(end 74.3458 -3.9116)
			(stroke
				(width 0)
				(type default)
			)
			(fill no)
			(layer "F.CrtYd")
		)
		(fp_poly
			(pts
				(xy -15.1638 5.6642) (xy -15.1638 -4.4196) (xy 74.8538 -4.4196) (xy 74.8538 -0.00635) (xy 74.3458 -0.00635)
				(xy 74.3458 -3.9116) (xy -14.6558 -3.9116) (xy -14.6558 5.1562) (xy 74.3458 5.1562) (xy 74.3458 0.00635)
				(xy 74.8538 0.00635) (xy 74.8538 5.6642)
			)
			(stroke
				(width 0)
				(type default)
			)
			(fill no)
			(layer "F.CrtYd")
		)
		(fp_poly
			(pts
				(xy -19.6596 10.16) (xy -19.6596 0.00635) (xy -15.1638 0.00635) (xy -15.1638 5.6642) (xy 74.8538 5.6642)
				(xy 74.8538 -4.4196) (xy -15.1638 -4.4196) (xy -15.1638 -0.00635) (xy -19.6596 -0.00635) (xy -19.6596 -8.9154)
				(xy 79.3496 -8.9154) (xy 79.3496 10.16)
			)
			(stroke
				(width 0)
				(type default)
			)
			(fill no)
			(layer "F.CrtYd")
		)
		(fp_rect
			(start -17.1958 8.7884)
			(end 76.8858 -8.7884)
			(stroke
				(width 0)
				(type default)
			)
			(fill no)
			(layer "B.Fab")
		)
		(fp_rect
			(start -22.1996 13.7922)
			(end 81.8896 -13.7922)
			(stroke
				(width 0)
				(type default)
			)
			(fill no)
			(layer "B.Fab")
		)
		(fp_rect
			(start -15.1638 5.6642)
			(end 74.8538 -4.4196)
			(stroke
				(width 0)
				(type default)
			)
			(fill no)
			(layer "F.Fab")
		)
		(fp_rect
			(start -19.6596 10.16)
			(end 79.3496 -8.9154)
			(stroke
				(width 0)
				(type default)
			)
			(fill no)
			(layer "F.Fab")
		)
		(fp_rect
			(start -24.6634 15.1638)
			(end 84.3534 -13.9192)
			(stroke
				(width 0)
				(type default)
			)
			(fill no)
			(layer "F.Fab")
		)
		(fp_text user "Press Fit"
			(at 23.495 4.6482 90)
			(unlocked yes)
			(layer "F.SilkS")
			(effects
				(font
					(size 1.016 1.016)
					(thickness 0.1524)
				)
				(justify left)
			)
		)
		(fp_text user "Can not place BGA,CSP,Wave Solder Component"
			(at 2.032 12.2428 90)
			(unlocked yes)
			(layer "B.Fab")
			(effects
				(font
					(size 1.016 1.016)
					(thickness 0.1524)
				)
				(justify left)
			)
		)
		(fp_text user "High Limit 2mm"
			(at 18.8214 9.025636 90)
			(unlocked yes)
			(layer "F.Fab")
			(effects
				(font
					(size 1.016 1.016)
					(thickness 0.1524)
				)
				(justify left)
			)
		)
		(fp_text user "Can not place BGA,CSP,Wave Solder Component"
			(at 2.032 13.7668 90)
			(unlocked yes)
			(layer "F.Fab")
			(effects
				(font
					(size 1.016 1.016)
					(thickness 0.1524)
				)
				(justify left)
			)
		)
		(pad "" np_thru_hole circle
			(at 0 0 90)
			(size 0.254 0.254)
			(drill 2.3622)
			(layers "*.Cu" "*.Mask")
			(clearance 1.4097)
			(thermal_gap 1.4097)
		)
		(pad "" np_thru_hole circle
			(at 73.149968 0 90)
			(size 0.254 0.254)
			(drill 2.3622)
			(layers "*.Cu" "*.Mask")
			(clearance 1.4097)
			(thermal_gap 1.4097)
		)
		(pad "A1" thru_hole circle
			(at -11.649964 -1.249934 90)
			(size 1.0668 1.0668)
			(drill 0.719836)
			(layers "*.Cu" "*.Mask")
			(remove_unused_layers no)
			(net "COMP_A_SEC_INS_N")
			(clearance 0.1905)
			(thermal_gap 0.1905)
		)
		(pad "A2" thru_hole circle
			(at -10.649966 -3.24993 90)
			(size 1.0668 1.0668)
			(drill 0.719836)
			(layers "*.Cu" "*.Mask")
			(remove_unused_layers no)
			(net "P12V_A_COMP")
			(clearance 0.1905)
			(thermal_gap 0.1905)
		)
		(pad "A3" thru_hole circle
			(at -9.649968 -1.249934 90)
			(size 1.0668 1.0668)
			(drill 0.719836)
			(layers "*.Cu" "*.Mask")
			(remove_unused_layers no)
			(net "P12V_A_COMP")
			(clearance 0.1905)
			(thermal_gap 0.1905)
		)
		(pad "A4" thru_hole circle
			(at -8.64997 -3.24993 90)
			(size 1.0668 1.0668)
			(drill 0.719836)
			(layers "*.Cu" "*.Mask")
			(remove_unused_layers no)
			(net "GND")
			(clearance 0.1905)
			(thermal_gap 0.1905)
		)
		(pad "A5" thru_hole circle
			(at -7.649972 -1.249934 90)
			(size 1.0668 1.0668)
			(drill 0.719836)
			(layers "*.Cu" "*.Mask")
			(remove_unused_layers no)
			(net "TP_COMP_A_NCSI_RCLK")
			(clearance 0.1905)
			(thermal_gap 0.1905)
		)
		(pad "A6" thru_hole circle
			(at -6.649974 -3.24993 90)
			(size 1.0668 1.0668)
			(drill 0.719836)
			(layers "*.Cu" "*.Mask")
			(remove_unused_layers no)
			(net "TP_COMP_A_NCSI_RXD0")
			(clearance 0.1905)
			(thermal_gap 0.1905)
		)
		(pad "A7" thru_hole circle
			(at -5.649976 -1.249934 90)
			(size 1.0668 1.0668)
			(drill 0.719836)
			(layers "*.Cu" "*.Mask")
			(remove_unused_layers no)
			(net "TP_COMP_A_NCSI_RXD1")
			(clearance 0.1905)
			(thermal_gap 0.1905)
		)
		(pad "A8" thru_hole circle
			(at -4.649978 -3.24993 90)
			(size 1.0668 1.0668)
			(drill 0.719836)
			(layers "*.Cu" "*.Mask")
			(remove_unused_layers no)
			(net "GND")
			(clearance 0.1905)
			(thermal_gap 0.1905)
		)
		(pad "A9" thru_hole circle
			(at -3.64998 -1.249934 90)
			(size 1.0668 1.0668)
			(drill 0.719836)
			(layers "*.Cu" "*.Mask")
			(remove_unused_layers no)
			(net "PCIE_COMP_A_TO_IOM_A_CLK_4_DP")
			(clearance 0.1905)
			(thermal_gap 0.1905)
		)
		(pad "A10" thru_hole circle
			(at -2.649982 -3.24993 90)
			(size 1.0668 1.0668)
			(drill 0.719836)
			(layers "*.Cu" "*.Mask")
			(remove_unused_layers no)
			(net "PCIE_COMP_A_TO_IOM_A_CLK_4_DN")
			(clearance 0.1905)
			(thermal_gap 0.1905)
		)
		(pad "A11" thru_hole circle
			(at -1.649984 -1.249934 90)
			(size 1.0668 1.0668)
			(drill 0.719836)
			(layers "*.Cu" "*.Mask")
			(remove_unused_layers no)
			(net "GND")
			(clearance 0.1905)
			(thermal_gap 0.1905)
		)
		(pad "A12" thru_hole circle
			(at 1.35001 -3.24993 90)
			(size 1.0668 1.0668)
			(drill 0.719836)
			(layers "*.Cu" "*.Mask")
			(remove_unused_layers no)
			(net "GND")
			(clearance 0.1905)
			(thermal_gap 0.1905)
		)
		(pad "A13" thru_hole circle
			(at 2.350008 -1.249934 90)
			(size 1.0668 1.0668)
			(drill 0.719836)
			(layers "*.Cu" "*.Mask")
			(remove_unused_layers no)
			(net "TP_PCIE_COMP_A_CLK_P5")
			(clearance 0.1905)
			(thermal_gap 0.1905)
		)
		(pad "A14" thru_hole circle
			(at 3.350006 -3.24993 90)
			(size 1.0668 1.0668)
			(drill 0.719836)
			(layers "*.Cu" "*.Mask")
			(remove_unused_layers no)
			(net "TP_PCIE_COMP_A_CLK_N5")
			(clearance 0.1905)
			(thermal_gap 0.1905)
		)
		(pad "A15" thru_hole circle
			(at 4.350004 -1.249934 90)
			(size 1.0668 1.0668)
			(drill 0.719836)
			(layers "*.Cu" "*.Mask")
			(remove_unused_layers no)
			(net "GND")
			(clearance 0.1905)
			(thermal_gap 0.1905)
		)
		(pad "A16" thru_hole circle
			(at 5.350002 -3.24993 90)
			(size 1.0668 1.0668)
			(drill 0.719836)
			(layers "*.Cu" "*.Mask")
			(remove_unused_layers no)
			(net "GND")
			(clearance 0.1905)
			(thermal_gap 0.1905)
		)
		(pad "A17" thru_hole circle
			(at 6.35 -1.249934 90)
			(size 1.0668 1.0668)
			(drill 0.719836)
			(layers "*.Cu" "*.Mask")
			(remove_unused_layers no)
			(net "Net_1399")
			(clearance 0.1905)
			(thermal_gap 0.1905)
		)
		(pad "A18" thru_hole circle
			(at 7.349998 -3.24993 90)
			(size 1.0668 1.0668)
			(drill 0.719836)
			(layers "*.Cu" "*.Mask")
			(remove_unused_layers no)
			(net "Net_1396")
			(clearance 0.1905)
			(thermal_gap 0.1905)
		)
		(pad "A19" thru_hole circle
			(at 8.349996 -1.249934 90)
			(size 1.0668 1.0668)
			(drill 0.719836)
			(layers "*.Cu" "*.Mask")
			(remove_unused_layers no)
			(net "GND")
			(clearance 0.1905)
			(thermal_gap 0.1905)
		)
		(pad "A20" thru_hole circle
			(at 9.349994 -3.24993 90)
			(size 1.0668 1.0668)
			(drill 0.719836)
			(layers "*.Cu" "*.Mask")
			(remove_unused_layers no)
			(net "GND")
			(clearance 0.1905)
			(thermal_gap 0.1905)
		)
		(pad "A21" thru_hole circle
			(at 10.349992 -1.249934 90)
			(size 1.0668 1.0668)
			(drill 0.719836)
			(layers "*.Cu" "*.Mask")
			(remove_unused_layers no)
			(net "Net_1398")
			(clearance 0.1905)
			(thermal_gap 0.1905)
		)
		(pad "A22" thru_hole circle
			(at 11.34999 -3.24993 90)
			(size 1.0668 1.0668)
			(drill 0.719836)
			(layers "*.Cu" "*.Mask")
			(remove_unused_layers no)
			(net "Net_1391")
			(clearance 0.1905)
			(thermal_gap 0.1905)
		)
		(pad "A23" thru_hole circle
			(at 12.349988 -1.249934 90)
			(size 1.0668 1.0668)
			(drill 0.719836)
			(layers "*.Cu" "*.Mask")
			(remove_unused_layers no)
			(net "GND")
			(clearance 0.1905)
			(thermal_gap 0.1905)
		)
		(pad "A24" thru_hole circle
			(at 13.349986 -3.24993 90)
			(size 1.0668 1.0668)
			(drill 0.719836)
			(layers "*.Cu" "*.Mask")
			(remove_unused_layers no)
			(net "GND")
			(clearance 0.1905)
			(thermal_gap 0.1905)
		)
		(pad "A25" thru_hole circle
			(at 14.349984 -1.249934 90)
			(size 1.0668 1.0668)
			(drill 0.719836)
			(layers "*.Cu" "*.Mask")
			(remove_unused_layers no)
			(net "Net_1394")
			(clearance 0.1905)
			(thermal_gap 0.1905)
		)
		(pad "A26" thru_hole circle
			(at 15.349982 -3.24993 90)
			(size 1.0668 1.0668)
			(drill 0.719836)
			(layers "*.Cu" "*.Mask")
			(remove_unused_layers no)
			(net "Net_1390")
			(clearance 0.1905)
			(thermal_gap 0.1905)
		)
		(pad "A27" thru_hole circle
			(at 16.34998 -1.249934 90)
			(size 1.0668 1.0668)
			(drill 0.719836)
			(layers "*.Cu" "*.Mask")
			(remove_unused_layers no)
			(net "GND")
			(clearance 0.1905)
			(thermal_gap 0.1905)
		)
		(pad "A28" thru_hole circle
			(at 17.349978 -3.24993 90)
			(size 1.0668 1.0668)
			(drill 0.719836)
			(layers "*.Cu" "*.Mask")
			(remove_unused_layers no)
			(net "GND")
			(clearance 0.1905)
			(thermal_gap 0.1905)
		)
		(pad "A29" thru_hole circle
			(at 18.349976 -1.249934 90)
			(size 1.0668 1.0668)
			(drill 0.719836)
			(layers "*.Cu" "*.Mask")
			(remove_unused_layers no)
			(net "Net_1388")
			(clearance 0.1905)
			(thermal_gap 0.1905)
		)
		(pad "A30" thru_hole circle
			(at 19.349974 -3.24993 90)
			(size 1.0668 1.0668)
			(drill 0.719836)
			(layers "*.Cu" "*.Mask")
			(remove_unused_layers no)
			(net "Net_1387")
			(clearance 0.1905)
			(thermal_gap 0.1905)
		)
		(pad "A31" thru_hole circle
			(at 20.349972 -1.249934 90)
			(size 1.0668 1.0668)
			(drill 0.719836)
			(layers "*.Cu" "*.Mask")
			(remove_unused_layers no)
			(net "GND")
			(clearance 0.1905)
			(thermal_gap 0.1905)
		)
		(pad "A32" thru_hole circle
			(at 21.34997 -3.24993 90)
			(size 1.0668 1.0668)
			(drill 0.719836)
			(layers "*.Cu" "*.Mask")
			(remove_unused_layers no)
			(net "GND")
			(clearance 0.1905)
			(thermal_gap 0.1905)
		)
		(pad "A33" thru_hole circle
			(at 22.349968 -1.249934 90)
			(size 1.0668 1.0668)
			(drill 0.719836)
			(layers "*.Cu" "*.Mask")
			(remove_unused_layers no)
			(net "PCIE_IOM_A_TO_COMP_A_12_DP")
			(clearance 0.1905)
			(thermal_gap 0.1905)
		)
		(pad "A34" thru_hole circle
			(at 23.349966 -3.24993 90)
			(size 1.0668 1.0668)
			(drill 0.719836)
			(layers "*.Cu" "*.Mask")
			(remove_unused_layers no)
			(net "PCIE_IOM_A_TO_COMP_A_12_DN")
			(clearance 0.1905)
			(thermal_gap 0.1905)
		)
		(pad "A35" thru_hole circle
			(at 24.349964 -1.249934 90)
			(size 1.0668 1.0668)
			(drill 0.719836)
			(layers "*.Cu" "*.Mask")
			(remove_unused_layers no)
			(net "GND")
			(clearance 0.1905)
			(thermal_gap 0.1905)
		)
		(pad "A36" thru_hole circle
			(at 25.349962 -3.24993 90)
			(size 1.0668 1.0668)
			(drill 0.719836)
			(layers "*.Cu" "*.Mask")
			(remove_unused_layers no)
			(net "GND")
			(clearance 0.1905)
			(thermal_gap 0.1905)
		)
		(pad "A37" thru_hole circle
			(at 26.34996 -1.249934 90)
			(size 1.0668 1.0668)
			(drill 0.719836)
			(layers "*.Cu" "*.Mask")
			(remove_unused_layers no)
			(net "PCIE_IOM_A_TO_COMP_A_13_DP")
			(clearance 0.1905)
			(thermal_gap 0.1905)
		)
		(pad "A38" thru_hole circle
			(at 27.349958 -3.24993 90)
			(size 1.0668 1.0668)
			(drill 0.719836)
			(layers "*.Cu" "*.Mask")
			(remove_unused_layers no)
			(net "PCIE_IOM_A_TO_COMP_A_13_DN")
			(clearance 0.1905)
			(thermal_gap 0.1905)
		)
		(pad "A39" thru_hole circle
			(at 28.349956 -1.249934 90)
			(size 1.0668 1.0668)
			(drill 0.719836)
			(layers "*.Cu" "*.Mask")
			(remove_unused_layers no)
			(net "GND")
			(clearance 0.1905)
			(thermal_gap 0.1905)
		)
		(pad "A40" thru_hole circle
			(at 29.349954 -3.24993 90)
			(size 1.0668 1.0668)
			(drill 0.719836)
			(layers "*.Cu" "*.Mask")
			(remove_unused_layers no)
			(net "GND")
			(clearance 0.1905)
			(thermal_gap 0.1905)
		)
		(pad "A41" thru_hole circle
			(at 30.349952 -1.249934 90)
			(size 1.0668 1.0668)
			(drill 0.719836)
			(layers "*.Cu" "*.Mask")
			(remove_unused_layers no)
			(net "PCIE_IOM_A_TO_COMP_A_14_DP")
			(clearance 0.1905)
			(thermal_gap 0.1905)
		)
		(pad "A42" thru_hole circle
			(at 31.34995 -3.24993 90)
			(size 1.0668 1.0668)
			(drill 0.719836)
			(layers "*.Cu" "*.Mask")
			(remove_unused_layers no)
			(net "PCIE_IOM_A_TO_COMP_A_14_DN")
			(clearance 0.1905)
			(thermal_gap 0.1905)
		)
		(pad "A43" thru_hole circle
			(at 32.349948 -1.249934 90)
			(size 1.0668 1.0668)
			(drill 0.719836)
			(layers "*.Cu" "*.Mask")
			(remove_unused_layers no)
			(net "GND")
			(clearance 0.1905)
			(thermal_gap 0.1905)
		)
		(pad "A44" thru_hole circle
			(at 33.349946 -3.24993 90)
			(size 1.0668 1.0668)
			(drill 0.719836)
			(layers "*.Cu" "*.Mask")
			(remove_unused_layers no)
			(net "GND")
			(clearance 0.1905)
			(thermal_gap 0.1905)
		)
		(pad "A45" thru_hole circle
			(at 34.349944 -1.249934 90)
			(size 1.0668 1.0668)
			(drill 0.719836)
			(layers "*.Cu" "*.Mask")
			(remove_unused_layers no)
			(net "PCIE_IOM_A_TO_COMP_A_15_DP")
			(clearance 0.1905)
			(thermal_gap 0.1905)
		)
		(pad "A46" thru_hole circle
			(at 35.349942 -3.24993 90)
			(size 1.0668 1.0668)
			(drill 0.719836)
			(layers "*.Cu" "*.Mask")
			(remove_unused_layers no)
			(net "PCIE_IOM_A_TO_COMP_A_15_DN")
			(clearance 0.1905)
			(thermal_gap 0.1905)
		)
		(pad "A47" thru_hole circle
			(at 36.34994 -1.249934 90)
			(size 1.0668 1.0668)
			(drill 0.719836)
			(layers "*.Cu" "*.Mask")
			(remove_unused_layers no)
			(net "GND")
			(clearance 0.1905)
			(thermal_gap 0.1905)
		)
		(pad "A48" thru_hole circle
			(at 37.349938 -3.24993 90)
			(size 1.0668 1.0668)
			(drill 0.719836)
			(layers "*.Cu" "*.Mask")
			(remove_unused_layers no)
			(net "GND")
			(clearance 0.1905)
			(thermal_gap 0.1905)
		)
		(pad "A49" thru_hole circle
			(at 38.349936 -1.249934 90)
			(size 1.0668 1.0668)
			(drill 0.719836)
			(layers "*.Cu" "*.Mask")
			(remove_unused_layers no)
			(net "PCIE_IOM_A_TO_COMP_A_16_DP")
			(clearance 0.1905)
			(thermal_gap 0.1905)
		)
		(pad "A50" thru_hole circle
			(at 39.349934 -3.24993 90)
			(size 1.0668 1.0668)
			(drill 0.719836)
			(layers "*.Cu" "*.Mask")
			(remove_unused_layers no)
			(net "PCIE_IOM_A_TO_COMP_A_16_DN")
			(clearance 0.1905)
			(thermal_gap 0.1905)
		)
		(pad "A51" thru_hole circle
			(at 40.349932 -1.249934 90)
			(size 1.0668 1.0668)
			(drill 0.719836)
			(layers "*.Cu" "*.Mask")
			(remove_unused_layers no)
			(net "GND")
			(clearance 0.1905)
			(thermal_gap 0.1905)
		)
		(pad "A52" thru_hole circle
			(at 41.34993 -3.24993 90)
			(size 1.0668 1.0668)
			(drill 0.719836)
			(layers "*.Cu" "*.Mask")
			(remove_unused_layers no)
			(net "GND")
			(clearance 0.1905)
			(thermal_gap 0.1905)
		)
		(pad "A53" thru_hole circle
			(at 42.349928 -1.249934 90)
			(size 1.0668 1.0668)
			(drill 0.719836)
			(layers "*.Cu" "*.Mask")
			(remove_unused_layers no)
			(net "PCIE_IOM_A_TO_COMP_A_17_DP")
			(clearance 0.1905)
			(thermal_gap 0.1905)
		)
		(pad "A54" thru_hole circle
			(at 43.349926 -3.24993 90)
			(size 1.0668 1.0668)
			(drill 0.719836)
			(layers "*.Cu" "*.Mask")
			(remove_unused_layers no)
			(net "PCIE_IOM_A_TO_COMP_A_17_DN")
			(clearance 0.1905)
			(thermal_gap 0.1905)
		)
		(pad "A55" thru_hole circle
			(at 44.349924 -1.249934 90)
			(size 1.0668 1.0668)
			(drill 0.719836)
			(layers "*.Cu" "*.Mask")
			(remove_unused_layers no)
			(net "GND")
			(clearance 0.1905)
			(thermal_gap 0.1905)
		)
		(pad "A56" thru_hole circle
			(at 45.349922 -3.24993 90)
			(size 1.0668 1.0668)
			(drill 0.719836)
			(layers "*.Cu" "*.Mask")
			(remove_unused_layers no)
			(net "GND")
			(clearance 0.1905)
			(thermal_gap 0.1905)
		)
		(pad "A57" thru_hole circle
			(at 46.34992 -1.249934 90)
			(size 1.0668 1.0668)
			(drill 0.719836)
			(layers "*.Cu" "*.Mask")
			(remove_unused_layers no)
			(net "PCIE_IOM_A_TO_COMP_A_18_DP")
			(clearance 0.1905)
			(thermal_gap 0.1905)
		)
		(pad "A58" thru_hole circle
			(at 47.349918 -3.24993 90)
			(size 1.0668 1.0668)
			(drill 0.719836)
			(layers "*.Cu" "*.Mask")
			(remove_unused_layers no)
			(net "PCIE_IOM_A_TO_COMP_A_18_DN")
			(clearance 0.1905)
			(thermal_gap 0.1905)
		)
		(pad "A59" thru_hole circle
			(at 48.349916 -1.249934 90)
			(size 1.0668 1.0668)
			(drill 0.719836)
			(layers "*.Cu" "*.Mask")
			(remove_unused_layers no)
			(net "GND")
			(clearance 0.1905)
			(thermal_gap 0.1905)
		)
		(pad "A60" thru_hole circle
			(at 49.349914 -3.24993 90)
			(size 1.0668 1.0668)
			(drill 0.719836)
			(layers "*.Cu" "*.Mask")
			(remove_unused_layers no)
			(net "GND")
			(clearance 0.1905)
			(thermal_gap 0.1905)
		)
		(pad "A61" thru_hole circle
			(at 50.349912 -1.249934 90)
			(size 1.0668 1.0668)
			(drill 0.719836)
			(layers "*.Cu" "*.Mask")
			(remove_unused_layers no)
			(net "PCIE_IOM_A_TO_COMP_A_19_DP")
			(clearance 0.1905)
			(thermal_gap 0.1905)
		)
		(pad "A62" thru_hole circle
			(at 51.34991 -3.24993 90)
			(size 1.0668 1.0668)
			(drill 0.719836)
			(layers "*.Cu" "*.Mask")
			(remove_unused_layers no)
			(net "PCIE_IOM_A_TO_COMP_A_19_DN")
			(clearance 0.1905)
			(thermal_gap 0.1905)
		)
		(pad "A63" thru_hole circle
			(at 52.349908 -1.249934 90)
			(size 1.0668 1.0668)
			(drill 0.719836)
			(layers "*.Cu" "*.Mask")
			(remove_unused_layers no)
			(net "GND")
			(clearance 0.1905)
			(thermal_gap 0.1905)
		)
		(pad "A64" thru_hole circle
			(at 53.349906 -3.24993 90)
			(size 1.0668 1.0668)
			(drill 0.719836)
			(layers "*.Cu" "*.Mask")
			(remove_unused_layers no)
			(net "GND")
			(clearance 0.1905)
			(thermal_gap 0.1905)
		)
		(pad "A65" thru_hole circle
			(at 54.349904 -1.249934 90)
			(size 1.0668 1.0668)
			(drill 0.719836)
			(layers "*.Cu" "*.Mask")
			(remove_unused_layers no)
			(net "PCIE_IOM_A_TO_COMP_A_20_DP")
			(clearance 0.1905)
			(thermal_gap 0.1905)
		)
		(pad "A66" thru_hole circle
			(at 55.349902 -3.24993 90)
			(size 1.0668 1.0668)
			(drill 0.719836)
			(layers "*.Cu" "*.Mask")
			(remove_unused_layers no)
			(net "PCIE_IOM_A_TO_COMP_A_20_DN")
			(clearance 0.1905)
			(thermal_gap 0.1905)
		)
		(pad "A67" thru_hole circle
			(at 56.3499 -1.249934 90)
			(size 1.0668 1.0668)
			(drill 0.719836)
			(layers "*.Cu" "*.Mask")
			(remove_unused_layers no)
			(net "GND")
			(clearance 0.1905)
			(thermal_gap 0.1905)
		)
		(pad "A68" thru_hole circle
			(at 57.349898 -3.24993 90)
			(size 1.0668 1.0668)
			(drill 0.719836)
			(layers "*.Cu" "*.Mask")
			(remove_unused_layers no)
			(net "GND")
			(clearance 0.1905)
			(thermal_gap 0.1905)
		)
		(pad "A69" thru_hole circle
			(at 58.349896 -1.249934 90)
			(size 1.0668 1.0668)
			(drill 0.719836)
			(layers "*.Cu" "*.Mask")
			(remove_unused_layers no)
			(net "PCIE_IOM_A_TO_COMP_A_21_DP")
			(clearance 0.1905)
			(thermal_gap 0.1905)
		)
		(pad "A70" thru_hole circle
			(at 59.349894 -3.24993 90)
			(size 1.0668 1.0668)
			(drill 0.719836)
			(layers "*.Cu" "*.Mask")
			(remove_unused_layers no)
			(net "PCIE_IOM_A_TO_COMP_A_21_DN")
			(clearance 0.1905)
			(thermal_gap 0.1905)
		)
		(pad "A71" thru_hole circle
			(at 60.349892 -1.249934 90)
			(size 1.0668 1.0668)
			(drill 0.719836)
			(layers "*.Cu" "*.Mask")
			(remove_unused_layers no)
			(net "GND")
			(clearance 0.1905)
			(thermal_gap 0.1905)
		)
		(pad "A72" thru_hole circle
			(at 61.34989 -3.24993 90)
			(size 1.0668 1.0668)
			(drill 0.719836)
			(layers "*.Cu" "*.Mask")
			(remove_unused_layers no)
			(net "GND")
			(clearance 0.1905)
			(thermal_gap 0.1905)
		)
		(pad "A73" thru_hole circle
			(at 62.349888 -1.249934 90)
			(size 1.0668 1.0668)
			(drill 0.719836)
			(layers "*.Cu" "*.Mask")
			(remove_unused_layers no)
			(net "PCIE_IOM_A_TO_COMP_A_22_DP")
			(clearance 0.1905)
			(thermal_gap 0.1905)
		)
		(pad "A74" thru_hole circle
			(at 63.349886 -3.24993 90)
			(size 1.0668 1.0668)
			(drill 0.719836)
			(layers "*.Cu" "*.Mask")
			(remove_unused_layers no)
			(net "PCIE_IOM_A_TO_COMP_A_22_DN")
			(clearance 0.1905)
			(thermal_gap 0.1905)
		)
		(pad "A75" thru_hole circle
			(at 64.349884 -1.249934 90)
			(size 1.0668 1.0668)
			(drill 0.719836)
			(layers "*.Cu" "*.Mask")
			(remove_unused_layers no)
			(net "GND")
			(clearance 0.1905)
			(thermal_gap 0.1905)
		)
		(pad "A76" thru_hole circle
			(at 65.349882 -3.24993 90)
			(size 1.0668 1.0668)
			(drill 0.719836)
			(layers "*.Cu" "*.Mask")
			(remove_unused_layers no)
			(net "GND")
			(clearance 0.1905)
			(thermal_gap 0.1905)
		)
		(pad "A77" thru_hole circle
			(at 66.34988 -1.249934 90)
			(size 1.0668 1.0668)
			(drill 0.719836)
			(layers "*.Cu" "*.Mask")
			(remove_unused_layers no)
			(net "PCIE_IOM_A_TO_COMP_A_23_DP")
			(clearance 0.1905)
			(thermal_gap 0.1905)
		)
		(pad "A78" thru_hole circle
			(at 67.349878 -3.24993 90)
			(size 1.0668 1.0668)
			(drill 0.719836)
			(layers "*.Cu" "*.Mask")
			(remove_unused_layers no)
			(net "PCIE_IOM_A_TO_COMP_A_23_DN")
			(clearance 0.1905)
			(thermal_gap 0.1905)
		)
		(pad "A79" thru_hole circle
			(at 68.349876 -1.249934 90)
			(size 1.0668 1.0668)
			(drill 0.719836)
			(layers "*.Cu" "*.Mask")
			(remove_unused_layers no)
			(net "GND")
			(clearance 0.1905)
			(thermal_gap 0.1905)
		)
		(pad "A80" thru_hole circle
			(at 69.349874 -3.24993 90)
			(size 1.0668 1.0668)
			(drill 0.719836)
			(layers "*.Cu" "*.Mask")
			(remove_unused_layers no)
			(net "GND")
			(clearance 0.1905)
			(thermal_gap 0.1905)
		)
		(pad "A81" thru_hole circle
			(at 70.350126 -1.249934 90)
			(size 1.0668 1.0668)
			(drill 0.719836)
			(layers "*.Cu" "*.Mask")
			(remove_unused_layers no)
			(net "P12V_A_COMP")
			(clearance 0.1905)
			(thermal_gap 0.1905)
		)
		(pad "A82" thru_hole circle
			(at 71.350124 -3.24993 90)
			(size 1.0668 1.0668)
			(drill 0.719836)
			(layers "*.Cu" "*.Mask")
			(remove_unused_layers no)
			(net "P12V_A_COMP")
			(clearance 0.1905)
			(thermal_gap 0.1905)
		)
		(pad "B1" thru_hole circle
			(at -11.649964 1.249934 90)
			(size 1.0668 1.0668)
			(drill 0.719836)
			(layers "*.Cu" "*.Mask")
			(remove_unused_layers no)
			(net "P12V_A_COMP")
			(clearance 0.1905)
			(thermal_gap 0.1905)
		)
		(pad "B2" thru_hole circle
			(at -10.649966 3.24993 90)
			(size 1.0668 1.0668)
			(drill 0.719836)
			(layers "*.Cu" "*.Mask")
			(remove_unused_layers no)
			(net "P12V_A_COMP")
			(clearance 0.1905)
			(thermal_gap 0.1905)
		)
		(pad "B3" thru_hole circle
			(at -9.649968 1.249934 90)
			(size 1.0668 1.0668)
			(drill 0.719836)
			(layers "*.Cu" "*.Mask")
			(remove_unused_layers no)
			(net "P12V_A_COMP")
			(clearance 0.1905)
			(thermal_gap 0.1905)
		)
		(pad "B4" thru_hole circle
			(at -8.64997 3.24993 90)
			(size 1.0668 1.0668)
			(drill 0.719836)
			(layers "*.Cu" "*.Mask")
			(remove_unused_layers no)
			(net "GND")
			(clearance 0.1905)
			(thermal_gap 0.1905)
		)
		(pad "B5" thru_hole circle
			(at -7.649972 1.249934 90)
			(size 1.0668 1.0668)
			(drill 0.719836)
			(layers "*.Cu" "*.Mask")
			(remove_unused_layers no)
			(net "TP_COMP_A_NCSI_TXEN")
			(clearance 0.1905)
			(thermal_gap 0.1905)
		)
		(pad "B6" thru_hole circle
			(at -6.649974 3.24993 90)
			(size 1.0668 1.0668)
			(drill 0.719836)
			(layers "*.Cu" "*.Mask")
			(remove_unused_layers no)
			(net "TP_COMP_A_NCSI_TXD0")
			(clearance 0.1905)
			(thermal_gap 0.1905)
		)
		(pad "B7" thru_hole circle
			(at -5.649976 1.249934 90)
			(size 1.0668 1.0668)
			(drill 0.719836)
			(layers "*.Cu" "*.Mask")
			(remove_unused_layers no)
			(net "TP_COMP_A_NCSI_TXD1")
			(clearance 0.1905)
			(thermal_gap 0.1905)
		)
		(pad "B8" thru_hole circle
			(at -4.649978 3.24993 90)
			(size 1.0668 1.0668)
			(drill 0.719836)
			(layers "*.Cu" "*.Mask")
			(remove_unused_layers no)
			(net "TP_COMP_A_NCSI_CRSDV")
			(clearance 0.1905)
			(thermal_gap 0.1905)
		)
		(pad "B9" thru_hole circle
			(at -3.64998 1.249934 90)
			(size 1.0668 1.0668)
			(drill 0.719836)
			(layers "*.Cu" "*.Mask")
			(remove_unused_layers no)
			(net "TP_COMP_A_NCSI_RXER")
			(clearance 0.1905)
			(thermal_gap 0.1905)
		)
		(pad "B10" thru_hole circle
			(at -2.649982 3.24993 90)
			(size 1.0668 1.0668)
			(drill 0.719836)
			(layers "*.Cu" "*.Mask")
			(remove_unused_layers no)
			(net "GND")
			(clearance 0.1905)
			(thermal_gap 0.1905)
		)
		(pad "B11" thru_hole circle
			(at -1.649984 1.249934 90)
			(size 1.0668 1.0668)
			(drill 0.719836)
			(layers "*.Cu" "*.Mask")
			(remove_unused_layers no)
			(net "PCIE_COMP_A_TO_IOM_A_RST_3")
			(clearance 0.1905)
			(thermal_gap 0.1905)
		)
		(pad "B12" thru_hole circle
			(at 1.35001 3.24993 90)
			(size 1.0668 1.0668)
			(drill 0.719836)
			(layers "*.Cu" "*.Mask")
			(remove_unused_layers no)
			(net "PCIE_COMP_A_TO_IOM_A_RST_4")
			(clearance 0.1905)
			(thermal_gap 0.1905)
		)
		(pad "B13" thru_hole circle
			(at 2.350008 1.249934 90)
			(size 1.0668 1.0668)
			(drill 0.719836)
			(layers "*.Cu" "*.Mask")
			(remove_unused_layers no)
			(net "PCIE_COMP_A_RST_5")
			(clearance 0.1905)
			(thermal_gap 0.1905)
		)
		(pad "B14" thru_hole circle
			(at 3.350006 3.24993 90)
			(size 1.0668 1.0668)
			(drill 0.719836)
			(layers "*.Cu" "*.Mask")
			(remove_unused_layers no)
			(net "GND")
			(clearance 0.1905)
			(thermal_gap 0.1905)
		)
		(pad "B15" thru_hole circle
			(at 4.350004 1.249934 90)
			(size 1.0668 1.0668)
			(drill 0.719836)
			(layers "*.Cu" "*.Mask")
			(remove_unused_layers no)
			(net "Net_1402")
			(clearance 0.1905)
			(thermal_gap 0.1905)
		)
		(pad "B16" thru_hole circle
			(at 5.350002 3.24993 90)
			(size 1.0668 1.0668)
			(drill 0.719836)
			(layers "*.Cu" "*.Mask")
			(remove_unused_layers no)
			(net "Net_1401")
			(clearance 0.1905)
			(thermal_gap 0.1905)
		)
		(pad "B17" thru_hole circle
			(at 6.35 1.249934 90)
			(size 1.0668 1.0668)
			(drill 0.719836)
			(layers "*.Cu" "*.Mask")
			(remove_unused_layers no)
			(net "GND")
			(clearance 0.1905)
			(thermal_gap 0.1905)
		)
		(pad "B18" thru_hole circle
			(at 7.349998 3.24993 90)
			(size 1.0668 1.0668)
			(drill 0.719836)
			(layers "*.Cu" "*.Mask")
			(remove_unused_layers no)
			(net "GND")
			(clearance 0.1905)
			(thermal_gap 0.1905)
		)
		(pad "B19" thru_hole circle
			(at 8.349996 1.249934 90)
			(size 1.0668 1.0668)
			(drill 0.719836)
			(layers "*.Cu" "*.Mask")
			(remove_unused_layers no)
			(net "Net_1397")
			(clearance 0.1905)
			(thermal_gap 0.1905)
		)
		(pad "B20" thru_hole circle
			(at 9.349994 3.24993 90)
			(size 1.0668 1.0668)
			(drill 0.719836)
			(layers "*.Cu" "*.Mask")
			(remove_unused_layers no)
			(net "Net_1400")
			(clearance 0.1905)
			(thermal_gap 0.1905)
		)
		(pad "B21" thru_hole circle
			(at 10.349992 1.249934 90)
			(size 1.0668 1.0668)
			(drill 0.719836)
			(layers "*.Cu" "*.Mask")
			(remove_unused_layers no)
			(net "GND")
			(clearance 0.1905)
			(thermal_gap 0.1905)
		)
		(pad "B22" thru_hole circle
			(at 11.34999 3.24993 90)
			(size 1.0668 1.0668)
			(drill 0.719836)
			(layers "*.Cu" "*.Mask")
			(remove_unused_layers no)
			(net "GND")
			(clearance 0.1905)
			(thermal_gap 0.1905)
		)
		(pad "B23" thru_hole circle
			(at 12.349988 1.249934 90)
			(size 1.0668 1.0668)
			(drill 0.719836)
			(layers "*.Cu" "*.Mask")
			(remove_unused_layers no)
			(net "Net_1393")
			(clearance 0.1905)
			(thermal_gap 0.1905)
		)
		(pad "B24" thru_hole circle
			(at 13.349986 3.24993 90)
			(size 1.0668 1.0668)
			(drill 0.719836)
			(layers "*.Cu" "*.Mask")
			(remove_unused_layers no)
			(net "Net_1395")
			(clearance 0.1905)
			(thermal_gap 0.1905)
		)
		(pad "B25" thru_hole circle
			(at 14.349984 1.249934 90)
			(size 1.0668 1.0668)
			(drill 0.719836)
			(layers "*.Cu" "*.Mask")
			(remove_unused_layers no)
			(net "GND")
			(clearance 0.1905)
			(thermal_gap 0.1905)
		)
		(pad "B26" thru_hole circle
			(at 15.349982 3.24993 90)
			(size 1.0668 1.0668)
			(drill 0.719836)
			(layers "*.Cu" "*.Mask")
			(remove_unused_layers no)
			(net "GND")
			(clearance 0.1905)
			(thermal_gap 0.1905)
		)
		(pad "B27" thru_hole circle
			(at 16.34998 1.249934 90)
			(size 1.0668 1.0668)
			(drill 0.719836)
			(layers "*.Cu" "*.Mask")
			(remove_unused_layers no)
			(net "Net_1392")
			(clearance 0.1905)
			(thermal_gap 0.1905)
		)
		(pad "B28" thru_hole circle
			(at 17.349978 3.24993 90)
			(size 1.0668 1.0668)
			(drill 0.719836)
			(layers "*.Cu" "*.Mask")
			(remove_unused_layers no)
			(net "Net_1389")
			(clearance 0.1905)
			(thermal_gap 0.1905)
		)
		(pad "B29" thru_hole circle
			(at 18.349976 1.249934 90)
			(size 1.0668 1.0668)
			(drill 0.719836)
			(layers "*.Cu" "*.Mask")
			(remove_unused_layers no)
			(net "GND")
			(clearance 0.1905)
			(thermal_gap 0.1905)
		)
		(pad "B30" thru_hole circle
			(at 19.349974 3.24993 90)
			(size 1.0668 1.0668)
			(drill 0.719836)
			(layers "*.Cu" "*.Mask")
			(remove_unused_layers no)
			(net "GND")
			(clearance 0.1905)
			(thermal_gap 0.1905)
		)
		(pad "B31" thru_hole circle
			(at 20.349972 1.249934 90)
			(size 1.0668 1.0668)
			(drill 0.719836)
			(layers "*.Cu" "*.Mask")
			(remove_unused_layers no)
			(net "PCIE_COMP_A_TO_IOM_A_CLK_3_DP")
			(clearance 0.1905)
			(thermal_gap 0.1905)
		)
		(pad "B32" thru_hole circle
			(at 21.34997 3.24993 90)
			(size 1.0668 1.0668)
			(drill 0.719836)
			(layers "*.Cu" "*.Mask")
			(remove_unused_layers no)
			(net "PCIE_COMP_A_TO_IOM_A_CLK_3_DN")
			(clearance 0.1905)
			(thermal_gap 0.1905)
		)
		(pad "B33" thru_hole circle
			(at 22.349968 1.249934 90)
			(size 1.0668 1.0668)
			(drill 0.719836)
			(layers "*.Cu" "*.Mask")
			(remove_unused_layers no)
			(net "GND")
			(clearance 0.1905)
			(thermal_gap 0.1905)
		)
		(pad "B34" thru_hole circle
			(at 23.349966 3.24993 90)
			(size 1.0668 1.0668)
			(drill 0.719836)
			(layers "*.Cu" "*.Mask")
			(remove_unused_layers no)
			(net "GND")
			(clearance 0.1905)
			(thermal_gap 0.1905)
		)
		(pad "B35" thru_hole circle
			(at 24.349964 1.249934 90)
			(size 1.0668 1.0668)
			(drill 0.719836)
			(layers "*.Cu" "*.Mask")
			(remove_unused_layers no)
			(net "PCIE_COMP_A_TO_IOM_A_12_DP")
			(clearance 0.1905)
			(thermal_gap 0.1905)
		)
		(pad "B36" thru_hole circle
			(at 25.349962 3.24993 90)
			(size 1.0668 1.0668)
			(drill 0.719836)
			(layers "*.Cu" "*.Mask")
			(remove_unused_layers no)
			(net "PCIE_COMP_A_TO_IOM_A_12_DN")
			(clearance 0.1905)
			(thermal_gap 0.1905)
		)
		(pad "B37" thru_hole circle
			(at 26.34996 1.249934 90)
			(size 1.0668 1.0668)
			(drill 0.719836)
			(layers "*.Cu" "*.Mask")
			(remove_unused_layers no)
			(net "GND")
			(clearance 0.1905)
			(thermal_gap 0.1905)
		)
		(pad "B38" thru_hole circle
			(at 27.349958 3.24993 90)
			(size 1.0668 1.0668)
			(drill 0.719836)
			(layers "*.Cu" "*.Mask")
			(remove_unused_layers no)
			(net "GND")
			(clearance 0.1905)
			(thermal_gap 0.1905)
		)
		(pad "B39" thru_hole circle
			(at 28.349956 1.249934 90)
			(size 1.0668 1.0668)
			(drill 0.719836)
			(layers "*.Cu" "*.Mask")
			(remove_unused_layers no)
			(net "PCIE_COMP_A_TO_IOM_A_13_DP")
			(clearance 0.1905)
			(thermal_gap 0.1905)
		)
		(pad "B40" thru_hole circle
			(at 29.349954 3.24993 90)
			(size 1.0668 1.0668)
			(drill 0.719836)
			(layers "*.Cu" "*.Mask")
			(remove_unused_layers no)
			(net "PCIE_COMP_A_TO_IOM_A_13_DN")
			(clearance 0.1905)
			(thermal_gap 0.1905)
		)
		(pad "B41" thru_hole circle
			(at 30.349952 1.249934 90)
			(size 1.0668 1.0668)
			(drill 0.719836)
			(layers "*.Cu" "*.Mask")
			(remove_unused_layers no)
			(net "GND")
			(clearance 0.1905)
			(thermal_gap 0.1905)
		)
		(pad "B42" thru_hole circle
			(at 31.34995 3.24993 90)
			(size 1.0668 1.0668)
			(drill 0.719836)
			(layers "*.Cu" "*.Mask")
			(remove_unused_layers no)
			(net "GND")
			(clearance 0.1905)
			(thermal_gap 0.1905)
		)
		(pad "B43" thru_hole circle
			(at 32.349948 1.249934 90)
			(size 1.0668 1.0668)
			(drill 0.719836)
			(layers "*.Cu" "*.Mask")
			(remove_unused_layers no)
			(net "PCIE_COMP_A_TO_IOM_A_14_DP")
			(clearance 0.1905)
			(thermal_gap 0.1905)
		)
		(pad "B44" thru_hole circle
			(at 33.349946 3.24993 90)
			(size 1.0668 1.0668)
			(drill 0.719836)
			(layers "*.Cu" "*.Mask")
			(remove_unused_layers no)
			(net "PCIE_COMP_A_TO_IOM_A_14_DN")
			(clearance 0.1905)
			(thermal_gap 0.1905)
		)
		(pad "B45" thru_hole circle
			(at 34.349944 1.249934 90)
			(size 1.0668 1.0668)
			(drill 0.719836)
			(layers "*.Cu" "*.Mask")
			(remove_unused_layers no)
			(net "GND")
			(clearance 0.1905)
			(thermal_gap 0.1905)
		)
		(pad "B46" thru_hole circle
			(at 35.349942 3.24993 90)
			(size 1.0668 1.0668)
			(drill 0.719836)
			(layers "*.Cu" "*.Mask")
			(remove_unused_layers no)
			(net "GND")
			(clearance 0.1905)
			(thermal_gap 0.1905)
		)
		(pad "B47" thru_hole circle
			(at 36.34994 1.249934 90)
			(size 1.0668 1.0668)
			(drill 0.719836)
			(layers "*.Cu" "*.Mask")
			(remove_unused_layers no)
			(net "PCIE_COMP_A_TO_IOM_A_15_DP")
			(clearance 0.1905)
			(thermal_gap 0.1905)
		)
		(pad "B48" thru_hole circle
			(at 37.349938 3.24993 90)
			(size 1.0668 1.0668)
			(drill 0.719836)
			(layers "*.Cu" "*.Mask")
			(remove_unused_layers no)
			(net "PCIE_COMP_A_TO_IOM_A_15_DN")
			(clearance 0.1905)
			(thermal_gap 0.1905)
		)
		(pad "B49" thru_hole circle
			(at 38.349936 1.249934 90)
			(size 1.0668 1.0668)
			(drill 0.719836)
			(layers "*.Cu" "*.Mask")
			(remove_unused_layers no)
			(net "GND")
			(clearance 0.1905)
			(thermal_gap 0.1905)
		)
		(pad "B50" thru_hole circle
			(at 39.349934 3.24993 90)
			(size 1.0668 1.0668)
			(drill 0.719836)
			(layers "*.Cu" "*.Mask")
			(remove_unused_layers no)
			(net "GND")
			(clearance 0.1905)
			(thermal_gap 0.1905)
		)
		(pad "B51" thru_hole circle
			(at 40.349932 1.249934 90)
			(size 1.0668 1.0668)
			(drill 0.719836)
			(layers "*.Cu" "*.Mask")
			(remove_unused_layers no)
			(net "PCIE_COMP_A_TO_IOM_A_16_DP")
			(clearance 0.1905)
			(thermal_gap 0.1905)
		)
		(pad "B52" thru_hole circle
			(at 41.34993 3.24993 90)
			(size 1.0668 1.0668)
			(drill 0.719836)
			(layers "*.Cu" "*.Mask")
			(remove_unused_layers no)
			(net "PCIE_COMP_A_TO_IOM_A_16_DN")
			(clearance 0.1905)
			(thermal_gap 0.1905)
		)
		(pad "B53" thru_hole circle
			(at 42.349928 1.249934 90)
			(size 1.0668 1.0668)
			(drill 0.719836)
			(layers "*.Cu" "*.Mask")
			(remove_unused_layers no)
			(net "GND")
			(clearance 0.1905)
			(thermal_gap 0.1905)
		)
		(pad "B54" thru_hole circle
			(at 43.349926 3.24993 90)
			(size 1.0668 1.0668)
			(drill 0.719836)
			(layers "*.Cu" "*.Mask")
			(remove_unused_layers no)
			(net "GND")
			(clearance 0.1905)
			(thermal_gap 0.1905)
		)
		(pad "B55" thru_hole circle
			(at 44.349924 1.249934 90)
			(size 1.0668 1.0668)
			(drill 0.719836)
			(layers "*.Cu" "*.Mask")
			(remove_unused_layers no)
			(net "PCIE_COMP_A_TO_IOM_A_17_DP")
			(clearance 0.1905)
			(thermal_gap 0.1905)
		)
		(pad "B56" thru_hole circle
			(at 45.349922 3.24993 90)
			(size 1.0668 1.0668)
			(drill 0.719836)
			(layers "*.Cu" "*.Mask")
			(remove_unused_layers no)
			(net "PCIE_COMP_A_TO_IOM_A_17_DN")
			(clearance 0.1905)
			(thermal_gap 0.1905)
		)
		(pad "B57" thru_hole circle
			(at 46.34992 1.249934 90)
			(size 1.0668 1.0668)
			(drill 0.719836)
			(layers "*.Cu" "*.Mask")
			(remove_unused_layers no)
			(net "GND")
			(clearance 0.1905)
			(thermal_gap 0.1905)
		)
		(pad "B58" thru_hole circle
			(at 47.349918 3.24993 90)
			(size 1.0668 1.0668)
			(drill 0.719836)
			(layers "*.Cu" "*.Mask")
			(remove_unused_layers no)
			(net "GND")
			(clearance 0.1905)
			(thermal_gap 0.1905)
		)
		(pad "B59" thru_hole circle
			(at 48.349916 1.249934 90)
			(size 1.0668 1.0668)
			(drill 0.719836)
			(layers "*.Cu" "*.Mask")
			(remove_unused_layers no)
			(net "PCIE_COMP_A_TO_IOM_A_18_DP")
			(clearance 0.1905)
			(thermal_gap 0.1905)
		)
		(pad "B60" thru_hole circle
			(at 49.349914 3.24993 90)
			(size 1.0668 1.0668)
			(drill 0.719836)
			(layers "*.Cu" "*.Mask")
			(remove_unused_layers no)
			(net "PCIE_COMP_A_TO_IOM_A_18_DN")
			(clearance 0.1905)
			(thermal_gap 0.1905)
		)
		(pad "B61" thru_hole circle
			(at 50.349912 1.249934 90)
			(size 1.0668 1.0668)
			(drill 0.719836)
			(layers "*.Cu" "*.Mask")
			(remove_unused_layers no)
			(net "GND")
			(clearance 0.1905)
			(thermal_gap 0.1905)
		)
		(pad "B62" thru_hole circle
			(at 51.34991 3.24993 90)
			(size 1.0668 1.0668)
			(drill 0.719836)
			(layers "*.Cu" "*.Mask")
			(remove_unused_layers no)
			(net "GND")
			(clearance 0.1905)
			(thermal_gap 0.1905)
		)
		(pad "B63" thru_hole circle
			(at 52.349908 1.249934 90)
			(size 1.0668 1.0668)
			(drill 0.719836)
			(layers "*.Cu" "*.Mask")
			(remove_unused_layers no)
			(net "PCIE_COMP_A_TO_IOM_A_19_DP")
			(clearance 0.1905)
			(thermal_gap 0.1905)
		)
		(pad "B64" thru_hole circle
			(at 53.349906 3.24993 90)
			(size 1.0668 1.0668)
			(drill 0.719836)
			(layers "*.Cu" "*.Mask")
			(remove_unused_layers no)
			(net "PCIE_COMP_A_TO_IOM_A_19_DN")
			(clearance 0.1905)
			(thermal_gap 0.1905)
		)
		(pad "B65" thru_hole circle
			(at 54.349904 1.249934 90)
			(size 1.0668 1.0668)
			(drill 0.719836)
			(layers "*.Cu" "*.Mask")
			(remove_unused_layers no)
			(net "GND")
			(clearance 0.1905)
			(thermal_gap 0.1905)
		)
		(pad "B66" thru_hole circle
			(at 55.349902 3.24993 90)
			(size 1.0668 1.0668)
			(drill 0.719836)
			(layers "*.Cu" "*.Mask")
			(remove_unused_layers no)
			(net "GND")
			(clearance 0.1905)
			(thermal_gap 0.1905)
		)
		(pad "B67" thru_hole circle
			(at 56.3499 1.249934 90)
			(size 1.0668 1.0668)
			(drill 0.719836)
			(layers "*.Cu" "*.Mask")
			(remove_unused_layers no)
			(net "PCIE_COMP_A_TO_IOM_A_20_DP")
			(clearance 0.1905)
			(thermal_gap 0.1905)
		)
		(pad "B68" thru_hole circle
			(at 57.349898 3.24993 90)
			(size 1.0668 1.0668)
			(drill 0.719836)
			(layers "*.Cu" "*.Mask")
			(remove_unused_layers no)
			(net "PCIE_COMP_A_TO_IOM_A_20_DN")
			(clearance 0.1905)
			(thermal_gap 0.1905)
		)
		(pad "B69" thru_hole circle
			(at 58.349896 1.249934 90)
			(size 1.0668 1.0668)
			(drill 0.719836)
			(layers "*.Cu" "*.Mask")
			(remove_unused_layers no)
			(net "GND")
			(clearance 0.1905)
			(thermal_gap 0.1905)
		)
		(pad "B70" thru_hole circle
			(at 59.349894 3.24993 90)
			(size 1.0668 1.0668)
			(drill 0.719836)
			(layers "*.Cu" "*.Mask")
			(remove_unused_layers no)
			(net "GND")
			(clearance 0.1905)
			(thermal_gap 0.1905)
		)
		(pad "B71" thru_hole circle
			(at 60.349892 1.249934 90)
			(size 1.0668 1.0668)
			(drill 0.719836)
			(layers "*.Cu" "*.Mask")
			(remove_unused_layers no)
			(net "PCIE_COMP_A_TO_IOM_A_21_DP")
			(clearance 0.1905)
			(thermal_gap 0.1905)
		)
		(pad "B72" thru_hole circle
			(at 61.34989 3.24993 90)
			(size 1.0668 1.0668)
			(drill 0.719836)
			(layers "*.Cu" "*.Mask")
			(remove_unused_layers no)
			(net "PCIE_COMP_A_TO_IOM_A_21_DN")
			(clearance 0.1905)
			(thermal_gap 0.1905)
		)
		(pad "B73" thru_hole circle
			(at 62.349888 1.249934 90)
			(size 1.0668 1.0668)
			(drill 0.719836)
			(layers "*.Cu" "*.Mask")
			(remove_unused_layers no)
			(net "GND")
			(clearance 0.1905)
			(thermal_gap 0.1905)
		)
		(pad "B74" thru_hole circle
			(at 63.349886 3.24993 90)
			(size 1.0668 1.0668)
			(drill 0.719836)
			(layers "*.Cu" "*.Mask")
			(remove_unused_layers no)
			(net "GND")
			(clearance 0.1905)
			(thermal_gap 0.1905)
		)
		(pad "B75" thru_hole circle
			(at 64.349884 1.249934 90)
			(size 1.0668 1.0668)
			(drill 0.719836)
			(layers "*.Cu" "*.Mask")
			(remove_unused_layers no)
			(net "PCIE_COMP_A_TO_IOM_A_22_DP")
			(clearance 0.1905)
			(thermal_gap 0.1905)
		)
		(pad "B76" thru_hole circle
			(at 65.349882 3.24993 90)
			(size 1.0668 1.0668)
			(drill 0.719836)
			(layers "*.Cu" "*.Mask")
			(remove_unused_layers no)
			(net "PCIE_COMP_A_TO_IOM_A_22_DN")
			(clearance 0.1905)
			(thermal_gap 0.1905)
		)
		(pad "B77" thru_hole circle
			(at 66.34988 1.249934 90)
			(size 1.0668 1.0668)
			(drill 0.719836)
			(layers "*.Cu" "*.Mask")
			(remove_unused_layers no)
			(net "GND")
			(clearance 0.1905)
			(thermal_gap 0.1905)
		)
		(pad "B78" thru_hole circle
			(at 67.349878 3.24993 90)
			(size 1.0668 1.0668)
			(drill 0.719836)
			(layers "*.Cu" "*.Mask")
			(remove_unused_layers no)
			(net "GND")
			(clearance 0.1905)
			(thermal_gap 0.1905)
		)
		(pad "B79" thru_hole circle
			(at 68.349876 1.249934 90)
			(size 1.0668 1.0668)
			(drill 0.719836)
			(layers "*.Cu" "*.Mask")
			(remove_unused_layers no)
			(net "PCIE_COMP_A_TO_IOM_A_23_DP")
			(clearance 0.1905)
			(thermal_gap 0.1905)
		)
		(pad "B80" thru_hole circle
			(at 69.349874 3.24993 90)
			(size 1.0668 1.0668)
			(drill 0.719836)
			(layers "*.Cu" "*.Mask")
			(remove_unused_layers no)
			(net "PCIE_COMP_A_TO_IOM_A_23_DN")
			(clearance 0.1905)
			(thermal_gap 0.1905)
		)
		(pad "B81" thru_hole circle
			(at 70.350126 1.249934 90)
			(size 1.0668 1.0668)
			(drill 0.719836)
			(layers "*.Cu" "*.Mask")
			(remove_unused_layers no)
			(net "GND")
			(clearance 0.1905)
			(thermal_gap 0.1905)
		)
		(pad "B82" thru_hole circle
			(at 71.350124 3.24993 90)
			(size 1.0668 1.0668)
			(drill 0.719836)
			(layers "*.Cu" "*.Mask")
			(remove_unused_layers no)
			(net "COMP_A_POWER_FAIL_N")
			(clearance 0.1905)
			(thermal_gap 0.1905)
		)
		(zone
			(layers "F.Cu" "B.Cu" "In1.Cu" "In2.Cu" "In3.Cu" "In4.Cu" "In5.Cu" "In6.Cu"
				"In7.Cu" "In8.Cu" "In9.Cu" "In10.Cu"
			)
			(hatch none 0.5)
			(connect_pads
				(clearance 0)
			)
			(min_thickness 0.25)
			(keepout
				(tracks not_allowed)
				(vias allowed)
				(pads allowed)
				(copperpour not_allowed)
				(footprints allowed)
			)
			(placement
				(enabled no)
				(sheetname "")
			)
			(fill
				(thermal_gap 0.5)
				(thermal_bridge_width 0.5)
				(island_removal_mode 0)
			)
			(polygon
				(pts
					(arc
						(start 240.785904 -88.000078)
						(mid 237.814104 -88.000078)
						(end 240.785904 -88.000078)
					)
				)
			)
		)
		(zone
			(layers "F.Cu" "B.Cu" "In1.Cu" "In2.Cu" "In3.Cu" "In4.Cu" "In5.Cu" "In6.Cu"
				"In7.Cu" "In8.Cu" "In9.Cu" "In10.Cu"
			)
			(hatch none 0.5)
			(connect_pads
				(clearance 0)
			)
			(min_thickness 0.25)
			(keepout
				(tracks not_allowed)
				(vias allowed)
				(pads allowed)
				(copperpour not_allowed)
				(footprints allowed)
			)
			(placement
				(enabled no)
				(sheetname "")
			)
			(fill
				(thermal_gap 0.5)
				(thermal_bridge_width 0.5)
				(island_removal_mode 0)
			)
			(polygon
				(pts
					(arc
						(start 240.785904 -14.85011)
						(mid 237.814104 -14.85011)
						(end 240.785904 -14.85011)
					)
				)
			)
		)
	)
	(footprint ""
		(layer "F.Cu")
		(at 468.354918 -164.701474)
		(property "Reference" "R674"
			(at 0 0 0)
			(layer "F.SilkS")
			(hide yes)
			(effects
				(font
					(size 1.27 1.27)
				)
			)
		)
		(property "Value" "4K7R2J-2-GP"
			(at 0.064008 -3.993896 0)
			(unlocked yes)
			(layer "F.Fab")
			(hide yes)
			(effects
				(font
					(size 1.016 1.016)
					(thickness 0.1524)
				)
			)
		)
		(property "Device Type" "R402H16"
			(at 0.064008 -5.517896 0)
			(unlocked yes)
			(layer "F.Fab")
			(hide yes)
			(effects
				(font
					(size 1.016 1.016)
					(thickness 0.1524)
				)
			)
		)
		(duplicate_pad_numbers_are_jumpers no)
		(fp_line
			(start -0.508 -0.9398)
			(end -0.508 0.9398)
			(stroke
				(width 0.1524)
				(type default)
			)
			(layer "F.SilkS")
		)
		(fp_line
			(start 0.508 -0.9398)
			(end -0.508 -0.9398)
			(stroke
				(width 0.1524)
				(type default)
			)
			(layer "F.SilkS")
		)
		(fp_rect
			(start -0.508 0.9398)
			(end 0.508 -0.9398)
			(stroke
				(width 0)
				(type default)
			)
			(fill no)
			(layer "F.CrtYd")
		)
		(fp_rect
			(start -0.508 0.9398)
			(end 0.508 -0.9398)
			(stroke
				(width 0)
				(type default)
			)
			(fill no)
			(layer "F.Fab")
		)
		(pad "1" smd custom
			(at 0 -0.4445)
			(size 0.1397 0.1397)
			(layers "F.Cu" "F.Mask" "F.Paste")
			(net "P12V_A")
			(options
				(clearance outline)
				(anchor circle)
			)
			(primitives
				(gr_poly
					(pts
						(arc
							(start -0.1778 -0.2794)
							(mid -0.249642 -0.249642)
							(end -0.2794 -0.1778)
						)
						(arc
							(start -0.2794 0.1778)
							(mid -0.249642 0.249642)
							(end -0.1778 0.2794)
						)
						(arc
							(start 0.1778 0.2794)
							(mid 0.249642 0.249642)
							(end 0.2794 0.1778)
						)
						(arc
							(start 0.2794 -0.1778)
							(mid 0.249642 -0.249642)
							(end 0.1778 -0.2794)
						)
					)
					(width 0)
					(fill yes)
				)
			)
		)
		(pad "2" smd custom
			(at 0 0.4445)
			(size 0.1397 0.1397)
			(layers "F.Cu" "F.Mask" "F.Paste")
			(net "SW_HDD_R23")
			(options
				(clearance outline)
				(anchor circle)
			)
			(primitives
				(gr_poly
					(pts
						(arc
							(start -0.1778 -0.2794)
							(mid -0.249642 -0.249642)
							(end -0.2794 -0.1778)
						)
						(arc
							(start -0.2794 0.1778)
							(mid -0.249642 0.249642)
							(end -0.1778 0.2794)
						)
						(arc
							(start 0.1778 0.2794)
							(mid 0.249642 0.249642)
							(end 0.2794 0.1778)
						)
						(arc
							(start 0.2794 -0.1778)
							(mid 0.249642 -0.249642)
							(end 0.1778 -0.2794)
						)
					)
					(width 0)
					(fill yes)
				)
			)
		)
	)
	(footprint ""
		(layer "F.Cu")
		(at 266.201398 -109.157262 -90)
		(property "Reference" "R361"
			(at 0 0 270)
			(layer "F.SilkS")
			(hide yes)
			(effects
				(font
					(size 1.27 1.27)
				)
			)
		)
		(property "Value" "0R2J-2-GP"
			(at 0.064008 -3.993896 270)
			(unlocked yes)
			(layer "F.Fab")
			(hide yes)
			(effects
				(font
					(size 1.016 1.016)
					(thickness 0.1524)
				)
			)
		)
		(property "Device Type" "R402H16"
			(at 0.064008 -5.517896 270)
			(unlocked yes)
			(layer "F.Fab")
			(hide yes)
			(effects
				(font
					(size 1.016 1.016)
					(thickness 0.1524)
				)
			)
		)
		(duplicate_pad_numbers_are_jumpers no)
		(fp_line
			(start -0.508 -0.9398)
			(end -0.508 0.9398)
			(stroke
				(width 0.1524)
				(type default)
			)
			(layer "F.SilkS")
		)
		(fp_line
			(start 0.508 -0.9398)
			(end -0.508 -0.9398)
			(stroke
				(width 0.1524)
				(type default)
			)
			(layer "F.SilkS")
		)
		(fp_rect
			(start -0.508 0.9398)
			(end 0.508 -0.9398)
			(stroke
				(width 0)
				(type default)
			)
			(fill no)
			(layer "F.CrtYd")
		)
		(fp_rect
			(start -0.508 0.9398)
			(end 0.508 -0.9398)
			(stroke
				(width 0)
				(type default)
			)
			(fill no)
			(layer "F.Fab")
		)
		(pad "1" smd custom
			(at 0 -0.4445 270)
			(size 0.1397 0.1397)
			(layers "F.Cu" "F.Mask" "F.Paste")
			(net "SLOT1_SVR_ID0_GPIO2")
			(options
				(clearance outline)
				(anchor circle)
			)
			(primitives
				(gr_poly
					(pts
						(arc
							(start -0.1778 -0.2794)
							(mid -0.249642 -0.249642)
							(end -0.2794 -0.1778)
						)
						(arc
							(start -0.2794 0.1778)
							(mid -0.249642 0.249642)
							(end -0.1778 0.2794)
						)
						(arc
							(start 0.1778 0.2794)
							(mid 0.249642 0.249642)
							(end 0.2794 0.1778)
						)
						(arc
							(start 0.2794 -0.1778)
							(mid 0.249642 -0.249642)
							(end 0.1778 -0.2794)
						)
					)
					(width 0)
					(fill yes)
				)
			)
		)
		(pad "2" smd custom
			(at 0 0.4445 270)
			(size 0.1397 0.1397)
			(layers "F.Cu" "F.Mask" "F.Paste")
			(net "COMP_B_EXP_B_SPARE_0")
			(options
				(clearance outline)
				(anchor circle)
			)
			(primitives
				(gr_poly
					(pts
						(arc
							(start -0.1778 -0.2794)
							(mid -0.249642 -0.249642)
							(end -0.2794 -0.1778)
						)
						(arc
							(start -0.2794 0.1778)
							(mid -0.249642 0.249642)
							(end -0.1778 0.2794)
						)
						(arc
							(start 0.1778 0.2794)
							(mid 0.249642 0.249642)
							(end 0.2794 0.1778)
						)
						(arc
							(start 0.2794 -0.1778)
							(mid 0.249642 -0.249642)
							(end 0.1778 -0.2794)
						)
					)
					(width 0)
					(fill yes)
				)
			)
		)
	)
	(footprint ""
		(layer "F.Cu")
		(at 461.9371 -160.735518 180)
		(property "Reference" "R653"
			(at 0 0 180)
			(layer "F.SilkS")
			(hide yes)
			(effects
				(font
					(size 1.27 1.27)
				)
			)
		)
		(property "Value" "0R2J-2-GP"
			(at 0.064008 -3.993896 180)
			(unlocked yes)
			(layer "F.Fab")
			(hide yes)
			(effects
				(font
					(size 1.016 1.016)
					(thickness 0.1524)
				)
			)
		)
		(property "Device Type" "R402H16"
			(at 0.064008 -5.517896 180)
			(unlocked yes)
			(layer "F.Fab")
			(hide yes)
			(effects
				(font
					(size 1.016 1.016)
					(thickness 0.1524)
				)
			)
		)
		(duplicate_pad_numbers_are_jumpers no)
		(fp_line
			(start 0.508 -0.9398)
			(end -0.508 -0.9398)
			(stroke
				(width 0.1524)
				(type default)
			)
			(layer "F.SilkS")
		)
		(fp_line
			(start -0.508 -0.9398)
			(end -0.508 0.9398)
			(stroke
				(width 0.1524)
				(type default)
			)
			(layer "F.SilkS")
		)
		(fp_rect
			(start -0.508 0.9398)
			(end 0.508 -0.9398)
			(stroke
				(width 0)
				(type default)
			)
			(fill no)
			(layer "F.CrtYd")
		)
		(fp_rect
			(start -0.508 0.9398)
			(end 0.508 -0.9398)
			(stroke
				(width 0)
				(type default)
			)
			(fill no)
			(layer "F.Fab")
		)
		(pad "1" smd custom
			(at 0 -0.4445 180)
			(size 0.1397 0.1397)
			(layers "F.Cu" "F.Mask" "F.Paste")
			(net "SW_HDD_G22")
			(options
				(clearance outline)
				(anchor circle)
			)
			(primitives
				(gr_poly
					(pts
						(arc
							(start -0.1778 -0.2794)
							(mid -0.249642 -0.249642)
							(end -0.2794 -0.1778)
						)
						(arc
							(start -0.2794 0.1778)
							(mid -0.249642 0.249642)
							(end -0.1778 0.2794)
						)
						(arc
							(start 0.1778 0.2794)
							(mid 0.249642 0.249642)
							(end 0.2794 0.1778)
						)
						(arc
							(start 0.2794 -0.1778)
							(mid 0.249642 -0.249642)
							(end 0.1778 -0.2794)
						)
					)
					(width 0)
					(fill yes)
				)
			)
		)
		(pad "2" smd custom
			(at 0 0.4445 180)
			(size 0.1397 0.1397)
			(layers "F.Cu" "F.Mask" "F.Paste")
			(net "SW_HDD_R22")
			(options
				(clearance outline)
				(anchor circle)
			)
			(primitives
				(gr_poly
					(pts
						(arc
							(start -0.1778 -0.2794)
							(mid -0.249642 -0.249642)
							(end -0.2794 -0.1778)
						)
						(arc
							(start -0.2794 0.1778)
							(mid -0.249642 0.249642)
							(end -0.1778 0.2794)
						)
						(arc
							(start 0.1778 0.2794)
							(mid 0.249642 0.249642)
							(end 0.2794 0.1778)
						)
						(arc
							(start 0.2794 -0.1778)
							(mid 0.249642 -0.249642)
							(end 0.1778 -0.2794)
						)
					)
					(width 0)
					(fill yes)
				)
			)
		)
	)
	(footprint ""
		(layer "F.Cu")
		(at 321.634612 -274.219416 -90)
		(property "Reference" "C116"
			(at 0 0 270)
			(layer "F.SilkS")
			(hide yes)
			(effects
				(font
					(size 1.27 1.27)
				)
			)
		)
		(property "Value" "SCD01U16V1KX-GP"
			(at -2.8321 -1.7399 270)
			(unlocked yes)
			(layer "F.Fab")
			(hide yes)
			(effects
				(font
					(size 1.016 1.016)
					(thickness 0.1524)
				)
			)
		)
		(property "Device Type" "C0201H13"
			(at -2.8321 -3.2639 270)
			(unlocked yes)
			(layer "F.Fab")
			(hide yes)
			(effects
				(font
					(size 1.016 1.016)
					(thickness 0.1524)
				)
			)
		)
		(duplicate_pad_numbers_are_jumpers no)
		(fp_rect
			(start -0.2794 0.6477)
			(end 0.2794 -0.6477)
			(stroke
				(width 0)
				(type default)
			)
			(fill no)
			(layer "F.CrtYd")
		)
		(fp_rect
			(start -0.2794 0.6477)
			(end 0.2794 -0.6477)
			(stroke
				(width 0)
				(type default)
			)
			(fill no)
			(layer "F.Fab")
		)
		(pad "1" smd custom
			(at 0 -0.2794 270)
			(size 0.0762 0.0762)
			(layers "F.Cu" "F.Mask" "F.Paste")
			(net "SAS_HDD_RX_N6")
			(options
				(clearance outline)
				(anchor circle)
			)
			(primitives
				(gr_poly
					(pts
						(arc
							(start 0.1524 -0.127)
							(mid 0.137521 -0.162921)
							(end 0.1016 -0.1778)
						)
						(arc
							(start -0.1016 -0.1778)
							(mid -0.137521 -0.162921)
							(end -0.1524 -0.127)
						)
						(arc
							(start -0.1524 0.127)
							(mid -0.137521 0.162921)
							(end -0.1016 0.1778)
						)
						(arc
							(start 0.1016 0.1778)
							(mid 0.137521 0.162921)
							(end 0.1524 0.127)
						)
					)
					(width 0)
					(fill yes)
				)
			)
		)
		(pad "2" smd custom
			(at 0 0.2794 270)
			(size 0.0762 0.0762)
			(layers "F.Cu" "F.Mask" "F.Paste")
			(net "PHY_SCC_A_TO_DRV_A_6_DN")
			(options
				(clearance outline)
				(anchor circle)
			)
			(primitives
				(gr_poly
					(pts
						(arc
							(start 0.1524 -0.127)
							(mid 0.137521 -0.162921)
							(end 0.1016 -0.1778)
						)
						(arc
							(start -0.1016 -0.1778)
							(mid -0.137521 -0.162921)
							(end -0.1524 -0.127)
						)
						(arc
							(start -0.1524 0.127)
							(mid -0.137521 0.162921)
							(end -0.1016 0.1778)
						)
						(arc
							(start 0.1016 0.1778)
							(mid 0.137521 0.162921)
							(end 0.1524 0.127)
						)
					)
					(width 0)
					(fill yes)
				)
			)
		)
	)
	(footprint ""
		(layer "F.Cu")
		(at 256.413 -301.244 180)
		(property "Reference" "R4"
			(at 0 0 180)
			(layer "F.SilkS")
			(hide yes)
			(effects
				(font
					(size 1.27 1.27)
				)
			)
		)
		(property "Value" "0R2J-2-GP"
			(at 0.064008 -3.993896 180)
			(unlocked yes)
			(layer "F.Fab")
			(hide yes)
			(effects
				(font
					(size 1.016 1.016)
					(thickness 0.1524)
				)
			)
		)
		(property "Device Type" "R402H16"
			(at 0.064008 -5.517896 180)
			(unlocked yes)
			(layer "F.Fab")
			(hide yes)
			(effects
				(font
					(size 1.016 1.016)
					(thickness 0.1524)
				)
			)
		)
		(duplicate_pad_numbers_are_jumpers no)
		(fp_line
			(start 0.508 -0.9398)
			(end -0.508 -0.9398)
			(stroke
				(width 0.1524)
				(type default)
			)
			(layer "F.SilkS")
		)
		(fp_line
			(start -0.508 -0.9398)
			(end -0.508 0.9398)
			(stroke
				(width 0.1524)
				(type default)
			)
			(layer "F.SilkS")
		)
		(fp_rect
			(start -0.508 0.9398)
			(end 0.508 -0.9398)
			(stroke
				(width 0)
				(type default)
			)
			(fill no)
			(layer "F.CrtYd")
		)
		(fp_rect
			(start -0.508 0.9398)
			(end 0.508 -0.9398)
			(stroke
				(width 0)
				(type default)
			)
			(fill no)
			(layer "F.Fab")
		)
		(pad "1" smd custom
			(at 0 -0.4445 180)
			(size 0.1397 0.1397)
			(layers "F.Cu" "F.Mask" "F.Paste")
			(net "EEPROM_SCL")
			(options
				(clearance outline)
				(anchor circle)
			)
			(primitives
				(gr_poly
					(pts
						(arc
							(start -0.1778 -0.2794)
							(mid -0.249642 -0.249642)
							(end -0.2794 -0.1778)
						)
						(arc
							(start -0.2794 0.1778)
							(mid -0.249642 0.249642)
							(end -0.1778 0.2794)
						)
						(arc
							(start 0.1778 0.2794)
							(mid 0.249642 0.249642)
							(end 0.2794 0.1778)
						)
						(arc
							(start 0.2794 -0.1778)
							(mid 0.249642 -0.249642)
							(end 0.1778 -0.2794)
						)
					)
					(width 0)
					(fill yes)
				)
			)
		)
		(pad "2" smd custom
			(at 0 0.4445 180)
			(size 0.1397 0.1397)
			(layers "F.Cu" "F.Mask" "F.Paste")
			(net "I2C_DPB_A_SCL_BUF")
			(options
				(clearance outline)
				(anchor circle)
			)
			(primitives
				(gr_poly
					(pts
						(arc
							(start -0.1778 -0.2794)
							(mid -0.249642 -0.249642)
							(end -0.2794 -0.1778)
						)
						(arc
							(start -0.2794 0.1778)
							(mid -0.249642 0.249642)
							(end -0.1778 0.2794)
						)
						(arc
							(start 0.1778 0.2794)
							(mid 0.249642 0.249642)
							(end 0.2794 0.1778)
						)
						(arc
							(start 0.2794 -0.1778)
							(mid 0.249642 -0.249642)
							(end 0.1778 -0.2794)
						)
					)
					(width 0)
					(fill yes)
				)
			)
		)
	)
	(footprint ""
		(layer "F.Cu")
		(at 396.672054 -69.419978 -90)
		(property "Reference" "R867"
			(at 0 0 270)
			(layer "F.SilkS")
			(hide yes)
			(effects
				(font
					(size 1.27 1.27)
				)
			)
		)
		(property "Value" "2R6F-GP"
			(at -0.0508 -4.8514 270)
			(unlocked yes)
			(layer "F.Fab")
			(hide yes)
			(effects
				(font
					(size 1.016 1.016)
					(thickness 0.1524)
				)
			)
		)
		(property "Device Type" "R1206H26"
			(at 0 -6.3754 270)
			(unlocked yes)
			(layer "F.Fab")
			(hide yes)
			(effects
				(font
					(size 1.016 1.016)
					(thickness 0.1524)
				)
			)
		)
		(duplicate_pad_numbers_are_jumpers no)
		(fp_line
			(start -1.016 2.2352)
			(end -1.016 -2.2352)
			(stroke
				(width 0.1524)
				(type default)
			)
			(layer "F.SilkS")
		)
		(fp_line
			(start 1.016 2.2352)
			(end -1.016 2.2352)
			(stroke
				(width 0.1524)
				(type default)
			)
			(layer "F.SilkS")
		)
		(fp_line
			(start -1.016 -2.2352)
			(end 1.016 -2.2352)
			(stroke
				(width 0.1524)
				(type default)
			)
			(layer "F.SilkS")
		)
		(fp_line
			(start 1.016 -2.2352)
			(end 1.016 2.2352)
			(stroke
				(width 0.1524)
				(type default)
			)
			(layer "F.SilkS")
		)
		(fp_rect
			(start -1.0922 2.3114)
			(end 1.0922 -2.3114)
			(stroke
				(width 0)
				(type default)
			)
			(fill no)
			(layer "F.CrtYd")
		)
		(fp_poly
			(pts
				(xy -1.0922 -2.3114) (xy 1.0922 -2.3114) (xy 1.0922 2.3114) (xy -1.0922 2.3114)
			)
			(stroke
				(width 0)
				(type default)
			)
			(fill no)
			(layer "F.Fab")
		)
		(pad "1" smd rect
			(at 0 -1.397 270)
			(size 1.651 1.27)
			(layers "F.Cu" "F.Mask" "F.Paste")
			(net "P12V_HDD32")
		)
		(pad "2" smd rect
			(at 0 1.397 270)
			(size 1.651 1.27)
			(layers "F.Cu" "F.Mask" "F.Paste")
			(net "12V_PRE_32")
		)
	)
	(footprint ""
		(layer "F.Cu")
		(at 473.1258 -179.6288 90)
		(property "Reference" "R660"
			(at 0 0 90)
			(layer "F.SilkS")
			(hide yes)
			(effects
				(font
					(size 1.27 1.27)
				)
			)
		)
		(property "Value" "2R6F-GP"
			(at -0.0508 -4.8514 90)
			(unlocked yes)
			(layer "F.Fab")
			(hide yes)
			(effects
				(font
					(size 1.016 1.016)
					(thickness 0.1524)
				)
			)
		)
		(property "Device Type" "R1206H26"
			(at 0 -6.3754 90)
			(unlocked yes)
			(layer "F.Fab")
			(hide yes)
			(effects
				(font
					(size 1.016 1.016)
					(thickness 0.1524)
				)
			)
		)
		(duplicate_pad_numbers_are_jumpers no)
		(fp_line
			(start 1.016 -2.2352)
			(end 1.016 2.2352)
			(stroke
				(width 0.1524)
				(type default)
			)
			(layer "F.SilkS")
		)
		(fp_line
			(start -1.016 -2.2352)
			(end 1.016 -2.2352)
			(stroke
				(width 0.1524)
				(type default)
			)
			(layer "F.SilkS")
		)
		(fp_line
			(start 1.016 2.2352)
			(end -1.016 2.2352)
			(stroke
				(width 0.1524)
				(type default)
			)
			(layer "F.SilkS")
		)
		(fp_line
			(start -1.016 2.2352)
			(end -1.016 -2.2352)
			(stroke
				(width 0.1524)
				(type default)
			)
			(layer "F.SilkS")
		)
		(fp_rect
			(start -1.0922 2.3114)
			(end 1.0922 -2.3114)
			(stroke
				(width 0)
				(type default)
			)
			(fill no)
			(layer "F.CrtYd")
		)
		(fp_poly
			(pts
				(xy -1.0922 -2.3114) (xy 1.0922 -2.3114) (xy 1.0922 2.3114) (xy -1.0922 2.3114)
			)
			(stroke
				(width 0)
				(type default)
			)
			(fill no)
			(layer "F.Fab")
		)
		(pad "1" smd rect
			(at 0 -1.397 90)
			(size 1.651 1.27)
			(layers "F.Cu" "F.Mask" "F.Paste")
			(net "P12V_HDD23")
		)
		(pad "2" smd rect
			(at 0 1.397 90)
			(size 1.651 1.27)
			(layers "F.Cu" "F.Mask" "F.Paste")
			(net "12V_PRE_23")
		)
	)
	(footprint ""
		(layer "F.Cu")
		(at 149.196298 -276.065742 -90)
		(property "Reference" "R231"
			(at 0 0 270)
			(layer "F.SilkS")
			(hide yes)
			(effects
				(font
					(size 1.27 1.27)
				)
			)
		)
		(property "Value" "1KR2F-3-GP"
			(at 0.064008 -3.993896 270)
			(unlocked yes)
			(layer "F.Fab")
			(hide yes)
			(effects
				(font
					(size 1.016 1.016)
					(thickness 0.1524)
				)
			)
		)
		(property "Device Type" "R402H16"
			(at 0.064008 -5.517896 270)
			(unlocked yes)
			(layer "F.Fab")
			(hide yes)
			(effects
				(font
					(size 1.016 1.016)
					(thickness 0.1524)
				)
			)
		)
		(duplicate_pad_numbers_are_jumpers no)
		(fp_line
			(start -0.508 -0.9398)
			(end -0.508 0.9398)
			(stroke
				(width 0.1524)
				(type default)
			)
			(layer "F.SilkS")
		)
		(fp_line
			(start 0.508 -0.9398)
			(end -0.508 -0.9398)
			(stroke
				(width 0.1524)
				(type default)
			)
			(layer "F.SilkS")
		)
		(fp_rect
			(start -0.508 0.9398)
			(end 0.508 -0.9398)
			(stroke
				(width 0)
				(type default)
			)
			(fill no)
			(layer "F.CrtYd")
		)
		(fp_rect
			(start -0.508 0.9398)
			(end 0.508 -0.9398)
			(stroke
				(width 0)
				(type default)
			)
			(fill no)
			(layer "F.Fab")
		)
		(pad "1" smd custom
			(at 0 -0.4445 270)
			(size 0.1397 0.1397)
			(layers "F.Cu" "F.Mask" "F.Paste")
			(net "P3V3_STBY_A")
			(options
				(clearance outline)
				(anchor circle)
			)
			(primitives
				(gr_poly
					(pts
						(arc
							(start -0.1778 -0.2794)
							(mid -0.249642 -0.249642)
							(end -0.2794 -0.1778)
						)
						(arc
							(start -0.2794 0.1778)
							(mid -0.249642 0.249642)
							(end -0.1778 0.2794)
						)
						(arc
							(start 0.1778 0.2794)
							(mid 0.249642 0.249642)
							(end 0.2794 0.1778)
						)
						(arc
							(start 0.2794 -0.1778)
							(mid 0.249642 -0.249642)
							(end 0.1778 -0.2794)
						)
					)
					(width 0)
					(fill yes)
				)
			)
		)
		(pad "2" smd custom
			(at 0 0.4445 270)
			(size 0.1397 0.1397)
			(layers "F.Cu" "F.Mask" "F.Paste")
			(net "SW_PWR_R_HDD4")
			(options
				(clearance outline)
				(anchor circle)
			)
			(primitives
				(gr_poly
					(pts
						(arc
							(start -0.1778 -0.2794)
							(mid -0.249642 -0.249642)
							(end -0.2794 -0.1778)
						)
						(arc
							(start -0.2794 0.1778)
							(mid -0.249642 0.249642)
							(end -0.1778 0.2794)
						)
						(arc
							(start 0.1778 0.2794)
							(mid 0.249642 0.249642)
							(end 0.2794 0.1778)
						)
						(arc
							(start 0.2794 -0.1778)
							(mid 0.249642 -0.249642)
							(end 0.1778 -0.2794)
						)
					)
					(width 0)
					(fill yes)
				)
			)
		)
	)
	(footprint ""
		(layer "F.Cu")
		(at 262.255 -272.288)
		(property "Reference" "R108"
			(at 0 0 0)
			(layer "F.SilkS")
			(hide yes)
			(effects
				(font
					(size 1.27 1.27)
				)
			)
		)
		(property "Value" "4K7R2F-GP"
			(at 0.064008 -3.993896 0)
			(unlocked yes)
			(layer "F.Fab")
			(hide yes)
			(effects
				(font
					(size 1.016 1.016)
					(thickness 0.1524)
				)
			)
		)
		(property "Device Type" "R402H16"
			(at 0.064008 -5.517896 0)
			(unlocked yes)
			(layer "F.Fab")
			(hide yes)
			(effects
				(font
					(size 1.016 1.016)
					(thickness 0.1524)
				)
			)
		)
		(duplicate_pad_numbers_are_jumpers no)
		(fp_line
			(start -0.508 -0.9398)
			(end -0.508 0.9398)
			(stroke
				(width 0.1524)
				(type default)
			)
			(layer "F.SilkS")
		)
		(fp_line
			(start 0.508 -0.9398)
			(end -0.508 -0.9398)
			(stroke
				(width 0.1524)
				(type default)
			)
			(layer "F.SilkS")
		)
		(fp_rect
			(start -0.508 0.9398)
			(end 0.508 -0.9398)
			(stroke
				(width 0)
				(type default)
			)
			(fill no)
			(layer "F.CrtYd")
		)
		(fp_rect
			(start -0.508 0.9398)
			(end 0.508 -0.9398)
			(stroke
				(width 0)
				(type default)
			)
			(fill no)
			(layer "F.Fab")
		)
		(pad "1" smd custom
			(at 0 -0.4445)
			(size 0.1397 0.1397)
			(layers "F.Cu" "F.Mask" "F.Paste")
			(net "IO_EXP0_HDD_FAULT_A1")
			(options
				(clearance outline)
				(anchor circle)
			)
			(primitives
				(gr_poly
					(pts
						(arc
							(start -0.1778 -0.2794)
							(mid -0.249642 -0.249642)
							(end -0.2794 -0.1778)
						)
						(arc
							(start -0.2794 0.1778)
							(mid -0.249642 0.249642)
							(end -0.1778 0.2794)
						)
						(arc
							(start 0.1778 0.2794)
							(mid 0.249642 0.249642)
							(end 0.2794 0.1778)
						)
						(arc
							(start 0.2794 -0.1778)
							(mid 0.249642 -0.249642)
							(end 0.1778 -0.2794)
						)
					)
					(width 0)
					(fill yes)
				)
			)
		)
		(pad "2" smd custom
			(at 0 0.4445)
			(size 0.1397 0.1397)
			(layers "F.Cu" "F.Mask" "F.Paste")
			(net "GND")
			(options
				(clearance outline)
				(anchor circle)
			)
			(primitives
				(gr_poly
					(pts
						(arc
							(start -0.1778 -0.2794)
							(mid -0.249642 -0.249642)
							(end -0.2794 -0.1778)
						)
						(arc
							(start -0.2794 0.1778)
							(mid -0.249642 0.249642)
							(end -0.1778 0.2794)
						)
						(arc
							(start 0.1778 0.2794)
							(mid 0.249642 0.249642)
							(end 0.2794 0.1778)
						)
						(arc
							(start 0.2794 -0.1778)
							(mid 0.249642 -0.249642)
							(end 0.1778 -0.2794)
						)
					)
					(width 0)
					(fill yes)
				)
			)
		)
	)
	(footprint ""
		(layer "F.Cu")
		(at 280.0604 19.9136 90)
		(property "Reference" "R15"
			(at 0 0 90)
			(layer "F.SilkS")
			(hide yes)
			(effects
				(font
					(size 1.27 1.27)
				)
			)
		)
		(property "Value" "0R2J-2-GP"
			(at 0.064008 -3.993896 90)
			(unlocked yes)
			(layer "F.Fab")
			(hide yes)
			(effects
				(font
					(size 1.016 1.016)
					(thickness 0.1524)
				)
			)
		)
		(property "Device Type" "R402H16"
			(at 0.064008 -5.517896 90)
			(unlocked yes)
			(layer "F.Fab")
			(hide yes)
			(effects
				(font
					(size 1.016 1.016)
					(thickness 0.1524)
				)
			)
		)
		(duplicate_pad_numbers_are_jumpers no)
		(fp_line
			(start 0.508 -0.9398)
			(end -0.508 -0.9398)
			(stroke
				(width 0.1524)
				(type default)
			)
			(layer "F.SilkS")
		)
		(fp_line
			(start -0.508 -0.9398)
			(end -0.508 0.9398)
			(stroke
				(width 0.1524)
				(type default)
			)
			(layer "F.SilkS")
		)
		(fp_rect
			(start -0.508 0.9398)
			(end 0.508 -0.9398)
			(stroke
				(width 0)
				(type default)
			)
			(fill no)
			(layer "F.CrtYd")
		)
		(fp_rect
			(start -0.508 0.9398)
			(end 0.508 -0.9398)
			(stroke
				(width 0)
				(type default)
			)
			(fill no)
			(layer "F.Fab")
		)
		(pad "1" smd custom
			(at 0 -0.4445 90)
			(size 0.1397 0.1397)
			(layers "F.Cu" "F.Mask" "F.Paste")
			(net "DPB_PWR_BTN_BUF_A")
			(options
				(clearance outline)
				(anchor circle)
			)
			(primitives
				(gr_poly
					(pts
						(arc
							(start -0.1778 -0.2794)
							(mid -0.249642 -0.249642)
							(end -0.2794 -0.1778)
						)
						(arc
							(start -0.2794 0.1778)
							(mid -0.249642 0.249642)
							(end -0.1778 0.2794)
						)
						(arc
							(start 0.1778 0.2794)
							(mid 0.249642 0.249642)
							(end 0.2794 0.1778)
						)
						(arc
							(start 0.2794 -0.1778)
							(mid 0.249642 -0.249642)
							(end 0.1778 -0.2794)
						)
					)
					(width 0)
					(fill yes)
				)
			)
		)
		(pad "2" smd custom
			(at 0 0.4445 90)
			(size 0.1397 0.1397)
			(layers "F.Cu" "F.Mask" "F.Paste")
			(net "DPB_PWR_BTN_A")
			(options
				(clearance outline)
				(anchor circle)
			)
			(primitives
				(gr_poly
					(pts
						(arc
							(start -0.1778 -0.2794)
							(mid -0.249642 -0.249642)
							(end -0.2794 -0.1778)
						)
						(arc
							(start -0.2794 0.1778)
							(mid -0.249642 0.249642)
							(end -0.1778 0.2794)
						)
						(arc
							(start 0.1778 0.2794)
							(mid 0.249642 0.249642)
							(end 0.2794 0.1778)
						)
						(arc
							(start 0.2794 -0.1778)
							(mid 0.249642 -0.249642)
							(end 0.1778 -0.2794)
						)
					)
					(width 0)
					(fill yes)
				)
			)
		)
	)
	(footprint ""
		(layer "F.Cu")
		(at 144.723866 -143.848074 -90)
		(property "Reference" "R1060"
			(at 0 0 270)
			(layer "F.SilkS")
			(hide yes)
			(effects
				(font
					(size 1.27 1.27)
				)
			)
		)
		(property "Value" "100KR2F-L1-GP"
			(at 0.064008 -3.993896 270)
			(unlocked yes)
			(layer "F.Fab")
			(hide yes)
			(effects
				(font
					(size 1.016 1.016)
					(thickness 0.1524)
				)
			)
		)
		(property "Device Type" "R402H16"
			(at 0.064008 -5.517896 270)
			(unlocked yes)
			(layer "F.Fab")
			(hide yes)
			(effects
				(font
					(size 1.016 1.016)
					(thickness 0.1524)
				)
			)
		)
		(duplicate_pad_numbers_are_jumpers no)
		(fp_line
			(start -0.508 -0.9398)
			(end -0.508 0.9398)
			(stroke
				(width 0.1524)
				(type default)
			)
			(layer "F.SilkS")
		)
		(fp_line
			(start 0.508 -0.9398)
			(end -0.508 -0.9398)
			(stroke
				(width 0.1524)
				(type default)
			)
			(layer "F.SilkS")
		)
		(fp_rect
			(start -0.508 0.9398)
			(end 0.508 -0.9398)
			(stroke
				(width 0)
				(type default)
			)
			(fill no)
			(layer "F.CrtYd")
		)
		(fp_rect
			(start -0.508 0.9398)
			(end 0.508 -0.9398)
			(stroke
				(width 0)
				(type default)
			)
			(fill no)
			(layer "F.Fab")
		)
		(pad "1" smd custom
			(at 0 -0.4445 270)
			(size 0.1397 0.1397)
			(layers "F.Cu" "F.Mask" "F.Paste")
			(net "MB0_VCAP_R")
			(options
				(clearance outline)
				(anchor circle)
			)
			(primitives
				(gr_poly
					(pts
						(arc
							(start -0.1778 -0.2794)
							(mid -0.249642 -0.249642)
							(end -0.2794 -0.1778)
						)
						(arc
							(start -0.2794 0.1778)
							(mid -0.249642 0.249642)
							(end -0.1778 0.2794)
						)
						(arc
							(start 0.1778 0.2794)
							(mid 0.249642 0.249642)
							(end 0.2794 0.1778)
						)
						(arc
							(start 0.2794 -0.1778)
							(mid 0.249642 -0.249642)
							(end 0.1778 -0.2794)
						)
					)
					(width 0)
					(fill yes)
				)
			)
		)
		(pad "2" smd custom
			(at 0 0.4445 270)
			(size 0.1397 0.1397)
			(layers "F.Cu" "F.Mask" "F.Paste")
			(net "MB0_ISTART_R")
			(options
				(clearance outline)
				(anchor circle)
			)
			(primitives
				(gr_poly
					(pts
						(arc
							(start -0.1778 -0.2794)
							(mid -0.249642 -0.249642)
							(end -0.2794 -0.1778)
						)
						(arc
							(start -0.2794 0.1778)
							(mid -0.249642 0.249642)
							(end -0.1778 0.2794)
						)
						(arc
							(start 0.1778 0.2794)
							(mid 0.249642 0.249642)
							(end 0.2794 0.1778)
						)
						(arc
							(start 0.2794 -0.1778)
							(mid 0.249642 -0.249642)
							(end 0.1778 -0.2794)
						)
					)
					(width 0)
					(fill yes)
				)
			)
		)
	)
	(footprint ""
		(layer "F.Cu")
		(at 79.924148 -167.060118 90)
		(property "Reference" "R459"
			(at 0 0 90)
			(layer "F.SilkS")
			(hide yes)
			(effects
				(font
					(size 1.27 1.27)
				)
			)
		)
		(property "Value" "4K7R2J-2-GP"
			(at 0.064008 -3.993896 90)
			(unlocked yes)
			(layer "F.Fab")
			(hide yes)
			(effects
				(font
					(size 1.016 1.016)
					(thickness 0.1524)
				)
			)
		)
		(property "Device Type" "R402H16"
			(at 0.064008 -5.517896 90)
			(unlocked yes)
			(layer "F.Fab")
			(hide yes)
			(effects
				(font
					(size 1.016 1.016)
					(thickness 0.1524)
				)
			)
		)
		(duplicate_pad_numbers_are_jumpers no)
		(fp_line
			(start 0.508 -0.9398)
			(end -0.508 -0.9398)
			(stroke
				(width 0.1524)
				(type default)
			)
			(layer "F.SilkS")
		)
		(fp_line
			(start -0.508 -0.9398)
			(end -0.508 0.9398)
			(stroke
				(width 0.1524)
				(type default)
			)
			(layer "F.SilkS")
		)
		(fp_rect
			(start -0.508 0.9398)
			(end 0.508 -0.9398)
			(stroke
				(width 0)
				(type default)
			)
			(fill no)
			(layer "F.CrtYd")
		)
		(fp_rect
			(start -0.508 0.9398)
			(end 0.508 -0.9398)
			(stroke
				(width 0)
				(type default)
			)
			(fill no)
			(layer "F.Fab")
		)
		(pad "1" smd custom
			(at 0 -0.4445 90)
			(size 0.1397 0.1397)
			(layers "F.Cu" "F.Mask" "F.Paste")
			(net "P12V_A")
			(options
				(clearance outline)
				(anchor circle)
			)
			(primitives
				(gr_poly
					(pts
						(arc
							(start -0.1778 -0.2794)
							(mid -0.249642 -0.249642)
							(end -0.2794 -0.1778)
						)
						(arc
							(start -0.2794 0.1778)
							(mid -0.249642 0.249642)
							(end -0.1778 0.2794)
						)
						(arc
							(start 0.1778 0.2794)
							(mid 0.249642 0.249642)
							(end 0.2794 0.1778)
						)
						(arc
							(start 0.2794 -0.1778)
							(mid 0.249642 -0.249642)
							(end 0.1778 -0.2794)
						)
					)
					(width 0)
					(fill yes)
				)
			)
		)
		(pad "2" smd custom
			(at 0 0.4445 90)
			(size 0.1397 0.1397)
			(layers "F.Cu" "F.Mask" "F.Paste")
			(net "SW_HDD_P14")
			(options
				(clearance outline)
				(anchor circle)
			)
			(primitives
				(gr_poly
					(pts
						(arc
							(start -0.1778 -0.2794)
							(mid -0.249642 -0.249642)
							(end -0.2794 -0.1778)
						)
						(arc
							(start -0.2794 0.1778)
							(mid -0.249642 0.249642)
							(end -0.1778 0.2794)
						)
						(arc
							(start 0.1778 0.2794)
							(mid 0.249642 0.249642)
							(end 0.2794 0.1778)
						)
						(arc
							(start 0.2794 -0.1778)
							(mid 0.249642 -0.249642)
							(end 0.1778 -0.2794)
						)
					)
					(width 0)
					(fill yes)
				)
			)
		)
	)
	(footprint ""
		(layer "F.Cu")
		(at 172.593 -54.523894 90)
		(property "Reference" "C426"
			(at 0 0 90)
			(layer "F.SilkS")
			(hide yes)
			(effects
				(font
					(size 1.27 1.27)
				)
			)
		)
		(property "Value" "SCD033U25V2KX-GP"
			(at 1.1811 -2.7051 90)
			(unlocked yes)
			(layer "F.Fab")
			(hide yes)
			(effects
				(font
					(size 1.016 1.016)
					(thickness 0.1524)
				)
			)
		)
		(property "Device Type" "C402H22"
			(at 1.1811 -4.2291 90)
			(unlocked yes)
			(layer "F.Fab")
			(hide yes)
			(effects
				(font
					(size 1.016 1.016)
					(thickness 0.1524)
				)
			)
		)
		(duplicate_pad_numbers_are_jumpers no)
		(fp_rect
			(start -0.4318 0.9525)
			(end 0.4318 -0.9525)
			(stroke
				(width 0)
				(type default)
			)
			(fill no)
			(layer "F.CrtYd")
		)
		(fp_rect
			(start -0.4318 0.9525)
			(end 0.4318 -0.9525)
			(stroke
				(width 0)
				(type default)
			)
			(fill no)
			(layer "F.Fab")
		)
		(pad "1" smd custom
			(at 0 -0.4445 90)
			(size 0.1524 0.1524)
			(layers "F.Cu" "F.Mask" "F.Paste")
			(net "P12V_A")
			(options
				(clearance outline)
				(anchor circle)
			)
			(primitives
				(gr_poly
					(pts
						(arc
							(start 0.3048 -0.2032)
							(mid 0.275042 -0.275042)
							(end 0.2032 -0.3048)
						)
						(arc
							(start -0.2032 -0.3048)
							(mid -0.275042 -0.275042)
							(end -0.3048 -0.2032)
						)
						(arc
							(start -0.3048 0.2032)
							(mid -0.275042 0.275042)
							(end -0.2032 0.3048)
						)
						(arc
							(start 0.2032 0.3048)
							(mid 0.275042 0.275042)
							(end 0.3048 0.2032)
						)
					)
					(width 0)
					(fill yes)
				)
			)
		)
		(pad "2" smd custom
			(at 0 0.4445 90)
			(size 0.1524 0.1524)
			(layers "F.Cu" "F.Mask" "F.Paste")
			(net "SW_HDD_N29")
			(options
				(clearance outline)
				(anchor circle)
			)
			(primitives
				(gr_poly
					(pts
						(arc
							(start 0.3048 -0.2032)
							(mid 0.275042 -0.275042)
							(end 0.2032 -0.3048)
						)
						(arc
							(start -0.2032 -0.3048)
							(mid -0.275042 -0.275042)
							(end -0.3048 -0.2032)
						)
						(arc
							(start -0.3048 0.2032)
							(mid -0.275042 0.275042)
							(end -0.2032 0.3048)
						)
						(arc
							(start 0.2032 0.3048)
							(mid 0.275042 0.275042)
							(end 0.3048 0.2032)
						)
					)
					(width 0)
					(fill yes)
				)
			)
		)
	)
	(footprint ""
		(layer "F.Cu")
		(at 190.807086 -41.307512 180)
		(property "Reference" "R801"
			(at 0 0 180)
			(layer "F.SilkS")
			(hide yes)
			(effects
				(font
					(size 1.27 1.27)
				)
			)
		)
		(property "Value" "220R3F-1-GP"
			(at -0.0254 -2.5146 180)
			(unlocked yes)
			(layer "F.Fab")
			(hide yes)
			(effects
				(font
					(size 1.016 1.016)
					(thickness 0.1524)
				)
			)
		)
		(property "Device Type" "R603H22"
			(at -0.0254 -4.0386 180)
			(unlocked yes)
			(layer "F.Fab")
			(hide yes)
			(effects
				(font
					(size 1.016 1.016)
					(thickness 0.1524)
				)
			)
		)
		(duplicate_pad_numbers_are_jumpers no)
		(fp_line
			(start 0.2032 0)
			(end 0.4826 0)
			(stroke
				(width 0.2032)
				(type default)
			)
			(layer "F.SilkS")
		)
		(fp_line
			(start -0.4826 0)
			(end -0.2032 0)
			(stroke
				(width 0.2032)
				(type default)
			)
			(layer "F.SilkS")
		)
		(fp_rect
			(start -0.5842 1.3335)
			(end 0.5842 -1.3335)
			(stroke
				(width 0)
				(type default)
			)
			(fill no)
			(layer "F.CrtYd")
		)
		(fp_rect
			(start -0.5842 1.3335)
			(end 0.5842 -1.3335)
			(stroke
				(width 0)
				(type default)
			)
			(fill no)
			(layer "F.Fab")
		)
		(pad "1" smd custom
			(at 0 -0.762 180)
			(size 0.2159 0.2159)
			(layers "F.Cu" "F.Mask" "F.Paste")
			(net "HDD_PRSNT_29")
			(options
				(clearance outline)
				(anchor circle)
			)
			(primitives
				(gr_poly
					(pts
						(arc
							(start -0.3302 -0.4318)
							(mid -0.402042 -0.402042)
							(end -0.4318 -0.3302)
						)
						(arc
							(start -0.4318 0.3302)
							(mid -0.402042 0.402042)
							(end -0.3302 0.4318)
						)
						(arc
							(start 0.3302 0.4318)
							(mid 0.402042 0.402042)
							(end 0.4318 0.3302)
						)
						(arc
							(start 0.4318 -0.3302)
							(mid 0.402042 -0.402042)
							(end 0.3302 -0.4318)
						)
					)
					(width 0)
					(fill yes)
				)
			)
		)
		(pad "2" smd custom
			(at 0 0.762 180)
			(size 0.2159 0.2159)
			(layers "F.Cu" "F.Mask" "F.Paste")
			(net "DRIVE_A_29_INS")
			(options
				(clearance outline)
				(anchor circle)
			)
			(primitives
				(gr_poly
					(pts
						(arc
							(start -0.3302 -0.4318)
							(mid -0.402042 -0.402042)
							(end -0.4318 -0.3302)
						)
						(arc
							(start -0.4318 0.3302)
							(mid -0.402042 0.402042)
							(end -0.3302 0.4318)
						)
						(arc
							(start 0.3302 0.4318)
							(mid 0.402042 0.402042)
							(end 0.4318 0.3302)
						)
						(arc
							(start 0.4318 -0.3302)
							(mid 0.402042 -0.402042)
							(end 0.3302 -0.4318)
						)
					)
					(width 0)
					(fill yes)
				)
			)
		)
	)
	(footprint ""
		(layer "F.Cu")
		(at 18.906998 -294.683942 90)
		(property "Reference" "R959"
			(at 0 0 90)
			(layer "F.SilkS")
			(hide yes)
			(effects
				(font
					(size 1.27 1.27)
				)
			)
		)
		(property "Value" "2R6F-GP"
			(at -0.0508 -4.8514 90)
			(unlocked yes)
			(layer "F.Fab")
			(hide yes)
			(effects
				(font
					(size 1.016 1.016)
					(thickness 0.1524)
				)
			)
		)
		(property "Device Type" "R1206H26"
			(at 0 -6.3754 90)
			(unlocked yes)
			(layer "F.Fab")
			(hide yes)
			(effects
				(font
					(size 1.016 1.016)
					(thickness 0.1524)
				)
			)
		)
		(duplicate_pad_numbers_are_jumpers no)
		(fp_line
			(start 1.016 -2.2352)
			(end 1.016 2.2352)
			(stroke
				(width 0.1524)
				(type default)
			)
			(layer "F.SilkS")
		)
		(fp_line
			(start -1.016 -2.2352)
			(end 1.016 -2.2352)
			(stroke
				(width 0.1524)
				(type default)
			)
			(layer "F.SilkS")
		)
		(fp_line
			(start 1.016 2.2352)
			(end -1.016 2.2352)
			(stroke
				(width 0.1524)
				(type default)
			)
			(layer "F.SilkS")
		)
		(fp_line
			(start -1.016 2.2352)
			(end -1.016 -2.2352)
			(stroke
				(width 0.1524)
				(type default)
			)
			(layer "F.SilkS")
		)
		(fp_rect
			(start -1.0922 2.3114)
			(end 1.0922 -2.3114)
			(stroke
				(width 0)
				(type default)
			)
			(fill no)
			(layer "F.CrtYd")
		)
		(fp_poly
			(pts
				(xy -1.0922 -2.3114) (xy 1.0922 -2.3114) (xy 1.0922 2.3114) (xy -1.0922 2.3114)
			)
			(stroke
				(width 0)
				(type default)
			)
			(fill no)
			(layer "F.Fab")
		)
		(pad "1" smd rect
			(at 0 -1.397 90)
			(size 1.651 1.27)
			(layers "F.Cu" "F.Mask" "F.Paste")
			(net "P12V_HDD0")
		)
		(pad "2" smd rect
			(at 0 1.397 90)
			(size 1.651 1.27)
			(layers "F.Cu" "F.Mask" "F.Paste")
			(net "12V_PRE_0")
		)
	)
	(footprint ""
		(layer "F.Cu")
		(at 190.213488 -44.219368 90)
		(property "Reference" "C415"
			(at 0 0 90)
			(layer "F.SilkS")
			(hide yes)
			(effects
				(font
					(size 1.27 1.27)
				)
			)
		)
		(property "Value" "SCD01U16V1KX-GP"
			(at -2.8321 -1.7399 90)
			(unlocked yes)
			(layer "F.Fab")
			(hide yes)
			(effects
				(font
					(size 1.016 1.016)
					(thickness 0.1524)
				)
			)
		)
		(property "Device Type" "C0201H13"
			(at -2.8321 -3.2639 90)
			(unlocked yes)
			(layer "F.Fab")
			(hide yes)
			(effects
				(font
					(size 1.016 1.016)
					(thickness 0.1524)
				)
			)
		)
		(duplicate_pad_numbers_are_jumpers no)
		(fp_rect
			(start -0.2794 0.6477)
			(end 0.2794 -0.6477)
			(stroke
				(width 0)
				(type default)
			)
			(fill no)
			(layer "F.CrtYd")
		)
		(fp_rect
			(start -0.2794 0.6477)
			(end 0.2794 -0.6477)
			(stroke
				(width 0)
				(type default)
			)
			(fill no)
			(layer "F.Fab")
		)
		(pad "1" smd custom
			(at 0 -0.2794 90)
			(size 0.0762 0.0762)
			(layers "F.Cu" "F.Mask" "F.Paste")
			(net "SAS_HDD_RX_N29")
			(options
				(clearance outline)
				(anchor circle)
			)
			(primitives
				(gr_poly
					(pts
						(arc
							(start 0.1524 -0.127)
							(mid 0.137521 -0.162921)
							(end 0.1016 -0.1778)
						)
						(arc
							(start -0.1016 -0.1778)
							(mid -0.137521 -0.162921)
							(end -0.1524 -0.127)
						)
						(arc
							(start -0.1524 0.127)
							(mid -0.137521 0.162921)
							(end -0.1016 0.1778)
						)
						(arc
							(start 0.1016 0.1778)
							(mid 0.137521 0.162921)
							(end 0.1524 0.127)
						)
					)
					(width 0)
					(fill yes)
				)
			)
		)
		(pad "2" smd custom
			(at 0 0.2794 90)
			(size 0.0762 0.0762)
			(layers "F.Cu" "F.Mask" "F.Paste")
			(net "PHY_SCC_A_TO_DRV_A_29_DN")
			(options
				(clearance outline)
				(anchor circle)
			)
			(primitives
				(gr_poly
					(pts
						(arc
							(start 0.1524 -0.127)
							(mid 0.137521 -0.162921)
							(end 0.1016 -0.1778)
						)
						(arc
							(start -0.1016 -0.1778)
							(mid -0.137521 -0.162921)
							(end -0.1524 -0.127)
						)
						(arc
							(start -0.1524 0.127)
							(mid -0.137521 0.162921)
							(end -0.1016 0.1778)
						)
						(arc
							(start 0.1016 0.1778)
							(mid 0.137521 0.162921)
							(end 0.1524 0.127)
						)
					)
					(width 0)
					(fill yes)
				)
			)
		)
	)
	(footprint ""
		(layer "F.Cu")
		(at 466.4456 -294.3098 180)
		(property "Reference" "R333"
			(at 0 0 180)
			(layer "F.SilkS")
			(hide yes)
			(effects
				(font
					(size 1.27 1.27)
				)
			)
		)
		(property "Value" "91R3F-1-GP"
			(at -0.0254 -2.5146 180)
			(unlocked yes)
			(layer "F.Fab")
			(hide yes)
			(effects
				(font
					(size 1.016 1.016)
					(thickness 0.1524)
				)
			)
		)
		(property "Device Type" "R603H22"
			(at -0.0254 -4.0386 180)
			(unlocked yes)
			(layer "F.Fab")
			(hide yes)
			(effects
				(font
					(size 1.016 1.016)
					(thickness 0.1524)
				)
			)
		)
		(duplicate_pad_numbers_are_jumpers no)
		(fp_line
			(start 0.2032 0)
			(end 0.4826 0)
			(stroke
				(width 0.2032)
				(type default)
			)
			(layer "F.SilkS")
		)
		(fp_line
			(start -0.4826 0)
			(end -0.2032 0)
			(stroke
				(width 0.2032)
				(type default)
			)
			(layer "F.SilkS")
		)
		(fp_rect
			(start -0.5842 1.3335)
			(end 0.5842 -1.3335)
			(stroke
				(width 0)
				(type default)
			)
			(fill no)
			(layer "F.CrtYd")
		)
		(fp_rect
			(start -0.5842 1.3335)
			(end 0.5842 -1.3335)
			(stroke
				(width 0)
				(type default)
			)
			(fill no)
			(layer "F.Fab")
		)
		(pad "1" smd custom
			(at 0 -0.762 180)
			(size 0.2159 0.2159)
			(layers "F.Cu" "F.Mask" "F.Paste")
			(net "P5V_B")
			(options
				(clearance outline)
				(anchor circle)
			)
			(primitives
				(gr_poly
					(pts
						(arc
							(start -0.3302 -0.4318)
							(mid -0.402042 -0.402042)
							(end -0.4318 -0.3302)
						)
						(arc
							(start -0.4318 0.3302)
							(mid -0.402042 0.402042)
							(end -0.3302 0.4318)
						)
						(arc
							(start 0.3302 0.4318)
							(mid 0.402042 0.402042)
							(end 0.4318 0.3302)
						)
						(arc
							(start 0.4318 -0.3302)
							(mid 0.402042 -0.402042)
							(end 0.3302 -0.4318)
						)
					)
					(width 0)
					(fill yes)
				)
			)
		)
		(pad "2" smd custom
			(at 0 0.762 180)
			(size 0.2159 0.2159)
			(layers "F.Cu" "F.Mask" "F.Paste")
			(net "DRV_ACT_35")
			(options
				(clearance outline)
				(anchor circle)
			)
			(primitives
				(gr_poly
					(pts
						(arc
							(start -0.3302 -0.4318)
							(mid -0.402042 -0.402042)
							(end -0.4318 -0.3302)
						)
						(arc
							(start -0.4318 0.3302)
							(mid -0.402042 0.402042)
							(end -0.3302 0.4318)
						)
						(arc
							(start 0.3302 0.4318)
							(mid 0.402042 0.402042)
							(end 0.4318 0.3302)
						)
						(arc
							(start 0.4318 -0.3302)
							(mid 0.402042 -0.402042)
							(end 0.3302 -0.4318)
						)
					)
					(width 0)
					(fill yes)
				)
			)
		)
	)
	(footprint ""
		(layer "F.Cu")
		(at 255.481328 11.049 -90)
		(property "Reference" "R634"
			(at 0 0 270)
			(layer "F.SilkS")
			(hide yes)
			(effects
				(font
					(size 1.27 1.27)
				)
			)
		)
		(property "Value" "10KR2F-2-GP"
			(at 0.064008 -3.993896 270)
			(unlocked yes)
			(layer "F.Fab")
			(hide yes)
			(effects
				(font
					(size 1.016 1.016)
					(thickness 0.1524)
				)
			)
		)
		(property "Device Type" "R402H16"
			(at 0.064008 -5.517896 270)
			(unlocked yes)
			(layer "F.Fab")
			(hide yes)
			(effects
				(font
					(size 1.016 1.016)
					(thickness 0.1524)
				)
			)
		)
		(duplicate_pad_numbers_are_jumpers no)
		(fp_line
			(start -0.508 -0.9398)
			(end -0.508 0.9398)
			(stroke
				(width 0.1524)
				(type default)
			)
			(layer "F.SilkS")
		)
		(fp_line
			(start 0.508 -0.9398)
			(end -0.508 -0.9398)
			(stroke
				(width 0.1524)
				(type default)
			)
			(layer "F.SilkS")
		)
		(fp_rect
			(start -0.508 0.9398)
			(end 0.508 -0.9398)
			(stroke
				(width 0)
				(type default)
			)
			(fill no)
			(layer "F.CrtYd")
		)
		(fp_rect
			(start -0.508 0.9398)
			(end 0.508 -0.9398)
			(stroke
				(width 0)
				(type default)
			)
			(fill no)
			(layer "F.Fab")
		)
		(pad "1" smd custom
			(at 0 -0.4445 270)
			(size 0.1397 0.1397)
			(layers "F.Cu" "F.Mask" "F.Paste")
			(net "P3V3_STBY_A")
			(options
				(clearance outline)
				(anchor circle)
			)
			(primitives
				(gr_poly
					(pts
						(arc
							(start -0.1778 -0.2794)
							(mid -0.249642 -0.249642)
							(end -0.2794 -0.1778)
						)
						(arc
							(start -0.2794 0.1778)
							(mid -0.249642 0.249642)
							(end -0.1778 0.2794)
						)
						(arc
							(start 0.1778 0.2794)
							(mid 0.249642 0.249642)
							(end 0.2794 0.1778)
						)
						(arc
							(start 0.2794 -0.1778)
							(mid 0.249642 -0.249642)
							(end 0.1778 -0.2794)
						)
					)
					(width 0)
					(fill yes)
				)
			)
		)
		(pad "2" smd custom
			(at 0 0.4445 270)
			(size 0.1397 0.1397)
			(layers "F.Cu" "F.Mask" "F.Paste")
			(net "IOM_A_PWR_LED")
			(options
				(clearance outline)
				(anchor circle)
			)
			(primitives
				(gr_poly
					(pts
						(arc
							(start -0.1778 -0.2794)
							(mid -0.249642 -0.249642)
							(end -0.2794 -0.1778)
						)
						(arc
							(start -0.2794 0.1778)
							(mid -0.249642 0.249642)
							(end -0.1778 0.2794)
						)
						(arc
							(start 0.1778 0.2794)
							(mid 0.249642 0.249642)
							(end 0.2794 0.1778)
						)
						(arc
							(start 0.2794 -0.1778)
							(mid 0.249642 -0.249642)
							(end 0.1778 -0.2794)
						)
					)
					(width 0)
					(fill yes)
				)
			)
		)
	)
	(footprint ""
		(layer "F.Cu")
		(at 36.178998 -180.064918 90)
		(property "Reference" "R410"
			(at 0 0 90)
			(layer "F.SilkS")
			(hide yes)
			(effects
				(font
					(size 1.27 1.27)
				)
			)
		)
		(property "Value" "220R3F-1-GP"
			(at -0.0254 -2.5146 90)
			(unlocked yes)
			(layer "F.Fab")
			(hide yes)
			(effects
				(font
					(size 1.016 1.016)
					(thickness 0.1524)
				)
			)
		)
		(property "Device Type" "R603H22"
			(at -0.0254 -4.0386 90)
			(unlocked yes)
			(layer "F.Fab")
			(hide yes)
			(effects
				(font
					(size 1.016 1.016)
					(thickness 0.1524)
				)
			)
		)
		(duplicate_pad_numbers_are_jumpers no)
		(fp_line
			(start 0.2032 0)
			(end 0.4826 0)
			(stroke
				(width 0.2032)
				(type default)
			)
			(layer "F.SilkS")
		)
		(fp_line
			(start -0.4826 0)
			(end -0.2032 0)
			(stroke
				(width 0.2032)
				(type default)
			)
			(layer "F.SilkS")
		)
		(fp_rect
			(start -0.5842 1.3335)
			(end 0.5842 -1.3335)
			(stroke
				(width 0)
				(type default)
			)
			(fill no)
			(layer "F.CrtYd")
		)
		(fp_rect
			(start -0.5842 1.3335)
			(end 0.5842 -1.3335)
			(stroke
				(width 0)
				(type default)
			)
			(fill no)
			(layer "F.Fab")
		)
		(pad "1" smd custom
			(at 0 -0.762 90)
			(size 0.2159 0.2159)
			(layers "F.Cu" "F.Mask" "F.Paste")
			(net "HDD_PRSNT_12")
			(options
				(clearance outline)
				(anchor circle)
			)
			(primitives
				(gr_poly
					(pts
						(arc
							(start -0.3302 -0.4318)
							(mid -0.402042 -0.402042)
							(end -0.4318 -0.3302)
						)
						(arc
							(start -0.4318 0.3302)
							(mid -0.402042 0.402042)
							(end -0.3302 0.4318)
						)
						(arc
							(start 0.3302 0.4318)
							(mid 0.402042 0.402042)
							(end 0.4318 0.3302)
						)
						(arc
							(start 0.4318 -0.3302)
							(mid 0.402042 -0.402042)
							(end 0.3302 -0.4318)
						)
					)
					(width 0)
					(fill yes)
				)
			)
		)
		(pad "2" smd custom
			(at 0 0.762 90)
			(size 0.2159 0.2159)
			(layers "F.Cu" "F.Mask" "F.Paste")
			(net "DRIVE_A_12_INS")
			(options
				(clearance outline)
				(anchor circle)
			)
			(primitives
				(gr_poly
					(pts
						(arc
							(start -0.3302 -0.4318)
							(mid -0.402042 -0.402042)
							(end -0.4318 -0.3302)
						)
						(arc
							(start -0.4318 0.3302)
							(mid -0.402042 0.402042)
							(end -0.3302 0.4318)
						)
						(arc
							(start 0.3302 0.4318)
							(mid 0.402042 0.402042)
							(end 0.4318 0.3302)
						)
						(arc
							(start 0.4318 -0.3302)
							(mid 0.402042 -0.402042)
							(end 0.3302 -0.4318)
						)
					)
					(width 0)
					(fill yes)
				)
			)
		)
	)
	(footprint ""
		(layer "F.Cu")
		(at 190.213488 -158.660592 90)
		(property "Reference" "C260"
			(at 0 0 90)
			(layer "F.SilkS")
			(hide yes)
			(effects
				(font
					(size 1.27 1.27)
				)
			)
		)
		(property "Value" "SCD01U16V1KX-GP"
			(at -2.8321 -1.7399 90)
			(unlocked yes)
			(layer "F.Fab")
			(hide yes)
			(effects
				(font
					(size 1.016 1.016)
					(thickness 0.1524)
				)
			)
		)
		(property "Device Type" "C0201H13"
			(at -2.8321 -3.2639 90)
			(unlocked yes)
			(layer "F.Fab")
			(hide yes)
			(effects
				(font
					(size 1.016 1.016)
					(thickness 0.1524)
				)
			)
		)
		(duplicate_pad_numbers_are_jumpers no)
		(fp_rect
			(start -0.2794 0.6477)
			(end 0.2794 -0.6477)
			(stroke
				(width 0)
				(type default)
			)
			(fill no)
			(layer "F.CrtYd")
		)
		(fp_rect
			(start -0.2794 0.6477)
			(end 0.2794 -0.6477)
			(stroke
				(width 0)
				(type default)
			)
			(fill no)
			(layer "F.Fab")
		)
		(pad "1" smd custom
			(at 0 -0.2794 90)
			(size 0.0762 0.0762)
			(layers "F.Cu" "F.Mask" "F.Paste")
			(net "SAS_HDD_RX_P17")
			(options
				(clearance outline)
				(anchor circle)
			)
			(primitives
				(gr_poly
					(pts
						(arc
							(start 0.1524 -0.127)
							(mid 0.137521 -0.162921)
							(end 0.1016 -0.1778)
						)
						(arc
							(start -0.1016 -0.1778)
							(mid -0.137521 -0.162921)
							(end -0.1524 -0.127)
						)
						(arc
							(start -0.1524 0.127)
							(mid -0.137521 0.162921)
							(end -0.1016 0.1778)
						)
						(arc
							(start 0.1016 0.1778)
							(mid 0.137521 0.162921)
							(end 0.1524 0.127)
						)
					)
					(width 0)
					(fill yes)
				)
			)
		)
		(pad "2" smd custom
			(at 0 0.2794 90)
			(size 0.0762 0.0762)
			(layers "F.Cu" "F.Mask" "F.Paste")
			(net "PHY_SCC_A_TO_DRV_A_17_DP")
			(options
				(clearance outline)
				(anchor circle)
			)
			(primitives
				(gr_poly
					(pts
						(arc
							(start 0.1524 -0.127)
							(mid 0.137521 -0.162921)
							(end 0.1016 -0.1778)
						)
						(arc
							(start -0.1016 -0.1778)
							(mid -0.137521 -0.162921)
							(end -0.1524 -0.127)
						)
						(arc
							(start -0.1524 0.127)
							(mid -0.137521 0.162921)
							(end -0.1016 0.1778)
						)
						(arc
							(start 0.1016 0.1778)
							(mid 0.137521 0.162921)
							(end 0.1524 0.127)
						)
					)
					(width 0)
					(fill yes)
				)
			)
		)
	)
	(footprint ""
		(layer "F.Cu")
		(at 409.800044 -324.39991)
		(property "Reference" "RLED34"
			(at 0 0 0)
			(layer "F.SilkS")
			(hide yes)
			(effects
				(font
					(size 1.27 1.27)
				)
			)
		)
		(property "Value" "LED-BY-19-GP"
			(at -2.132076 1.414018 0)
			(unlocked yes)
			(layer "F.Fab")
			(hide yes)
			(effects
				(font
					(size 1.016 1.016)
					(thickness 0.1524)
				)
			)
		)
		(property "Device Type" "LED-1615-4PH26"
			(at -2.132076 -0.109982 0)
			(unlocked yes)
			(layer "F.Fab")
			(hide yes)
			(effects
				(font
					(size 1.016 1.016)
					(thickness 0.1524)
				)
			)
		)
		(duplicate_pad_numbers_are_jumpers no)
		(fp_line
			(start -1.2954 0.254)
			(end -1.2954 1.6002)
			(stroke
				(width 0.508)
				(type default)
			)
			(layer "F.SilkS")
		)
		(fp_line
			(start -1.2954 1.6002)
			(end 1.2954 1.6002)
			(stroke
				(width 0.508)
				(type default)
			)
			(layer "F.SilkS")
		)
		(fp_line
			(start -1.1176 -1.4224)
			(end 1.1176 -1.4224)
			(stroke
				(width 0.1524)
				(type default)
			)
			(layer "F.SilkS")
		)
		(fp_line
			(start -1.1176 1.4224)
			(end -1.1176 -1.4224)
			(stroke
				(width 0.1524)
				(type default)
			)
			(layer "F.SilkS")
		)
		(fp_line
			(start 1.1176 -1.4224)
			(end 1.1176 1.4224)
			(stroke
				(width 0.1524)
				(type default)
			)
			(layer "F.SilkS")
		)
		(fp_line
			(start 1.1176 1.4224)
			(end -1.1176 1.4224)
			(stroke
				(width 0.1524)
				(type default)
			)
			(layer "F.SilkS")
		)
		(fp_line
			(start 1.2954 1.6002)
			(end 1.2954 0.254)
			(stroke
				(width 0.508)
				(type default)
			)
			(layer "F.SilkS")
		)
		(fp_rect
			(start -0.7493 0.8001)
			(end 0.7493 -0.8001)
			(stroke
				(width 0)
				(type default)
			)
			(fill no)
			(layer "F.CrtYd")
		)
		(fp_poly
			(pts
				(xy -1.3716 1.6764) (xy -1.3716 -1.6764) (xy 1.3716 -1.6764) (xy 1.3716 0.0635) (xy 0.7493 0.0635)
				(xy 0.7493 -0.8001) (xy -0.7493 -0.8001) (xy -0.7493 0.8001) (xy 0.7493 0.8001) (xy 0.7493 0.0762)
				(xy 1.3716 0.0762) (xy 1.3716 1.6764)
			)
			(stroke
				(width 0)
				(type default)
			)
			(fill no)
			(layer "F.CrtYd")
		)
		(fp_rect
			(start -1.3716 1.6764)
			(end 1.3716 -1.6764)
			(stroke
				(width 0)
				(type default)
			)
			(fill no)
			(layer "F.Fab")
		)
		(pad "1" smd rect
			(at 0.50038 -0.73025)
			(size 0.7112 0.8636)
			(layers "F.Cu" "F.Mask" "F.Paste")
			(net "DRV_ACT_33")
		)
		(pad "2" smd rect
			(at -0.50038 -0.73025)
			(size 0.7112 0.8636)
			(layers "F.Cu" "F.Mask" "F.Paste")
			(net "FLT_HDD33")
		)
		(pad "3" smd rect
			(at 0.50038 0.73025)
			(size 0.7112 0.8636)
			(layers "F.Cu" "F.Mask" "F.Paste")
			(net "DRV_ACT_33_N")
		)
		(pad "4" smd rect
			(at -0.50038 0.73025)
			(size 0.7112 0.8636)
			(layers "F.Cu" "F.Mask" "F.Paste")
			(net "FLT_HDD33_N")
		)
	)
	(footprint ""
		(layer "F.Cu")
		(at 79.924148 -282.085542 90)
		(property "Reference" "R183"
			(at 0 0 90)
			(layer "F.SilkS")
			(hide yes)
			(effects
				(font
					(size 1.27 1.27)
				)
			)
		)
		(property "Value" "4K7R2J-2-GP"
			(at 0.064008 -3.993896 90)
			(unlocked yes)
			(layer "F.Fab")
			(hide yes)
			(effects
				(font
					(size 1.016 1.016)
					(thickness 0.1524)
				)
			)
		)
		(property "Device Type" "R402H16"
			(at 0.064008 -5.517896 90)
			(unlocked yes)
			(layer "F.Fab")
			(hide yes)
			(effects
				(font
					(size 1.016 1.016)
					(thickness 0.1524)
				)
			)
		)
		(duplicate_pad_numbers_are_jumpers no)
		(fp_line
			(start 0.508 -0.9398)
			(end -0.508 -0.9398)
			(stroke
				(width 0.1524)
				(type default)
			)
			(layer "F.SilkS")
		)
		(fp_line
			(start -0.508 -0.9398)
			(end -0.508 0.9398)
			(stroke
				(width 0.1524)
				(type default)
			)
			(layer "F.SilkS")
		)
		(fp_rect
			(start -0.508 0.9398)
			(end 0.508 -0.9398)
			(stroke
				(width 0)
				(type default)
			)
			(fill no)
			(layer "F.CrtYd")
		)
		(fp_rect
			(start -0.508 0.9398)
			(end 0.508 -0.9398)
			(stroke
				(width 0)
				(type default)
			)
			(fill no)
			(layer "F.Fab")
		)
		(pad "1" smd custom
			(at 0 -0.4445 90)
			(size 0.1397 0.1397)
			(layers "F.Cu" "F.Mask" "F.Paste")
			(net "P12V_A")
			(options
				(clearance outline)
				(anchor circle)
			)
			(primitives
				(gr_poly
					(pts
						(arc
							(start -0.1778 -0.2794)
							(mid -0.249642 -0.249642)
							(end -0.2794 -0.1778)
						)
						(arc
							(start -0.2794 0.1778)
							(mid -0.249642 0.249642)
							(end -0.1778 0.2794)
						)
						(arc
							(start 0.1778 0.2794)
							(mid 0.249642 0.249642)
							(end 0.2794 0.1778)
						)
						(arc
							(start 0.2794 -0.1778)
							(mid 0.249642 -0.249642)
							(end 0.1778 -0.2794)
						)
					)
					(width 0)
					(fill yes)
				)
			)
		)
		(pad "2" smd custom
			(at 0 0.4445 90)
			(size 0.1397 0.1397)
			(layers "F.Cu" "F.Mask" "F.Paste")
			(net "SW_HDD_P2")
			(options
				(clearance outline)
				(anchor circle)
			)
			(primitives
				(gr_poly
					(pts
						(arc
							(start -0.1778 -0.2794)
							(mid -0.249642 -0.249642)
							(end -0.2794 -0.1778)
						)
						(arc
							(start -0.2794 0.1778)
							(mid -0.249642 0.249642)
							(end -0.1778 0.2794)
						)
						(arc
							(start 0.1778 0.2794)
							(mid 0.249642 0.249642)
							(end 0.2794 0.1778)
						)
						(arc
							(start 0.2794 -0.1778)
							(mid 0.249642 -0.249642)
							(end 0.1778 -0.2794)
						)
					)
					(width 0)
					(fill yes)
				)
			)
		)
	)
	(footprint ""
		(layer "F.Cu")
		(at 79.84998 -31.404814 180)
		(property "Reference" "R1297"
			(at 0 0 180)
			(layer "F.SilkS")
			(hide yes)
			(effects
				(font
					(size 1.27 1.27)
				)
			)
		)
		(property "Value" "2K2R2F-GP"
			(at 0.064008 -3.993896 180)
			(unlocked yes)
			(layer "F.Fab")
			(hide yes)
			(effects
				(font
					(size 1.016 1.016)
					(thickness 0.1524)
				)
			)
		)
		(property "Device Type" "R402H16"
			(at 0.064008 -5.517896 180)
			(unlocked yes)
			(layer "F.Fab")
			(hide yes)
			(effects
				(font
					(size 1.016 1.016)
					(thickness 0.1524)
				)
			)
		)
		(duplicate_pad_numbers_are_jumpers no)
		(fp_line
			(start 0.508 -0.9398)
			(end -0.508 -0.9398)
			(stroke
				(width 0.1524)
				(type default)
			)
			(layer "F.SilkS")
		)
		(fp_line
			(start -0.508 -0.9398)
			(end -0.508 0.9398)
			(stroke
				(width 0.1524)
				(type default)
			)
			(layer "F.SilkS")
		)
		(fp_rect
			(start -0.508 0.9398)
			(end 0.508 -0.9398)
			(stroke
				(width 0)
				(type default)
			)
			(fill no)
			(layer "F.CrtYd")
		)
		(fp_rect
			(start -0.508 0.9398)
			(end 0.508 -0.9398)
			(stroke
				(width 0)
				(type default)
			)
			(fill no)
			(layer "F.Fab")
		)
		(pad "1" smd custom
			(at 0 -0.4445 180)
			(size 0.1397 0.1397)
			(layers "F.Cu" "F.Mask" "F.Paste")
			(net "P3V3_STBY_A")
			(options
				(clearance outline)
				(anchor circle)
			)
			(primitives
				(gr_poly
					(pts
						(arc
							(start -0.1778 -0.2794)
							(mid -0.249642 -0.249642)
							(end -0.2794 -0.1778)
						)
						(arc
							(start -0.2794 0.1778)
							(mid -0.249642 0.249642)
							(end -0.1778 0.2794)
						)
						(arc
							(start 0.1778 0.2794)
							(mid 0.249642 0.249642)
							(end 0.2794 0.1778)
						)
						(arc
							(start 0.2794 -0.1778)
							(mid 0.249642 -0.249642)
							(end 0.1778 -0.2794)
						)
					)
					(width 0)
					(fill yes)
				)
			)
		)
		(pad "2" smd custom
			(at 0 0.4445 180)
			(size 0.1397 0.1397)
			(layers "F.Cu" "F.Mask" "F.Paste")
			(net "I2C_BMC_A_MISC_SDA")
			(options
				(clearance outline)
				(anchor circle)
			)
			(primitives
				(gr_poly
					(pts
						(arc
							(start -0.1778 -0.2794)
							(mid -0.249642 -0.249642)
							(end -0.2794 -0.1778)
						)
						(arc
							(start -0.2794 0.1778)
							(mid -0.249642 0.249642)
							(end -0.1778 0.2794)
						)
						(arc
							(start 0.1778 0.2794)
							(mid 0.249642 0.249642)
							(end 0.2794 0.1778)
						)
						(arc
							(start 0.2794 -0.1778)
							(mid 0.249642 -0.249642)
							(end 0.1778 -0.2794)
						)
					)
					(width 0)
					(fill yes)
				)
			)
		)
	)
	(footprint ""
		(layer "F.Cu")
		(at 98.897948 -292.169342 -90)
		(property "Reference" "R177"
			(at 0 0 270)
			(layer "F.SilkS")
			(hide yes)
			(effects
				(font
					(size 1.27 1.27)
				)
			)
		)
		(property "Value" "10KR2F-2-GP"
			(at 0.064008 -3.993896 270)
			(unlocked yes)
			(layer "F.Fab")
			(hide yes)
			(effects
				(font
					(size 1.016 1.016)
					(thickness 0.1524)
				)
			)
		)
		(property "Device Type" "R402H16"
			(at 0.064008 -5.517896 270)
			(unlocked yes)
			(layer "F.Fab")
			(hide yes)
			(effects
				(font
					(size 1.016 1.016)
					(thickness 0.1524)
				)
			)
		)
		(duplicate_pad_numbers_are_jumpers no)
		(fp_line
			(start -0.508 -0.9398)
			(end -0.508 0.9398)
			(stroke
				(width 0.1524)
				(type default)
			)
			(layer "F.SilkS")
		)
		(fp_line
			(start 0.508 -0.9398)
			(end -0.508 -0.9398)
			(stroke
				(width 0.1524)
				(type default)
			)
			(layer "F.SilkS")
		)
		(fp_rect
			(start -0.508 0.9398)
			(end 0.508 -0.9398)
			(stroke
				(width 0)
				(type default)
			)
			(fill no)
			(layer "F.CrtYd")
		)
		(fp_rect
			(start -0.508 0.9398)
			(end 0.508 -0.9398)
			(stroke
				(width 0)
				(type default)
			)
			(fill no)
			(layer "F.Fab")
		)
		(pad "1" smd custom
			(at 0 -0.4445 270)
			(size 0.1397 0.1397)
			(layers "F.Cu" "F.Mask" "F.Paste")
			(net "P3V3_STBY_A")
			(options
				(clearance outline)
				(anchor circle)
			)
			(primitives
				(gr_poly
					(pts
						(arc
							(start -0.1778 -0.2794)
							(mid -0.249642 -0.249642)
							(end -0.2794 -0.1778)
						)
						(arc
							(start -0.2794 0.1778)
							(mid -0.249642 0.249642)
							(end -0.1778 0.2794)
						)
						(arc
							(start 0.1778 0.2794)
							(mid 0.249642 0.249642)
							(end 0.2794 0.1778)
						)
						(arc
							(start 0.2794 -0.1778)
							(mid 0.249642 -0.249642)
							(end 0.1778 -0.2794)
						)
					)
					(width 0)
					(fill yes)
				)
			)
		)
		(pad "2" smd custom
			(at 0 0.4445 270)
			(size 0.1397 0.1397)
			(layers "F.Cu" "F.Mask" "F.Paste")
			(net "HDD_PRSNT_2")
			(options
				(clearance outline)
				(anchor circle)
			)
			(primitives
				(gr_poly
					(pts
						(arc
							(start -0.1778 -0.2794)
							(mid -0.249642 -0.249642)
							(end -0.2794 -0.1778)
						)
						(arc
							(start -0.2794 0.1778)
							(mid -0.249642 0.249642)
							(end -0.1778 0.2794)
						)
						(arc
							(start 0.1778 0.2794)
							(mid 0.249642 0.249642)
							(end 0.2794 0.1778)
						)
						(arc
							(start 0.2794 -0.1778)
							(mid 0.249642 -0.249642)
							(end 0.1778 -0.2794)
						)
					)
					(width 0)
					(fill yes)
				)
			)
		)
	)
	(footprint ""
		(layer "F.Cu")
		(at 149.196298 -159.871918 -90)
		(property "Reference" "R509"
			(at 0 0 270)
			(layer "F.SilkS")
			(hide yes)
			(effects
				(font
					(size 1.27 1.27)
				)
			)
		)
		(property "Value" "0R2J-2-GP"
			(at 0.064008 -3.993896 270)
			(unlocked yes)
			(layer "F.Fab")
			(hide yes)
			(effects
				(font
					(size 1.016 1.016)
					(thickness 0.1524)
				)
			)
		)
		(property "Device Type" "R402H16"
			(at 0.064008 -5.517896 270)
			(unlocked yes)
			(layer "F.Fab")
			(hide yes)
			(effects
				(font
					(size 1.016 1.016)
					(thickness 0.1524)
				)
			)
		)
		(duplicate_pad_numbers_are_jumpers no)
		(fp_line
			(start -0.508 -0.9398)
			(end -0.508 0.9398)
			(stroke
				(width 0.1524)
				(type default)
			)
			(layer "F.SilkS")
		)
		(fp_line
			(start 0.508 -0.9398)
			(end -0.508 -0.9398)
			(stroke
				(width 0.1524)
				(type default)
			)
			(layer "F.SilkS")
		)
		(fp_rect
			(start -0.508 0.9398)
			(end 0.508 -0.9398)
			(stroke
				(width 0)
				(type default)
			)
			(fill no)
			(layer "F.CrtYd")
		)
		(fp_rect
			(start -0.508 0.9398)
			(end 0.508 -0.9398)
			(stroke
				(width 0)
				(type default)
			)
			(fill no)
			(layer "F.Fab")
		)
		(pad "1" smd custom
			(at 0 -0.4445 270)
			(size 0.1397 0.1397)
			(layers "F.Cu" "F.Mask" "F.Paste")
			(net "DRIVE_A_16_PWR")
			(options
				(clearance outline)
				(anchor circle)
			)
			(primitives
				(gr_poly
					(pts
						(arc
							(start -0.1778 -0.2794)
							(mid -0.249642 -0.249642)
							(end -0.2794 -0.1778)
						)
						(arc
							(start -0.2794 0.1778)
							(mid -0.249642 0.249642)
							(end -0.1778 0.2794)
						)
						(arc
							(start 0.1778 0.2794)
							(mid 0.249642 0.249642)
							(end 0.2794 0.1778)
						)
						(arc
							(start 0.2794 -0.1778)
							(mid 0.249642 -0.249642)
							(end 0.1778 -0.2794)
						)
					)
					(width 0)
					(fill yes)
				)
			)
		)
		(pad "2" smd custom
			(at 0 0.4445 270)
			(size 0.1397 0.1397)
			(layers "F.Cu" "F.Mask" "F.Paste")
			(net "SW_PWR_R_HDD16")
			(options
				(clearance outline)
				(anchor circle)
			)
			(primitives
				(gr_poly
					(pts
						(arc
							(start -0.1778 -0.2794)
							(mid -0.249642 -0.249642)
							(end -0.2794 -0.1778)
						)
						(arc
							(start -0.2794 0.1778)
							(mid -0.249642 0.249642)
							(end -0.1778 0.2794)
						)
						(arc
							(start 0.1778 0.2794)
							(mid 0.249642 0.249642)
							(end 0.2794 0.1778)
						)
						(arc
							(start 0.2794 -0.1778)
							(mid 0.249642 -0.249642)
							(end 0.1778 -0.2794)
						)
					)
					(width 0)
					(fill yes)
				)
			)
		)
	)
	(footprint ""
		(layer "F.Cu")
		(at 338.709 -56.809894 -90)
		(property "Reference" "R835"
			(at 0 0 270)
			(layer "F.SilkS")
			(hide yes)
			(effects
				(font
					(size 1.27 1.27)
				)
			)
		)
		(property "Value" "300KR2F-GP"
			(at 0.064008 -3.993896 270)
			(unlocked yes)
			(layer "F.Fab")
			(hide yes)
			(effects
				(font
					(size 1.016 1.016)
					(thickness 0.1524)
				)
			)
		)
		(property "Device Type" "R402H16"
			(at 0.064008 -5.517896 270)
			(unlocked yes)
			(layer "F.Fab")
			(hide yes)
			(effects
				(font
					(size 1.016 1.016)
					(thickness 0.1524)
				)
			)
		)
		(duplicate_pad_numbers_are_jumpers no)
		(fp_line
			(start -0.508 -0.9398)
			(end -0.508 0.9398)
			(stroke
				(width 0.1524)
				(type default)
			)
			(layer "F.SilkS")
		)
		(fp_line
			(start 0.508 -0.9398)
			(end -0.508 -0.9398)
			(stroke
				(width 0.1524)
				(type default)
			)
			(layer "F.SilkS")
		)
		(fp_rect
			(start -0.508 0.9398)
			(end 0.508 -0.9398)
			(stroke
				(width 0)
				(type default)
			)
			(fill no)
			(layer "F.CrtYd")
		)
		(fp_rect
			(start -0.508 0.9398)
			(end 0.508 -0.9398)
			(stroke
				(width 0)
				(type default)
			)
			(fill no)
			(layer "F.Fab")
		)
		(pad "1" smd custom
			(at 0 -0.4445 270)
			(size 0.1397 0.1397)
			(layers "F.Cu" "F.Mask" "F.Paste")
			(net "SW_HDD_N30")
			(options
				(clearance outline)
				(anchor circle)
			)
			(primitives
				(gr_poly
					(pts
						(arc
							(start -0.1778 -0.2794)
							(mid -0.249642 -0.249642)
							(end -0.2794 -0.1778)
						)
						(arc
							(start -0.2794 0.1778)
							(mid -0.249642 0.249642)
							(end -0.1778 0.2794)
						)
						(arc
							(start 0.1778 0.2794)
							(mid 0.249642 0.249642)
							(end 0.2794 0.1778)
						)
						(arc
							(start 0.2794 -0.1778)
							(mid 0.249642 -0.249642)
							(end 0.1778 -0.2794)
						)
					)
					(width 0)
					(fill yes)
				)
			)
		)
		(pad "2" smd custom
			(at 0 0.4445 270)
			(size 0.1397 0.1397)
			(layers "F.Cu" "F.Mask" "F.Paste")
			(net "P12V_A")
			(options
				(clearance outline)
				(anchor circle)
			)
			(primitives
				(gr_poly
					(pts
						(arc
							(start -0.1778 -0.2794)
							(mid -0.249642 -0.249642)
							(end -0.2794 -0.1778)
						)
						(arc
							(start -0.2794 0.1778)
							(mid -0.249642 0.249642)
							(end -0.1778 0.2794)
						)
						(arc
							(start 0.1778 0.2794)
							(mid 0.249642 0.249642)
							(end 0.2794 0.1778)
						)
						(arc
							(start 0.2794 -0.1778)
							(mid 0.249642 -0.249642)
							(end 0.1778 -0.2794)
						)
					)
					(width 0)
					(fill yes)
				)
			)
		)
	)
	(footprint ""
		(layer "F.Cu")
		(at 392.91895 -296.842942 180)
		(property "Reference" "C144"
			(at 0 0 180)
			(layer "F.SilkS")
			(hide yes)
			(effects
				(font
					(size 1.27 1.27)
				)
			)
		)
		(property "Value" "SC1U16V3KX-5GP"
			(at 0 -2.8194 180)
			(unlocked yes)
			(layer "F.Fab")
			(hide yes)
			(effects
				(font
					(size 1.016 1.016)
					(thickness 0.1524)
				)
			)
		)
		(property "Device Type" "C603H36"
			(at 0 -4.3434 180)
			(unlocked yes)
			(layer "F.Fab")
			(hide yes)
			(effects
				(font
					(size 1.016 1.016)
					(thickness 0.1524)
				)
			)
		)
		(duplicate_pad_numbers_are_jumpers no)
		(fp_line
			(start 0.508 0)
			(end -0.508 0)
			(stroke
				(width 0.2032)
				(type default)
			)
			(layer "F.SilkS")
		)
		(fp_rect
			(start -0.5842 1.3335)
			(end 0.5842 -1.3335)
			(stroke
				(width 0)
				(type default)
			)
			(fill no)
			(layer "F.CrtYd")
		)
		(fp_rect
			(start -0.5842 1.3335)
			(end 0.5842 -1.3335)
			(stroke
				(width 0)
				(type default)
			)
			(fill no)
			(layer "F.Fab")
		)
		(pad "1" smd custom
			(at 0 -0.762 180)
			(size 0.2159 0.2159)
			(layers "F.Cu" "F.Mask" "F.Paste")
			(net "P5V_HDD8")
			(options
				(clearance outline)
				(anchor circle)
			)
			(primitives
				(gr_poly
					(pts
						(arc
							(start -0.3302 -0.4318)
							(mid -0.402042 -0.402042)
							(end -0.4318 -0.3302)
						)
						(arc
							(start -0.4318 0.3302)
							(mid -0.402042 0.402042)
							(end -0.3302 0.4318)
						)
						(arc
							(start 0.3302 0.4318)
							(mid 0.402042 0.402042)
							(end 0.4318 0.3302)
						)
						(arc
							(start 0.4318 -0.3302)
							(mid 0.402042 -0.402042)
							(end 0.3302 -0.4318)
						)
					)
					(width 0)
					(fill yes)
				)
			)
		)
		(pad "2" smd custom
			(at 0 0.762 180)
			(size 0.2159 0.2159)
			(layers "F.Cu" "F.Mask" "F.Paste")
			(net "GND")
			(options
				(clearance outline)
				(anchor circle)
			)
			(primitives
				(gr_poly
					(pts
						(arc
							(start -0.3302 -0.4318)
							(mid -0.402042 -0.402042)
							(end -0.4318 -0.3302)
						)
						(arc
							(start -0.4318 0.3302)
							(mid -0.402042 0.402042)
							(end -0.3302 0.4318)
						)
						(arc
							(start 0.3302 0.4318)
							(mid 0.402042 0.402042)
							(end 0.4318 0.3302)
						)
						(arc
							(start 0.4318 -0.3302)
							(mid 0.402042 -0.402042)
							(end 0.3302 -0.4318)
						)
					)
					(width 0)
					(fill yes)
				)
			)
		)
	)
	(footprint ""
		(layer "F.Cu")
		(at 333.329534 -23.07717 90)
		(property "Reference" "R75"
			(at 0 0 90)
			(layer "F.SilkS")
			(hide yes)
			(effects
				(font
					(size 1.27 1.27)
				)
			)
		)
		(property "Value" "100KR2F-L1-GP"
			(at 0.064008 -3.993896 90)
			(unlocked yes)
			(layer "F.Fab")
			(hide yes)
			(effects
				(font
					(size 1.016 1.016)
					(thickness 0.1524)
				)
			)
		)
		(property "Device Type" "R402H16"
			(at 0.064008 -5.517896 90)
			(unlocked yes)
			(layer "F.Fab")
			(hide yes)
			(effects
				(font
					(size 1.016 1.016)
					(thickness 0.1524)
				)
			)
		)
		(duplicate_pad_numbers_are_jumpers no)
		(fp_line
			(start 0.508 -0.9398)
			(end -0.508 -0.9398)
			(stroke
				(width 0.1524)
				(type default)
			)
			(layer "F.SilkS")
		)
		(fp_line
			(start -0.508 -0.9398)
			(end -0.508 0.9398)
			(stroke
				(width 0.1524)
				(type default)
			)
			(layer "F.SilkS")
		)
		(fp_rect
			(start -0.508 0.9398)
			(end 0.508 -0.9398)
			(stroke
				(width 0)
				(type default)
			)
			(fill no)
			(layer "F.CrtYd")
		)
		(fp_rect
			(start -0.508 0.9398)
			(end 0.508 -0.9398)
			(stroke
				(width 0)
				(type default)
			)
			(fill no)
			(layer "F.Fab")
		)
		(pad "1" smd custom
			(at 0 -0.4445 90)
			(size 0.1397 0.1397)
			(layers "F.Cu" "F.Mask" "F.Paste")
			(net "P3V3_STBY_B")
			(options
				(clearance outline)
				(anchor circle)
			)
			(primitives
				(gr_poly
					(pts
						(arc
							(start -0.1778 -0.2794)
							(mid -0.249642 -0.249642)
							(end -0.2794 -0.1778)
						)
						(arc
							(start -0.2794 0.1778)
							(mid -0.249642 0.249642)
							(end -0.1778 0.2794)
						)
						(arc
							(start 0.1778 0.2794)
							(mid 0.249642 0.249642)
							(end 0.2794 0.1778)
						)
						(arc
							(start 0.2794 -0.1778)
							(mid 0.249642 -0.249642)
							(end 0.1778 -0.2794)
						)
					)
					(width 0)
					(fill yes)
				)
			)
		)
		(pad "2" smd custom
			(at 0 0.4445 90)
			(size 0.1397 0.1397)
			(layers "F.Cu" "F.Mask" "F.Paste")
			(net "BMC_B_MISC_ALERT_N")
			(options
				(clearance outline)
				(anchor circle)
			)
			(primitives
				(gr_poly
					(pts
						(arc
							(start -0.1778 -0.2794)
							(mid -0.249642 -0.249642)
							(end -0.2794 -0.1778)
						)
						(arc
							(start -0.2794 0.1778)
							(mid -0.249642 0.249642)
							(end -0.1778 0.2794)
						)
						(arc
							(start 0.1778 0.2794)
							(mid 0.249642 0.249642)
							(end 0.2794 0.1778)
						)
						(arc
							(start 0.2794 -0.1778)
							(mid 0.249642 -0.249642)
							(end 0.1778 -0.2794)
						)
					)
					(width 0)
					(fill yes)
				)
			)
		)
	)
	(footprint ""
		(layer "F.Cu")
		(at 393.90955 -287.597342 -90)
		(property "Reference" "R321"
			(at 0 0 270)
			(layer "F.SilkS")
			(hide yes)
			(effects
				(font
					(size 1.27 1.27)
				)
			)
		)
		(property "Value" "4K7R2J-2-GP"
			(at 0.064008 -3.993896 270)
			(unlocked yes)
			(layer "F.Fab")
			(hide yes)
			(effects
				(font
					(size 1.016 1.016)
					(thickness 0.1524)
				)
			)
		)
		(property "Device Type" "R402H16"
			(at 0.064008 -5.517896 270)
			(unlocked yes)
			(layer "F.Fab")
			(hide yes)
			(effects
				(font
					(size 1.016 1.016)
					(thickness 0.1524)
				)
			)
		)
		(duplicate_pad_numbers_are_jumpers no)
		(fp_line
			(start -0.508 -0.9398)
			(end -0.508 0.9398)
			(stroke
				(width 0.1524)
				(type default)
			)
			(layer "F.SilkS")
		)
		(fp_line
			(start 0.508 -0.9398)
			(end -0.508 -0.9398)
			(stroke
				(width 0.1524)
				(type default)
			)
			(layer "F.SilkS")
		)
		(fp_rect
			(start -0.508 0.9398)
			(end 0.508 -0.9398)
			(stroke
				(width 0)
				(type default)
			)
			(fill no)
			(layer "F.CrtYd")
		)
		(fp_rect
			(start -0.508 0.9398)
			(end 0.508 -0.9398)
			(stroke
				(width 0)
				(type default)
			)
			(fill no)
			(layer "F.Fab")
		)
		(pad "1" smd custom
			(at 0 -0.4445 270)
			(size 0.1397 0.1397)
			(layers "F.Cu" "F.Mask" "F.Paste")
			(net "P12V_A")
			(options
				(clearance outline)
				(anchor circle)
			)
			(primitives
				(gr_poly
					(pts
						(arc
							(start -0.1778 -0.2794)
							(mid -0.249642 -0.249642)
							(end -0.2794 -0.1778)
						)
						(arc
							(start -0.2794 0.1778)
							(mid -0.249642 0.249642)
							(end -0.1778 0.2794)
						)
						(arc
							(start 0.1778 0.2794)
							(mid 0.249642 0.249642)
							(end 0.2794 0.1778)
						)
						(arc
							(start 0.2794 -0.1778)
							(mid 0.249642 -0.249642)
							(end 0.1778 -0.2794)
						)
					)
					(width 0)
					(fill yes)
				)
			)
		)
		(pad "2" smd custom
			(at 0 0.4445 270)
			(size 0.1397 0.1397)
			(layers "F.Cu" "F.Mask" "F.Paste")
			(net "SW_HDD_P8")
			(options
				(clearance outline)
				(anchor circle)
			)
			(primitives
				(gr_poly
					(pts
						(arc
							(start -0.1778 -0.2794)
							(mid -0.249642 -0.249642)
							(end -0.2794 -0.1778)
						)
						(arc
							(start -0.2794 0.1778)
							(mid -0.249642 0.249642)
							(end -0.1778 0.2794)
						)
						(arc
							(start 0.1778 0.2794)
							(mid 0.249642 0.249642)
							(end 0.2794 0.1778)
						)
						(arc
							(start 0.2794 -0.1778)
							(mid 0.249642 -0.249642)
							(end 0.1778 -0.2794)
						)
					)
					(width 0)
					(fill yes)
				)
			)
		)
	)
	(footprint ""
		(layer "F.Cu")
		(at 109.492796 -168.482518 -90)
		(property "Reference" "R490"
			(at 0 0 270)
			(layer "F.SilkS")
			(hide yes)
			(effects
				(font
					(size 1.27 1.27)
				)
			)
		)
		(property "Value" "300KR2F-GP"
			(at 0.064008 -3.993896 270)
			(unlocked yes)
			(layer "F.Fab")
			(hide yes)
			(effects
				(font
					(size 1.016 1.016)
					(thickness 0.1524)
				)
			)
		)
		(property "Device Type" "R402H16"
			(at 0.064008 -5.517896 270)
			(unlocked yes)
			(layer "F.Fab")
			(hide yes)
			(effects
				(font
					(size 1.016 1.016)
					(thickness 0.1524)
				)
			)
		)
		(duplicate_pad_numbers_are_jumpers no)
		(fp_line
			(start -0.508 -0.9398)
			(end -0.508 0.9398)
			(stroke
				(width 0.1524)
				(type default)
			)
			(layer "F.SilkS")
		)
		(fp_line
			(start 0.508 -0.9398)
			(end -0.508 -0.9398)
			(stroke
				(width 0.1524)
				(type default)
			)
			(layer "F.SilkS")
		)
		(fp_rect
			(start -0.508 0.9398)
			(end 0.508 -0.9398)
			(stroke
				(width 0)
				(type default)
			)
			(fill no)
			(layer "F.CrtYd")
		)
		(fp_rect
			(start -0.508 0.9398)
			(end 0.508 -0.9398)
			(stroke
				(width 0)
				(type default)
			)
			(fill no)
			(layer "F.Fab")
		)
		(pad "1" smd custom
			(at 0 -0.4445 270)
			(size 0.1397 0.1397)
			(layers "F.Cu" "F.Mask" "F.Paste")
			(net "SW_HDD_N15")
			(options
				(clearance outline)
				(anchor circle)
			)
			(primitives
				(gr_poly
					(pts
						(arc
							(start -0.1778 -0.2794)
							(mid -0.249642 -0.249642)
							(end -0.2794 -0.1778)
						)
						(arc
							(start -0.2794 0.1778)
							(mid -0.249642 0.249642)
							(end -0.1778 0.2794)
						)
						(arc
							(start 0.1778 0.2794)
							(mid 0.249642 0.249642)
							(end 0.2794 0.1778)
						)
						(arc
							(start 0.2794 -0.1778)
							(mid 0.249642 -0.249642)
							(end 0.1778 -0.2794)
						)
					)
					(width 0)
					(fill yes)
				)
			)
		)
		(pad "2" smd custom
			(at 0 0.4445 270)
			(size 0.1397 0.1397)
			(layers "F.Cu" "F.Mask" "F.Paste")
			(net "P12V_A")
			(options
				(clearance outline)
				(anchor circle)
			)
			(primitives
				(gr_poly
					(pts
						(arc
							(start -0.1778 -0.2794)
							(mid -0.249642 -0.249642)
							(end -0.2794 -0.1778)
						)
						(arc
							(start -0.2794 0.1778)
							(mid -0.249642 0.249642)
							(end -0.1778 0.2794)
						)
						(arc
							(start 0.1778 0.2794)
							(mid 0.249642 0.249642)
							(end 0.2794 0.1778)
						)
						(arc
							(start 0.2794 -0.1778)
							(mid 0.249642 -0.249642)
							(end 0.1778 -0.2794)
						)
					)
					(width 0)
					(fill yes)
				)
			)
		)
	)
	(footprint ""
		(layer "F.Cu")
		(at 304.0634 -69.6468 180)
		(property "Reference" "R641"
			(at 0 0 180)
			(layer "F.SilkS")
			(hide yes)
			(effects
				(font
					(size 1.27 1.27)
				)
			)
		)
		(property "Value" "0R2J-2-GP"
			(at 0.064008 -3.993896 180)
			(unlocked yes)
			(layer "F.Fab")
			(hide yes)
			(effects
				(font
					(size 1.016 1.016)
					(thickness 0.1524)
				)
			)
		)
		(property "Device Type" "R402H16"
			(at 0.064008 -5.517896 180)
			(unlocked yes)
			(layer "F.Fab")
			(hide yes)
			(effects
				(font
					(size 1.016 1.016)
					(thickness 0.1524)
				)
			)
		)
		(duplicate_pad_numbers_are_jumpers no)
		(fp_line
			(start 0.508 -0.9398)
			(end -0.508 -0.9398)
			(stroke
				(width 0.1524)
				(type default)
			)
			(layer "F.SilkS")
		)
		(fp_line
			(start -0.508 -0.9398)
			(end -0.508 0.9398)
			(stroke
				(width 0.1524)
				(type default)
			)
			(layer "F.SilkS")
		)
		(fp_rect
			(start -0.508 0.9398)
			(end 0.508 -0.9398)
			(stroke
				(width 0)
				(type default)
			)
			(fill no)
			(layer "F.CrtYd")
		)
		(fp_rect
			(start -0.508 0.9398)
			(end 0.508 -0.9398)
			(stroke
				(width 0)
				(type default)
			)
			(fill no)
			(layer "F.Fab")
		)
		(pad "1" smd custom
			(at 0 -0.4445 180)
			(size 0.1397 0.1397)
			(layers "F.Cu" "F.Mask" "F.Paste")
			(net "I2C_BMC_B_COMP_B_SCL_R")
			(options
				(clearance outline)
				(anchor circle)
			)
			(primitives
				(gr_poly
					(pts
						(arc
							(start -0.1778 -0.2794)
							(mid -0.249642 -0.249642)
							(end -0.2794 -0.1778)
						)
						(arc
							(start -0.2794 0.1778)
							(mid -0.249642 0.249642)
							(end -0.1778 0.2794)
						)
						(arc
							(start 0.1778 0.2794)
							(mid 0.249642 0.249642)
							(end 0.2794 0.1778)
						)
						(arc
							(start 0.2794 -0.1778)
							(mid 0.249642 -0.249642)
							(end 0.1778 -0.2794)
						)
					)
					(width 0)
					(fill yes)
				)
			)
		)
		(pad "2" smd custom
			(at 0 0.4445 180)
			(size 0.1397 0.1397)
			(layers "F.Cu" "F.Mask" "F.Paste")
			(net "I2C_BMC_B_COMP_B_SCL_BUF")
			(options
				(clearance outline)
				(anchor circle)
			)
			(primitives
				(gr_poly
					(pts
						(arc
							(start -0.1778 -0.2794)
							(mid -0.249642 -0.249642)
							(end -0.2794 -0.1778)
						)
						(arc
							(start -0.2794 0.1778)
							(mid -0.249642 0.249642)
							(end -0.1778 0.2794)
						)
						(arc
							(start 0.1778 0.2794)
							(mid 0.249642 0.249642)
							(end 0.2794 0.1778)
						)
						(arc
							(start 0.2794 -0.1778)
							(mid 0.249642 -0.249642)
							(end 0.1778 -0.2794)
						)
					)
					(width 0)
					(fill yes)
				)
			)
		)
	)
	(footprint ""
		(layer "F.Cu")
		(at 255.498092 -20.094956 -90)
		(property "Reference" "TP246"
			(at 0 0 270)
			(layer "F.SilkS")
			(hide yes)
			(effects
				(font
					(size 1.27 1.27)
				)
			)
		)
		(property "Value" "TPAD32-GP"
			(at -0.0508 -1.6764 270)
			(unlocked yes)
			(layer "F.Fab")
			(hide yes)
			(effects
				(font
					(size 1.016 1.016)
					(thickness 0.1524)
				)
			)
		)
		(property "Device Type" "TPAD32"
			(at -0.0508 -3.2004 270)
			(unlocked yes)
			(layer "F.Fab")
			(hide yes)
			(effects
				(font
					(size 1.016 1.016)
					(thickness 0.1524)
				)
			)
		)
		(duplicate_pad_numbers_are_jumpers no)
		(fp_poly
			(pts
				(arc
					(start 0 -0.4064)
					(mid 0 0.4064)
					(end 0 -0.4064)
				)
			)
			(stroke
				(width 0)
				(type default)
			)
			(fill no)
			(layer "F.CrtYd")
		)
		(fp_poly
			(pts
				(arc
					(start 0 -0.7112)
					(mid 0 0.7112)
					(end 0 -0.7112)
				)
			)
			(stroke
				(width 0)
				(type default)
			)
			(fill no)
			(layer "F.Fab")
		)
		(pad "1" smd circle
			(at 0 0 270)
			(size 0.8128 0.8128)
			(layers "F.Cu" "F.Mask" "F.Paste")
			(net "TP_PCIE_COMP_A_CLK_N5")
		)
	)
	(footprint ""
		(layer "F.Cu")
		(at 144.6149 -242.25377)
		(property "Reference" "R240"
			(at 0 0 0)
			(layer "F.SilkS")
			(hide yes)
			(effects
				(font
					(size 1.27 1.27)
				)
			)
		)
		(property "Value" "91R3F-1-GP"
			(at -0.0254 -2.5146 0)
			(unlocked yes)
			(layer "F.Fab")
			(hide yes)
			(effects
				(font
					(size 1.016 1.016)
					(thickness 0.1524)
				)
			)
		)
		(property "Device Type" "R603H22"
			(at -0.0254 -4.0386 0)
			(unlocked yes)
			(layer "F.Fab")
			(hide yes)
			(effects
				(font
					(size 1.016 1.016)
					(thickness 0.1524)
				)
			)
		)
		(duplicate_pad_numbers_are_jumpers no)
		(fp_line
			(start -0.4826 0)
			(end -0.2032 0)
			(stroke
				(width 0.2032)
				(type default)
			)
			(layer "F.SilkS")
		)
		(fp_line
			(start 0.2032 0)
			(end 0.4826 0)
			(stroke
				(width 0.2032)
				(type default)
			)
			(layer "F.SilkS")
		)
		(fp_rect
			(start -0.5842 1.3335)
			(end 0.5842 -1.3335)
			(stroke
				(width 0)
				(type default)
			)
			(fill no)
			(layer "F.CrtYd")
		)
		(fp_rect
			(start -0.5842 1.3335)
			(end 0.5842 -1.3335)
			(stroke
				(width 0)
				(type default)
			)
			(fill no)
			(layer "F.Fab")
		)
		(pad "1" smd custom
			(at 0 -0.762)
			(size 0.2159 0.2159)
			(layers "F.Cu" "F.Mask" "F.Paste")
			(net "P5V_A_1")
			(options
				(clearance outline)
				(anchor circle)
			)
			(primitives
				(gr_poly
					(pts
						(arc
							(start -0.3302 -0.4318)
							(mid -0.402042 -0.402042)
							(end -0.4318 -0.3302)
						)
						(arc
							(start -0.4318 0.3302)
							(mid -0.402042 0.402042)
							(end -0.3302 0.4318)
						)
						(arc
							(start 0.3302 0.4318)
							(mid 0.402042 0.402042)
							(end 0.4318 0.3302)
						)
						(arc
							(start 0.4318 -0.3302)
							(mid 0.402042 -0.402042)
							(end 0.3302 -0.4318)
						)
					)
					(width 0)
					(fill yes)
				)
			)
		)
		(pad "2" smd custom
			(at 0 0.762)
			(size 0.2159 0.2159)
			(layers "F.Cu" "F.Mask" "F.Paste")
			(net "DRV_ACT_4")
			(options
				(clearance outline)
				(anchor circle)
			)
			(primitives
				(gr_poly
					(pts
						(arc
							(start -0.3302 -0.4318)
							(mid -0.402042 -0.402042)
							(end -0.4318 -0.3302)
						)
						(arc
							(start -0.4318 0.3302)
							(mid -0.402042 0.402042)
							(end -0.3302 0.4318)
						)
						(arc
							(start 0.3302 0.4318)
							(mid 0.402042 0.402042)
							(end 0.4318 0.3302)
						)
						(arc
							(start 0.4318 -0.3302)
							(mid 0.402042 -0.402042)
							(end 0.3302 -0.4318)
						)
					)
					(width 0)
					(fill yes)
				)
			)
		)
	)
	(footprint ""
		(layer "F.Cu")
		(at 477.719136 -294.679878 90)
		(property "Reference" "R384"
			(at 0 0 90)
			(layer "F.SilkS")
			(hide yes)
			(effects
				(font
					(size 1.27 1.27)
				)
			)
		)
		(property "Value" "2R6F-GP"
			(at -0.0508 -4.8514 90)
			(unlocked yes)
			(layer "F.Fab")
			(hide yes)
			(effects
				(font
					(size 1.016 1.016)
					(thickness 0.1524)
				)
			)
		)
		(property "Device Type" "R1206H26"
			(at 0 -6.3754 90)
			(unlocked yes)
			(layer "F.Fab")
			(hide yes)
			(effects
				(font
					(size 1.016 1.016)
					(thickness 0.1524)
				)
			)
		)
		(duplicate_pad_numbers_are_jumpers no)
		(fp_line
			(start 1.016 -2.2352)
			(end 1.016 2.2352)
			(stroke
				(width 0.1524)
				(type default)
			)
			(layer "F.SilkS")
		)
		(fp_line
			(start -1.016 -2.2352)
			(end 1.016 -2.2352)
			(stroke
				(width 0.1524)
				(type default)
			)
			(layer "F.SilkS")
		)
		(fp_line
			(start 1.016 2.2352)
			(end -1.016 2.2352)
			(stroke
				(width 0.1524)
				(type default)
			)
			(layer "F.SilkS")
		)
		(fp_line
			(start -1.016 2.2352)
			(end -1.016 -2.2352)
			(stroke
				(width 0.1524)
				(type default)
			)
			(layer "F.SilkS")
		)
		(fp_rect
			(start -1.0922 2.3114)
			(end 1.0922 -2.3114)
			(stroke
				(width 0)
				(type default)
			)
			(fill no)
			(layer "F.CrtYd")
		)
		(fp_poly
			(pts
				(xy -1.0922 -2.3114) (xy 1.0922 -2.3114) (xy 1.0922 2.3114) (xy -1.0922 2.3114)
			)
			(stroke
				(width 0)
				(type default)
			)
			(fill no)
			(layer "F.Fab")
		)
		(pad "1" smd rect
			(at 0 -1.397 90)
			(size 1.651 1.27)
			(layers "F.Cu" "F.Mask" "F.Paste")
			(net "P12V_HDD11")
		)
		(pad "2" smd rect
			(at 0 1.397 90)
			(size 1.651 1.27)
			(layers "F.Cu" "F.Mask" "F.Paste")
			(net "12V_PRE_11")
		)
	)
	(footprint ""
		(layer "F.Cu")
		(at 303.8729 -72.3265 -90)
		(property "Reference" "R347"
			(at 0 0 270)
			(layer "F.SilkS")
			(hide yes)
			(effects
				(font
					(size 1.27 1.27)
				)
			)
		)
		(property "Value" "4K7R2F-GP"
			(at 0.064008 -3.993896 270)
			(unlocked yes)
			(layer "F.Fab")
			(hide yes)
			(effects
				(font
					(size 1.016 1.016)
					(thickness 0.1524)
				)
			)
		)
		(property "Device Type" "R402H16"
			(at 0.064008 -5.517896 270)
			(unlocked yes)
			(layer "F.Fab")
			(hide yes)
			(effects
				(font
					(size 1.016 1.016)
					(thickness 0.1524)
				)
			)
		)
		(duplicate_pad_numbers_are_jumpers no)
		(fp_line
			(start -0.508 -0.9398)
			(end -0.508 0.9398)
			(stroke
				(width 0.1524)
				(type default)
			)
			(layer "F.SilkS")
		)
		(fp_line
			(start 0.508 -0.9398)
			(end -0.508 -0.9398)
			(stroke
				(width 0.1524)
				(type default)
			)
			(layer "F.SilkS")
		)
		(fp_rect
			(start -0.508 0.9398)
			(end 0.508 -0.9398)
			(stroke
				(width 0)
				(type default)
			)
			(fill no)
			(layer "F.CrtYd")
		)
		(fp_rect
			(start -0.508 0.9398)
			(end 0.508 -0.9398)
			(stroke
				(width 0)
				(type default)
			)
			(fill no)
			(layer "F.Fab")
		)
		(pad "1" smd custom
			(at 0 -0.4445 270)
			(size 0.1397 0.1397)
			(layers "F.Cu" "F.Mask" "F.Paste")
			(net "TXS0102_B_OE")
			(options
				(clearance outline)
				(anchor circle)
			)
			(primitives
				(gr_poly
					(pts
						(arc
							(start -0.1778 -0.2794)
							(mid -0.249642 -0.249642)
							(end -0.2794 -0.1778)
						)
						(arc
							(start -0.2794 0.1778)
							(mid -0.249642 0.249642)
							(end -0.1778 0.2794)
						)
						(arc
							(start 0.1778 0.2794)
							(mid 0.249642 0.249642)
							(end 0.2794 0.1778)
						)
						(arc
							(start 0.2794 -0.1778)
							(mid 0.249642 -0.249642)
							(end 0.1778 -0.2794)
						)
					)
					(width 0)
					(fill yes)
				)
			)
		)
		(pad "2" smd custom
			(at 0 0.4445 270)
			(size 0.1397 0.1397)
			(layers "F.Cu" "F.Mask" "F.Paste")
			(net "P3V3_STBY_B")
			(options
				(clearance outline)
				(anchor circle)
			)
			(primitives
				(gr_poly
					(pts
						(arc
							(start -0.1778 -0.2794)
							(mid -0.249642 -0.249642)
							(end -0.2794 -0.1778)
						)
						(arc
							(start -0.2794 0.1778)
							(mid -0.249642 0.249642)
							(end -0.1778 0.2794)
						)
						(arc
							(start 0.1778 0.2794)
							(mid 0.249642 0.249642)
							(end 0.2794 0.1778)
						)
						(arc
							(start 0.2794 -0.1778)
							(mid 0.249642 -0.249642)
							(end 0.1778 -0.2794)
						)
					)
					(width 0)
					(fill yes)
				)
			)
		)
	)
	(footprint ""
		(layer "F.Cu")
		(at 250.94438 -256.795778)
		(property "Reference" "C17"
			(at 0 0 0)
			(layer "F.SilkS")
			(hide yes)
			(effects
				(font
					(size 1.27 1.27)
				)
			)
		)
		(property "Value" "SC1U16V3KX-5GP"
			(at 0 -2.8194 0)
			(unlocked yes)
			(layer "F.Fab")
			(hide yes)
			(effects
				(font
					(size 1.016 1.016)
					(thickness 0.1524)
				)
			)
		)
		(property "Device Type" "C603H36"
			(at 0 -4.3434 0)
			(unlocked yes)
			(layer "F.Fab")
			(hide yes)
			(effects
				(font
					(size 1.016 1.016)
					(thickness 0.1524)
				)
			)
		)
		(duplicate_pad_numbers_are_jumpers no)
		(fp_line
			(start 0.508 0)
			(end -0.508 0)
			(stroke
				(width 0.2032)
				(type default)
			)
			(layer "F.SilkS")
		)
		(fp_rect
			(start -0.5842 1.3335)
			(end 0.5842 -1.3335)
			(stroke
				(width 0)
				(type default)
			)
			(fill no)
			(layer "F.CrtYd")
		)
		(fp_rect
			(start -0.5842 1.3335)
			(end 0.5842 -1.3335)
			(stroke
				(width 0)
				(type default)
			)
			(fill no)
			(layer "F.Fab")
		)
		(pad "1" smd custom
			(at 0 -0.762)
			(size 0.2159 0.2159)
			(layers "F.Cu" "F.Mask" "F.Paste")
			(net "P3V3_STBY_A")
			(options
				(clearance outline)
				(anchor circle)
			)
			(primitives
				(gr_poly
					(pts
						(arc
							(start -0.3302 -0.4318)
							(mid -0.402042 -0.402042)
							(end -0.4318 -0.3302)
						)
						(arc
							(start -0.4318 0.3302)
							(mid -0.402042 0.402042)
							(end -0.3302 0.4318)
						)
						(arc
							(start 0.3302 0.4318)
							(mid 0.402042 0.402042)
							(end 0.4318 0.3302)
						)
						(arc
							(start 0.4318 -0.3302)
							(mid 0.402042 -0.402042)
							(end 0.3302 -0.4318)
						)
					)
					(width 0)
					(fill yes)
				)
			)
		)
		(pad "2" smd custom
			(at 0 0.762)
			(size 0.2159 0.2159)
			(layers "F.Cu" "F.Mask" "F.Paste")
			(net "GND")
			(options
				(clearance outline)
				(anchor circle)
			)
			(primitives
				(gr_poly
					(pts
						(arc
							(start -0.3302 -0.4318)
							(mid -0.402042 -0.402042)
							(end -0.4318 -0.3302)
						)
						(arc
							(start -0.4318 0.3302)
							(mid -0.402042 0.402042)
							(end -0.3302 0.4318)
						)
						(arc
							(start 0.3302 0.4318)
							(mid 0.402042 0.402042)
							(end 0.4318 0.3302)
						)
						(arc
							(start 0.4318 -0.3302)
							(mid 0.402042 -0.402042)
							(end 0.3302 -0.4318)
						)
					)
					(width 0)
					(fill yes)
				)
			)
		)
	)
	(footprint ""
		(layer "F.Cu")
		(at 150.311866 -137.371074)
		(property "Reference" "C569"
			(at 0 0 0)
			(layer "F.SilkS")
			(hide yes)
			(effects
				(font
					(size 1.27 1.27)
				)
			)
		)
		(property "Value" "SCD015U25V2KX-GP"
			(at 1.1811 -2.7051 0)
			(unlocked yes)
			(layer "F.Fab")
			(hide yes)
			(effects
				(font
					(size 1.016 1.016)
					(thickness 0.1524)
				)
			)
		)
		(property "Device Type" "C402H22"
			(at 1.1811 -4.2291 0)
			(unlocked yes)
			(layer "F.Fab")
			(hide yes)
			(effects
				(font
					(size 1.016 1.016)
					(thickness 0.1524)
				)
			)
		)
		(duplicate_pad_numbers_are_jumpers no)
		(fp_rect
			(start -0.4318 0.9525)
			(end 0.4318 -0.9525)
			(stroke
				(width 0)
				(type default)
			)
			(fill no)
			(layer "F.CrtYd")
		)
		(fp_rect
			(start -0.4318 0.9525)
			(end 0.4318 -0.9525)
			(stroke
				(width 0)
				(type default)
			)
			(fill no)
			(layer "F.Fab")
		)
		(pad "1" smd custom
			(at 0 -0.4445)
			(size 0.1524 0.1524)
			(layers "F.Cu" "F.Mask" "F.Paste")
			(net "MB0_HS_SENSE_P")
			(options
				(clearance outline)
				(anchor circle)
			)
			(primitives
				(gr_poly
					(pts
						(arc
							(start 0.3048 -0.2032)
							(mid 0.275042 -0.275042)
							(end 0.2032 -0.3048)
						)
						(arc
							(start -0.2032 -0.3048)
							(mid -0.275042 -0.275042)
							(end -0.3048 -0.2032)
						)
						(arc
							(start -0.3048 0.2032)
							(mid -0.275042 0.275042)
							(end -0.2032 0.3048)
						)
						(arc
							(start 0.2032 0.3048)
							(mid 0.275042 0.275042)
							(end 0.3048 0.2032)
						)
					)
					(width 0)
					(fill yes)
				)
			)
		)
		(pad "2" smd custom
			(at 0 0.4445)
			(size 0.1524 0.1524)
			(layers "F.Cu" "F.Mask" "F.Paste")
			(net "MB0_HS_SENSE_N")
			(options
				(clearance outline)
				(anchor circle)
			)
			(primitives
				(gr_poly
					(pts
						(arc
							(start 0.3048 -0.2032)
							(mid 0.275042 -0.275042)
							(end 0.2032 -0.3048)
						)
						(arc
							(start -0.2032 -0.3048)
							(mid -0.275042 -0.275042)
							(end -0.3048 -0.2032)
						)
						(arc
							(start -0.3048 0.2032)
							(mid -0.275042 0.275042)
							(end -0.2032 0.3048)
						)
						(arc
							(start 0.2032 0.3048)
							(mid 0.275042 0.275042)
							(end 0.3048 0.2032)
						)
					)
					(width 0)
					(fill yes)
				)
			)
		)
	)
	(footprint ""
		(layer "F.Cu")
		(at 96.324928 -322.799964)
		(property "Reference" ""
			(at 0 0 0)
			(layer "F.SilkS")
			(hide yes)
			(effects
				(font
					(size 1.27 1.27)
				)
			)
		)
		(property "Value" "*"
			(at -8.398764 -8.057642 0)
			(unlocked yes)
			(layer "F.Fab")
			(hide yes)
			(effects
				(font
					(size 1.016 1.016)
					(thickness 0.1524)
				)
			)
		)
		(duplicate_pad_numbers_are_jumpers no)
		(fp_poly
			(pts
				(arc
					(start 7.3152 0)
					(mid 0 7.3152)
					(end -7.3152 0)
				)
				(arc
					(start -7.3152 -5.9944)
					(mid 0 -13.3096)
					(end 7.3152 -5.9944)
				)
			)
			(stroke
				(width 0)
				(type default)
			)
			(fill no)
			(layer "B.CrtYd")
		)
		(fp_poly
			(pts
				(arc
					(start 7.3152 0)
					(mid 0 7.3152)
					(end -7.3152 0)
				)
				(arc
					(start -7.3152 -5.9944)
					(mid 0 -13.3096)
					(end 7.3152 -5.9944)
				)
			)
			(stroke
				(width 0)
				(type default)
			)
			(fill no)
			(layer "F.CrtYd")
		)
		(fp_poly
			(pts
				(arc
					(start 7.3152 0)
					(mid 0 7.3152)
					(end -7.3152 0)
				)
				(arc
					(start -7.3152 -5.9944)
					(mid 0 -13.3096)
					(end 7.3152 -5.9944)
				)
			)
			(stroke
				(width 0)
				(type default)
			)
			(fill no)
			(layer "B.Fab")
		)
		(fp_poly
			(pts
				(arc
					(start 7.3152 0)
					(mid 0 7.3152)
					(end -7.3152 0)
				)
				(arc
					(start -7.3152 -5.9944)
					(mid 0 -13.3096)
					(end 7.3152 -5.9944)
				)
			)
			(stroke
				(width 0)
				(type default)
			)
			(fill no)
			(layer "F.Fab")
		)
		(pad "1" thru_hole oval
			(at 0 0)
			(size 14.0208 20.0152)
			(drill 0.0254
				(offset 0 -2.9972)
			)
			(layers "*.Cu" "*.Mask")
			(remove_unused_layers no)
			(net "Net_106")
			(clearance -1.002284)
			(thermal_gap 0.1524)
			(padstack
				(mode front_inner_back)
				(layer "Inner"
					(shape custom)
					(size 2.928012 2.928012)
					(options
						(anchor circle)
					)
					(primitives
						(gr_poly
							(pts
								(arc
									(start 4.571746 -2.084324)
									(mid 0.000333 7.430372)
									(end -4.571492 -2.084324)
								)
								(arc
									(start -4.571492 -2.084324)
									(mid -3.570296 -3.611977)
									(end -2.875026 -5.30098)
								)
								(arc
									(start -2.875026 -5.30098)
									(mid 0.000217 -7.43089)
									(end 2.87528 -5.30098)
								)
								(arc
									(start 2.87528 -5.30098)
									(mid 3.570511 -3.611956)
									(end 4.571746 -2.084324)
								)
							)
							(width 0)
							(fill yes)
						)
					)
					(clearance 0.1524)
				)
				(layer "B.Cu"
					(shape oval)
					(size 14.0208 20.0152)
					(offset 0 -2.9972)
					(clearance -1.002284)
				)
			)
		)
		(zone
			(layers "F.Cu" "B.Cu" "In1.Cu" "In2.Cu" "In3.Cu" "In4.Cu" "In5.Cu" "In6.Cu"
				"In7.Cu" "In8.Cu" "In9.Cu" "In10.Cu"
			)
			(hatch none 0.5)
			(connect_pads
				(clearance 0)
			)
			(min_thickness 0.25)
			(keepout
				(tracks not_allowed)
				(vias allowed)
				(pads allowed)
				(copperpour not_allowed)
				(footprints allowed)
			)
			(placement
				(enabled no)
				(sheetname "")
			)
			(fill
				(thermal_gap 0.5)
				(thermal_bridge_width 0.5)
				(island_removal_mode 0)
			)
			(polygon
				(pts
					(arc
						(start 89.314528 -328.794364)
						(mid 96.324928 -335.804764)
						(end 103.335328 -328.794364)
					)
					(arc
						(start 103.335328 -322.799964)
						(mid 96.324928 -315.789564)
						(end 89.314528 -322.799964)
					)
				)
			)
		)
	)
	(footprint ""
		(layer "F.Cu")
		(at 416.284664 -158.660592 -90)
		(property "Reference" "C312"
			(at 0 0 270)
			(layer "F.SilkS")
			(hide yes)
			(effects
				(font
					(size 1.27 1.27)
				)
			)
		)
		(property "Value" "SCD01U16V1KX-GP"
			(at -2.8321 -1.7399 270)
			(unlocked yes)
			(layer "F.Fab")
			(hide yes)
			(effects
				(font
					(size 1.016 1.016)
					(thickness 0.1524)
				)
			)
		)
		(property "Device Type" "C0201H13"
			(at -2.8321 -3.2639 270)
			(unlocked yes)
			(layer "F.Fab")
			(hide yes)
			(effects
				(font
					(size 1.016 1.016)
					(thickness 0.1524)
				)
			)
		)
		(duplicate_pad_numbers_are_jumpers no)
		(fp_rect
			(start -0.2794 0.6477)
			(end 0.2794 -0.6477)
			(stroke
				(width 0)
				(type default)
			)
			(fill no)
			(layer "F.CrtYd")
		)
		(fp_rect
			(start -0.2794 0.6477)
			(end 0.2794 -0.6477)
			(stroke
				(width 0)
				(type default)
			)
			(fill no)
			(layer "F.Fab")
		)
		(pad "1" smd custom
			(at 0 -0.2794 270)
			(size 0.0762 0.0762)
			(layers "F.Cu" "F.Mask" "F.Paste")
			(net "SAS_HDD_RX_P21")
			(options
				(clearance outline)
				(anchor circle)
			)
			(primitives
				(gr_poly
					(pts
						(arc
							(start 0.1524 -0.127)
							(mid 0.137521 -0.162921)
							(end 0.1016 -0.1778)
						)
						(arc
							(start -0.1016 -0.1778)
							(mid -0.137521 -0.162921)
							(end -0.1524 -0.127)
						)
						(arc
							(start -0.1524 0.127)
							(mid -0.137521 0.162921)
							(end -0.1016 0.1778)
						)
						(arc
							(start 0.1016 0.1778)
							(mid 0.137521 0.162921)
							(end 0.1524 0.127)
						)
					)
					(width 0)
					(fill yes)
				)
			)
		)
		(pad "2" smd custom
			(at 0 0.2794 270)
			(size 0.0762 0.0762)
			(layers "F.Cu" "F.Mask" "F.Paste")
			(net "PHY_SCC_A_TO_DRV_A_21_DP")
			(options
				(clearance outline)
				(anchor circle)
			)
			(primitives
				(gr_poly
					(pts
						(arc
							(start 0.1524 -0.127)
							(mid 0.137521 -0.162921)
							(end 0.1016 -0.1778)
						)
						(arc
							(start -0.1016 -0.1778)
							(mid -0.137521 -0.162921)
							(end -0.1524 -0.127)
						)
						(arc
							(start -0.1524 0.127)
							(mid -0.137521 0.162921)
							(end -0.1016 0.1778)
						)
						(arc
							(start 0.1016 0.1778)
							(mid 0.137521 0.162921)
							(end 0.1524 0.127)
						)
					)
					(width 0)
					(fill yes)
				)
			)
		)
	)
	(footprint ""
		(layer "F.Cu")
		(at 412.531052 -180.064918 -90)
		(property "Reference" "R617"
			(at 0 0 270)
			(layer "F.SilkS")
			(hide yes)
			(effects
				(font
					(size 1.27 1.27)
				)
			)
		)
		(property "Value" "220R3F-1-GP"
			(at -0.0254 -2.5146 270)
			(unlocked yes)
			(layer "F.Fab")
			(hide yes)
			(effects
				(font
					(size 1.016 1.016)
					(thickness 0.1524)
				)
			)
		)
		(property "Device Type" "R603H22"
			(at -0.0254 -4.0386 270)
			(unlocked yes)
			(layer "F.Fab")
			(hide yes)
			(effects
				(font
					(size 1.016 1.016)
					(thickness 0.1524)
				)
			)
		)
		(duplicate_pad_numbers_are_jumpers no)
		(fp_line
			(start -0.4826 0)
			(end -0.2032 0)
			(stroke
				(width 0.2032)
				(type default)
			)
			(layer "F.SilkS")
		)
		(fp_line
			(start 0.2032 0)
			(end 0.4826 0)
			(stroke
				(width 0.2032)
				(type default)
			)
			(layer "F.SilkS")
		)
		(fp_rect
			(start -0.5842 1.3335)
			(end 0.5842 -1.3335)
			(stroke
				(width 0)
				(type default)
			)
			(fill no)
			(layer "F.CrtYd")
		)
		(fp_rect
			(start -0.5842 1.3335)
			(end 0.5842 -1.3335)
			(stroke
				(width 0)
				(type default)
			)
			(fill no)
			(layer "F.Fab")
		)
		(pad "1" smd custom
			(at 0 -0.762 270)
			(size 0.2159 0.2159)
			(layers "F.Cu" "F.Mask" "F.Paste")
			(net "HDD_PRSNT_21")
			(options
				(clearance outline)
				(anchor circle)
			)
			(primitives
				(gr_poly
					(pts
						(arc
							(start -0.3302 -0.4318)
							(mid -0.402042 -0.402042)
							(end -0.4318 -0.3302)
						)
						(arc
							(start -0.4318 0.3302)
							(mid -0.402042 0.402042)
							(end -0.3302 0.4318)
						)
						(arc
							(start 0.3302 0.4318)
							(mid 0.402042 0.402042)
							(end 0.4318 0.3302)
						)
						(arc
							(start 0.4318 -0.3302)
							(mid 0.402042 -0.402042)
							(end 0.3302 -0.4318)
						)
					)
					(width 0)
					(fill yes)
				)
			)
		)
		(pad "2" smd custom
			(at 0 0.762 270)
			(size 0.2159 0.2159)
			(layers "F.Cu" "F.Mask" "F.Paste")
			(net "DRIVE_A_21_INS")
			(options
				(clearance outline)
				(anchor circle)
			)
			(primitives
				(gr_poly
					(pts
						(arc
							(start -0.3302 -0.4318)
							(mid -0.402042 -0.402042)
							(end -0.4318 -0.3302)
						)
						(arc
							(start -0.4318 0.3302)
							(mid -0.402042 0.402042)
							(end -0.3302 0.4318)
						)
						(arc
							(start 0.3302 0.4318)
							(mid 0.402042 0.402042)
							(end 0.4318 0.3302)
						)
						(arc
							(start 0.4318 -0.3302)
							(mid 0.402042 -0.402042)
							(end 0.3302 -0.4318)
						)
					)
					(width 0)
					(fill yes)
				)
			)
		)
	)
	(footprint ""
		(layer "F.Cu")
		(at 281.999944 -111.149892 90)
		(property "Reference" "MONO3"
			(at 0 0 90)
			(layer "F.SilkS")
			(hide yes)
			(effects
				(font
					(size 1.27 1.27)
				)
			)
		)
		(property "Value" "AMP-CONN164-4R-1-GP"
			(at -25.705054 -1.203706 90)
			(unlocked yes)
			(layer "F.Fab")
			(hide yes)
			(effects
				(font
					(size 1.016 1.016)
					(thickness 0.1524)
				)
			)
		)
		(property "Device Type" "PREFIT-164P-890091-1H441"
			(at -25.705054 -2.727706 90)
			(unlocked yes)
			(layer "F.Fab")
			(hide yes)
			(effects
				(font
					(size 1.016 1.016)
					(thickness 0.1524)
				)
			)
		)
		(duplicate_pad_numbers_are_jumpers no)
		(fp_line
			(start 74.5998 -4.1656)
			(end 74.5998 5.4102)
			(stroke
				(width 0.1524)
				(type default)
			)
			(layer "F.SilkS")
		)
		(fp_line
			(start -14.9098 -4.1656)
			(end 74.5998 -4.1656)
			(stroke
				(width 0.1524)
				(type default)
			)
			(layer "F.SilkS")
		)
		(fp_line
			(start 74.5998 5.4102)
			(end -14.9098 5.4102)
			(stroke
				(width 0.1524)
				(type default)
			)
			(layer "F.SilkS")
		)
		(fp_line
			(start -14.9098 5.4102)
			(end -14.9098 -4.1656)
			(stroke
				(width 0.1524)
				(type default)
			)
			(layer "F.SilkS")
		)
		(fp_poly
			(pts
				(xy -14.9098 5.4102) (xy -14.9098 -4.1656) (xy 74.5998 -4.1656) (xy 74.5998 -3.98653) (xy -13.5636 -3.98653)
				(xy -13.5636 3.98653) (xy 23.4442 3.98653) (xy 23.4442 5.3086) (xy 33.8074 5.3086) (xy 33.8074 3.98653)
				(xy 74.5998 3.98653) (xy 74.5998 5.4102)
			)
			(stroke
				(width 0)
				(type default)
			)
			(fill yes)
			(layer "F.SilkS")
		)
		(fp_poly
			(pts
				(arc
					(start -13.1826 -2.99593)
					(mid -13.4366 -3.24993)
					(end -13.1826 -3.50393)
				)
				(arc
					(start -12.6746 -3.50393)
					(mid -12.4206 -3.24993)
					(end -12.6746 -2.99593)
				)
			)
			(stroke
				(width 0)
				(type default)
			)
			(fill yes)
			(layer "F.SilkS")
		)
		(fp_poly
			(pts
				(arc
					(start -13.1826 -0.995934)
					(mid -13.4366 -1.249934)
					(end -13.1826 -1.503934)
				)
				(arc
					(start -12.6746 -1.503934)
					(mid -12.4206 -1.249934)
					(end -12.6746 -0.995934)
				)
			)
			(stroke
				(width 0)
				(type default)
			)
			(fill yes)
			(layer "F.SilkS")
		)
		(fp_poly
			(pts
				(arc
					(start -13.1826 1.503934)
					(mid -13.4366 1.249934)
					(end -13.1826 0.995934)
				)
				(arc
					(start -12.6746 0.995934)
					(mid -12.4206 1.249934)
					(end -12.6746 1.503934)
				)
			)
			(stroke
				(width 0)
				(type default)
			)
			(fill yes)
			(layer "F.SilkS")
		)
		(fp_poly
			(pts
				(arc
					(start -13.1826 3.50393)
					(mid -13.4366 3.24993)
					(end -13.1826 2.99593)
				)
				(arc
					(start -12.6746 2.99593)
					(mid -12.4206 3.24993)
					(end -12.6746 3.50393)
				)
			)
			(stroke
				(width 0)
				(type default)
			)
			(fill yes)
			(layer "F.SilkS")
		)
		(fp_rect
			(start -17.1958 8.7884)
			(end 76.8858 -8.7884)
			(stroke
				(width 0)
				(type default)
			)
			(fill no)
			(layer "B.CrtYd")
		)
		(fp_rect
			(start -14.6558 5.1562)
			(end 74.3458 -3.9116)
			(stroke
				(width 0)
				(type default)
			)
			(fill no)
			(layer "F.CrtYd")
		)
		(fp_poly
			(pts
				(xy -15.1638 5.6642) (xy -15.1638 -4.4196) (xy 74.8538 -4.4196) (xy 74.8538 -0.00635) (xy 74.3458 -0.00635)
				(xy 74.3458 -3.9116) (xy -14.6558 -3.9116) (xy -14.6558 5.1562) (xy 74.3458 5.1562) (xy 74.3458 0.00635)
				(xy 74.8538 0.00635) (xy 74.8538 5.6642)
			)
			(stroke
				(width 0)
				(type default)
			)
			(fill no)
			(layer "F.CrtYd")
		)
		(fp_poly
			(pts
				(xy -19.6596 10.16) (xy -19.6596 0.00635) (xy -15.1638 0.00635) (xy -15.1638 5.6642) (xy 74.8538 5.6642)
				(xy 74.8538 -4.4196) (xy -15.1638 -4.4196) (xy -15.1638 -0.00635) (xy -19.6596 -0.00635) (xy -19.6596 -8.9154)
				(xy 79.3496 -8.9154) (xy 79.3496 10.16)
			)
			(stroke
				(width 0)
				(type default)
			)
			(fill no)
			(layer "F.CrtYd")
		)
		(fp_rect
			(start -17.1958 8.7884)
			(end 76.8858 -8.7884)
			(stroke
				(width 0)
				(type default)
			)
			(fill no)
			(layer "B.Fab")
		)
		(fp_rect
			(start -22.1996 13.7922)
			(end 81.8896 -13.7922)
			(stroke
				(width 0)
				(type default)
			)
			(fill no)
			(layer "B.Fab")
		)
		(fp_rect
			(start -15.1638 5.6642)
			(end 74.8538 -4.4196)
			(stroke
				(width 0)
				(type default)
			)
			(fill no)
			(layer "F.Fab")
		)
		(fp_rect
			(start -19.6596 10.16)
			(end 79.3496 -8.9154)
			(stroke
				(width 0)
				(type default)
			)
			(fill no)
			(layer "F.Fab")
		)
		(fp_rect
			(start -24.6634 15.1638)
			(end 84.3534 -13.9192)
			(stroke
				(width 0)
				(type default)
			)
			(fill no)
			(layer "F.Fab")
		)
		(fp_text user "Press Fit"
			(at 23.495 4.6482 90)
			(unlocked yes)
			(layer "F.SilkS")
			(effects
				(font
					(size 1.016 1.016)
					(thickness 0.1524)
				)
				(justify left)
			)
		)
		(fp_text user "Can not place BGA,CSP,Wave Solder Component"
			(at 2.032 12.2428 90)
			(unlocked yes)
			(layer "B.Fab")
			(effects
				(font
					(size 1.016 1.016)
					(thickness 0.1524)
				)
				(justify left)
			)
		)
		(fp_text user "High Limit 2mm"
			(at 18.8214 9.025636 90)
			(unlocked yes)
			(layer "F.Fab")
			(effects
				(font
					(size 1.016 1.016)
					(thickness 0.1524)
				)
				(justify left)
			)
		)
		(fp_text user "Can not place BGA,CSP,Wave Solder Component"
			(at 2.032 13.7668 90)
			(unlocked yes)
			(layer "F.Fab")
			(effects
				(font
					(size 1.016 1.016)
					(thickness 0.1524)
				)
				(justify left)
			)
		)
		(pad "" np_thru_hole circle
			(at 0 0 90)
			(size 0.254 0.254)
			(drill 2.3622)
			(layers "*.Cu" "*.Mask")
			(clearance 1.4097)
			(thermal_gap 1.4097)
		)
		(pad "" np_thru_hole circle
			(at 73.149968 0 90)
			(size 0.254 0.254)
			(drill 2.3622)
			(layers "*.Cu" "*.Mask")
			(clearance 1.4097)
			(thermal_gap 1.4097)
		)
		(pad "A1" thru_hole circle
			(at -11.649964 -1.249934 90)
			(size 1.0668 1.0668)
			(drill 0.719836)
			(layers "*.Cu" "*.Mask")
			(remove_unused_layers no)
			(net "COMP_B_PRI_INS_N")
			(clearance 0.1905)
			(thermal_gap 0.1905)
		)
		(pad "A2" thru_hole circle
			(at -10.649966 -3.24993 90)
			(size 1.0668 1.0668)
			(drill 0.719836)
			(layers "*.Cu" "*.Mask")
			(remove_unused_layers no)
			(net "P12V_B_COMP")
			(clearance 0.1905)
			(thermal_gap 0.1905)
		)
		(pad "A3" thru_hole circle
			(at -9.649968 -1.249934 90)
			(size 1.0668 1.0668)
			(drill 0.719836)
			(layers "*.Cu" "*.Mask")
			(remove_unused_layers no)
			(net "P12V_B_COMP")
			(clearance 0.1905)
			(thermal_gap 0.1905)
		)
		(pad "A4" thru_hole circle
			(at -8.64997 -3.24993 90)
			(size 1.0668 1.0668)
			(drill 0.719836)
			(layers "*.Cu" "*.Mask")
			(remove_unused_layers no)
			(net "GND")
			(clearance 0.1905)
			(thermal_gap 0.1905)
		)
		(pad "A5" thru_hole circle
			(at -7.649972 -1.249934 90)
			(size 1.0668 1.0668)
			(drill 0.719836)
			(layers "*.Cu" "*.Mask")
			(remove_unused_layers no)
			(net "SLOT1_SVR_ID0_GPIO0")
			(clearance 0.1905)
			(thermal_gap 0.1905)
		)
		(pad "A6" thru_hole circle
			(at -6.649974 -3.24993 90)
			(size 1.0668 1.0668)
			(drill 0.719836)
			(layers "*.Cu" "*.Mask")
			(remove_unused_layers no)
			(net "SLOT1_SVR_ID0_GPIO1")
			(clearance 0.1905)
			(thermal_gap 0.1905)
		)
		(pad "A7" thru_hole circle
			(at -5.649976 -1.249934 90)
			(size 1.0668 1.0668)
			(drill 0.719836)
			(layers "*.Cu" "*.Mask")
			(remove_unused_layers no)
			(net "UART_COMP_B_TX")
			(clearance 0.1905)
			(thermal_gap 0.1905)
		)
		(pad "A8" thru_hole circle
			(at -4.649978 -3.24993 90)
			(size 1.0668 1.0668)
			(drill 0.719836)
			(layers "*.Cu" "*.Mask")
			(remove_unused_layers no)
			(net "UART_COMP_B_RX")
			(clearance 0.1905)
			(thermal_gap 0.1905)
		)
		(pad "A9" thru_hole circle
			(at -3.64998 -1.249934 90)
			(size 1.0668 1.0668)
			(drill 0.719836)
			(layers "*.Cu" "*.Mask")
			(remove_unused_layers no)
			(net "SLOT1_SVR_ID0_GPIO2")
			(clearance 0.1905)
			(thermal_gap 0.1905)
		)
		(pad "A10" thru_hole circle
			(at -2.649982 -3.24993 90)
			(size 1.0668 1.0668)
			(drill 0.719836)
			(layers "*.Cu" "*.Mask")
			(remove_unused_layers no)
			(net "SLOT1_SVR_ID0_GPIO3")
			(clearance 0.1905)
			(thermal_gap 0.1905)
		)
		(pad "A11" thru_hole circle
			(at -1.649984 -1.249934 90)
			(size 1.0668 1.0668)
			(drill 0.719836)
			(layers "*.Cu" "*.Mask")
			(remove_unused_layers no)
			(net "PCIE_COMP_B_TO_SCC_B_RST_0")
			(clearance 0.1905)
			(thermal_gap 0.1905)
		)
		(pad "A12" thru_hole circle
			(at 1.35001 -3.24993 90)
			(size 1.0668 1.0668)
			(drill 0.719836)
			(layers "*.Cu" "*.Mask")
			(remove_unused_layers no)
			(net "GND")
			(clearance 0.1905)
			(thermal_gap 0.1905)
		)
		(pad "A13" thru_hole circle
			(at 2.350008 -1.249934 90)
			(size 1.0668 1.0668)
			(drill 0.719836)
			(layers "*.Cu" "*.Mask")
			(remove_unused_layers no)
			(net "PCIE_COMP_B_TO_SCC_B_CLK_0_DP")
			(clearance 0.1905)
			(thermal_gap 0.1905)
		)
		(pad "A14" thru_hole circle
			(at 3.350006 -3.24993 90)
			(size 1.0668 1.0668)
			(drill 0.719836)
			(layers "*.Cu" "*.Mask")
			(remove_unused_layers no)
			(net "PCIE_COMP_B_TO_SCC_B_CLK_0_DN")
			(clearance 0.1905)
			(thermal_gap 0.1905)
		)
		(pad "A15" thru_hole circle
			(at 4.350004 -1.249934 90)
			(size 1.0668 1.0668)
			(drill 0.719836)
			(layers "*.Cu" "*.Mask")
			(remove_unused_layers no)
			(net "GND")
			(clearance 0.1905)
			(thermal_gap 0.1905)
		)
		(pad "A16" thru_hole circle
			(at 5.350002 -3.24993 90)
			(size 1.0668 1.0668)
			(drill 0.719836)
			(layers "*.Cu" "*.Mask")
			(remove_unused_layers no)
			(net "GND")
			(clearance 0.1905)
			(thermal_gap 0.1905)
		)
		(pad "A17" thru_hole circle
			(at 6.35 -1.249934 90)
			(size 1.0668 1.0668)
			(drill 0.719836)
			(layers "*.Cu" "*.Mask")
			(remove_unused_layers no)
			(net "PCIE_SCC_B_TO_COMP_B_0_DP")
			(clearance 0.1905)
			(thermal_gap 0.1905)
		)
		(pad "A18" thru_hole circle
			(at 7.349998 -3.24993 90)
			(size 1.0668 1.0668)
			(drill 0.719836)
			(layers "*.Cu" "*.Mask")
			(remove_unused_layers no)
			(net "PCIE_SCC_B_TO_COMP_B_0_DN")
			(clearance 0.1905)
			(thermal_gap 0.1905)
		)
		(pad "A19" thru_hole circle
			(at 8.349996 -1.249934 90)
			(size 1.0668 1.0668)
			(drill 0.719836)
			(layers "*.Cu" "*.Mask")
			(remove_unused_layers no)
			(net "GND")
			(clearance 0.1905)
			(thermal_gap 0.1905)
		)
		(pad "A20" thru_hole circle
			(at 9.349994 -3.24993 90)
			(size 1.0668 1.0668)
			(drill 0.719836)
			(layers "*.Cu" "*.Mask")
			(remove_unused_layers no)
			(net "GND")
			(clearance 0.1905)
			(thermal_gap 0.1905)
		)
		(pad "A21" thru_hole circle
			(at 10.349992 -1.249934 90)
			(size 1.0668 1.0668)
			(drill 0.719836)
			(layers "*.Cu" "*.Mask")
			(remove_unused_layers no)
			(net "PCIE_SCC_B_TO_COMP_B_1_DP")
			(clearance 0.1905)
			(thermal_gap 0.1905)
		)
		(pad "A22" thru_hole circle
			(at 11.34999 -3.24993 90)
			(size 1.0668 1.0668)
			(drill 0.719836)
			(layers "*.Cu" "*.Mask")
			(remove_unused_layers no)
			(net "PCIE_SCC_B_TO_COMP_B_1_DN")
			(clearance 0.1905)
			(thermal_gap 0.1905)
		)
		(pad "A23" thru_hole circle
			(at 12.349988 -1.249934 90)
			(size 1.0668 1.0668)
			(drill 0.719836)
			(layers "*.Cu" "*.Mask")
			(remove_unused_layers no)
			(net "GND")
			(clearance 0.1905)
			(thermal_gap 0.1905)
		)
		(pad "A24" thru_hole circle
			(at 13.349986 -3.24993 90)
			(size 1.0668 1.0668)
			(drill 0.719836)
			(layers "*.Cu" "*.Mask")
			(remove_unused_layers no)
			(net "GND")
			(clearance 0.1905)
			(thermal_gap 0.1905)
		)
		(pad "A25" thru_hole circle
			(at 14.349984 -1.249934 90)
			(size 1.0668 1.0668)
			(drill 0.719836)
			(layers "*.Cu" "*.Mask")
			(remove_unused_layers no)
			(net "PCIE_SCC_B_TO_COMP_B_2_DP")
			(clearance 0.1905)
			(thermal_gap 0.1905)
		)
		(pad "A26" thru_hole circle
			(at 15.349982 -3.24993 90)
			(size 1.0668 1.0668)
			(drill 0.719836)
			(layers "*.Cu" "*.Mask")
			(remove_unused_layers no)
			(net "PCIE_SCC_B_TO_COMP_B_2_DN")
			(clearance 0.1905)
			(thermal_gap 0.1905)
		)
		(pad "A27" thru_hole circle
			(at 16.34998 -1.249934 90)
			(size 1.0668 1.0668)
			(drill 0.719836)
			(layers "*.Cu" "*.Mask")
			(remove_unused_layers no)
			(net "GND")
			(clearance 0.1905)
			(thermal_gap 0.1905)
		)
		(pad "A28" thru_hole circle
			(at 17.349978 -3.24993 90)
			(size 1.0668 1.0668)
			(drill 0.719836)
			(layers "*.Cu" "*.Mask")
			(remove_unused_layers no)
			(net "GND")
			(clearance 0.1905)
			(thermal_gap 0.1905)
		)
		(pad "A29" thru_hole circle
			(at 18.349976 -1.249934 90)
			(size 1.0668 1.0668)
			(drill 0.719836)
			(layers "*.Cu" "*.Mask")
			(remove_unused_layers no)
			(net "PCIE_SCC_B_TO_COMP_B_3_DP")
			(clearance 0.1905)
			(thermal_gap 0.1905)
		)
		(pad "A30" thru_hole circle
			(at 19.349974 -3.24993 90)
			(size 1.0668 1.0668)
			(drill 0.719836)
			(layers "*.Cu" "*.Mask")
			(remove_unused_layers no)
			(net "PCIE_SCC_B_TO_COMP_B_3_DN")
			(clearance 0.1905)
			(thermal_gap 0.1905)
		)
		(pad "A31" thru_hole circle
			(at 20.349972 -1.249934 90)
			(size 1.0668 1.0668)
			(drill 0.719836)
			(layers "*.Cu" "*.Mask")
			(remove_unused_layers no)
			(net "GND")
			(clearance 0.1905)
			(thermal_gap 0.1905)
		)
		(pad "A32" thru_hole circle
			(at 21.34997 -3.24993 90)
			(size 1.0668 1.0668)
			(drill 0.719836)
			(layers "*.Cu" "*.Mask")
			(remove_unused_layers no)
			(net "GND")
			(clearance 0.1905)
			(thermal_gap 0.1905)
		)
		(pad "A33" thru_hole circle
			(at 22.349968 -1.249934 90)
			(size 1.0668 1.0668)
			(drill 0.719836)
			(layers "*.Cu" "*.Mask")
			(remove_unused_layers no)
			(net "TP_COMP_B_SATA_P0_RX_DP")
			(clearance 0.1905)
			(thermal_gap 0.1905)
		)
		(pad "A34" thru_hole circle
			(at 23.349966 -3.24993 90)
			(size 1.0668 1.0668)
			(drill 0.719836)
			(layers "*.Cu" "*.Mask")
			(remove_unused_layers no)
			(net "TP_COMP_B_SATA_P0_RX_DN")
			(clearance 0.1905)
			(thermal_gap 0.1905)
		)
		(pad "A35" thru_hole circle
			(at 24.349964 -1.249934 90)
			(size 1.0668 1.0668)
			(drill 0.719836)
			(layers "*.Cu" "*.Mask")
			(remove_unused_layers no)
			(net "GND")
			(clearance 0.1905)
			(thermal_gap 0.1905)
		)
		(pad "A36" thru_hole circle
			(at 25.349962 -3.24993 90)
			(size 1.0668 1.0668)
			(drill 0.719836)
			(layers "*.Cu" "*.Mask")
			(remove_unused_layers no)
			(net "GND")
			(clearance 0.1905)
			(thermal_gap 0.1905)
		)
		(pad "A37" thru_hole circle
			(at 26.34996 -1.249934 90)
			(size 1.0668 1.0668)
			(drill 0.719836)
			(layers "*.Cu" "*.Mask")
			(remove_unused_layers no)
			(net "PCIE_COMP_B_TO_IOM_B_CLK_2_DP")
			(clearance 0.1905)
			(thermal_gap 0.1905)
		)
		(pad "A38" thru_hole circle
			(at 27.349958 -3.24993 90)
			(size 1.0668 1.0668)
			(drill 0.719836)
			(layers "*.Cu" "*.Mask")
			(remove_unused_layers no)
			(net "PCIE_COMP_B_TO_IOM_B_CLK_2_DN")
			(clearance 0.1905)
			(thermal_gap 0.1905)
		)
		(pad "A39" thru_hole circle
			(at 28.349956 -1.249934 90)
			(size 1.0668 1.0668)
			(drill 0.719836)
			(layers "*.Cu" "*.Mask")
			(remove_unused_layers no)
			(net "GND")
			(clearance 0.1905)
			(thermal_gap 0.1905)
		)
		(pad "A40" thru_hole circle
			(at 29.349954 -3.24993 90)
			(size 1.0668 1.0668)
			(drill 0.719836)
			(layers "*.Cu" "*.Mask")
			(remove_unused_layers no)
			(net "GND")
			(clearance 0.1905)
			(thermal_gap 0.1905)
		)
		(pad "A41" thru_hole circle
			(at 30.349952 -1.249934 90)
			(size 1.0668 1.0668)
			(drill 0.719836)
			(layers "*.Cu" "*.Mask")
			(remove_unused_layers no)
			(net "COMP_B_FAST_THROTTLE_N")
			(clearance 0.1905)
			(thermal_gap 0.1905)
		)
		(pad "A42" thru_hole circle
			(at 31.34995 -3.24993 90)
			(size 1.0668 1.0668)
			(drill 0.719836)
			(layers "*.Cu" "*.Mask")
			(remove_unused_layers no)
			(net "TP_SMB_COMP_B_NIC_ALERT_N")
			(clearance 0.1905)
			(thermal_gap 0.1905)
		)
		(pad "A43" thru_hole circle
			(at 32.349948 -1.249934 90)
			(size 1.0668 1.0668)
			(drill 0.719836)
			(layers "*.Cu" "*.Mask")
			(remove_unused_layers no)
			(net "GND")
			(clearance 0.1905)
			(thermal_gap 0.1905)
		)
		(pad "A44" thru_hole circle
			(at 33.349946 -3.24993 90)
			(size 1.0668 1.0668)
			(drill 0.719836)
			(layers "*.Cu" "*.Mask")
			(remove_unused_layers no)
			(net "GND")
			(clearance 0.1905)
			(thermal_gap 0.1905)
		)
		(pad "A45" thru_hole circle
			(at 34.349944 -1.249934 90)
			(size 1.0668 1.0668)
			(drill 0.719836)
			(layers "*.Cu" "*.Mask")
			(remove_unused_layers no)
			(net "TP_COMP_B_KR_P0_RX_DP")
			(clearance 0.1905)
			(thermal_gap 0.1905)
		)
		(pad "A46" thru_hole circle
			(at 35.349942 -3.24993 90)
			(size 1.0668 1.0668)
			(drill 0.719836)
			(layers "*.Cu" "*.Mask")
			(remove_unused_layers no)
			(net "TP_COMP_B_KR_P0_RX_DN")
			(clearance 0.1905)
			(thermal_gap 0.1905)
		)
		(pad "A47" thru_hole circle
			(at 36.34994 -1.249934 90)
			(size 1.0668 1.0668)
			(drill 0.719836)
			(layers "*.Cu" "*.Mask")
			(remove_unused_layers no)
			(net "GND")
			(clearance 0.1905)
			(thermal_gap 0.1905)
		)
		(pad "A48" thru_hole circle
			(at 37.349938 -3.24993 90)
			(size 1.0668 1.0668)
			(drill 0.719836)
			(layers "*.Cu" "*.Mask")
			(remove_unused_layers no)
			(net "GND")
			(clearance 0.1905)
			(thermal_gap 0.1905)
		)
		(pad "A49" thru_hole circle
			(at 38.349936 -1.249934 90)
			(size 1.0668 1.0668)
			(drill 0.719836)
			(layers "*.Cu" "*.Mask")
			(remove_unused_layers no)
			(net "PCIE_SCC_B_TO_COMP_B_4_DP")
			(clearance 0.1905)
			(thermal_gap 0.1905)
		)
		(pad "A50" thru_hole circle
			(at 39.349934 -3.24993 90)
			(size 1.0668 1.0668)
			(drill 0.719836)
			(layers "*.Cu" "*.Mask")
			(remove_unused_layers no)
			(net "PCIE_SCC_B_TO_COMP_B_4_DN")
			(clearance 0.1905)
			(thermal_gap 0.1905)
		)
		(pad "A51" thru_hole circle
			(at 40.349932 -1.249934 90)
			(size 1.0668 1.0668)
			(drill 0.719836)
			(layers "*.Cu" "*.Mask")
			(remove_unused_layers no)
			(net "GND")
			(clearance 0.1905)
			(thermal_gap 0.1905)
		)
		(pad "A52" thru_hole circle
			(at 41.34993 -3.24993 90)
			(size 1.0668 1.0668)
			(drill 0.719836)
			(layers "*.Cu" "*.Mask")
			(remove_unused_layers no)
			(net "GND")
			(clearance 0.1905)
			(thermal_gap 0.1905)
		)
		(pad "A53" thru_hole circle
			(at 42.349928 -1.249934 90)
			(size 1.0668 1.0668)
			(drill 0.719836)
			(layers "*.Cu" "*.Mask")
			(remove_unused_layers no)
			(net "PCIE_SCC_B_TO_COMP_B_5_DP")
			(clearance 0.1905)
			(thermal_gap 0.1905)
		)
		(pad "A54" thru_hole circle
			(at 43.349926 -3.24993 90)
			(size 1.0668 1.0668)
			(drill 0.719836)
			(layers "*.Cu" "*.Mask")
			(remove_unused_layers no)
			(net "PCIE_SCC_B_TO_COMP_B_5_DN")
			(clearance 0.1905)
			(thermal_gap 0.1905)
		)
		(pad "A55" thru_hole circle
			(at 44.349924 -1.249934 90)
			(size 1.0668 1.0668)
			(drill 0.719836)
			(layers "*.Cu" "*.Mask")
			(remove_unused_layers no)
			(net "GND")
			(clearance 0.1905)
			(thermal_gap 0.1905)
		)
		(pad "A56" thru_hole circle
			(at 45.349922 -3.24993 90)
			(size 1.0668 1.0668)
			(drill 0.719836)
			(layers "*.Cu" "*.Mask")
			(remove_unused_layers no)
			(net "GND")
			(clearance 0.1905)
			(thermal_gap 0.1905)
		)
		(pad "A57" thru_hole circle
			(at 46.34992 -1.249934 90)
			(size 1.0668 1.0668)
			(drill 0.719836)
			(layers "*.Cu" "*.Mask")
			(remove_unused_layers no)
			(net "PCIE_SCC_B_TO_COMP_B_6_DP")
			(clearance 0.1905)
			(thermal_gap 0.1905)
		)
		(pad "A58" thru_hole circle
			(at 47.349918 -3.24993 90)
			(size 1.0668 1.0668)
			(drill 0.719836)
			(layers "*.Cu" "*.Mask")
			(remove_unused_layers no)
			(net "PCIE_SCC_B_TO_COMP_B_6_DN")
			(clearance 0.1905)
			(thermal_gap 0.1905)
		)
		(pad "A59" thru_hole circle
			(at 48.349916 -1.249934 90)
			(size 1.0668 1.0668)
			(drill 0.719836)
			(layers "*.Cu" "*.Mask")
			(remove_unused_layers no)
			(net "GND")
			(clearance 0.1905)
			(thermal_gap 0.1905)
		)
		(pad "A60" thru_hole circle
			(at 49.349914 -3.24993 90)
			(size 1.0668 1.0668)
			(drill 0.719836)
			(layers "*.Cu" "*.Mask")
			(remove_unused_layers no)
			(net "GND")
			(clearance 0.1905)
			(thermal_gap 0.1905)
		)
		(pad "A61" thru_hole circle
			(at 50.349912 -1.249934 90)
			(size 1.0668 1.0668)
			(drill 0.719836)
			(layers "*.Cu" "*.Mask")
			(remove_unused_layers no)
			(net "PCIE_SCC_B_TO_COMP_B_7_DP")
			(clearance 0.1905)
			(thermal_gap 0.1905)
		)
		(pad "A62" thru_hole circle
			(at 51.34991 -3.24993 90)
			(size 1.0668 1.0668)
			(drill 0.719836)
			(layers "*.Cu" "*.Mask")
			(remove_unused_layers no)
			(net "PCIE_SCC_B_TO_COMP_B_7_DN")
			(clearance 0.1905)
			(thermal_gap 0.1905)
		)
		(pad "A63" thru_hole circle
			(at 52.349908 -1.249934 90)
			(size 1.0668 1.0668)
			(drill 0.719836)
			(layers "*.Cu" "*.Mask")
			(remove_unused_layers no)
			(net "GND")
			(clearance 0.1905)
			(thermal_gap 0.1905)
		)
		(pad "A64" thru_hole circle
			(at 53.349906 -3.24993 90)
			(size 1.0668 1.0668)
			(drill 0.719836)
			(layers "*.Cu" "*.Mask")
			(remove_unused_layers no)
			(net "GND")
			(clearance 0.1905)
			(thermal_gap 0.1905)
		)
		(pad "A65" thru_hole circle
			(at 54.349904 -1.249934 90)
			(size 1.0668 1.0668)
			(drill 0.719836)
			(layers "*.Cu" "*.Mask")
			(remove_unused_layers no)
			(net "PCIE_IOM_B_TO_COMP_B_8_DP")
			(clearance 0.1905)
			(thermal_gap 0.1905)
		)
		(pad "A66" thru_hole circle
			(at 55.349902 -3.24993 90)
			(size 1.0668 1.0668)
			(drill 0.719836)
			(layers "*.Cu" "*.Mask")
			(remove_unused_layers no)
			(net "PCIE_IOM_B_TO_COMP_B_8_DN")
			(clearance 0.1905)
			(thermal_gap 0.1905)
		)
		(pad "A67" thru_hole circle
			(at 56.3499 -1.249934 90)
			(size 1.0668 1.0668)
			(drill 0.719836)
			(layers "*.Cu" "*.Mask")
			(remove_unused_layers no)
			(net "GND")
			(clearance 0.1905)
			(thermal_gap 0.1905)
		)
		(pad "A68" thru_hole circle
			(at 57.349898 -3.24993 90)
			(size 1.0668 1.0668)
			(drill 0.719836)
			(layers "*.Cu" "*.Mask")
			(remove_unused_layers no)
			(net "GND")
			(clearance 0.1905)
			(thermal_gap 0.1905)
		)
		(pad "A69" thru_hole circle
			(at 58.349896 -1.249934 90)
			(size 1.0668 1.0668)
			(drill 0.719836)
			(layers "*.Cu" "*.Mask")
			(remove_unused_layers no)
			(net "PCIE_IOM_B_TO_COMP_B_9_DP")
			(clearance 0.1905)
			(thermal_gap 0.1905)
		)
		(pad "A70" thru_hole circle
			(at 59.349894 -3.24993 90)
			(size 1.0668 1.0668)
			(drill 0.719836)
			(layers "*.Cu" "*.Mask")
			(remove_unused_layers no)
			(net "PCIE_IOM_B_TO_COMP_B_9_DN")
			(clearance 0.1905)
			(thermal_gap 0.1905)
		)
		(pad "A71" thru_hole circle
			(at 60.349892 -1.249934 90)
			(size 1.0668 1.0668)
			(drill 0.719836)
			(layers "*.Cu" "*.Mask")
			(remove_unused_layers no)
			(net "GND")
			(clearance 0.1905)
			(thermal_gap 0.1905)
		)
		(pad "A72" thru_hole circle
			(at 61.34989 -3.24993 90)
			(size 1.0668 1.0668)
			(drill 0.719836)
			(layers "*.Cu" "*.Mask")
			(remove_unused_layers no)
			(net "GND")
			(clearance 0.1905)
			(thermal_gap 0.1905)
		)
		(pad "A73" thru_hole circle
			(at 62.349888 -1.249934 90)
			(size 1.0668 1.0668)
			(drill 0.719836)
			(layers "*.Cu" "*.Mask")
			(remove_unused_layers no)
			(net "PCIE_IOM_B_TO_COMP_B_10_DP")
			(clearance 0.1905)
			(thermal_gap 0.1905)
		)
		(pad "A74" thru_hole circle
			(at 63.349886 -3.24993 90)
			(size 1.0668 1.0668)
			(drill 0.719836)
			(layers "*.Cu" "*.Mask")
			(remove_unused_layers no)
			(net "PCIE_IOM_B_TO_COMP_B_10_DN")
			(clearance 0.1905)
			(thermal_gap 0.1905)
		)
		(pad "A75" thru_hole circle
			(at 64.349884 -1.249934 90)
			(size 1.0668 1.0668)
			(drill 0.719836)
			(layers "*.Cu" "*.Mask")
			(remove_unused_layers no)
			(net "GND")
			(clearance 0.1905)
			(thermal_gap 0.1905)
		)
		(pad "A76" thru_hole circle
			(at 65.349882 -3.24993 90)
			(size 1.0668 1.0668)
			(drill 0.719836)
			(layers "*.Cu" "*.Mask")
			(remove_unused_layers no)
			(net "GND")
			(clearance 0.1905)
			(thermal_gap 0.1905)
		)
		(pad "A77" thru_hole circle
			(at 66.34988 -1.249934 90)
			(size 1.0668 1.0668)
			(drill 0.719836)
			(layers "*.Cu" "*.Mask")
			(remove_unused_layers no)
			(net "PCIE_IOM_B_TO_COMP_B_11_DP")
			(clearance 0.1905)
			(thermal_gap 0.1905)
		)
		(pad "A78" thru_hole circle
			(at 67.349878 -3.24993 90)
			(size 1.0668 1.0668)
			(drill 0.719836)
			(layers "*.Cu" "*.Mask")
			(remove_unused_layers no)
			(net "PCIE_IOM_B_TO_COMP_B_11_DN")
			(clearance 0.1905)
			(thermal_gap 0.1905)
		)
		(pad "A79" thru_hole circle
			(at 68.349876 -1.249934 90)
			(size 1.0668 1.0668)
			(drill 0.719836)
			(layers "*.Cu" "*.Mask")
			(remove_unused_layers no)
			(net "GND")
			(clearance 0.1905)
			(thermal_gap 0.1905)
		)
		(pad "A80" thru_hole circle
			(at 69.349874 -3.24993 90)
			(size 1.0668 1.0668)
			(drill 0.719836)
			(layers "*.Cu" "*.Mask")
			(remove_unused_layers no)
			(net "GND")
			(clearance 0.1905)
			(thermal_gap 0.1905)
		)
		(pad "A81" thru_hole circle
			(at 70.350126 -1.249934 90)
			(size 1.0668 1.0668)
			(drill 0.719836)
			(layers "*.Cu" "*.Mask")
			(remove_unused_layers no)
			(net "P12V_B_COMP")
			(clearance 0.1905)
			(thermal_gap 0.1905)
		)
		(pad "A82" thru_hole circle
			(at 71.350124 -3.24993 90)
			(size 1.0668 1.0668)
			(drill 0.719836)
			(layers "*.Cu" "*.Mask")
			(remove_unused_layers no)
			(net "P12V_B_COMP")
			(clearance 0.1905)
			(thermal_gap 0.1905)
		)
		(pad "B1" thru_hole circle
			(at -11.649964 1.249934 90)
			(size 1.0668 1.0668)
			(drill 0.719836)
			(layers "*.Cu" "*.Mask")
			(remove_unused_layers no)
			(net "P12V_B_COMP")
			(clearance 0.1905)
			(thermal_gap 0.1905)
		)
		(pad "B2" thru_hole circle
			(at -10.649966 3.24993 90)
			(size 1.0668 1.0668)
			(drill 0.719836)
			(layers "*.Cu" "*.Mask")
			(remove_unused_layers no)
			(net "P12V_B_COMP")
			(clearance 0.1905)
			(thermal_gap 0.1905)
		)
		(pad "B3" thru_hole circle
			(at -9.649968 1.249934 90)
			(size 1.0668 1.0668)
			(drill 0.719836)
			(layers "*.Cu" "*.Mask")
			(remove_unused_layers no)
			(net "P12V_B_COMP")
			(clearance 0.1905)
			(thermal_gap 0.1905)
		)
		(pad "B4" thru_hole circle
			(at -8.64997 3.24993 90)
			(size 1.0668 1.0668)
			(drill 0.719836)
			(layers "*.Cu" "*.Mask")
			(remove_unused_layers no)
			(net "GND")
			(clearance 0.1905)
			(thermal_gap 0.1905)
		)
		(pad "B5" thru_hole circle
			(at -7.649972 1.249934 90)
			(size 1.0668 1.0668)
			(drill 0.719836)
			(layers "*.Cu" "*.Mask")
			(remove_unused_layers no)
			(net "I2C_BMC_B_COMP_B_SCL")
			(clearance 0.1905)
			(thermal_gap 0.1905)
		)
		(pad "B6" thru_hole circle
			(at -6.649974 3.24993 90)
			(size 1.0668 1.0668)
			(drill 0.719836)
			(layers "*.Cu" "*.Mask")
			(remove_unused_layers no)
			(net "I2C_BMC_B_COMP_B_SDA")
			(clearance 0.1905)
			(thermal_gap 0.1905)
		)
		(pad "B7" thru_hole circle
			(at -5.649976 1.249934 90)
			(size 1.0668 1.0668)
			(drill 0.719836)
			(layers "*.Cu" "*.Mask")
			(remove_unused_layers no)
			(net "GND")
			(clearance 0.1905)
			(thermal_gap 0.1905)
		)
		(pad "B8" thru_hole circle
			(at -4.649978 3.24993 90)
			(size 1.0668 1.0668)
			(drill 0.719836)
			(layers "*.Cu" "*.Mask")
			(remove_unused_layers no)
			(net "COMP_B_PWR_BTN_N")
			(clearance 0.1905)
			(thermal_gap 0.1905)
		)
		(pad "B9" thru_hole circle
			(at -3.64998 1.249934 90)
			(size 1.0668 1.0668)
			(drill 0.719836)
			(layers "*.Cu" "*.Mask")
			(remove_unused_layers no)
			(net "USB_COMP_B_DP")
			(clearance 0.1905)
			(thermal_gap 0.1905)
		)
		(pad "B10" thru_hole circle
			(at -2.649982 3.24993 90)
			(size 1.0668 1.0668)
			(drill 0.719836)
			(layers "*.Cu" "*.Mask")
			(remove_unused_layers no)
			(net "USB_COMP_B_DN")
			(clearance 0.1905)
			(thermal_gap 0.1905)
		)
		(pad "B11" thru_hole circle
			(at -1.649984 1.249934 90)
			(size 1.0668 1.0668)
			(drill 0.719836)
			(layers "*.Cu" "*.Mask")
			(remove_unused_layers no)
			(net "SYS_B_RESET_BUFFER_N")
			(clearance 0.1905)
			(thermal_gap 0.1905)
		)
		(pad "B12" thru_hole circle
			(at 1.35001 3.24993 90)
			(size 1.0668 1.0668)
			(drill 0.719836)
			(layers "*.Cu" "*.Mask")
			(remove_unused_layers no)
			(net "COMP_B_BMC_B_ALERT_N")
			(clearance 0.1905)
			(thermal_gap 0.1905)
		)
		(pad "B13" thru_hole circle
			(at 2.350008 1.249934 90)
			(size 1.0668 1.0668)
			(drill 0.719836)
			(layers "*.Cu" "*.Mask")
			(remove_unused_layers no)
			(net "GND")
			(clearance 0.1905)
			(thermal_gap 0.1905)
		)
		(pad "B14" thru_hole circle
			(at 3.350006 3.24993 90)
			(size 1.0668 1.0668)
			(drill 0.719836)
			(layers "*.Cu" "*.Mask")
			(remove_unused_layers no)
			(net "GND")
			(clearance 0.1905)
			(thermal_gap 0.1905)
		)
		(pad "B15" thru_hole circle
			(at 4.350004 1.249934 90)
			(size 1.0668 1.0668)
			(drill 0.719836)
			(layers "*.Cu" "*.Mask")
			(remove_unused_layers no)
			(net "PCIE_COMP_B_TO_SCC_B_0_DP")
			(clearance 0.1905)
			(thermal_gap 0.1905)
		)
		(pad "B16" thru_hole circle
			(at 5.350002 3.24993 90)
			(size 1.0668 1.0668)
			(drill 0.719836)
			(layers "*.Cu" "*.Mask")
			(remove_unused_layers no)
			(net "PCIE_COMP_B_TO_SCC_B_0_DN")
			(clearance 0.1905)
			(thermal_gap 0.1905)
		)
		(pad "B17" thru_hole circle
			(at 6.35 1.249934 90)
			(size 1.0668 1.0668)
			(drill 0.719836)
			(layers "*.Cu" "*.Mask")
			(remove_unused_layers no)
			(net "GND")
			(clearance 0.1905)
			(thermal_gap 0.1905)
		)
		(pad "B18" thru_hole circle
			(at 7.349998 3.24993 90)
			(size 1.0668 1.0668)
			(drill 0.719836)
			(layers "*.Cu" "*.Mask")
			(remove_unused_layers no)
			(net "GND")
			(clearance 0.1905)
			(thermal_gap 0.1905)
		)
		(pad "B19" thru_hole circle
			(at 8.349996 1.249934 90)
			(size 1.0668 1.0668)
			(drill 0.719836)
			(layers "*.Cu" "*.Mask")
			(remove_unused_layers no)
			(net "PCIE_COMP_B_TO_SCC_B_1_DP")
			(clearance 0.1905)
			(thermal_gap 0.1905)
		)
		(pad "B20" thru_hole circle
			(at 9.349994 3.24993 90)
			(size 1.0668 1.0668)
			(drill 0.719836)
			(layers "*.Cu" "*.Mask")
			(remove_unused_layers no)
			(net "PCIE_COMP_B_TO_SCC_B_1_DN")
			(clearance 0.1905)
			(thermal_gap 0.1905)
		)
		(pad "B21" thru_hole circle
			(at 10.349992 1.249934 90)
			(size 1.0668 1.0668)
			(drill 0.719836)
			(layers "*.Cu" "*.Mask")
			(remove_unused_layers no)
			(net "GND")
			(clearance 0.1905)
			(thermal_gap 0.1905)
		)
		(pad "B22" thru_hole circle
			(at 11.34999 3.24993 90)
			(size 1.0668 1.0668)
			(drill 0.719836)
			(layers "*.Cu" "*.Mask")
			(remove_unused_layers no)
			(net "GND")
			(clearance 0.1905)
			(thermal_gap 0.1905)
		)
		(pad "B23" thru_hole circle
			(at 12.349988 1.249934 90)
			(size 1.0668 1.0668)
			(drill 0.719836)
			(layers "*.Cu" "*.Mask")
			(remove_unused_layers no)
			(net "PCIE_COMP_B_TO_SCC_B_2_DP")
			(clearance 0.1905)
			(thermal_gap 0.1905)
		)
		(pad "B24" thru_hole circle
			(at 13.349986 3.24993 90)
			(size 1.0668 1.0668)
			(drill 0.719836)
			(layers "*.Cu" "*.Mask")
			(remove_unused_layers no)
			(net "PCIE_COMP_B_TO_SCC_B_2_DN")
			(clearance 0.1905)
			(thermal_gap 0.1905)
		)
		(pad "B25" thru_hole circle
			(at 14.349984 1.249934 90)
			(size 1.0668 1.0668)
			(drill 0.719836)
			(layers "*.Cu" "*.Mask")
			(remove_unused_layers no)
			(net "GND")
			(clearance 0.1905)
			(thermal_gap 0.1905)
		)
		(pad "B26" thru_hole circle
			(at 15.349982 3.24993 90)
			(size 1.0668 1.0668)
			(drill 0.719836)
			(layers "*.Cu" "*.Mask")
			(remove_unused_layers no)
			(net "GND")
			(clearance 0.1905)
			(thermal_gap 0.1905)
		)
		(pad "B27" thru_hole circle
			(at 16.34998 1.249934 90)
			(size 1.0668 1.0668)
			(drill 0.719836)
			(layers "*.Cu" "*.Mask")
			(remove_unused_layers no)
			(net "PCIE_COMP_B_TO_SCC_B_3_DP")
			(clearance 0.1905)
			(thermal_gap 0.1905)
		)
		(pad "B28" thru_hole circle
			(at 17.349978 3.24993 90)
			(size 1.0668 1.0668)
			(drill 0.719836)
			(layers "*.Cu" "*.Mask")
			(remove_unused_layers no)
			(net "PCIE_COMP_B_TO_SCC_B_3_DN")
			(clearance 0.1905)
			(thermal_gap 0.1905)
		)
		(pad "B29" thru_hole circle
			(at 18.349976 1.249934 90)
			(size 1.0668 1.0668)
			(drill 0.719836)
			(layers "*.Cu" "*.Mask")
			(remove_unused_layers no)
			(net "GND")
			(clearance 0.1905)
			(thermal_gap 0.1905)
		)
		(pad "B30" thru_hole circle
			(at 19.349974 3.24993 90)
			(size 1.0668 1.0668)
			(drill 0.719836)
			(layers "*.Cu" "*.Mask")
			(remove_unused_layers no)
			(net "GND")
			(clearance 0.1905)
			(thermal_gap 0.1905)
		)
		(pad "B31" thru_hole circle
			(at 20.349972 1.249934 90)
			(size 1.0668 1.0668)
			(drill 0.719836)
			(layers "*.Cu" "*.Mask")
			(remove_unused_layers no)
			(net "TP_COMP_B_SATA_P0_TX_DP")
			(clearance 0.1905)
			(thermal_gap 0.1905)
		)
		(pad "B32" thru_hole circle
			(at 21.34997 3.24993 90)
			(size 1.0668 1.0668)
			(drill 0.719836)
			(layers "*.Cu" "*.Mask")
			(remove_unused_layers no)
			(net "TP_COMP_B_SATA_P0_TX_DN")
			(clearance 0.1905)
			(thermal_gap 0.1905)
		)
		(pad "B33" thru_hole circle
			(at 22.349968 1.249934 90)
			(size 1.0668 1.0668)
			(drill 0.719836)
			(layers "*.Cu" "*.Mask")
			(remove_unused_layers no)
			(net "GND")
			(clearance 0.1905)
			(thermal_gap 0.1905)
		)
		(pad "B34" thru_hole circle
			(at 23.349966 3.24993 90)
			(size 1.0668 1.0668)
			(drill 0.719836)
			(layers "*.Cu" "*.Mask")
			(remove_unused_layers no)
			(net "GND")
			(clearance 0.1905)
			(thermal_gap 0.1905)
		)
		(pad "B35" thru_hole circle
			(at 24.349964 1.249934 90)
			(size 1.0668 1.0668)
			(drill 0.719836)
			(layers "*.Cu" "*.Mask")
			(remove_unused_layers no)
			(net "TP_PCIE_COMP_B_CLK_1_DP")
			(clearance 0.1905)
			(thermal_gap 0.1905)
		)
		(pad "B36" thru_hole circle
			(at 25.349962 3.24993 90)
			(size 1.0668 1.0668)
			(drill 0.719836)
			(layers "*.Cu" "*.Mask")
			(remove_unused_layers no)
			(net "TP_PCIE_COMP_B_CLK_1_DN")
			(clearance 0.1905)
			(thermal_gap 0.1905)
		)
		(pad "B37" thru_hole circle
			(at 26.34996 1.249934 90)
			(size 1.0668 1.0668)
			(drill 0.719836)
			(layers "*.Cu" "*.Mask")
			(remove_unused_layers no)
			(net "GND")
			(clearance 0.1905)
			(thermal_gap 0.1905)
		)
		(pad "B38" thru_hole circle
			(at 27.349958 3.24993 90)
			(size 1.0668 1.0668)
			(drill 0.719836)
			(layers "*.Cu" "*.Mask")
			(remove_unused_layers no)
			(net "GND")
			(clearance 0.1905)
			(thermal_gap 0.1905)
		)
		(pad "B39" thru_hole circle
			(at 28.349956 1.249934 90)
			(size 1.0668 1.0668)
			(drill 0.719836)
			(layers "*.Cu" "*.Mask")
			(remove_unused_layers no)
			(net "PCIE_COMP_B_PCIE_RST_1")
			(clearance 0.1905)
			(thermal_gap 0.1905)
		)
		(pad "B40" thru_hole circle
			(at 29.349954 3.24993 90)
			(size 1.0668 1.0668)
			(drill 0.719836)
			(layers "*.Cu" "*.Mask")
			(remove_unused_layers no)
			(net "PCIE_COMP_B_TO_IOM_B_RST_2")
			(clearance 0.1905)
			(thermal_gap 0.1905)
		)
		(pad "B41" thru_hole circle
			(at 30.349952 1.249934 90)
			(size 1.0668 1.0668)
			(drill 0.719836)
			(layers "*.Cu" "*.Mask")
			(remove_unused_layers no)
			(net "GND")
			(clearance 0.1905)
			(thermal_gap 0.1905)
		)
		(pad "B42" thru_hole circle
			(at 31.34995 3.24993 90)
			(size 1.0668 1.0668)
			(drill 0.719836)
			(layers "*.Cu" "*.Mask")
			(remove_unused_layers no)
			(net "GND")
			(clearance 0.1905)
			(thermal_gap 0.1905)
		)
		(pad "B43" thru_hole circle
			(at 32.349948 1.249934 90)
			(size 1.0668 1.0668)
			(drill 0.719836)
			(layers "*.Cu" "*.Mask")
			(remove_unused_layers no)
			(net "TP_SMB_COMP_B_NIC_SCL")
			(clearance 0.1905)
			(thermal_gap 0.1905)
		)
		(pad "B44" thru_hole circle
			(at 33.349946 3.24993 90)
			(size 1.0668 1.0668)
			(drill 0.719836)
			(layers "*.Cu" "*.Mask")
			(remove_unused_layers no)
			(net "TP_SMB_COMP_B_NIC_SDA")
			(clearance 0.1905)
			(thermal_gap 0.1905)
		)
		(pad "B45" thru_hole circle
			(at 34.349944 1.249934 90)
			(size 1.0668 1.0668)
			(drill 0.719836)
			(layers "*.Cu" "*.Mask")
			(remove_unused_layers no)
			(net "GND")
			(clearance 0.1905)
			(thermal_gap 0.1905)
		)
		(pad "B46" thru_hole circle
			(at 35.349942 3.24993 90)
			(size 1.0668 1.0668)
			(drill 0.719836)
			(layers "*.Cu" "*.Mask")
			(remove_unused_layers no)
			(net "GND")
			(clearance 0.1905)
			(thermal_gap 0.1905)
		)
		(pad "B47" thru_hole circle
			(at 36.34994 1.249934 90)
			(size 1.0668 1.0668)
			(drill 0.719836)
			(layers "*.Cu" "*.Mask")
			(remove_unused_layers no)
			(net "TP_COMP_B_KR_P0_TX_DP")
			(clearance 0.1905)
			(thermal_gap 0.1905)
		)
		(pad "B48" thru_hole circle
			(at 37.349938 3.24993 90)
			(size 1.0668 1.0668)
			(drill 0.719836)
			(layers "*.Cu" "*.Mask")
			(remove_unused_layers no)
			(net "TP_COMP_B_KR_P0_TX_DN")
			(clearance 0.1905)
			(thermal_gap 0.1905)
		)
		(pad "B49" thru_hole circle
			(at 38.349936 1.249934 90)
			(size 1.0668 1.0668)
			(drill 0.719836)
			(layers "*.Cu" "*.Mask")
			(remove_unused_layers no)
			(net "GND")
			(clearance 0.1905)
			(thermal_gap 0.1905)
		)
		(pad "B50" thru_hole circle
			(at 39.349934 3.24993 90)
			(size 1.0668 1.0668)
			(drill 0.719836)
			(layers "*.Cu" "*.Mask")
			(remove_unused_layers no)
			(net "GND")
			(clearance 0.1905)
			(thermal_gap 0.1905)
		)
		(pad "B51" thru_hole circle
			(at 40.349932 1.249934 90)
			(size 1.0668 1.0668)
			(drill 0.719836)
			(layers "*.Cu" "*.Mask")
			(remove_unused_layers no)
			(net "PCIE_COMP_B_TO_SCC_B_4_DP")
			(clearance 0.1905)
			(thermal_gap 0.1905)
		)
		(pad "B52" thru_hole circle
			(at 41.34993 3.24993 90)
			(size 1.0668 1.0668)
			(drill 0.719836)
			(layers "*.Cu" "*.Mask")
			(remove_unused_layers no)
			(net "PCIE_COMP_B_TO_SCC_B_4_DN")
			(clearance 0.1905)
			(thermal_gap 0.1905)
		)
		(pad "B53" thru_hole circle
			(at 42.349928 1.249934 90)
			(size 1.0668 1.0668)
			(drill 0.719836)
			(layers "*.Cu" "*.Mask")
			(remove_unused_layers no)
			(net "GND")
			(clearance 0.1905)
			(thermal_gap 0.1905)
		)
		(pad "B54" thru_hole circle
			(at 43.349926 3.24993 90)
			(size 1.0668 1.0668)
			(drill 0.719836)
			(layers "*.Cu" "*.Mask")
			(remove_unused_layers no)
			(net "GND")
			(clearance 0.1905)
			(thermal_gap 0.1905)
		)
		(pad "B55" thru_hole circle
			(at 44.349924 1.249934 90)
			(size 1.0668 1.0668)
			(drill 0.719836)
			(layers "*.Cu" "*.Mask")
			(remove_unused_layers no)
			(net "PCIE_COMP_B_TO_SCC_B_5_DP")
			(clearance 0.1905)
			(thermal_gap 0.1905)
		)
		(pad "B56" thru_hole circle
			(at 45.349922 3.24993 90)
			(size 1.0668 1.0668)
			(drill 0.719836)
			(layers "*.Cu" "*.Mask")
			(remove_unused_layers no)
			(net "PCIE_COMP_B_TO_SCC_B_5_DN")
			(clearance 0.1905)
			(thermal_gap 0.1905)
		)
		(pad "B57" thru_hole circle
			(at 46.34992 1.249934 90)
			(size 1.0668 1.0668)
			(drill 0.719836)
			(layers "*.Cu" "*.Mask")
			(remove_unused_layers no)
			(net "GND")
			(clearance 0.1905)
			(thermal_gap 0.1905)
		)
		(pad "B58" thru_hole circle
			(at 47.349918 3.24993 90)
			(size 1.0668 1.0668)
			(drill 0.719836)
			(layers "*.Cu" "*.Mask")
			(remove_unused_layers no)
			(net "GND")
			(clearance 0.1905)
			(thermal_gap 0.1905)
		)
		(pad "B59" thru_hole circle
			(at 48.349916 1.249934 90)
			(size 1.0668 1.0668)
			(drill 0.719836)
			(layers "*.Cu" "*.Mask")
			(remove_unused_layers no)
			(net "PCIE_COMP_B_TO_SCC_B_6_DP")
			(clearance 0.1905)
			(thermal_gap 0.1905)
		)
		(pad "B60" thru_hole circle
			(at 49.349914 3.24993 90)
			(size 1.0668 1.0668)
			(drill 0.719836)
			(layers "*.Cu" "*.Mask")
			(remove_unused_layers no)
			(net "PCIE_COMP_B_TO_SCC_B_6_DN")
			(clearance 0.1905)
			(thermal_gap 0.1905)
		)
		(pad "B61" thru_hole circle
			(at 50.349912 1.249934 90)
			(size 1.0668 1.0668)
			(drill 0.719836)
			(layers "*.Cu" "*.Mask")
			(remove_unused_layers no)
			(net "GND")
			(clearance 0.1905)
			(thermal_gap 0.1905)
		)
		(pad "B62" thru_hole circle
			(at 51.34991 3.24993 90)
			(size 1.0668 1.0668)
			(drill 0.719836)
			(layers "*.Cu" "*.Mask")
			(remove_unused_layers no)
			(net "GND")
			(clearance 0.1905)
			(thermal_gap 0.1905)
		)
		(pad "B63" thru_hole circle
			(at 52.349908 1.249934 90)
			(size 1.0668 1.0668)
			(drill 0.719836)
			(layers "*.Cu" "*.Mask")
			(remove_unused_layers no)
			(net "PCIE_COMP_B_TO_SCC_B_7_DP")
			(clearance 0.1905)
			(thermal_gap 0.1905)
		)
		(pad "B64" thru_hole circle
			(at 53.349906 3.24993 90)
			(size 1.0668 1.0668)
			(drill 0.719836)
			(layers "*.Cu" "*.Mask")
			(remove_unused_layers no)
			(net "PCIE_COMP_B_TO_SCC_B_7_DN")
			(clearance 0.1905)
			(thermal_gap 0.1905)
		)
		(pad "B65" thru_hole circle
			(at 54.349904 1.249934 90)
			(size 1.0668 1.0668)
			(drill 0.719836)
			(layers "*.Cu" "*.Mask")
			(remove_unused_layers no)
			(net "GND")
			(clearance 0.1905)
			(thermal_gap 0.1905)
		)
		(pad "B66" thru_hole circle
			(at 55.349902 3.24993 90)
			(size 1.0668 1.0668)
			(drill 0.719836)
			(layers "*.Cu" "*.Mask")
			(remove_unused_layers no)
			(net "GND")
			(clearance 0.1905)
			(thermal_gap 0.1905)
		)
		(pad "B67" thru_hole circle
			(at 56.3499 1.249934 90)
			(size 1.0668 1.0668)
			(drill 0.719836)
			(layers "*.Cu" "*.Mask")
			(remove_unused_layers no)
			(net "PCIE_COMP_B_TO_IOM_B_8_DP")
			(clearance 0.1905)
			(thermal_gap 0.1905)
		)
		(pad "B68" thru_hole circle
			(at 57.349898 3.24993 90)
			(size 1.0668 1.0668)
			(drill 0.719836)
			(layers "*.Cu" "*.Mask")
			(remove_unused_layers no)
			(net "PCIE_COMP_B_TO_IOM_B_8_DN")
			(clearance 0.1905)
			(thermal_gap 0.1905)
		)
		(pad "B69" thru_hole circle
			(at 58.349896 1.249934 90)
			(size 1.0668 1.0668)
			(drill 0.719836)
			(layers "*.Cu" "*.Mask")
			(remove_unused_layers no)
			(net "GND")
			(clearance 0.1905)
			(thermal_gap 0.1905)
		)
		(pad "B70" thru_hole circle
			(at 59.349894 3.24993 90)
			(size 1.0668 1.0668)
			(drill 0.719836)
			(layers "*.Cu" "*.Mask")
			(remove_unused_layers no)
			(net "GND")
			(clearance 0.1905)
			(thermal_gap 0.1905)
		)
		(pad "B71" thru_hole circle
			(at 60.349892 1.249934 90)
			(size 1.0668 1.0668)
			(drill 0.719836)
			(layers "*.Cu" "*.Mask")
			(remove_unused_layers no)
			(net "PCIE_COMP_B_TO_IOM_B_9_DP")
			(clearance 0.1905)
			(thermal_gap 0.1905)
		)
		(pad "B72" thru_hole circle
			(at 61.34989 3.24993 90)
			(size 1.0668 1.0668)
			(drill 0.719836)
			(layers "*.Cu" "*.Mask")
			(remove_unused_layers no)
			(net "PCIE_COMP_B_TO_IOM_B_9_DN")
			(clearance 0.1905)
			(thermal_gap 0.1905)
		)
		(pad "B73" thru_hole circle
			(at 62.349888 1.249934 90)
			(size 1.0668 1.0668)
			(drill 0.719836)
			(layers "*.Cu" "*.Mask")
			(remove_unused_layers no)
			(net "GND")
			(clearance 0.1905)
			(thermal_gap 0.1905)
		)
		(pad "B74" thru_hole circle
			(at 63.349886 3.24993 90)
			(size 1.0668 1.0668)
			(drill 0.719836)
			(layers "*.Cu" "*.Mask")
			(remove_unused_layers no)
			(net "GND")
			(clearance 0.1905)
			(thermal_gap 0.1905)
		)
		(pad "B75" thru_hole circle
			(at 64.349884 1.249934 90)
			(size 1.0668 1.0668)
			(drill 0.719836)
			(layers "*.Cu" "*.Mask")
			(remove_unused_layers no)
			(net "PCIE_COMP_B_TO_IOM_B_10_DP")
			(clearance 0.1905)
			(thermal_gap 0.1905)
		)
		(pad "B76" thru_hole circle
			(at 65.349882 3.24993 90)
			(size 1.0668 1.0668)
			(drill 0.719836)
			(layers "*.Cu" "*.Mask")
			(remove_unused_layers no)
			(net "PCIE_COMP_B_TO_IOM_B_10_DN")
			(clearance 0.1905)
			(thermal_gap 0.1905)
		)
		(pad "B77" thru_hole circle
			(at 66.34988 1.249934 90)
			(size 1.0668 1.0668)
			(drill 0.719836)
			(layers "*.Cu" "*.Mask")
			(remove_unused_layers no)
			(net "GND")
			(clearance 0.1905)
			(thermal_gap 0.1905)
		)
		(pad "B78" thru_hole circle
			(at 67.349878 3.24993 90)
			(size 1.0668 1.0668)
			(drill 0.719836)
			(layers "*.Cu" "*.Mask")
			(remove_unused_layers no)
			(net "GND")
			(clearance 0.1905)
			(thermal_gap 0.1905)
		)
		(pad "B79" thru_hole circle
			(at 68.349876 1.249934 90)
			(size 1.0668 1.0668)
			(drill 0.719836)
			(layers "*.Cu" "*.Mask")
			(remove_unused_layers no)
			(net "PCIE_COMP_B_TO_IOM_B_11_DP")
			(clearance 0.1905)
			(thermal_gap 0.1905)
		)
		(pad "B80" thru_hole circle
			(at 69.349874 3.24993 90)
			(size 1.0668 1.0668)
			(drill 0.719836)
			(layers "*.Cu" "*.Mask")
			(remove_unused_layers no)
			(net "PCIE_COMP_B_TO_IOM_B_11_DN")
			(clearance 0.1905)
			(thermal_gap 0.1905)
		)
		(pad "B81" thru_hole circle
			(at 70.350126 1.249934 90)
			(size 1.0668 1.0668)
			(drill 0.719836)
			(layers "*.Cu" "*.Mask")
			(remove_unused_layers no)
			(net "GND")
			(clearance 0.1905)
			(thermal_gap 0.1905)
		)
		(pad "B82" thru_hole circle
			(at 71.350124 3.24993 90)
			(size 1.0668 1.0668)
			(drill 0.719836)
			(layers "*.Cu" "*.Mask")
			(remove_unused_layers no)
			(net "GND")
			(clearance 0.1905)
			(thermal_gap 0.1905)
		)
		(zone
			(layers "F.Cu" "B.Cu" "In1.Cu" "In2.Cu" "In3.Cu" "In4.Cu" "In5.Cu" "In6.Cu"
				"In7.Cu" "In8.Cu" "In9.Cu" "In10.Cu"
			)
			(hatch none 0.5)
			(connect_pads
				(clearance 0)
			)
			(min_thickness 0.25)
			(keepout
				(tracks not_allowed)
				(vias allowed)
				(pads allowed)
				(copperpour not_allowed)
				(footprints allowed)
			)
			(placement
				(enabled no)
				(sheetname "")
			)
			(fill
				(thermal_gap 0.5)
				(thermal_bridge_width 0.5)
				(island_removal_mode 0)
			)
			(polygon
				(pts
					(arc
						(start 283.485844 -184.29986)
						(mid 280.514044 -184.29986)
						(end 283.485844 -184.29986)
					)
				)
			)
		)
		(zone
			(layers "F.Cu" "B.Cu" "In1.Cu" "In2.Cu" "In3.Cu" "In4.Cu" "In5.Cu" "In6.Cu"
				"In7.Cu" "In8.Cu" "In9.Cu" "In10.Cu"
			)
			(hatch none 0.5)
			(connect_pads
				(clearance 0)
			)
			(min_thickness 0.25)
			(keepout
				(tracks not_allowed)
				(vias allowed)
				(pads allowed)
				(copperpour not_allowed)
				(footprints allowed)
			)
			(placement
				(enabled no)
				(sheetname "")
			)
			(fill
				(thermal_gap 0.5)
				(thermal_bridge_width 0.5)
				(island_removal_mode 0)
			)
			(polygon
				(pts
					(arc
						(start 283.485844 -111.149892)
						(mid 280.514044 -111.149892)
						(end 283.485844 -111.149892)
					)
				)
			)
		)
	)
	(footprint ""
		(layer "F.Cu")
		(at 32.508952 -277.750016 -90)
		(property "Reference" "VIA34"
			(at 0 0 270)
			(layer "F.SilkS")
			(hide yes)
			(effects
				(font
					(size 1.27 1.27)
				)
			)
		)
		(property "Value" "100OHM-8L-1D6MM-L18L16-GP"
			(at -3.7211 -4.5085 270)
			(unlocked yes)
			(layer "F.Fab")
			(hide yes)
			(effects
				(font
					(size 1.016 1.016)
					(thickness 0.1524)
				)
			)
		)
		(property "Device Type" "VIA-PCIE-4P-394076"
			(at -3.7211 -6.0325 270)
			(unlocked yes)
			(layer "F.Fab")
			(hide yes)
			(effects
				(font
					(size 1.016 1.016)
					(thickness 0.1524)
				)
			)
		)
		(duplicate_pad_numbers_are_jumpers no)
		(fp_rect
			(start -1.9685 0.381)
			(end 1.9685 -0.381)
			(stroke
				(width 0)
				(type default)
			)
			(fill no)
			(layer "F.CrtYd")
		)
		(fp_rect
			(start -1.9685 0.381)
			(end 1.9685 -0.381)
			(stroke
				(width 0)
				(type default)
			)
			(fill no)
			(layer "F.Fab")
		)
		(pad "1" thru_hole circle
			(at -1.5875 0 270)
			(size 0.508 0.508)
			(drill 0.254)
			(layers "*.Cu" "*.Mask")
			(remove_unused_layers no)
			(net "GND")
			(clearance 0.127)
			(thermal_gap 0.127)
		)
		(pad "2" thru_hole circle
			(at -0.5715 0 270)
			(size 0.508 0.508)
			(drill 0.254)
			(layers "*.Cu" "*.Mask")
			(remove_unused_layers no)
			(net "PHY_DRV_A_TO_SCC_A_0_DP")
			(clearance 0.127)
			(thermal_gap 0.127)
		)
		(pad "3" thru_hole circle
			(at 0.5715 0 270)
			(size 0.508 0.508)
			(drill 0.254)
			(layers "*.Cu" "*.Mask")
			(remove_unused_layers no)
			(net "PHY_DRV_A_TO_SCC_A_0_DN")
			(clearance 0.127)
			(thermal_gap 0.127)
		)
		(pad "4" thru_hole circle
			(at 1.5875 0 270)
			(size 0.508 0.508)
			(drill 0.254)
			(layers "*.Cu" "*.Mask")
			(remove_unused_layers no)
			(net "GND")
			(clearance 0.127)
			(thermal_gap 0.127)
		)
	)
	(footprint ""
		(layer "F.Cu")
		(at 156.92374 -141.014196 -90)
		(property "Reference" "R1064"
			(at 0 0 270)
			(layer "F.SilkS")
			(hide yes)
			(effects
				(font
					(size 1.27 1.27)
				)
			)
		)
		(property "Value" "49K9R2F-L-GP"
			(at 0.064008 -3.993896 270)
			(unlocked yes)
			(layer "F.Fab")
			(hide yes)
			(effects
				(font
					(size 1.016 1.016)
					(thickness 0.1524)
				)
			)
		)
		(property "Device Type" "R402H16"
			(at 0.064008 -5.517896 270)
			(unlocked yes)
			(layer "F.Fab")
			(hide yes)
			(effects
				(font
					(size 1.016 1.016)
					(thickness 0.1524)
				)
			)
		)
		(duplicate_pad_numbers_are_jumpers no)
		(fp_line
			(start -0.508 -0.9398)
			(end -0.508 0.9398)
			(stroke
				(width 0.1524)
				(type default)
			)
			(layer "F.SilkS")
		)
		(fp_line
			(start 0.508 -0.9398)
			(end -0.508 -0.9398)
			(stroke
				(width 0.1524)
				(type default)
			)
			(layer "F.SilkS")
		)
		(fp_rect
			(start -0.508 0.9398)
			(end 0.508 -0.9398)
			(stroke
				(width 0)
				(type default)
			)
			(fill no)
			(layer "F.CrtYd")
		)
		(fp_rect
			(start -0.508 0.9398)
			(end 0.508 -0.9398)
			(stroke
				(width 0)
				(type default)
			)
			(fill no)
			(layer "F.Fab")
		)
		(pad "1" smd custom
			(at 0 -0.4445 270)
			(size 0.1397 0.1397)
			(layers "F.Cu" "F.Mask" "F.Paste")
			(net "P12V_A")
			(options
				(clearance outline)
				(anchor circle)
			)
			(primitives
				(gr_poly
					(pts
						(arc
							(start -0.1778 -0.2794)
							(mid -0.249642 -0.249642)
							(end -0.2794 -0.1778)
						)
						(arc
							(start -0.2794 0.1778)
							(mid -0.249642 0.249642)
							(end -0.1778 0.2794)
						)
						(arc
							(start 0.1778 0.2794)
							(mid 0.249642 0.249642)
							(end 0.2794 0.1778)
						)
						(arc
							(start 0.2794 -0.1778)
							(mid 0.249642 -0.249642)
							(end 0.1778 -0.2794)
						)
					)
					(width 0)
					(fill yes)
				)
			)
		)
		(pad "2" smd custom
			(at 0 0.4445 270)
			(size 0.1397 0.1397)
			(layers "F.Cu" "F.Mask" "F.Paste")
			(net "MB0_CM_UV_R")
			(options
				(clearance outline)
				(anchor circle)
			)
			(primitives
				(gr_poly
					(pts
						(arc
							(start -0.1778 -0.2794)
							(mid -0.249642 -0.249642)
							(end -0.2794 -0.1778)
						)
						(arc
							(start -0.2794 0.1778)
							(mid -0.249642 0.249642)
							(end -0.1778 0.2794)
						)
						(arc
							(start 0.1778 0.2794)
							(mid 0.249642 0.249642)
							(end 0.2794 0.1778)
						)
						(arc
							(start 0.2794 -0.1778)
							(mid 0.249642 -0.249642)
							(end 0.1778 -0.2794)
						)
					)
					(width 0)
					(fill yes)
				)
			)
		)
	)
	(footprint ""
		(layer "F.Cu")
		(at 54.546246 -44.871894 -90)
		(property "Reference" "R716"
			(at 0 0 270)
			(layer "F.SilkS")
			(hide yes)
			(effects
				(font
					(size 1.27 1.27)
				)
			)
		)
		(property "Value" "0R2J-2-GP"
			(at 0.064008 -3.993896 270)
			(unlocked yes)
			(layer "F.Fab")
			(hide yes)
			(effects
				(font
					(size 1.016 1.016)
					(thickness 0.1524)
				)
			)
		)
		(property "Device Type" "R402H16"
			(at 0.064008 -5.517896 270)
			(unlocked yes)
			(layer "F.Fab")
			(hide yes)
			(effects
				(font
					(size 1.016 1.016)
					(thickness 0.1524)
				)
			)
		)
		(duplicate_pad_numbers_are_jumpers no)
		(fp_line
			(start -0.508 -0.9398)
			(end -0.508 0.9398)
			(stroke
				(width 0.1524)
				(type default)
			)
			(layer "F.SilkS")
		)
		(fp_line
			(start 0.508 -0.9398)
			(end -0.508 -0.9398)
			(stroke
				(width 0.1524)
				(type default)
			)
			(layer "F.SilkS")
		)
		(fp_rect
			(start -0.508 0.9398)
			(end 0.508 -0.9398)
			(stroke
				(width 0)
				(type default)
			)
			(fill no)
			(layer "F.CrtYd")
		)
		(fp_rect
			(start -0.508 0.9398)
			(end 0.508 -0.9398)
			(stroke
				(width 0)
				(type default)
			)
			(fill no)
			(layer "F.Fab")
		)
		(pad "1" smd custom
			(at 0 -0.4445 270)
			(size 0.1397 0.1397)
			(layers "F.Cu" "F.Mask" "F.Paste")
			(net "DRIVE_A_25_PWR")
			(options
				(clearance outline)
				(anchor circle)
			)
			(primitives
				(gr_poly
					(pts
						(arc
							(start -0.1778 -0.2794)
							(mid -0.249642 -0.249642)
							(end -0.2794 -0.1778)
						)
						(arc
							(start -0.2794 0.1778)
							(mid -0.249642 0.249642)
							(end -0.1778 0.2794)
						)
						(arc
							(start 0.1778 0.2794)
							(mid 0.249642 0.249642)
							(end 0.2794 0.1778)
						)
						(arc
							(start 0.2794 -0.1778)
							(mid 0.249642 -0.249642)
							(end 0.1778 -0.2794)
						)
					)
					(width 0)
					(fill yes)
				)
			)
		)
		(pad "2" smd custom
			(at 0 0.4445 270)
			(size 0.1397 0.1397)
			(layers "F.Cu" "F.Mask" "F.Paste")
			(net "SW_PWR_R_HDD25")
			(options
				(clearance outline)
				(anchor circle)
			)
			(primitives
				(gr_poly
					(pts
						(arc
							(start -0.1778 -0.2794)
							(mid -0.249642 -0.249642)
							(end -0.2794 -0.1778)
						)
						(arc
							(start -0.2794 0.1778)
							(mid -0.249642 0.249642)
							(end -0.1778 0.2794)
						)
						(arc
							(start 0.1778 0.2794)
							(mid 0.249642 0.249642)
							(end 0.2794 0.1778)
						)
						(arc
							(start 0.2794 -0.1778)
							(mid 0.249642 -0.249642)
							(end 0.1778 -0.2794)
						)
					)
					(width 0)
					(fill yes)
				)
			)
		)
	)
	(footprint ""
		(layer "F.Cu")
		(at 361.4928 -145.1864 -90)
		(property "Reference" "Q221"
			(at 0 0 270)
			(layer "F.SilkS")
			(hide yes)
			(effects
				(font
					(size 1.27 1.27)
				)
			)
		)
		(property "Value" "MMBT3904-3-GP"
			(at 0.10287 -10.29843 270)
			(unlocked yes)
			(layer "F.Fab")
			(hide yes)
			(effects
				(font
					(size 1.016 1.016)
					(thickness 0.1524)
				)
			)
		)
		(property "Device Type" "SOT23CBE2D4H44"
			(at 0.10287 -12.20343 270)
			(unlocked yes)
			(layer "F.Fab")
			(hide yes)
			(effects
				(font
					(size 1.016 1.016)
					(thickness 0.1524)
				)
			)
		)
		(duplicate_pad_numbers_are_jumpers no)
		(fp_line
			(start -1.651 1.778)
			(end 1.651 1.778)
			(stroke
				(width 0.1524)
				(type default)
			)
			(layer "F.SilkS")
		)
		(fp_line
			(start 1.651 1.778)
			(end 1.651 -1.778)
			(stroke
				(width 0.1524)
				(type default)
			)
			(layer "F.SilkS")
		)
		(fp_line
			(start -1.651 -1.778)
			(end -1.651 1.778)
			(stroke
				(width 0.1524)
				(type default)
			)
			(layer "F.SilkS")
		)
		(fp_line
			(start 1.651 -1.778)
			(end -1.651 -1.778)
			(stroke
				(width 0.1524)
				(type default)
			)
			(layer "F.SilkS")
		)
		(fp_poly
			(pts
				(xy -1.778 1.8796) (xy -1.778 -1.8796) (xy 1.778 -1.8796) (xy 1.778 1.8796)
			)
			(stroke
				(width 0)
				(type default)
			)
			(fill no)
			(layer "F.CrtYd")
		)
		(fp_poly
			(pts
				(xy -1.778 1.8796) (xy -1.778 -1.8796) (xy 1.778 -1.8796) (xy 1.778 1.8796)
			)
			(stroke
				(width 0)
				(type default)
			)
			(fill no)
			(layer "F.Fab")
		)
		(pad "B" smd custom
			(at -0.98425 0.9525 270)
			(size 0.1905 0.1905)
			(layers "F.Cu" "F.Mask" "F.Paste")
			(net "MB1_TEMP_B")
			(options
				(clearance outline)
				(anchor circle)
			)
			(primitives
				(gr_poly
					(pts
						(arc
							(start -0.1778 0.5715)
							(mid -0.321484 0.511984)
							(end -0.381 0.3683)
						)
						(arc
							(start -0.381 -0.3683)
							(mid -0.321484 -0.511984)
							(end -0.1778 -0.5715)
						)
						(arc
							(start 0.1778 -0.5715)
							(mid 0.321484 -0.511984)
							(end 0.381 -0.3683)
						)
						(arc
							(start 0.381 0.3683)
							(mid 0.321484 0.511984)
							(end 0.1778 0.5715)
						)
					)
					(width 0)
					(fill yes)
				)
			)
		)
		(pad "C" smd custom
			(at 0 -0.9525 270)
			(size 0.1905 0.1905)
			(layers "F.Cu" "F.Mask" "F.Paste")
			(net "MB1_TEMP_B")
			(options
				(clearance outline)
				(anchor circle)
			)
			(primitives
				(gr_poly
					(pts
						(arc
							(start -0.1778 0.5715)
							(mid -0.321484 0.511984)
							(end -0.381 0.3683)
						)
						(arc
							(start -0.381 -0.3683)
							(mid -0.321484 -0.511984)
							(end -0.1778 -0.5715)
						)
						(arc
							(start 0.1778 -0.5715)
							(mid 0.321484 -0.511984)
							(end 0.381 -0.3683)
						)
						(arc
							(start 0.381 0.3683)
							(mid 0.321484 0.511984)
							(end 0.1778 0.5715)
						)
					)
					(width 0)
					(fill yes)
				)
			)
		)
		(pad "E" smd custom
			(at 0.98425 0.9525 270)
			(size 0.1905 0.1905)
			(layers "F.Cu" "F.Mask" "F.Paste")
			(net "MB1_TEMP_E")
			(options
				(clearance outline)
				(anchor circle)
			)
			(primitives
				(gr_poly
					(pts
						(arc
							(start -0.1778 0.5715)
							(mid -0.321484 0.511984)
							(end -0.381 0.3683)
						)
						(arc
							(start -0.381 -0.3683)
							(mid -0.321484 -0.511984)
							(end -0.1778 -0.5715)
						)
						(arc
							(start 0.1778 -0.5715)
							(mid 0.321484 -0.511984)
							(end 0.381 -0.3683)
						)
						(arc
							(start 0.381 0.3683)
							(mid 0.321484 0.511984)
							(end 0.1778 0.5715)
						)
					)
					(width 0)
					(fill yes)
				)
			)
		)
	)
	(footprint ""
		(layer "F.Cu")
		(at 267.174726 -136.672066 -90)
		(property "Reference" "TP198"
			(at 0 0 270)
			(layer "F.SilkS")
			(hide yes)
			(effects
				(font
					(size 1.27 1.27)
				)
			)
		)
		(property "Value" "TPAD32-GP"
			(at -0.0508 -1.6764 270)
			(unlocked yes)
			(layer "F.Fab")
			(hide yes)
			(effects
				(font
					(size 1.016 1.016)
					(thickness 0.1524)
				)
			)
		)
		(property "Device Type" "TPAD32"
			(at -0.0508 -3.2004 270)
			(unlocked yes)
			(layer "F.Fab")
			(hide yes)
			(effects
				(font
					(size 1.016 1.016)
					(thickness 0.1524)
				)
			)
		)
		(duplicate_pad_numbers_are_jumpers no)
		(fp_poly
			(pts
				(arc
					(start 0 -0.4064)
					(mid 0 0.4064)
					(end 0 -0.4064)
				)
			)
			(stroke
				(width 0)
				(type default)
			)
			(fill no)
			(layer "F.CrtYd")
		)
		(fp_poly
			(pts
				(arc
					(start 0 -0.7112)
					(mid 0 0.7112)
					(end 0 -0.7112)
				)
			)
			(stroke
				(width 0)
				(type default)
			)
			(fill no)
			(layer "F.Fab")
		)
		(pad "1" smd circle
			(at 0 0 270)
			(size 0.8128 0.8128)
			(layers "F.Cu" "F.Mask" "F.Paste")
			(net "TP_PCIE_COMP_B_CLK_1_DP")
		)
	)
	(footprint ""
		(layer "F.Cu")
		(at 67.093846 -183.747918)
		(property "Reference" "TP67"
			(at 0 0 0)
			(layer "F.SilkS")
			(hide yes)
			(effects
				(font
					(size 1.27 1.27)
				)
			)
		)
		(property "Value" "TPAD32-GP"
			(at -0.0508 -1.6764 0)
			(unlocked yes)
			(layer "F.Fab")
			(hide yes)
			(effects
				(font
					(size 1.016 1.016)
					(thickness 0.1524)
				)
			)
		)
		(property "Device Type" "TPAD32"
			(at -0.0508 -3.2004 0)
			(unlocked yes)
			(layer "F.Fab")
			(hide yes)
			(effects
				(font
					(size 1.016 1.016)
					(thickness 0.1524)
				)
			)
		)
		(duplicate_pad_numbers_are_jumpers no)
		(fp_poly
			(pts
				(arc
					(start 0.4064 0)
					(mid -0.4064 0)
					(end 0.4064 0)
				)
			)
			(stroke
				(width 0)
				(type default)
			)
			(fill no)
			(layer "F.CrtYd")
		)
		(fp_poly
			(pts
				(arc
					(start 0.7112 0)
					(mid -0.7112 0)
					(end 0.7112 0)
				)
			)
			(stroke
				(width 0)
				(type default)
			)
			(fill no)
			(layer "F.Fab")
		)
		(pad "1" smd circle
			(at 0 0)
			(size 0.8128 0.8128)
			(layers "F.Cu" "F.Mask" "F.Paste")
			(net "ACT_HDD_13")
		)
	)
	(footprint ""
		(layer "F.Cu")
		(at 127.15875 -277.750016 -90)
		(property "Reference" "VIA40"
			(at 0 0 270)
			(layer "F.SilkS")
			(hide yes)
			(effects
				(font
					(size 1.27 1.27)
				)
			)
		)
		(property "Value" "100OHM-8L-1D6MM-L18L16-GP"
			(at -3.7211 -4.5085 270)
			(unlocked yes)
			(layer "F.Fab")
			(hide yes)
			(effects
				(font
					(size 1.016 1.016)
					(thickness 0.1524)
				)
			)
		)
		(property "Device Type" "VIA-PCIE-4P-394076"
			(at -3.7211 -6.0325 270)
			(unlocked yes)
			(layer "F.Fab")
			(hide yes)
			(effects
				(font
					(size 1.016 1.016)
					(thickness 0.1524)
				)
			)
		)
		(duplicate_pad_numbers_are_jumpers no)
		(fp_rect
			(start -1.9685 0.381)
			(end 1.9685 -0.381)
			(stroke
				(width 0)
				(type default)
			)
			(fill no)
			(layer "F.CrtYd")
		)
		(fp_rect
			(start -1.9685 0.381)
			(end 1.9685 -0.381)
			(stroke
				(width 0)
				(type default)
			)
			(fill no)
			(layer "F.Fab")
		)
		(pad "1" thru_hole circle
			(at -1.5875 0 270)
			(size 0.508 0.508)
			(drill 0.254)
			(layers "*.Cu" "*.Mask")
			(remove_unused_layers no)
			(net "GND")
			(clearance 0.127)
			(thermal_gap 0.127)
		)
		(pad "2" thru_hole circle
			(at -0.5715 0 270)
			(size 0.508 0.508)
			(drill 0.254)
			(layers "*.Cu" "*.Mask")
			(remove_unused_layers no)
			(net "PHY_DRV_A_TO_SCC_A_3_DP")
			(clearance 0.127)
			(thermal_gap 0.127)
		)
		(pad "3" thru_hole circle
			(at 0.5715 0 270)
			(size 0.508 0.508)
			(drill 0.254)
			(layers "*.Cu" "*.Mask")
			(remove_unused_layers no)
			(net "PHY_DRV_A_TO_SCC_A_3_DN")
			(clearance 0.127)
			(thermal_gap 0.127)
		)
		(pad "4" thru_hole circle
			(at 1.5875 0 270)
			(size 0.508 0.508)
			(drill 0.254)
			(layers "*.Cu" "*.Mask")
			(remove_unused_layers no)
			(net "GND")
			(clearance 0.127)
			(thermal_gap 0.127)
		)
	)
	(footprint ""
		(layer "F.Cu")
		(at 341.300054 -269.999968)
		(property "Reference" ""
			(at 0 0 0)
			(layer "F.SilkS")
			(hide yes)
			(effects
				(font
					(size 1.27 1.27)
				)
			)
		)
		(property "Value" "*"
			(at -6.3373 -0.4572 0)
			(unlocked yes)
			(layer "F.Fab")
			(hide yes)
			(effects
				(font
					(size 1.016 1.016)
					(thickness 0.1524)
				)
			)
		)
		(duplicate_pad_numbers_are_jumpers no)
		(fp_poly
			(pts
				(arc
					(start 5.0673 0)
					(mid -5.0673 0)
					(end 5.0673 0)
				)
			)
			(stroke
				(width 0)
				(type default)
			)
			(fill no)
			(layer "B.CrtYd")
		)
		(fp_poly
			(pts
				(arc
					(start 5.0673 0)
					(mid -5.0673 0)
					(end 5.0673 0)
				)
			)
			(stroke
				(width 0)
				(type default)
			)
			(fill no)
			(layer "F.CrtYd")
		)
		(fp_poly
			(pts
				(arc
					(start 5.0673 0)
					(mid -5.0673 0)
					(end 5.0673 0)
				)
			)
			(stroke
				(width 0)
				(type default)
			)
			(fill no)
			(layer "B.Fab")
		)
		(fp_poly
			(pts
				(arc
					(start 5.0673 0)
					(mid -5.0673 0)
					(end 5.0673 0)
				)
			)
			(stroke
				(width 0)
				(type default)
			)
			(fill no)
			(layer "F.Fab")
		)
		(pad "1" thru_hole circle
			(at 0 0)
			(size 9.525 9.525)
			(drill 3.556)
			(layers "*.Cu" "*.Mask")
			(remove_unused_layers no)
			(net "Net_93")
			(clearance -2.4765)
			(thermal_gap 0.3048)
			(padstack
				(mode front_inner_back)
				(layer "Inner"
					(shape circle)
					(size 3.9624 3.9624)
					(clearance 0.3048)
				)
				(layer "B.Cu"
					(shape circle)
					(size 9.525 9.525)
					(clearance -2.4765)
				)
			)
		)
		(zone
			(layers "F.Cu" "B.Cu" "In1.Cu" "In2.Cu" "In3.Cu" "In4.Cu" "In5.Cu" "In6.Cu"
				"In7.Cu" "In8.Cu" "In9.Cu" "In10.Cu"
			)
			(hatch none 0.5)
			(connect_pads
				(clearance 0)
			)
			(min_thickness 0.25)
			(keepout
				(tracks not_allowed)
				(vias allowed)
				(pads allowed)
				(copperpour not_allowed)
				(footprints allowed)
			)
			(placement
				(enabled no)
				(sheetname "")
			)
			(fill
				(thermal_gap 0.5)
				(thermal_bridge_width 0.5)
				(island_removal_mode 0)
			)
			(polygon
				(pts
					(arc
						(start 346.062554 -269.999968)
						(mid 336.537554 -269.999968)
						(end 346.062554 -269.999968)
					)
				)
			)
		)
	)
	(footprint ""
		(layer "F.Cu")
		(at 127.399796 -291.077142 -90)
		(property "Reference" "R201"
			(at 0 0 270)
			(layer "F.SilkS")
			(hide yes)
			(effects
				(font
					(size 1.27 1.27)
				)
			)
		)
		(property "Value" "10KR2F-2-GP"
			(at 0.064008 -3.993896 270)
			(unlocked yes)
			(layer "F.Fab")
			(hide yes)
			(effects
				(font
					(size 1.016 1.016)
					(thickness 0.1524)
				)
			)
		)
		(property "Device Type" "R402H16"
			(at 0.064008 -5.517896 270)
			(unlocked yes)
			(layer "F.Fab")
			(hide yes)
			(effects
				(font
					(size 1.016 1.016)
					(thickness 0.1524)
				)
			)
		)
		(duplicate_pad_numbers_are_jumpers no)
		(fp_line
			(start -0.508 -0.9398)
			(end -0.508 0.9398)
			(stroke
				(width 0.1524)
				(type default)
			)
			(layer "F.SilkS")
		)
		(fp_line
			(start 0.508 -0.9398)
			(end -0.508 -0.9398)
			(stroke
				(width 0.1524)
				(type default)
			)
			(layer "F.SilkS")
		)
		(fp_rect
			(start -0.508 0.9398)
			(end 0.508 -0.9398)
			(stroke
				(width 0)
				(type default)
			)
			(fill no)
			(layer "F.CrtYd")
		)
		(fp_rect
			(start -0.508 0.9398)
			(end 0.508 -0.9398)
			(stroke
				(width 0)
				(type default)
			)
			(fill no)
			(layer "F.Fab")
		)
		(pad "1" smd custom
			(at 0 -0.4445 270)
			(size 0.1397 0.1397)
			(layers "F.Cu" "F.Mask" "F.Paste")
			(net "P3V3_STBY_A")
			(options
				(clearance outline)
				(anchor circle)
			)
			(primitives
				(gr_poly
					(pts
						(arc
							(start -0.1778 -0.2794)
							(mid -0.249642 -0.249642)
							(end -0.2794 -0.1778)
						)
						(arc
							(start -0.2794 0.1778)
							(mid -0.249642 0.249642)
							(end -0.1778 0.2794)
						)
						(arc
							(start 0.1778 0.2794)
							(mid 0.249642 0.249642)
							(end 0.2794 0.1778)
						)
						(arc
							(start 0.2794 -0.1778)
							(mid 0.249642 -0.249642)
							(end 0.1778 -0.2794)
						)
					)
					(width 0)
					(fill yes)
				)
			)
		)
		(pad "2" smd custom
			(at 0 0.4445 270)
			(size 0.1397 0.1397)
			(layers "F.Cu" "F.Mask" "F.Paste")
			(net "HDD_PRSNT_3")
			(options
				(clearance outline)
				(anchor circle)
			)
			(primitives
				(gr_poly
					(pts
						(arc
							(start -0.1778 -0.2794)
							(mid -0.249642 -0.249642)
							(end -0.2794 -0.1778)
						)
						(arc
							(start -0.2794 0.1778)
							(mid -0.249642 0.249642)
							(end -0.1778 0.2794)
						)
						(arc
							(start 0.1778 0.2794)
							(mid 0.249642 0.249642)
							(end 0.2794 0.1778)
						)
						(arc
							(start 0.2794 -0.1778)
							(mid 0.249642 -0.249642)
							(end 0.1778 -0.2794)
						)
					)
					(width 0)
					(fill yes)
				)
			)
		)
	)
	(footprint ""
		(layer "F.Cu")
		(at 144.469866 -131.656074)
		(property "Reference" "C544"
			(at 0 0 0)
			(layer "F.SilkS")
			(hide yes)
			(effects
				(font
					(size 1.27 1.27)
				)
			)
		)
		(property "Value" "SCD1U16V2KX-3GP"
			(at 1.1811 -2.7051 0)
			(unlocked yes)
			(layer "F.Fab")
			(hide yes)
			(effects
				(font
					(size 1.016 1.016)
					(thickness 0.1524)
				)
			)
		)
		(property "Device Type" "C402H22"
			(at 1.1811 -4.2291 0)
			(unlocked yes)
			(layer "F.Fab")
			(hide yes)
			(effects
				(font
					(size 1.016 1.016)
					(thickness 0.1524)
				)
			)
		)
		(duplicate_pad_numbers_are_jumpers no)
		(fp_rect
			(start -0.4318 0.9525)
			(end 0.4318 -0.9525)
			(stroke
				(width 0)
				(type default)
			)
			(fill no)
			(layer "F.CrtYd")
		)
		(fp_rect
			(start -0.4318 0.9525)
			(end 0.4318 -0.9525)
			(stroke
				(width 0)
				(type default)
			)
			(fill no)
			(layer "F.Fab")
		)
		(pad "1" smd custom
			(at 0 -0.4445)
			(size 0.1524 0.1524)
			(layers "F.Cu" "F.Mask" "F.Paste")
			(net "MB0_CM_VOUT_R")
			(options
				(clearance outline)
				(anchor circle)
			)
			(primitives
				(gr_poly
					(pts
						(arc
							(start 0.3048 -0.2032)
							(mid 0.275042 -0.275042)
							(end 0.2032 -0.3048)
						)
						(arc
							(start -0.2032 -0.3048)
							(mid -0.275042 -0.275042)
							(end -0.3048 -0.2032)
						)
						(arc
							(start -0.3048 0.2032)
							(mid -0.275042 0.275042)
							(end -0.2032 0.3048)
						)
						(arc
							(start 0.2032 0.3048)
							(mid 0.275042 0.275042)
							(end 0.3048 0.2032)
						)
					)
					(width 0)
					(fill yes)
				)
			)
		)
		(pad "2" smd custom
			(at 0 0.4445)
			(size 0.1524 0.1524)
			(layers "F.Cu" "F.Mask" "F.Paste")
			(net "AGND_CURRENT_MONOA")
			(options
				(clearance outline)
				(anchor circle)
			)
			(primitives
				(gr_poly
					(pts
						(arc
							(start 0.3048 -0.2032)
							(mid 0.275042 -0.275042)
							(end 0.2032 -0.3048)
						)
						(arc
							(start -0.2032 -0.3048)
							(mid -0.275042 -0.275042)
							(end -0.3048 -0.2032)
						)
						(arc
							(start -0.3048 0.2032)
							(mid -0.275042 0.275042)
							(end -0.2032 0.3048)
						)
						(arc
							(start 0.2032 0.3048)
							(mid 0.275042 0.275042)
							(end 0.3048 0.2032)
						)
					)
					(width 0)
					(fill yes)
				)
			)
		)
	)
	(footprint ""
		(layer "F.Cu")
		(at 388.649972 -57.909968 -90)
		(property "Reference" "HDDSAS32"
			(at 0 0 270)
			(layer "F.SilkS")
			(hide yes)
			(effects
				(font
					(size 1.27 1.27)
				)
			)
		)
		(property "Value" "SKT-SAS15P-14P-45-GP"
			(at -20.7645 -8.9789 270)
			(unlocked yes)
			(layer "F.Fab")
			(hide yes)
			(effects
				(font
					(size 1.016 1.016)
					(thickness 0.1524)
				)
			)
		)
		(property "Device Type" "10120818-001C-TRLF"
			(at -20.7645 -10.5029 270)
			(unlocked yes)
			(layer "F.Fab")
			(hide yes)
			(effects
				(font
					(size 1.016 1.016)
					(thickness 0.1524)
				)
			)
		)
		(duplicate_pad_numbers_are_jumpers no)
		(fp_line
			(start 1.651 4.2926)
			(end 1.651 3.0099)
			(stroke
				(width 0.1524)
				(type default)
			)
			(layer "F.SilkS")
		)
		(fp_line
			(start 8.509 4.2926)
			(end 1.651 4.2926)
			(stroke
				(width 0.1524)
				(type default)
			)
			(layer "F.SilkS")
		)
		(fp_line
			(start -23.4188 3.0099)
			(end -23.4188 -3.2512)
			(stroke
				(width 0.1524)
				(type default)
			)
			(layer "F.SilkS")
		)
		(fp_line
			(start 1.651 3.0099)
			(end -23.4188 3.0099)
			(stroke
				(width 0.1524)
				(type default)
			)
			(layer "F.SilkS")
		)
		(fp_line
			(start 8.509 3.0099)
			(end 8.509 4.2926)
			(stroke
				(width 0.1524)
				(type default)
			)
			(layer "F.SilkS")
		)
		(fp_line
			(start 23.4188 3.0099)
			(end 8.509 3.0099)
			(stroke
				(width 0.1524)
				(type default)
			)
			(layer "F.SilkS")
		)
		(fp_line
			(start -23.4188 -3.2512)
			(end 23.4188 -3.2512)
			(stroke
				(width 0.1524)
				(type default)
			)
			(layer "F.SilkS")
		)
		(fp_line
			(start 23.4188 -3.2512)
			(end 23.4188 3.0099)
			(stroke
				(width 0.1524)
				(type default)
			)
			(layer "F.SilkS")
		)
		(fp_line
			(start 15.5067 -3.3401)
			(end 16.2687 -3.3401)
			(stroke
				(width 0.3302)
				(type default)
			)
			(layer "F.SilkS")
		)
		(fp_poly
			(pts
				(xy 15.868904 -3.230372) (xy 16.503904 -3.865372) (xy 15.233904 -3.865372)
			)
			(stroke
				(width 0)
				(type default)
			)
			(fill yes)
			(layer "F.SilkS")
		)
		(fp_poly
			(pts
				(xy -22.8727 -2.7559) (xy 22.8727 -2.7559) (xy 22.8727 2.7559) (xy 8.255 2.7559) (xy 8.255 3.5179)
				(xy 1.905 3.5179) (xy 1.905 2.7559) (xy -22.8727 2.7559)
			)
			(stroke
				(width 0)
				(type default)
			)
			(fill no)
			(layer "F.CrtYd")
		)
		(fp_poly
			(pts
				(xy 1.397 4.5466) (xy 1.397 3.2639) (xy -23.6728 3.2639) (xy -23.6728 -3.5052) (xy 23.6728 -3.5052)
				(xy 23.6728 -0.00635) (xy 22.8727 -0.00635) (xy 22.8727 -2.7559) (xy -22.8727 -2.7559) (xy -22.8727 2.7559)
				(xy 1.905 2.7559) (xy 1.905 3.5179) (xy 8.255 3.5179) (xy 8.255 2.7559) (xy 22.8727 2.7559) (xy 22.8727 0.00635)
				(xy 23.6728 0.00635) (xy 23.6728 3.2639) (xy 8.763 3.2639) (xy 8.763 4.5466)
			)
			(stroke
				(width 0)
				(type default)
			)
			(fill no)
			(layer "F.CrtYd")
		)
		(fp_poly
			(pts
				(xy 1.397 4.5466) (xy 1.397 3.2639) (xy -23.6728 3.2639) (xy -23.6728 -3.5052) (xy 23.6728 -3.5052)
				(xy 23.6728 3.2639) (xy 8.763 3.2639) (xy 8.763 4.5466)
			)
			(stroke
				(width 0)
				(type default)
			)
			(fill no)
			(layer "F.Fab")
		)
		(pad "" np_thru_hole circle
			(at -18.874994 0 270)
			(size 0.254 0.254)
			(drill 1.3462)
			(layers "*.Cu" "*.Mask")
			(clearance 0.9017)
			(thermal_gap 0.9017)
		)
		(pad "" np_thru_hole circle
			(at 18.874994 0 270)
			(size 0.254 0.254)
			(drill 0.9398)
			(layers "*.Cu" "*.Mask")
			(clearance 0.6985)
			(thermal_gap 0.6985)
		)
		(pad "G1" smd rect
			(at 21.874988 0 270)
			(size 2.5908 2.5908)
			(layers "F.Cu" "F.Mask" "F.Paste")
			(net "GND")
		)
		(pad "G2" smd rect
			(at -21.874988 0 270)
			(size 2.5908 2.5908)
			(layers "F.Cu" "F.Mask" "F.Paste")
			(net "GND")
		)
		(pad "P1" smd rect
			(at 1.905 -1.82499 270)
			(size 0.6096 2.3622)
			(layers "F.Cu" "F.Mask" "F.Paste")
			(net "Net_2046")
		)
		(pad "P2" smd rect
			(at 0.635 -1.82499 270)
			(size 0.6096 2.3622)
			(layers "F.Cu" "F.Mask" "F.Paste")
			(net "Net_2047")
		)
		(pad "P3" smd rect
			(at -0.635 -1.82499 270)
			(size 0.6096 2.3622)
			(layers "F.Cu" "F.Mask" "F.Paste")
			(net "Net_2048")
		)
		(pad "P4" smd rect
			(at -1.905 -1.82499 270)
			(size 0.6096 2.3622)
			(layers "F.Cu" "F.Mask" "F.Paste")
			(net "GND")
		)
		(pad "P5" smd rect
			(at -3.175 -1.82499 270)
			(size 0.6096 2.3622)
			(layers "F.Cu" "F.Mask" "F.Paste")
			(net "HDD_PRSNT_32")
		)
		(pad "P6" smd rect
			(at -4.445 -1.82499 270)
			(size 0.6096 2.3622)
			(layers "F.Cu" "F.Mask" "F.Paste")
			(net "GND")
		)
		(pad "P7" smd rect
			(at -5.715 -1.82499 270)
			(size 0.6096 2.3622)
			(layers "F.Cu" "F.Mask" "F.Paste")
			(net "5V_PRE_32")
		)
		(pad "P8" smd rect
			(at -6.985 -1.82499 270)
			(size 0.6096 2.3622)
			(layers "F.Cu" "F.Mask" "F.Paste")
			(net "P5V_HDD32")
		)
		(pad "P9" smd rect
			(at -8.255 -1.82499 270)
			(size 0.6096 2.3622)
			(layers "F.Cu" "F.Mask" "F.Paste")
			(net "P5V_HDD32")
		)
		(pad "P10" smd rect
			(at -9.525 -1.82499 270)
			(size 0.6096 2.3622)
			(layers "F.Cu" "F.Mask" "F.Paste")
			(net "GND")
		)
		(pad "P11" smd rect
			(at -10.795 -1.82499 270)
			(size 0.6096 2.3622)
			(layers "F.Cu" "F.Mask" "F.Paste")
			(net "ACT_HDD_32")
		)
		(pad "P12" smd rect
			(at -12.065 -1.82499 270)
			(size 0.6096 2.3622)
			(layers "F.Cu" "F.Mask" "F.Paste")
			(net "GND")
		)
		(pad "P13" smd rect
			(at -13.335 -1.82499 270)
			(size 0.6096 2.3622)
			(layers "F.Cu" "F.Mask" "F.Paste")
			(net "12V_PRE_32")
		)
		(pad "P14" smd rect
			(at -14.605 -1.82499 270)
			(size 0.6096 2.3622)
			(layers "F.Cu" "F.Mask" "F.Paste")
			(net "P12V_HDD32")
		)
		(pad "P15" smd rect
			(at -15.875 -1.82499 270)
			(size 0.6096 2.3622)
			(layers "F.Cu" "F.Mask" "F.Paste")
			(net "P12V_HDD32")
		)
		(pad "S1" smd rect
			(at 15.875 -1.82499 270)
			(size 0.6096 2.3622)
			(layers "F.Cu" "F.Mask" "F.Paste")
			(net "GND")
		)
		(pad "S2" smd rect
			(at 14.605 -1.82499 270)
			(size 0.6096 2.3622)
			(layers "F.Cu" "F.Mask" "F.Paste")
			(net "SAS_HDD_RX_P32")
		)
		(pad "S3" smd rect
			(at 13.335 -1.82499 270)
			(size 0.6096 2.3622)
			(layers "F.Cu" "F.Mask" "F.Paste")
			(net "SAS_HDD_RX_N32")
		)
		(pad "S4" smd rect
			(at 12.065 -1.82499 270)
			(size 0.6096 2.3622)
			(layers "F.Cu" "F.Mask" "F.Paste")
			(net "GND")
		)
		(pad "S5" smd rect
			(at 10.795 -1.82499 270)
			(size 0.6096 2.3622)
			(layers "F.Cu" "F.Mask" "F.Paste")
			(net "PHY_DRV_A_TO_SCC_A_32_DN")
		)
		(pad "S6" smd rect
			(at 9.525 -1.82499 270)
			(size 0.6096 2.3622)
			(layers "F.Cu" "F.Mask" "F.Paste")
			(net "PHY_DRV_A_TO_SCC_A_32_DP")
		)
		(pad "S7" smd rect
			(at 8.255 -1.82499 270)
			(size 0.6096 2.3622)
			(layers "F.Cu" "F.Mask" "F.Paste")
			(net "GND")
		)
		(pad "S8" smd rect
			(at 7.480046 2.845054 270)
			(size 0.508 2.3622)
			(layers "F.Cu" "F.Mask" "F.Paste")
			(net "GND")
		)
		(pad "S9" smd rect
			(at 6.679946 2.845054 270)
			(size 0.508 2.3622)
			(layers "F.Cu" "F.Mask" "F.Paste")
			(net "Net_471")
		)
		(pad "S10" smd rect
			(at 5.8801 2.845054 270)
			(size 0.508 2.3622)
			(layers "F.Cu" "F.Mask" "F.Paste")
			(net "Net_363")
		)
		(pad "S11" smd rect
			(at 5.08 2.845054 270)
			(size 0.508 2.3622)
			(layers "F.Cu" "F.Mask" "F.Paste")
			(net "GND")
		)
		(pad "S12" smd rect
			(at 4.2799 2.845054 270)
			(size 0.508 2.3622)
			(layers "F.Cu" "F.Mask" "F.Paste")
			(net "Net_399")
		)
		(pad "S13" smd rect
			(at 3.480054 2.845054 270)
			(size 0.508 2.3622)
			(layers "F.Cu" "F.Mask" "F.Paste")
			(net "Net_435")
		)
		(pad "S14" smd rect
			(at 2.679954 2.845054 270)
			(size 0.508 2.3622)
			(layers "F.Cu" "F.Mask" "F.Paste")
			(net "GND")
		)
		(zone
			(layer "F.Cu")
			(hatch none 0.5)
			(connect_pads
				(clearance 0)
			)
			(min_thickness 0.25)
			(keepout
				(tracks not_allowed)
				(vias allowed)
				(pads allowed)
				(copperpour not_allowed)
				(footprints allowed)
			)
			(placement
				(enabled no)
				(sheetname "")
			)
			(fill
				(thermal_gap 0.5)
				(thermal_bridge_width 0.5)
				(island_removal_mode 0)
			)
			(polygon
				(pts
					(xy 392.307572 -74.648568) (xy 385.233672 -74.648568) (xy 385.233672 -81.582768) (xy 386.338572 -81.582768)
					(xy 386.338572 -77.467968) (xy 390.961372 -77.467968) (xy 390.961372 -81.582768) (xy 392.307572 -81.582768)
				)
			)
		)
		(zone
			(layer "F.Cu")
			(hatch none 0.5)
			(connect_pads
				(clearance 0)
			)
			(min_thickness 0.25)
			(keepout
				(tracks allowed)
				(vias not_allowed)
				(pads allowed)
				(copperpour not_allowed)
				(footprints allowed)
			)
			(placement
				(enabled no)
				(sheetname "")
			)
			(fill
				(thermal_gap 0.5)
				(thermal_bridge_width 0.5)
				(island_removal_mode 0)
			)
			(polygon
				(pts
					(xy 392.307572 -74.648568) (xy 385.233672 -74.648568) (xy 385.233672 -81.582768) (xy 386.338572 -81.582768)
					(xy 386.338572 -77.467968) (xy 390.961372 -77.467968) (xy 390.961372 -81.582768) (xy 392.307572 -81.582768)
				)
			)
		)
		(zone
			(layer "F.Cu")
			(hatch none 0.5)
			(connect_pads
				(clearance 0)
			)
			(min_thickness 0.25)
			(keepout
				(tracks not_allowed)
				(vias allowed)
				(pads allowed)
				(copperpour not_allowed)
				(footprints allowed)
			)
			(placement
				(enabled no)
				(sheetname "")
			)
			(fill
				(thermal_gap 0.5)
				(thermal_bridge_width 0.5)
				(island_removal_mode 0)
			)
			(polygon
				(pts
					(xy 392.307572 -41.171368) (xy 385.233672 -41.171368) (xy 385.233672 -34.237168) (xy 386.338572 -34.237168)
					(xy 386.338572 -38.351968) (xy 390.961372 -38.351968) (xy 390.961372 -34.237168) (xy 392.307572 -34.237168)
				)
			)
		)
		(zone
			(layer "F.Cu")
			(hatch none 0.5)
			(connect_pads
				(clearance 0)
			)
			(min_thickness 0.25)
			(keepout
				(tracks allowed)
				(vias not_allowed)
				(pads allowed)
				(copperpour not_allowed)
				(footprints allowed)
			)
			(placement
				(enabled no)
				(sheetname "")
			)
			(fill
				(thermal_gap 0.5)
				(thermal_bridge_width 0.5)
				(island_removal_mode 0)
			)
			(polygon
				(pts
					(xy 392.307572 -41.171368) (xy 385.233672 -41.171368) (xy 385.233672 -34.237168) (xy 386.338572 -34.237168)
					(xy 386.338572 -38.351968) (xy 390.961372 -38.351968) (xy 390.961372 -34.237168) (xy 392.307572 -34.237168)
				)
			)
		)
		(zone
			(layers "F.Cu" "B.Cu" "In1.Cu" "In2.Cu" "In3.Cu" "In4.Cu" "In5.Cu" "In6.Cu"
				"In7.Cu" "In8.Cu" "In9.Cu" "In10.Cu"
			)
			(hatch none 0.5)
			(connect_pads
				(clearance 0)
			)
			(min_thickness 0.25)
			(keepout
				(tracks not_allowed)
				(vias allowed)
				(pads allowed)
				(copperpour not_allowed)
				(footprints allowed)
			)
			(placement
				(enabled no)
				(sheetname "")
			)
			(fill
				(thermal_gap 0.5)
				(thermal_bridge_width 0.5)
				(island_removal_mode 0)
			)
			(polygon
				(pts
					(arc
						(start 389.424672 -39.034974)
						(mid 387.875272 -39.034974)
						(end 389.424672 -39.034974)
					)
				)
			)
		)
		(zone
			(layers "F.Cu" "B.Cu" "In1.Cu" "In2.Cu" "In3.Cu" "In4.Cu" "In5.Cu" "In6.Cu"
				"In7.Cu" "In8.Cu" "In9.Cu" "In10.Cu"
			)
			(hatch none 0.5)
			(connect_pads
				(clearance 0)
			)
			(min_thickness 0.25)
			(keepout
				(tracks not_allowed)
				(vias allowed)
				(pads allowed)
				(copperpour not_allowed)
				(footprints allowed)
			)
			(placement
				(enabled no)
				(sheetname "")
			)
			(fill
				(thermal_gap 0.5)
				(thermal_bridge_width 0.5)
				(island_removal_mode 0)
			)
			(polygon
				(pts
					(arc
						(start 389.627872 -76.784962)
						(mid 387.672072 -76.784962)
						(end 389.627872 -76.784962)
					)
				)
			)
		)
	)
	(footprint ""
		(layer "F.Cu")
		(at 271.19707 -10.841228 180)
		(property "Reference" "TP200"
			(at 0 0 180)
			(layer "F.SilkS")
			(hide yes)
			(effects
				(font
					(size 1.27 1.27)
				)
			)
		)
		(property "Value" "TPAD32-GP"
			(at -0.0508 -1.6764 180)
			(unlocked yes)
			(layer "F.Fab")
			(hide yes)
			(effects
				(font
					(size 1.016 1.016)
					(thickness 0.1524)
				)
			)
		)
		(property "Device Type" "TPAD32"
			(at -0.0508 -3.2004 180)
			(unlocked yes)
			(layer "F.Fab")
			(hide yes)
			(effects
				(font
					(size 1.016 1.016)
					(thickness 0.1524)
				)
			)
		)
		(duplicate_pad_numbers_are_jumpers no)
		(fp_poly
			(pts
				(arc
					(start -0.4064 0)
					(mid 0.4064 0)
					(end -0.4064 0)
				)
			)
			(stroke
				(width 0)
				(type default)
			)
			(fill no)
			(layer "F.CrtYd")
		)
		(fp_poly
			(pts
				(arc
					(start -0.7112 0)
					(mid 0.7112 0)
					(end -0.7112 0)
				)
			)
			(stroke
				(width 0)
				(type default)
			)
			(fill no)
			(layer "F.Fab")
		)
		(pad "1" smd circle
			(at 0 0 180)
			(size 0.8128 0.8128)
			(layers "F.Cu" "F.Mask" "F.Paste")
			(net "TP_COMP_B_NCSI_RXD1")
		)
	)
	(footprint ""
		(layer "F.Cu")
		(at 224.572322 -132.79247 -90)
		(property "Reference" "TP206"
			(at 0 0 270)
			(layer "F.SilkS")
			(hide yes)
			(effects
				(font
					(size 1.27 1.27)
				)
			)
		)
		(property "Value" "TPAD32-GP"
			(at -0.0508 -1.6764 270)
			(unlocked yes)
			(layer "F.Fab")
			(hide yes)
			(effects
				(font
					(size 1.016 1.016)
					(thickness 0.1524)
				)
			)
		)
		(property "Device Type" "TPAD32"
			(at -0.0508 -3.2004 270)
			(unlocked yes)
			(layer "F.Fab")
			(hide yes)
			(effects
				(font
					(size 1.016 1.016)
					(thickness 0.1524)
				)
			)
		)
		(duplicate_pad_numbers_are_jumpers no)
		(fp_poly
			(pts
				(arc
					(start 0 -0.4064)
					(mid 0 0.4064)
					(end 0 -0.4064)
				)
			)
			(stroke
				(width 0)
				(type default)
			)
			(fill no)
			(layer "F.CrtYd")
		)
		(fp_poly
			(pts
				(arc
					(start 0 -0.7112)
					(mid 0 0.7112)
					(end 0 -0.7112)
				)
			)
			(stroke
				(width 0)
				(type default)
			)
			(fill no)
			(layer "F.Fab")
		)
		(pad "1" smd circle
			(at 0 0 270)
			(size 0.8128 0.8128)
			(layers "F.Cu" "F.Mask" "F.Paste")
			(net "TP_COMP_A_SATA_P0_RX_DN")
		)
	)
	(footprint ""
		(layer "F.Cu")
		(at 270.223234 20.568412 90)
		(property "Reference" "R141"
			(at 0 0 90)
			(layer "F.SilkS")
			(hide yes)
			(effects
				(font
					(size 1.27 1.27)
				)
			)
		)
		(property "Value" "4K7R2F-GP"
			(at 0.064008 -3.993896 90)
			(unlocked yes)
			(layer "F.Fab")
			(hide yes)
			(effects
				(font
					(size 1.016 1.016)
					(thickness 0.1524)
				)
			)
		)
		(property "Device Type" "R402H16"
			(at 0.064008 -5.517896 90)
			(unlocked yes)
			(layer "F.Fab")
			(hide yes)
			(effects
				(font
					(size 1.016 1.016)
					(thickness 0.1524)
				)
			)
		)
		(duplicate_pad_numbers_are_jumpers no)
		(fp_line
			(start 0.508 -0.9398)
			(end -0.508 -0.9398)
			(stroke
				(width 0.1524)
				(type default)
			)
			(layer "F.SilkS")
		)
		(fp_line
			(start -0.508 -0.9398)
			(end -0.508 0.9398)
			(stroke
				(width 0.1524)
				(type default)
			)
			(layer "F.SilkS")
		)
		(fp_rect
			(start -0.508 0.9398)
			(end 0.508 -0.9398)
			(stroke
				(width 0)
				(type default)
			)
			(fill no)
			(layer "F.CrtYd")
		)
		(fp_rect
			(start -0.508 0.9398)
			(end 0.508 -0.9398)
			(stroke
				(width 0)
				(type default)
			)
			(fill no)
			(layer "F.Fab")
		)
		(pad "1" smd custom
			(at 0 -0.4445 90)
			(size 0.1397 0.1397)
			(layers "F.Cu" "F.Mask" "F.Paste")
			(net "USB_OCS_N2")
			(options
				(clearance outline)
				(anchor circle)
			)
			(primitives
				(gr_poly
					(pts
						(arc
							(start -0.1778 -0.2794)
							(mid -0.249642 -0.249642)
							(end -0.2794 -0.1778)
						)
						(arc
							(start -0.2794 0.1778)
							(mid -0.249642 0.249642)
							(end -0.1778 0.2794)
						)
						(arc
							(start 0.1778 0.2794)
							(mid 0.249642 0.249642)
							(end 0.2794 0.1778)
						)
						(arc
							(start 0.2794 -0.1778)
							(mid 0.249642 -0.249642)
							(end 0.1778 -0.2794)
						)
					)
					(width 0)
					(fill yes)
				)
			)
		)
		(pad "2" smd custom
			(at 0 0.4445 90)
			(size 0.1397 0.1397)
			(layers "F.Cu" "F.Mask" "F.Paste")
			(net "GND")
			(options
				(clearance outline)
				(anchor circle)
			)
			(primitives
				(gr_poly
					(pts
						(arc
							(start -0.1778 -0.2794)
							(mid -0.249642 -0.249642)
							(end -0.2794 -0.1778)
						)
						(arc
							(start -0.2794 0.1778)
							(mid -0.249642 0.249642)
							(end -0.1778 0.2794)
						)
						(arc
							(start 0.1778 0.2794)
							(mid 0.249642 0.249642)
							(end 0.2794 0.1778)
						)
						(arc
							(start 0.2794 -0.1778)
							(mid 0.249642 -0.249642)
							(end 0.1778 -0.2794)
						)
					)
					(width 0)
					(fill yes)
				)
			)
		)
	)
	(footprint ""
		(layer "F.Cu")
		(at 161.743898 -68.697094)
		(property "Reference" "TP142"
			(at 0 0 0)
			(layer "F.SilkS")
			(hide yes)
			(effects
				(font
					(size 1.27 1.27)
				)
			)
		)
		(property "Value" "TPAD32-GP"
			(at -0.0508 -1.6764 0)
			(unlocked yes)
			(layer "F.Fab")
			(hide yes)
			(effects
				(font
					(size 1.016 1.016)
					(thickness 0.1524)
				)
			)
		)
		(property "Device Type" "TPAD32"
			(at -0.0508 -3.2004 0)
			(unlocked yes)
			(layer "F.Fab")
			(hide yes)
			(effects
				(font
					(size 1.016 1.016)
					(thickness 0.1524)
				)
			)
		)
		(duplicate_pad_numbers_are_jumpers no)
		(fp_poly
			(pts
				(arc
					(start 0.4064 0)
					(mid -0.4064 0)
					(end 0.4064 0)
				)
			)
			(stroke
				(width 0)
				(type default)
			)
			(fill no)
			(layer "F.CrtYd")
		)
		(fp_poly
			(pts
				(arc
					(start 0.7112 0)
					(mid -0.7112 0)
					(end 0.7112 0)
				)
			)
			(stroke
				(width 0)
				(type default)
			)
			(fill no)
			(layer "F.Fab")
		)
		(pad "1" smd circle
			(at 0 0)
			(size 0.8128 0.8128)
			(layers "F.Cu" "F.Mask" "F.Paste")
			(net "ACT_HDD_28")
		)
	)
	(footprint ""
		(layer "F.Cu")
		(at 77.942948 -284.523942 90)
		(property "Reference" "C75"
			(at 0 0 90)
			(layer "F.SilkS")
			(hide yes)
			(effects
				(font
					(size 1.27 1.27)
				)
			)
		)
		(property "Value" "SCD033U25V2KX-GP"
			(at 1.1811 -2.7051 90)
			(unlocked yes)
			(layer "F.Fab")
			(hide yes)
			(effects
				(font
					(size 1.016 1.016)
					(thickness 0.1524)
				)
			)
		)
		(property "Device Type" "C402H22"
			(at 1.1811 -4.2291 90)
			(unlocked yes)
			(layer "F.Fab")
			(hide yes)
			(effects
				(font
					(size 1.016 1.016)
					(thickness 0.1524)
				)
			)
		)
		(duplicate_pad_numbers_are_jumpers no)
		(fp_rect
			(start -0.4318 0.9525)
			(end 0.4318 -0.9525)
			(stroke
				(width 0)
				(type default)
			)
			(fill no)
			(layer "F.CrtYd")
		)
		(fp_rect
			(start -0.4318 0.9525)
			(end 0.4318 -0.9525)
			(stroke
				(width 0)
				(type default)
			)
			(fill no)
			(layer "F.Fab")
		)
		(pad "1" smd custom
			(at 0 -0.4445 90)
			(size 0.1524 0.1524)
			(layers "F.Cu" "F.Mask" "F.Paste")
			(net "P12V_A")
			(options
				(clearance outline)
				(anchor circle)
			)
			(primitives
				(gr_poly
					(pts
						(arc
							(start 0.3048 -0.2032)
							(mid 0.275042 -0.275042)
							(end 0.2032 -0.3048)
						)
						(arc
							(start -0.2032 -0.3048)
							(mid -0.275042 -0.275042)
							(end -0.3048 -0.2032)
						)
						(arc
							(start -0.3048 0.2032)
							(mid -0.275042 0.275042)
							(end -0.2032 0.3048)
						)
						(arc
							(start 0.2032 0.3048)
							(mid 0.275042 0.275042)
							(end 0.3048 0.2032)
						)
					)
					(width 0)
					(fill yes)
				)
			)
		)
		(pad "2" smd custom
			(at 0 0.4445 90)
			(size 0.1524 0.1524)
			(layers "F.Cu" "F.Mask" "F.Paste")
			(net "SW_HDD_N2")
			(options
				(clearance outline)
				(anchor circle)
			)
			(primitives
				(gr_poly
					(pts
						(arc
							(start 0.3048 -0.2032)
							(mid 0.275042 -0.275042)
							(end 0.2032 -0.3048)
						)
						(arc
							(start -0.2032 -0.3048)
							(mid -0.275042 -0.275042)
							(end -0.3048 -0.2032)
						)
						(arc
							(start -0.3048 0.2032)
							(mid -0.275042 0.275042)
							(end -0.2032 0.3048)
						)
						(arc
							(start 0.2032 0.3048)
							(mid 0.275042 0.275042)
							(end 0.3048 0.2032)
						)
					)
					(width 0)
					(fill yes)
				)
			)
		)
	)
	(footprint ""
		(layer "F.Cu")
		(at 130.193796 -68.747894)
		(property "Reference" "TP137"
			(at 0 0 0)
			(layer "F.SilkS")
			(hide yes)
			(effects
				(font
					(size 1.27 1.27)
				)
			)
		)
		(property "Value" "TPAD32-GP"
			(at -0.0508 -1.6764 0)
			(unlocked yes)
			(layer "F.Fab")
			(hide yes)
			(effects
				(font
					(size 1.016 1.016)
					(thickness 0.1524)
				)
			)
		)
		(property "Device Type" "TPAD32"
			(at -0.0508 -3.2004 0)
			(unlocked yes)
			(layer "F.Fab")
			(hide yes)
			(effects
				(font
					(size 1.016 1.016)
					(thickness 0.1524)
				)
			)
		)
		(duplicate_pad_numbers_are_jumpers no)
		(fp_poly
			(pts
				(arc
					(start 0.4064 0)
					(mid -0.4064 0)
					(end 0.4064 0)
				)
			)
			(stroke
				(width 0)
				(type default)
			)
			(fill no)
			(layer "F.CrtYd")
		)
		(fp_poly
			(pts
				(arc
					(start 0.7112 0)
					(mid -0.7112 0)
					(end 0.7112 0)
				)
			)
			(stroke
				(width 0)
				(type default)
			)
			(fill no)
			(layer "F.Fab")
		)
		(pad "1" smd circle
			(at 0 0)
			(size 0.8128 0.8128)
			(layers "F.Cu" "F.Mask" "F.Paste")
			(net "ACT_HDD_27")
		)
	)
	(footprint ""
		(layer "F.Cu")
		(at 451.749922 -57.909968 -90)
		(property "Reference" "HDDSAS34"
			(at 0 0 270)
			(layer "F.SilkS")
			(hide yes)
			(effects
				(font
					(size 1.27 1.27)
				)
			)
		)
		(property "Value" "SKT-SAS15P-14P-45-GP"
			(at -20.7645 -8.9789 270)
			(unlocked yes)
			(layer "F.Fab")
			(hide yes)
			(effects
				(font
					(size 1.016 1.016)
					(thickness 0.1524)
				)
			)
		)
		(property "Device Type" "10120818-001C-TRLF"
			(at -20.7645 -10.5029 270)
			(unlocked yes)
			(layer "F.Fab")
			(hide yes)
			(effects
				(font
					(size 1.016 1.016)
					(thickness 0.1524)
				)
			)
		)
		(duplicate_pad_numbers_are_jumpers no)
		(fp_line
			(start 1.651 4.2926)
			(end 1.651 3.0099)
			(stroke
				(width 0.1524)
				(type default)
			)
			(layer "F.SilkS")
		)
		(fp_line
			(start 8.509 4.2926)
			(end 1.651 4.2926)
			(stroke
				(width 0.1524)
				(type default)
			)
			(layer "F.SilkS")
		)
		(fp_line
			(start -23.4188 3.0099)
			(end -23.4188 -3.2512)
			(stroke
				(width 0.1524)
				(type default)
			)
			(layer "F.SilkS")
		)
		(fp_line
			(start 1.651 3.0099)
			(end -23.4188 3.0099)
			(stroke
				(width 0.1524)
				(type default)
			)
			(layer "F.SilkS")
		)
		(fp_line
			(start 8.509 3.0099)
			(end 8.509 4.2926)
			(stroke
				(width 0.1524)
				(type default)
			)
			(layer "F.SilkS")
		)
		(fp_line
			(start 23.4188 3.0099)
			(end 8.509 3.0099)
			(stroke
				(width 0.1524)
				(type default)
			)
			(layer "F.SilkS")
		)
		(fp_line
			(start -23.4188 -3.2512)
			(end 23.4188 -3.2512)
			(stroke
				(width 0.1524)
				(type default)
			)
			(layer "F.SilkS")
		)
		(fp_line
			(start 23.4188 -3.2512)
			(end 23.4188 3.0099)
			(stroke
				(width 0.1524)
				(type default)
			)
			(layer "F.SilkS")
		)
		(fp_line
			(start 15.5067 -3.3401)
			(end 16.2687 -3.3401)
			(stroke
				(width 0.3302)
				(type default)
			)
			(layer "F.SilkS")
		)
		(fp_poly
			(pts
				(xy 15.868904 -3.230372) (xy 16.503904 -3.865372) (xy 15.233904 -3.865372)
			)
			(stroke
				(width 0)
				(type default)
			)
			(fill yes)
			(layer "F.SilkS")
		)
		(fp_poly
			(pts
				(xy -22.8727 -2.7559) (xy 22.8727 -2.7559) (xy 22.8727 2.7559) (xy 8.255 2.7559) (xy 8.255 3.5179)
				(xy 1.905 3.5179) (xy 1.905 2.7559) (xy -22.8727 2.7559)
			)
			(stroke
				(width 0)
				(type default)
			)
			(fill no)
			(layer "F.CrtYd")
		)
		(fp_poly
			(pts
				(xy 1.397 4.5466) (xy 1.397 3.2639) (xy -23.6728 3.2639) (xy -23.6728 -3.5052) (xy 23.6728 -3.5052)
				(xy 23.6728 -0.00635) (xy 22.8727 -0.00635) (xy 22.8727 -2.7559) (xy -22.8727 -2.7559) (xy -22.8727 2.7559)
				(xy 1.905 2.7559) (xy 1.905 3.5179) (xy 8.255 3.5179) (xy 8.255 2.7559) (xy 22.8727 2.7559) (xy 22.8727 0.00635)
				(xy 23.6728 0.00635) (xy 23.6728 3.2639) (xy 8.763 3.2639) (xy 8.763 4.5466)
			)
			(stroke
				(width 0)
				(type default)
			)
			(fill no)
			(layer "F.CrtYd")
		)
		(fp_poly
			(pts
				(xy 1.397 4.5466) (xy 1.397 3.2639) (xy -23.6728 3.2639) (xy -23.6728 -3.5052) (xy 23.6728 -3.5052)
				(xy 23.6728 3.2639) (xy 8.763 3.2639) (xy 8.763 4.5466)
			)
			(stroke
				(width 0)
				(type default)
			)
			(fill no)
			(layer "F.Fab")
		)
		(pad "" np_thru_hole circle
			(at -18.874994 0 270)
			(size 0.254 0.254)
			(drill 1.3462)
			(layers "*.Cu" "*.Mask")
			(clearance 0.9017)
			(thermal_gap 0.9017)
		)
		(pad "" np_thru_hole circle
			(at 18.874994 0 270)
			(size 0.254 0.254)
			(drill 0.9398)
			(layers "*.Cu" "*.Mask")
			(clearance 0.6985)
			(thermal_gap 0.6985)
		)
		(pad "G1" smd rect
			(at 21.874988 0 270)
			(size 2.5908 2.5908)
			(layers "F.Cu" "F.Mask" "F.Paste")
			(net "GND")
		)
		(pad "G2" smd rect
			(at -21.874988 0 270)
			(size 2.5908 2.5908)
			(layers "F.Cu" "F.Mask" "F.Paste")
			(net "GND")
		)
		(pad "P1" smd rect
			(at 1.905 -1.82499 270)
			(size 0.6096 2.3622)
			(layers "F.Cu" "F.Mask" "F.Paste")
			(net "Net_2036")
		)
		(pad "P2" smd rect
			(at 0.635 -1.82499 270)
			(size 0.6096 2.3622)
			(layers "F.Cu" "F.Mask" "F.Paste")
			(net "Net_2037")
		)
		(pad "P3" smd rect
			(at -0.635 -1.82499 270)
			(size 0.6096 2.3622)
			(layers "F.Cu" "F.Mask" "F.Paste")
			(net "Net_2038")
		)
		(pad "P4" smd rect
			(at -1.905 -1.82499 270)
			(size 0.6096 2.3622)
			(layers "F.Cu" "F.Mask" "F.Paste")
			(net "GND")
		)
		(pad "P5" smd rect
			(at -3.175 -1.82499 270)
			(size 0.6096 2.3622)
			(layers "F.Cu" "F.Mask" "F.Paste")
			(net "HDD_PRSNT_34")
		)
		(pad "P6" smd rect
			(at -4.445 -1.82499 270)
			(size 0.6096 2.3622)
			(layers "F.Cu" "F.Mask" "F.Paste")
			(net "GND")
		)
		(pad "P7" smd rect
			(at -5.715 -1.82499 270)
			(size 0.6096 2.3622)
			(layers "F.Cu" "F.Mask" "F.Paste")
			(net "5V_PRE_34")
		)
		(pad "P8" smd rect
			(at -6.985 -1.82499 270)
			(size 0.6096 2.3622)
			(layers "F.Cu" "F.Mask" "F.Paste")
			(net "P5V_HDD34")
		)
		(pad "P9" smd rect
			(at -8.255 -1.82499 270)
			(size 0.6096 2.3622)
			(layers "F.Cu" "F.Mask" "F.Paste")
			(net "P5V_HDD34")
		)
		(pad "P10" smd rect
			(at -9.525 -1.82499 270)
			(size 0.6096 2.3622)
			(layers "F.Cu" "F.Mask" "F.Paste")
			(net "GND")
		)
		(pad "P11" smd rect
			(at -10.795 -1.82499 270)
			(size 0.6096 2.3622)
			(layers "F.Cu" "F.Mask" "F.Paste")
			(net "ACT_HDD_34")
		)
		(pad "P12" smd rect
			(at -12.065 -1.82499 270)
			(size 0.6096 2.3622)
			(layers "F.Cu" "F.Mask" "F.Paste")
			(net "GND")
		)
		(pad "P13" smd rect
			(at -13.335 -1.82499 270)
			(size 0.6096 2.3622)
			(layers "F.Cu" "F.Mask" "F.Paste")
			(net "12V_PRE_34")
		)
		(pad "P14" smd rect
			(at -14.605 -1.82499 270)
			(size 0.6096 2.3622)
			(layers "F.Cu" "F.Mask" "F.Paste")
			(net "P12V_HDD34")
		)
		(pad "P15" smd rect
			(at -15.875 -1.82499 270)
			(size 0.6096 2.3622)
			(layers "F.Cu" "F.Mask" "F.Paste")
			(net "P12V_HDD34")
		)
		(pad "S1" smd rect
			(at 15.875 -1.82499 270)
			(size 0.6096 2.3622)
			(layers "F.Cu" "F.Mask" "F.Paste")
			(net "GND")
		)
		(pad "S2" smd rect
			(at 14.605 -1.82499 270)
			(size 0.6096 2.3622)
			(layers "F.Cu" "F.Mask" "F.Paste")
			(net "SAS_HDD_RX_P34")
		)
		(pad "S3" smd rect
			(at 13.335 -1.82499 270)
			(size 0.6096 2.3622)
			(layers "F.Cu" "F.Mask" "F.Paste")
			(net "SAS_HDD_RX_N34")
		)
		(pad "S4" smd rect
			(at 12.065 -1.82499 270)
			(size 0.6096 2.3622)
			(layers "F.Cu" "F.Mask" "F.Paste")
			(net "GND")
		)
		(pad "S5" smd rect
			(at 10.795 -1.82499 270)
			(size 0.6096 2.3622)
			(layers "F.Cu" "F.Mask" "F.Paste")
			(net "PHY_DRV_A_TO_SCC_A_34_DN")
		)
		(pad "S6" smd rect
			(at 9.525 -1.82499 270)
			(size 0.6096 2.3622)
			(layers "F.Cu" "F.Mask" "F.Paste")
			(net "PHY_DRV_A_TO_SCC_A_34_DP")
		)
		(pad "S7" smd rect
			(at 8.255 -1.82499 270)
			(size 0.6096 2.3622)
			(layers "F.Cu" "F.Mask" "F.Paste")
			(net "GND")
		)
		(pad "S8" smd rect
			(at 7.480046 2.845054 270)
			(size 0.508 2.3622)
			(layers "F.Cu" "F.Mask" "F.Paste")
			(net "GND")
		)
		(pad "S9" smd rect
			(at 6.679946 2.845054 270)
			(size 0.508 2.3622)
			(layers "F.Cu" "F.Mask" "F.Paste")
			(net "Net_473")
		)
		(pad "S10" smd rect
			(at 5.8801 2.845054 270)
			(size 0.508 2.3622)
			(layers "F.Cu" "F.Mask" "F.Paste")
			(net "Net_365")
		)
		(pad "S11" smd rect
			(at 5.08 2.845054 270)
			(size 0.508 2.3622)
			(layers "F.Cu" "F.Mask" "F.Paste")
			(net "GND")
		)
		(pad "S12" smd rect
			(at 4.2799 2.845054 270)
			(size 0.508 2.3622)
			(layers "F.Cu" "F.Mask" "F.Paste")
			(net "Net_401")
		)
		(pad "S13" smd rect
			(at 3.480054 2.845054 270)
			(size 0.508 2.3622)
			(layers "F.Cu" "F.Mask" "F.Paste")
			(net "Net_437")
		)
		(pad "S14" smd rect
			(at 2.679954 2.845054 270)
			(size 0.508 2.3622)
			(layers "F.Cu" "F.Mask" "F.Paste")
			(net "GND")
		)
		(zone
			(layer "F.Cu")
			(hatch none 0.5)
			(connect_pads
				(clearance 0)
			)
			(min_thickness 0.25)
			(keepout
				(tracks not_allowed)
				(vias allowed)
				(pads allowed)
				(copperpour not_allowed)
				(footprints allowed)
			)
			(placement
				(enabled no)
				(sheetname "")
			)
			(fill
				(thermal_gap 0.5)
				(thermal_bridge_width 0.5)
				(island_removal_mode 0)
			)
			(polygon
				(pts
					(xy 455.407522 -74.648568) (xy 448.333622 -74.648568) (xy 448.333622 -81.582768) (xy 449.438522 -81.582768)
					(xy 449.438522 -77.467968) (xy 454.061322 -77.467968) (xy 454.061322 -81.582768) (xy 455.407522 -81.582768)
				)
			)
		)
		(zone
			(layer "F.Cu")
			(hatch none 0.5)
			(connect_pads
				(clearance 0)
			)
			(min_thickness 0.25)
			(keepout
				(tracks allowed)
				(vias not_allowed)
				(pads allowed)
				(copperpour not_allowed)
				(footprints allowed)
			)
			(placement
				(enabled no)
				(sheetname "")
			)
			(fill
				(thermal_gap 0.5)
				(thermal_bridge_width 0.5)
				(island_removal_mode 0)
			)
			(polygon
				(pts
					(xy 455.407522 -74.648568) (xy 448.333622 -74.648568) (xy 448.333622 -81.582768) (xy 449.438522 -81.582768)
					(xy 449.438522 -77.467968) (xy 454.061322 -77.467968) (xy 454.061322 -81.582768) (xy 455.407522 -81.582768)
				)
			)
		)
		(zone
			(layer "F.Cu")
			(hatch none 0.5)
			(connect_pads
				(clearance 0)
			)
			(min_thickness 0.25)
			(keepout
				(tracks not_allowed)
				(vias allowed)
				(pads allowed)
				(copperpour not_allowed)
				(footprints allowed)
			)
			(placement
				(enabled no)
				(sheetname "")
			)
			(fill
				(thermal_gap 0.5)
				(thermal_bridge_width 0.5)
				(island_removal_mode 0)
			)
			(polygon
				(pts
					(xy 455.407522 -41.171368) (xy 448.333622 -41.171368) (xy 448.333622 -34.237168) (xy 449.438522 -34.237168)
					(xy 449.438522 -38.351968) (xy 454.061322 -38.351968) (xy 454.061322 -34.237168) (xy 455.407522 -34.237168)
				)
			)
		)
		(zone
			(layer "F.Cu")
			(hatch none 0.5)
			(connect_pads
				(clearance 0)
			)
			(min_thickness 0.25)
			(keepout
				(tracks allowed)
				(vias not_allowed)
				(pads allowed)
				(copperpour not_allowed)
				(footprints allowed)
			)
			(placement
				(enabled no)
				(sheetname "")
			)
			(fill
				(thermal_gap 0.5)
				(thermal_bridge_width 0.5)
				(island_removal_mode 0)
			)
			(polygon
				(pts
					(xy 455.407522 -41.171368) (xy 448.333622 -41.171368) (xy 448.333622 -34.237168) (xy 449.438522 -34.237168)
					(xy 449.438522 -38.351968) (xy 454.061322 -38.351968) (xy 454.061322 -34.237168) (xy 455.407522 -34.237168)
				)
			)
		)
		(zone
			(layers "F.Cu" "B.Cu" "In1.Cu" "In2.Cu" "In3.Cu" "In4.Cu" "In5.Cu" "In6.Cu"
				"In7.Cu" "In8.Cu" "In9.Cu" "In10.Cu"
			)
			(hatch none 0.5)
			(connect_pads
				(clearance 0)
			)
			(min_thickness 0.25)
			(keepout
				(tracks not_allowed)
				(vias allowed)
				(pads allowed)
				(copperpour not_allowed)
				(footprints allowed)
			)
			(placement
				(enabled no)
				(sheetname "")
			)
			(fill
				(thermal_gap 0.5)
				(thermal_bridge_width 0.5)
				(island_removal_mode 0)
			)
			(polygon
				(pts
					(arc
						(start 452.524622 -39.034974)
						(mid 450.975222 -39.034974)
						(end 452.524622 -39.034974)
					)
				)
			)
		)
		(zone
			(layers "F.Cu" "B.Cu" "In1.Cu" "In2.Cu" "In3.Cu" "In4.Cu" "In5.Cu" "In6.Cu"
				"In7.Cu" "In8.Cu" "In9.Cu" "In10.Cu"
			)
			(hatch none 0.5)
			(connect_pads
				(clearance 0)
			)
			(min_thickness 0.25)
			(keepout
				(tracks not_allowed)
				(vias allowed)
				(pads allowed)
				(copperpour not_allowed)
				(footprints allowed)
			)
			(placement
				(enabled no)
				(sheetname "")
			)
			(fill
				(thermal_gap 0.5)
				(thermal_bridge_width 0.5)
				(island_removal_mode 0)
			)
			(polygon
				(pts
					(arc
						(start 452.727822 -76.784962)
						(mid 450.772022 -76.784962)
						(end 452.727822 -76.784962)
					)
				)
			)
		)
	)
	(footprint ""
		(layer "F.Cu")
		(at 172.466 -294.683942 -90)
		(property "Reference" "C110"
			(at 0 0 270)
			(layer "F.SilkS")
			(hide yes)
			(effects
				(font
					(size 1.27 1.27)
				)
			)
		)
		(property "Value" "SC4D7U25V5KX-1-GP"
			(at -0.0762 -6.1214 270)
			(unlocked yes)
			(layer "F.Fab")
			(hide yes)
			(effects
				(font
					(size 1.016 1.016)
					(thickness 0.1524)
				)
			)
		)
		(property "Device Type" "C805H58"
			(at -0.0762 -8.1534 270)
			(unlocked yes)
			(layer "F.Fab")
			(hide yes)
			(effects
				(font
					(size 1.016 1.016)
					(thickness 0.1524)
				)
			)
		)
		(duplicate_pad_numbers_are_jumpers no)
		(fp_line
			(start 0.635 0)
			(end -0.635 0)
			(stroke
				(width 0.508)
				(type default)
			)
			(layer "F.SilkS")
		)
		(fp_rect
			(start -0.9652 1.778)
			(end 0.9652 -1.778)
			(stroke
				(width 0)
				(type default)
			)
			(fill no)
			(layer "F.CrtYd")
		)
		(fp_poly
			(pts
				(xy -0.9652 -1.778) (xy 0.9652 -1.778) (xy 0.9652 1.778) (xy -0.9652 1.778)
			)
			(stroke
				(width 0)
				(type default)
			)
			(fill no)
			(layer "F.Fab")
		)
		(pad "1" smd rect
			(at 0 -0.9652 270)
			(size 1.397 1.143)
			(layers "F.Cu" "F.Mask" "F.Paste")
			(net "P12V_HDD5")
		)
		(pad "2" smd rect
			(at 0 0.9652 270)
			(size 1.397 1.143)
			(layers "F.Cu" "F.Mask" "F.Paste")
			(net "GND")
		)
	)
	(footprint ""
		(layer "F.Cu")
		(at 224.572322 -131.11607 -90)
		(property "Reference" "TP205"
			(at 0 0 270)
			(layer "F.SilkS")
			(hide yes)
			(effects
				(font
					(size 1.27 1.27)
				)
			)
		)
		(property "Value" "TPAD32-GP"
			(at -0.0508 -1.6764 270)
			(unlocked yes)
			(layer "F.Fab")
			(hide yes)
			(effects
				(font
					(size 1.016 1.016)
					(thickness 0.1524)
				)
			)
		)
		(property "Device Type" "TPAD32"
			(at -0.0508 -3.2004 270)
			(unlocked yes)
			(layer "F.Fab")
			(hide yes)
			(effects
				(font
					(size 1.016 1.016)
					(thickness 0.1524)
				)
			)
		)
		(duplicate_pad_numbers_are_jumpers no)
		(fp_poly
			(pts
				(arc
					(start 0 -0.4064)
					(mid 0 0.4064)
					(end 0 -0.4064)
				)
			)
			(stroke
				(width 0)
				(type default)
			)
			(fill no)
			(layer "F.CrtYd")
		)
		(fp_poly
			(pts
				(arc
					(start 0 -0.7112)
					(mid 0 0.7112)
					(end 0 -0.7112)
				)
			)
			(stroke
				(width 0)
				(type default)
			)
			(fill no)
			(layer "F.Fab")
		)
		(pad "1" smd circle
			(at 0 0 270)
			(size 0.8128 0.8128)
			(layers "F.Cu" "F.Mask" "F.Paste")
			(net "TP_COMP_A_SATA_P0_RX_DP")
		)
	)
	(footprint ""
		(layer "F.Cu")
		(at 445.0207 -61.102494 -90)
		(property "Reference" "C487"
			(at 0 0 270)
			(layer "F.SilkS")
			(hide yes)
			(effects
				(font
					(size 1.27 1.27)
				)
			)
		)
		(property "Value" "SCD01U50V2KX-1GP"
			(at 1.1811 -2.7051 270)
			(unlocked yes)
			(layer "F.Fab")
			(hide yes)
			(effects
				(font
					(size 1.016 1.016)
					(thickness 0.1524)
				)
			)
		)
		(property "Device Type" "C402H22"
			(at 1.1811 -4.2291 270)
			(unlocked yes)
			(layer "F.Fab")
			(hide yes)
			(effects
				(font
					(size 1.016 1.016)
					(thickness 0.1524)
				)
			)
		)
		(duplicate_pad_numbers_are_jumpers no)
		(fp_rect
			(start -0.4318 0.9525)
			(end 0.4318 -0.9525)
			(stroke
				(width 0)
				(type default)
			)
			(fill no)
			(layer "F.CrtYd")
		)
		(fp_rect
			(start -0.4318 0.9525)
			(end 0.4318 -0.9525)
			(stroke
				(width 0)
				(type default)
			)
			(fill no)
			(layer "F.Fab")
		)
		(pad "1" smd custom
			(at 0 -0.4445 270)
			(size 0.1524 0.1524)
			(layers "F.Cu" "F.Mask" "F.Paste")
			(net "HDD_PRSNT_34")
			(options
				(clearance outline)
				(anchor circle)
			)
			(primitives
				(gr_poly
					(pts
						(arc
							(start 0.3048 -0.2032)
							(mid 0.275042 -0.275042)
							(end 0.2032 -0.3048)
						)
						(arc
							(start -0.2032 -0.3048)
							(mid -0.275042 -0.275042)
							(end -0.3048 -0.2032)
						)
						(arc
							(start -0.3048 0.2032)
							(mid -0.275042 0.275042)
							(end -0.2032 0.3048)
						)
						(arc
							(start 0.2032 0.3048)
							(mid 0.275042 0.275042)
							(end 0.3048 0.2032)
						)
					)
					(width 0)
					(fill yes)
				)
			)
		)
		(pad "2" smd custom
			(at 0 0.4445 270)
			(size 0.1524 0.1524)
			(layers "F.Cu" "F.Mask" "F.Paste")
			(net "GND")
			(options
				(clearance outline)
				(anchor circle)
			)
			(primitives
				(gr_poly
					(pts
						(arc
							(start 0.3048 -0.2032)
							(mid 0.275042 -0.275042)
							(end 0.2032 -0.3048)
						)
						(arc
							(start -0.2032 -0.3048)
							(mid -0.275042 -0.275042)
							(end -0.3048 -0.2032)
						)
						(arc
							(start -0.3048 0.2032)
							(mid -0.275042 0.275042)
							(end -0.2032 0.3048)
						)
						(arc
							(start 0.2032 0.3048)
							(mid 0.275042 0.275042)
							(end 0.3048 0.2032)
						)
					)
					(width 0)
					(fill yes)
				)
			)
		)
	)
	(footprint ""
		(layer "F.Cu")
		(at 333.329534 -21.88337 90)
		(property "Reference" "R79"
			(at 0 0 90)
			(layer "F.SilkS")
			(hide yes)
			(effects
				(font
					(size 1.27 1.27)
				)
			)
		)
		(property "Value" "4K7R2F-GP"
			(at 0.064008 -3.993896 90)
			(unlocked yes)
			(layer "F.Fab")
			(hide yes)
			(effects
				(font
					(size 1.016 1.016)
					(thickness 0.1524)
				)
			)
		)
		(property "Device Type" "R402H16"
			(at 0.064008 -5.517896 90)
			(unlocked yes)
			(layer "F.Fab")
			(hide yes)
			(effects
				(font
					(size 1.016 1.016)
					(thickness 0.1524)
				)
			)
		)
		(duplicate_pad_numbers_are_jumpers no)
		(fp_line
			(start 0.508 -0.9398)
			(end -0.508 -0.9398)
			(stroke
				(width 0.1524)
				(type default)
			)
			(layer "F.SilkS")
		)
		(fp_line
			(start -0.508 -0.9398)
			(end -0.508 0.9398)
			(stroke
				(width 0.1524)
				(type default)
			)
			(layer "F.SilkS")
		)
		(fp_rect
			(start -0.508 0.9398)
			(end 0.508 -0.9398)
			(stroke
				(width 0)
				(type default)
			)
			(fill no)
			(layer "F.CrtYd")
		)
		(fp_rect
			(start -0.508 0.9398)
			(end 0.508 -0.9398)
			(stroke
				(width 0)
				(type default)
			)
			(fill no)
			(layer "F.Fab")
		)
		(pad "1" smd custom
			(at 0 -0.4445 90)
			(size 0.1397 0.1397)
			(layers "F.Cu" "F.Mask" "F.Paste")
			(net "P3V3_STBY_B")
			(options
				(clearance outline)
				(anchor circle)
			)
			(primitives
				(gr_poly
					(pts
						(arc
							(start -0.1778 -0.2794)
							(mid -0.249642 -0.249642)
							(end -0.2794 -0.1778)
						)
						(arc
							(start -0.2794 0.1778)
							(mid -0.249642 0.249642)
							(end -0.1778 0.2794)
						)
						(arc
							(start 0.1778 0.2794)
							(mid 0.249642 0.249642)
							(end 0.2794 0.1778)
						)
						(arc
							(start 0.2794 -0.1778)
							(mid 0.249642 -0.249642)
							(end 0.1778 -0.2794)
						)
					)
					(width 0)
					(fill yes)
				)
			)
		)
		(pad "2" smd custom
			(at 0 0.4445 90)
			(size 0.1397 0.1397)
			(layers "F.Cu" "F.Mask" "F.Paste")
			(net "IO_EXP11_A1")
			(options
				(clearance outline)
				(anchor circle)
			)
			(primitives
				(gr_poly
					(pts
						(arc
							(start -0.1778 -0.2794)
							(mid -0.249642 -0.249642)
							(end -0.2794 -0.1778)
						)
						(arc
							(start -0.2794 0.1778)
							(mid -0.249642 0.249642)
							(end -0.1778 0.2794)
						)
						(arc
							(start 0.1778 0.2794)
							(mid 0.249642 0.249642)
							(end 0.2794 0.1778)
						)
						(arc
							(start 0.2794 -0.1778)
							(mid 0.249642 -0.249642)
							(end 0.1778 -0.2794)
						)
					)
					(width 0)
					(fill yes)
				)
			)
		)
	)
	(footprint ""
		(layer "F.Cu")
		(at 47.866046 -284.371542 -90)
		(property "Reference" "R167"
			(at 0 0 270)
			(layer "F.SilkS")
			(hide yes)
			(effects
				(font
					(size 1.27 1.27)
				)
			)
		)
		(property "Value" "300KR2F-GP"
			(at 0.064008 -3.993896 270)
			(unlocked yes)
			(layer "F.Fab")
			(hide yes)
			(effects
				(font
					(size 1.016 1.016)
					(thickness 0.1524)
				)
			)
		)
		(property "Device Type" "R402H16"
			(at 0.064008 -5.517896 270)
			(unlocked yes)
			(layer "F.Fab")
			(hide yes)
			(effects
				(font
					(size 1.016 1.016)
					(thickness 0.1524)
				)
			)
		)
		(duplicate_pad_numbers_are_jumpers no)
		(fp_line
			(start -0.508 -0.9398)
			(end -0.508 0.9398)
			(stroke
				(width 0.1524)
				(type default)
			)
			(layer "F.SilkS")
		)
		(fp_line
			(start 0.508 -0.9398)
			(end -0.508 -0.9398)
			(stroke
				(width 0.1524)
				(type default)
			)
			(layer "F.SilkS")
		)
		(fp_rect
			(start -0.508 0.9398)
			(end 0.508 -0.9398)
			(stroke
				(width 0)
				(type default)
			)
			(fill no)
			(layer "F.CrtYd")
		)
		(fp_rect
			(start -0.508 0.9398)
			(end 0.508 -0.9398)
			(stroke
				(width 0)
				(type default)
			)
			(fill no)
			(layer "F.Fab")
		)
		(pad "1" smd custom
			(at 0 -0.4445 270)
			(size 0.1397 0.1397)
			(layers "F.Cu" "F.Mask" "F.Paste")
			(net "SW_HDD_N1")
			(options
				(clearance outline)
				(anchor circle)
			)
			(primitives
				(gr_poly
					(pts
						(arc
							(start -0.1778 -0.2794)
							(mid -0.249642 -0.249642)
							(end -0.2794 -0.1778)
						)
						(arc
							(start -0.2794 0.1778)
							(mid -0.249642 0.249642)
							(end -0.1778 0.2794)
						)
						(arc
							(start 0.1778 0.2794)
							(mid 0.249642 0.249642)
							(end 0.2794 0.1778)
						)
						(arc
							(start 0.2794 -0.1778)
							(mid 0.249642 -0.249642)
							(end 0.1778 -0.2794)
						)
					)
					(width 0)
					(fill yes)
				)
			)
		)
		(pad "2" smd custom
			(at 0 0.4445 270)
			(size 0.1397 0.1397)
			(layers "F.Cu" "F.Mask" "F.Paste")
			(net "P12V_A")
			(options
				(clearance outline)
				(anchor circle)
			)
			(primitives
				(gr_poly
					(pts
						(arc
							(start -0.1778 -0.2794)
							(mid -0.249642 -0.249642)
							(end -0.2794 -0.1778)
						)
						(arc
							(start -0.2794 0.1778)
							(mid -0.249642 0.249642)
							(end -0.1778 0.2794)
						)
						(arc
							(start 0.1778 0.2794)
							(mid 0.249642 0.249642)
							(end 0.2794 0.1778)
						)
						(arc
							(start 0.2794 -0.1778)
							(mid 0.249642 -0.249642)
							(end 0.1778 -0.2794)
						)
					)
					(width 0)
					(fill yes)
				)
			)
		)
	)
	(footprint ""
		(layer "F.Cu")
		(at 38.763448 -294.191182 90)
		(property "Reference" "R554"
			(at 0 0 90)
			(layer "F.SilkS")
			(hide yes)
			(effects
				(font
					(size 1.27 1.27)
				)
			)
		)
		(property "Value" "4K7R2J-2-GP"
			(at 0.064008 -3.993896 90)
			(unlocked yes)
			(layer "F.Fab")
			(hide yes)
			(effects
				(font
					(size 1.016 1.016)
					(thickness 0.1524)
				)
			)
		)
		(property "Device Type" "R402H16"
			(at 0.064008 -5.517896 90)
			(unlocked yes)
			(layer "F.Fab")
			(hide yes)
			(effects
				(font
					(size 1.016 1.016)
					(thickness 0.1524)
				)
			)
		)
		(duplicate_pad_numbers_are_jumpers no)
		(fp_line
			(start 0.508 -0.9398)
			(end -0.508 -0.9398)
			(stroke
				(width 0.1524)
				(type default)
			)
			(layer "F.SilkS")
		)
		(fp_line
			(start -0.508 -0.9398)
			(end -0.508 0.9398)
			(stroke
				(width 0.1524)
				(type default)
			)
			(layer "F.SilkS")
		)
		(fp_rect
			(start -0.508 0.9398)
			(end 0.508 -0.9398)
			(stroke
				(width 0)
				(type default)
			)
			(fill no)
			(layer "F.CrtYd")
		)
		(fp_rect
			(start -0.508 0.9398)
			(end 0.508 -0.9398)
			(stroke
				(width 0)
				(type default)
			)
			(fill no)
			(layer "F.Fab")
		)
		(pad "1" smd custom
			(at 0 -0.4445 90)
			(size 0.1397 0.1397)
			(layers "F.Cu" "F.Mask" "F.Paste")
			(net "DRIVE_B_25_ACT")
			(options
				(clearance outline)
				(anchor circle)
			)
			(primitives
				(gr_poly
					(pts
						(arc
							(start -0.1778 -0.2794)
							(mid -0.249642 -0.249642)
							(end -0.2794 -0.1778)
						)
						(arc
							(start -0.2794 0.1778)
							(mid -0.249642 0.249642)
							(end -0.1778 0.2794)
						)
						(arc
							(start 0.1778 0.2794)
							(mid 0.249642 0.249642)
							(end 0.2794 0.1778)
						)
						(arc
							(start 0.2794 -0.1778)
							(mid 0.249642 -0.249642)
							(end 0.1778 -0.2794)
						)
					)
					(width 0)
					(fill yes)
				)
			)
		)
		(pad "2" smd custom
			(at 0 0.4445 90)
			(size 0.1397 0.1397)
			(layers "F.Cu" "F.Mask" "F.Paste")
			(net "GND")
			(options
				(clearance outline)
				(anchor circle)
			)
			(primitives
				(gr_poly
					(pts
						(arc
							(start -0.1778 -0.2794)
							(mid -0.249642 -0.249642)
							(end -0.2794 -0.1778)
						)
						(arc
							(start -0.2794 0.1778)
							(mid -0.249642 0.249642)
							(end -0.1778 0.2794)
						)
						(arc
							(start 0.1778 0.2794)
							(mid 0.249642 0.249642)
							(end 0.2794 0.1778)
						)
						(arc
							(start 0.2794 -0.1778)
							(mid 0.249642 -0.249642)
							(end 0.1778 -0.2794)
						)
					)
					(width 0)
					(fill yes)
				)
			)
		)
	)
	(footprint ""
		(layer "F.Cu")
		(at 471.980514 -280.158698 -90)
		(property "Reference" "C191"
			(at 0 0 270)
			(layer "F.SilkS")
			(hide yes)
			(effects
				(font
					(size 1.27 1.27)
				)
			)
		)
		(property "Value" "SCD033U25V2KX-GP"
			(at 1.1811 -2.7051 270)
			(unlocked yes)
			(layer "F.Fab")
			(hide yes)
			(effects
				(font
					(size 1.016 1.016)
					(thickness 0.1524)
				)
			)
		)
		(property "Device Type" "C402H22"
			(at 1.1811 -4.2291 270)
			(unlocked yes)
			(layer "F.Fab")
			(hide yes)
			(effects
				(font
					(size 1.016 1.016)
					(thickness 0.1524)
				)
			)
		)
		(duplicate_pad_numbers_are_jumpers no)
		(fp_rect
			(start -0.4318 0.9525)
			(end 0.4318 -0.9525)
			(stroke
				(width 0)
				(type default)
			)
			(fill no)
			(layer "F.CrtYd")
		)
		(fp_rect
			(start -0.4318 0.9525)
			(end 0.4318 -0.9525)
			(stroke
				(width 0)
				(type default)
			)
			(fill no)
			(layer "F.Fab")
		)
		(pad "1" smd custom
			(at 0 -0.4445 270)
			(size 0.1524 0.1524)
			(layers "F.Cu" "F.Mask" "F.Paste")
			(net "SW_HDD_P11")
			(options
				(clearance outline)
				(anchor circle)
			)
			(primitives
				(gr_poly
					(pts
						(arc
							(start 0.3048 -0.2032)
							(mid 0.275042 -0.275042)
							(end 0.2032 -0.3048)
						)
						(arc
							(start -0.2032 -0.3048)
							(mid -0.275042 -0.275042)
							(end -0.3048 -0.2032)
						)
						(arc
							(start -0.3048 0.2032)
							(mid -0.275042 0.275042)
							(end -0.2032 0.3048)
						)
						(arc
							(start 0.2032 0.3048)
							(mid 0.275042 0.275042)
							(end 0.3048 0.2032)
						)
					)
					(width 0)
					(fill yes)
				)
			)
		)
		(pad "2" smd custom
			(at 0 0.4445 270)
			(size 0.1524 0.1524)
			(layers "F.Cu" "F.Mask" "F.Paste")
			(net "GND")
			(options
				(clearance outline)
				(anchor circle)
			)
			(primitives
				(gr_poly
					(pts
						(arc
							(start 0.3048 -0.2032)
							(mid 0.275042 -0.275042)
							(end 0.2032 -0.3048)
						)
						(arc
							(start -0.2032 -0.3048)
							(mid -0.275042 -0.275042)
							(end -0.3048 -0.2032)
						)
						(arc
							(start -0.3048 0.2032)
							(mid -0.275042 0.275042)
							(end -0.2032 0.3048)
						)
						(arc
							(start 0.2032 0.3048)
							(mid 0.275042 0.275042)
							(end 0.3048 0.2032)
						)
					)
					(width 0)
					(fill yes)
				)
			)
		)
	)
	(footprint ""
		(layer "F.Cu")
		(at 77.815948 -64.683894 -90)
		(property "Reference" "C382"
			(at 0 0 270)
			(layer "F.SilkS")
			(hide yes)
			(effects
				(font
					(size 1.27 1.27)
				)
			)
		)
		(property "Value" "SC4D7U25V5KX-1-GP"
			(at -0.0762 -6.1214 270)
			(unlocked yes)
			(layer "F.Fab")
			(hide yes)
			(effects
				(font
					(size 1.016 1.016)
					(thickness 0.1524)
				)
			)
		)
		(property "Device Type" "C805H58"
			(at -0.0762 -8.1534 270)
			(unlocked yes)
			(layer "F.Fab")
			(hide yes)
			(effects
				(font
					(size 1.016 1.016)
					(thickness 0.1524)
				)
			)
		)
		(duplicate_pad_numbers_are_jumpers no)
		(fp_line
			(start 0.635 0)
			(end -0.635 0)
			(stroke
				(width 0.508)
				(type default)
			)
			(layer "F.SilkS")
		)
		(fp_rect
			(start -0.9652 1.778)
			(end 0.9652 -1.778)
			(stroke
				(width 0)
				(type default)
			)
			(fill no)
			(layer "F.CrtYd")
		)
		(fp_poly
			(pts
				(xy -0.9652 -1.778) (xy 0.9652 -1.778) (xy 0.9652 1.778) (xy -0.9652 1.778)
			)
			(stroke
				(width 0)
				(type default)
			)
			(fill no)
			(layer "F.Fab")
		)
		(pad "1" smd rect
			(at 0 -0.9652 270)
			(size 1.397 1.143)
			(layers "F.Cu" "F.Mask" "F.Paste")
			(net "P12V_HDD26")
		)
		(pad "2" smd rect
			(at 0 0.9652 270)
			(size 1.397 1.143)
			(layers "F.Cu" "F.Mask" "F.Paste")
			(net "GND")
		)
	)
	(footprint ""
		(layer "F.Cu")
		(at 298.7802 -74.7776)
		(property "Reference" "R370"
			(at 0 0 0)
			(layer "F.SilkS")
			(hide yes)
			(effects
				(font
					(size 1.27 1.27)
				)
			)
		)
		(property "Value" "4K7R2F-GP"
			(at 0.064008 -3.993896 0)
			(unlocked yes)
			(layer "F.Fab")
			(hide yes)
			(effects
				(font
					(size 1.016 1.016)
					(thickness 0.1524)
				)
			)
		)
		(property "Device Type" "R402H16"
			(at 0.064008 -5.517896 0)
			(unlocked yes)
			(layer "F.Fab")
			(hide yes)
			(effects
				(font
					(size 1.016 1.016)
					(thickness 0.1524)
				)
			)
		)
		(duplicate_pad_numbers_are_jumpers no)
		(fp_line
			(start -0.508 -0.9398)
			(end -0.508 0.9398)
			(stroke
				(width 0.1524)
				(type default)
			)
			(layer "F.SilkS")
		)
		(fp_line
			(start 0.508 -0.9398)
			(end -0.508 -0.9398)
			(stroke
				(width 0.1524)
				(type default)
			)
			(layer "F.SilkS")
		)
		(fp_rect
			(start -0.508 0.9398)
			(end 0.508 -0.9398)
			(stroke
				(width 0)
				(type default)
			)
			(fill no)
			(layer "F.CrtYd")
		)
		(fp_rect
			(start -0.508 0.9398)
			(end 0.508 -0.9398)
			(stroke
				(width 0)
				(type default)
			)
			(fill no)
			(layer "F.Fab")
		)
		(pad "1" smd custom
			(at 0 -0.4445)
			(size 0.1397 0.1397)
			(layers "F.Cu" "F.Mask" "F.Paste")
			(net "COMP_B_POWER_FAIL_N")
			(options
				(clearance outline)
				(anchor circle)
			)
			(primitives
				(gr_poly
					(pts
						(arc
							(start -0.1778 -0.2794)
							(mid -0.249642 -0.249642)
							(end -0.2794 -0.1778)
						)
						(arc
							(start -0.2794 0.1778)
							(mid -0.249642 0.249642)
							(end -0.1778 0.2794)
						)
						(arc
							(start 0.1778 0.2794)
							(mid 0.249642 0.249642)
							(end 0.2794 0.1778)
						)
						(arc
							(start 0.2794 -0.1778)
							(mid 0.249642 -0.249642)
							(end 0.1778 -0.2794)
						)
					)
					(width 0)
					(fill yes)
				)
			)
		)
		(pad "2" smd custom
			(at 0 0.4445)
			(size 0.1397 0.1397)
			(layers "F.Cu" "F.Mask" "F.Paste")
			(net "P3V3_STBY_B")
			(options
				(clearance outline)
				(anchor circle)
			)
			(primitives
				(gr_poly
					(pts
						(arc
							(start -0.1778 -0.2794)
							(mid -0.249642 -0.249642)
							(end -0.2794 -0.1778)
						)
						(arc
							(start -0.2794 0.1778)
							(mid -0.249642 0.249642)
							(end -0.1778 0.2794)
						)
						(arc
							(start 0.1778 0.2794)
							(mid 0.249642 0.249642)
							(end 0.2794 0.1778)
						)
						(arc
							(start 0.2794 -0.1778)
							(mid 0.249642 -0.249642)
							(end 0.1778 -0.2794)
						)
					)
					(width 0)
					(fill yes)
				)
			)
		)
	)
	(footprint ""
		(layer "F.Cu")
		(at 431.962052 -277.792942 90)
		(property "Reference" "D9"
			(at 0 0 90)
			(layer "F.SilkS")
			(hide yes)
			(effects
				(font
					(size 1.27 1.27)
				)
			)
		)
		(property "Value" "RB551V30-GP"
			(at 0 -6.7818 90)
			(unlocked yes)
			(layer "F.Fab")
			(hide yes)
			(effects
				(font
					(size 1.016 1.016)
					(thickness 0.1524)
				)
			)
		)
		(property "Device Type" "SOD323AKH38"
			(at 0 -8.6868 90)
			(unlocked yes)
			(layer "F.Fab")
			(hide yes)
			(effects
				(font
					(size 1.016 1.016)
					(thickness 0.1524)
				)
			)
		)
		(duplicate_pad_numbers_are_jumpers no)
		(fp_line
			(start 0.889 -1.9304)
			(end 0.889 2.159)
			(stroke
				(width 0.1524)
				(type default)
			)
			(layer "F.SilkS")
		)
		(fp_line
			(start -0.889 -1.9304)
			(end 0.889 -1.9304)
			(stroke
				(width 0.1524)
				(type default)
			)
			(layer "F.SilkS")
		)
		(fp_line
			(start 0.762 2.0574)
			(end -0.762 2.0574)
			(stroke
				(width 0.508)
				(type default)
			)
			(layer "F.SilkS")
		)
		(fp_line
			(start 0.889 2.159)
			(end -0.889 2.159)
			(stroke
				(width 0.1524)
				(type default)
			)
			(layer "F.SilkS")
		)
		(fp_line
			(start -0.889 2.159)
			(end -0.889 -1.9304)
			(stroke
				(width 0.1524)
				(type default)
			)
			(layer "F.SilkS")
		)
		(fp_rect
			(start -1.016 2.3114)
			(end 1.016 -2.0066)
			(stroke
				(width 0)
				(type default)
			)
			(fill no)
			(layer "F.CrtYd")
		)
		(fp_poly
			(pts
				(xy -1.016 -2.0066) (xy 1.016 -2.0066) (xy 1.016 2.3114) (xy -1.016 2.3114)
			)
			(stroke
				(width 0)
				(type default)
			)
			(fill no)
			(layer "F.Fab")
		)
		(pad "A" smd rect
			(at 0 -1.143 90)
			(size 0.5588 1.016)
			(layers "F.Cu" "F.Mask" "F.Paste")
			(net "SW_HDD_R9")
		)
		(pad "K" smd rect
			(at 0 1.143 90)
			(size 0.5588 1.016)
			(layers "F.Cu" "F.Mask" "F.Paste")
			(net "SW_HDD_N9")
		)
	)
	(footprint ""
		(layer "F.Cu")
		(at 222.616522 -117.98427 -90)
		(property "Reference" "R1001"
			(at 0 0 270)
			(layer "F.SilkS")
			(hide yes)
			(effects
				(font
					(size 1.27 1.27)
				)
			)
		)
		(property "Value" "100KR2F-L1-GP"
			(at 0.064008 -3.993896 270)
			(unlocked yes)
			(layer "F.Fab")
			(hide yes)
			(effects
				(font
					(size 1.016 1.016)
					(thickness 0.1524)
				)
			)
		)
		(property "Device Type" "R402H16"
			(at 0.064008 -5.517896 270)
			(unlocked yes)
			(layer "F.Fab")
			(hide yes)
			(effects
				(font
					(size 1.016 1.016)
					(thickness 0.1524)
				)
			)
		)
		(duplicate_pad_numbers_are_jumpers no)
		(fp_line
			(start -0.508 -0.9398)
			(end -0.508 0.9398)
			(stroke
				(width 0.1524)
				(type default)
			)
			(layer "F.SilkS")
		)
		(fp_line
			(start 0.508 -0.9398)
			(end -0.508 -0.9398)
			(stroke
				(width 0.1524)
				(type default)
			)
			(layer "F.SilkS")
		)
		(fp_rect
			(start -0.508 0.9398)
			(end 0.508 -0.9398)
			(stroke
				(width 0)
				(type default)
			)
			(fill no)
			(layer "F.CrtYd")
		)
		(fp_rect
			(start -0.508 0.9398)
			(end 0.508 -0.9398)
			(stroke
				(width 0)
				(type default)
			)
			(fill no)
			(layer "F.Fab")
		)
		(pad "1" smd custom
			(at 0 -0.4445 270)
			(size 0.1397 0.1397)
			(layers "F.Cu" "F.Mask" "F.Paste")
			(net "PCIE_COMP_A_TO_SCC_A_RST_0")
			(options
				(clearance outline)
				(anchor circle)
			)
			(primitives
				(gr_poly
					(pts
						(arc
							(start -0.1778 -0.2794)
							(mid -0.249642 -0.249642)
							(end -0.2794 -0.1778)
						)
						(arc
							(start -0.2794 0.1778)
							(mid -0.249642 0.249642)
							(end -0.1778 0.2794)
						)
						(arc
							(start 0.1778 0.2794)
							(mid 0.249642 0.249642)
							(end 0.2794 0.1778)
						)
						(arc
							(start 0.2794 -0.1778)
							(mid 0.249642 -0.249642)
							(end 0.1778 -0.2794)
						)
					)
					(width 0)
					(fill yes)
				)
			)
		)
		(pad "2" smd custom
			(at 0 0.4445 270)
			(size 0.1397 0.1397)
			(layers "F.Cu" "F.Mask" "F.Paste")
			(net "GND")
			(options
				(clearance outline)
				(anchor circle)
			)
			(primitives
				(gr_poly
					(pts
						(arc
							(start -0.1778 -0.2794)
							(mid -0.249642 -0.249642)
							(end -0.2794 -0.1778)
						)
						(arc
							(start -0.2794 0.1778)
							(mid -0.249642 0.249642)
							(end -0.1778 0.2794)
						)
						(arc
							(start 0.1778 0.2794)
							(mid 0.249642 0.249642)
							(end 0.2794 0.1778)
						)
						(arc
							(start 0.2794 -0.1778)
							(mid 0.249642 -0.249642)
							(end 0.1778 -0.2794)
						)
					)
					(width 0)
					(fill yes)
				)
			)
		)
	)
	(footprint ""
		(layer "F.Cu")
		(at 433.359052 -286.809942 -90)
		(property "Reference" "R352"
			(at 0 0 270)
			(layer "F.SilkS")
			(hide yes)
			(effects
				(font
					(size 1.27 1.27)
				)
			)
		)
		(property "Value" "300KR2F-GP"
			(at 0.064008 -3.993896 270)
			(unlocked yes)
			(layer "F.Fab")
			(hide yes)
			(effects
				(font
					(size 1.016 1.016)
					(thickness 0.1524)
				)
			)
		)
		(property "Device Type" "R402H16"
			(at 0.064008 -5.517896 270)
			(unlocked yes)
			(layer "F.Fab")
			(hide yes)
			(effects
				(font
					(size 1.016 1.016)
					(thickness 0.1524)
				)
			)
		)
		(duplicate_pad_numbers_are_jumpers no)
		(fp_line
			(start -0.508 -0.9398)
			(end -0.508 0.9398)
			(stroke
				(width 0.1524)
				(type default)
			)
			(layer "F.SilkS")
		)
		(fp_line
			(start 0.508 -0.9398)
			(end -0.508 -0.9398)
			(stroke
				(width 0.1524)
				(type default)
			)
			(layer "F.SilkS")
		)
		(fp_rect
			(start -0.508 0.9398)
			(end 0.508 -0.9398)
			(stroke
				(width 0)
				(type default)
			)
			(fill no)
			(layer "F.CrtYd")
		)
		(fp_rect
			(start -0.508 0.9398)
			(end 0.508 -0.9398)
			(stroke
				(width 0)
				(type default)
			)
			(fill no)
			(layer "F.Fab")
		)
		(pad "1" smd custom
			(at 0 -0.4445 270)
			(size 0.1397 0.1397)
			(layers "F.Cu" "F.Mask" "F.Paste")
			(net "SW_HDD_N9")
			(options
				(clearance outline)
				(anchor circle)
			)
			(primitives
				(gr_poly
					(pts
						(arc
							(start -0.1778 -0.2794)
							(mid -0.249642 -0.249642)
							(end -0.2794 -0.1778)
						)
						(arc
							(start -0.2794 0.1778)
							(mid -0.249642 0.249642)
							(end -0.1778 0.2794)
						)
						(arc
							(start 0.1778 0.2794)
							(mid 0.249642 0.249642)
							(end 0.2794 0.1778)
						)
						(arc
							(start 0.2794 -0.1778)
							(mid 0.249642 -0.249642)
							(end 0.1778 -0.2794)
						)
					)
					(width 0)
					(fill yes)
				)
			)
		)
		(pad "2" smd custom
			(at 0 0.4445 270)
			(size 0.1397 0.1397)
			(layers "F.Cu" "F.Mask" "F.Paste")
			(net "P12V_A")
			(options
				(clearance outline)
				(anchor circle)
			)
			(primitives
				(gr_poly
					(pts
						(arc
							(start -0.1778 -0.2794)
							(mid -0.249642 -0.249642)
							(end -0.2794 -0.1778)
						)
						(arc
							(start -0.2794 0.1778)
							(mid -0.249642 0.249642)
							(end -0.1778 0.2794)
						)
						(arc
							(start 0.1778 0.2794)
							(mid 0.249642 0.249642)
							(end 0.2794 0.1778)
						)
						(arc
							(start 0.2794 -0.1778)
							(mid 0.249642 -0.249642)
							(end 0.1778 -0.2794)
						)
					)
					(width 0)
					(fill yes)
				)
			)
		)
	)
	(footprint ""
		(layer "F.Cu")
		(at 234.963462 -261.71779 180)
		(property "Reference" "R37"
			(at 0 0 180)
			(layer "F.SilkS")
			(hide yes)
			(effects
				(font
					(size 1.27 1.27)
				)
			)
		)
		(property "Value" "4K7R2F-GP"
			(at 0.064008 -3.993896 180)
			(unlocked yes)
			(layer "F.Fab")
			(hide yes)
			(effects
				(font
					(size 1.016 1.016)
					(thickness 0.1524)
				)
			)
		)
		(property "Device Type" "R402H16"
			(at 0.064008 -5.517896 180)
			(unlocked yes)
			(layer "F.Fab")
			(hide yes)
			(effects
				(font
					(size 1.016 1.016)
					(thickness 0.1524)
				)
			)
		)
		(duplicate_pad_numbers_are_jumpers no)
		(fp_line
			(start 0.508 -0.9398)
			(end -0.508 -0.9398)
			(stroke
				(width 0.1524)
				(type default)
			)
			(layer "F.SilkS")
		)
		(fp_line
			(start -0.508 -0.9398)
			(end -0.508 0.9398)
			(stroke
				(width 0.1524)
				(type default)
			)
			(layer "F.SilkS")
		)
		(fp_rect
			(start -0.508 0.9398)
			(end 0.508 -0.9398)
			(stroke
				(width 0)
				(type default)
			)
			(fill no)
			(layer "F.CrtYd")
		)
		(fp_rect
			(start -0.508 0.9398)
			(end 0.508 -0.9398)
			(stroke
				(width 0)
				(type default)
			)
			(fill no)
			(layer "F.Fab")
		)
		(pad "1" smd custom
			(at 0 -0.4445 180)
			(size 0.1397 0.1397)
			(layers "F.Cu" "F.Mask" "F.Paste")
			(net "IO_EXP4_A1")
			(options
				(clearance outline)
				(anchor circle)
			)
			(primitives
				(gr_poly
					(pts
						(arc
							(start -0.1778 -0.2794)
							(mid -0.249642 -0.249642)
							(end -0.2794 -0.1778)
						)
						(arc
							(start -0.2794 0.1778)
							(mid -0.249642 0.249642)
							(end -0.1778 0.2794)
						)
						(arc
							(start 0.1778 0.2794)
							(mid 0.249642 0.249642)
							(end 0.2794 0.1778)
						)
						(arc
							(start 0.2794 -0.1778)
							(mid 0.249642 -0.249642)
							(end 0.1778 -0.2794)
						)
					)
					(width 0)
					(fill yes)
				)
			)
		)
		(pad "2" smd custom
			(at 0 0.4445 180)
			(size 0.1397 0.1397)
			(layers "F.Cu" "F.Mask" "F.Paste")
			(net "GND")
			(options
				(clearance outline)
				(anchor circle)
			)
			(primitives
				(gr_poly
					(pts
						(arc
							(start -0.1778 -0.2794)
							(mid -0.249642 -0.249642)
							(end -0.2794 -0.1778)
						)
						(arc
							(start -0.2794 0.1778)
							(mid -0.249642 0.249642)
							(end -0.1778 0.2794)
						)
						(arc
							(start 0.1778 0.2794)
							(mid 0.249642 0.249642)
							(end 0.2794 0.1778)
						)
						(arc
							(start 0.2794 -0.1778)
							(mid 0.249642 -0.249642)
							(end 0.1778 -0.2794)
						)
					)
					(width 0)
					(fill yes)
				)
			)
		)
	)
	(footprint ""
		(layer "F.Cu")
		(at 143.049498 -52.034694 90)
		(property "Reference" "R781"
			(at 0 0 90)
			(layer "F.SilkS")
			(hide yes)
			(effects
				(font
					(size 1.27 1.27)
				)
			)
		)
		(property "Value" "4K7R2J-2-GP"
			(at 0.064008 -3.993896 90)
			(unlocked yes)
			(layer "F.Fab")
			(hide yes)
			(effects
				(font
					(size 1.016 1.016)
					(thickness 0.1524)
				)
			)
		)
		(property "Device Type" "R402H16"
			(at 0.064008 -5.517896 90)
			(unlocked yes)
			(layer "F.Fab")
			(hide yes)
			(effects
				(font
					(size 1.016 1.016)
					(thickness 0.1524)
				)
			)
		)
		(duplicate_pad_numbers_are_jumpers no)
		(fp_line
			(start 0.508 -0.9398)
			(end -0.508 -0.9398)
			(stroke
				(width 0.1524)
				(type default)
			)
			(layer "F.SilkS")
		)
		(fp_line
			(start -0.508 -0.9398)
			(end -0.508 0.9398)
			(stroke
				(width 0.1524)
				(type default)
			)
			(layer "F.SilkS")
		)
		(fp_rect
			(start -0.508 0.9398)
			(end 0.508 -0.9398)
			(stroke
				(width 0)
				(type default)
			)
			(fill no)
			(layer "F.CrtYd")
		)
		(fp_rect
			(start -0.508 0.9398)
			(end 0.508 -0.9398)
			(stroke
				(width 0)
				(type default)
			)
			(fill no)
			(layer "F.Fab")
		)
		(pad "1" smd custom
			(at 0 -0.4445 90)
			(size 0.1397 0.1397)
			(layers "F.Cu" "F.Mask" "F.Paste")
			(net "P12V_A")
			(options
				(clearance outline)
				(anchor circle)
			)
			(primitives
				(gr_poly
					(pts
						(arc
							(start -0.1778 -0.2794)
							(mid -0.249642 -0.249642)
							(end -0.2794 -0.1778)
						)
						(arc
							(start -0.2794 0.1778)
							(mid -0.249642 0.249642)
							(end -0.1778 0.2794)
						)
						(arc
							(start 0.1778 0.2794)
							(mid 0.249642 0.249642)
							(end 0.2794 0.1778)
						)
						(arc
							(start 0.2794 -0.1778)
							(mid 0.249642 -0.249642)
							(end 0.1778 -0.2794)
						)
					)
					(width 0)
					(fill yes)
				)
			)
		)
		(pad "2" smd custom
			(at 0 0.4445 90)
			(size 0.1397 0.1397)
			(layers "F.Cu" "F.Mask" "F.Paste")
			(net "SW_HDD_P28")
			(options
				(clearance outline)
				(anchor circle)
			)
			(primitives
				(gr_poly
					(pts
						(arc
							(start -0.1778 -0.2794)
							(mid -0.249642 -0.249642)
							(end -0.2794 -0.1778)
						)
						(arc
							(start -0.2794 0.1778)
							(mid -0.249642 0.249642)
							(end -0.1778 0.2794)
						)
						(arc
							(start 0.1778 0.2794)
							(mid 0.249642 0.249642)
							(end 0.2794 0.1778)
						)
						(arc
							(start 0.2794 -0.1778)
							(mid 0.249642 -0.249642)
							(end 0.1778 -0.2794)
						)
					)
					(width 0)
					(fill yes)
				)
			)
		)
	)
	(footprint ""
		(layer "F.Cu")
		(at 95.608902 -162.749992 -90)
		(property "Reference" "VIA50"
			(at 0 0 270)
			(layer "F.SilkS")
			(hide yes)
			(effects
				(font
					(size 1.27 1.27)
				)
			)
		)
		(property "Value" "100OHM-8L-1D6MM-L18L16-GP"
			(at -3.7211 -4.5085 270)
			(unlocked yes)
			(layer "F.Fab")
			(hide yes)
			(effects
				(font
					(size 1.016 1.016)
					(thickness 0.1524)
				)
			)
		)
		(property "Device Type" "VIA-PCIE-4P-394076"
			(at -3.7211 -6.0325 270)
			(unlocked yes)
			(layer "F.Fab")
			(hide yes)
			(effects
				(font
					(size 1.016 1.016)
					(thickness 0.1524)
				)
			)
		)
		(duplicate_pad_numbers_are_jumpers no)
		(fp_rect
			(start -1.9685 0.381)
			(end 1.9685 -0.381)
			(stroke
				(width 0)
				(type default)
			)
			(fill no)
			(layer "F.CrtYd")
		)
		(fp_rect
			(start -1.9685 0.381)
			(end 1.9685 -0.381)
			(stroke
				(width 0)
				(type default)
			)
			(fill no)
			(layer "F.Fab")
		)
		(pad "1" thru_hole circle
			(at -1.5875 0 270)
			(size 0.508 0.508)
			(drill 0.254)
			(layers "*.Cu" "*.Mask")
			(remove_unused_layers no)
			(net "GND")
			(clearance 0.127)
			(thermal_gap 0.127)
		)
		(pad "2" thru_hole circle
			(at -0.5715 0 270)
			(size 0.508 0.508)
			(drill 0.254)
			(layers "*.Cu" "*.Mask")
			(remove_unused_layers no)
			(net "PHY_DRV_A_TO_SCC_A_14_DP")
			(clearance 0.127)
			(thermal_gap 0.127)
		)
		(pad "3" thru_hole circle
			(at 0.5715 0 270)
			(size 0.508 0.508)
			(drill 0.254)
			(layers "*.Cu" "*.Mask")
			(remove_unused_layers no)
			(net "PHY_DRV_A_TO_SCC_A_14_DN")
			(clearance 0.127)
			(thermal_gap 0.127)
		)
		(pad "4" thru_hole circle
			(at 1.5875 0 270)
			(size 0.508 0.508)
			(drill 0.254)
			(layers "*.Cu" "*.Mask")
			(remove_unused_layers no)
			(net "GND")
			(clearance 0.127)
			(thermal_gap 0.127)
		)
	)
	(footprint ""
		(layer "F.Cu")
		(at 426.755052 -45.252894 -90)
		(property "Reference" "Q199"
			(at 0 0 270)
			(layer "F.SilkS")
			(hide yes)
			(effects
				(font
					(size 1.27 1.27)
				)
			)
		)
		(property "Value" "2N7002KDW-GP"
			(at -2.3622 -8.2042 270)
			(unlocked yes)
			(layer "F.Fab")
			(hide yes)
			(effects
				(font
					(size 1.016 1.016)
					(thickness 0.1524)
				)
			)
		)
		(property "Device Type" "SOT-363H44"
			(at -2.3622 -10.1092 270)
			(unlocked yes)
			(layer "F.Fab")
			(hide yes)
			(effects
				(font
					(size 1.016 1.016)
					(thickness 0.1524)
				)
			)
		)
		(duplicate_pad_numbers_are_jumpers no)
		(fp_line
			(start -1.4478 1.7018)
			(end 1.4478 1.7018)
			(stroke
				(width 0.1524)
				(type default)
			)
			(layer "F.SilkS")
		)
		(fp_line
			(start 1.4478 1.7018)
			(end 1.4478 -1.7018)
			(stroke
				(width 0.1524)
				(type default)
			)
			(layer "F.SilkS")
		)
		(fp_line
			(start -1.27 1.524)
			(end -1.27 0.6604)
			(stroke
				(width 0.4826)
				(type default)
			)
			(layer "F.SilkS")
		)
		(fp_line
			(start -1.4478 -1.7018)
			(end -1.4478 1.7018)
			(stroke
				(width 0.1524)
				(type default)
			)
			(layer "F.SilkS")
		)
		(fp_line
			(start 1.4478 -1.7018)
			(end -1.4478 -1.7018)
			(stroke
				(width 0.1524)
				(type default)
			)
			(layer "F.SilkS")
		)
		(fp_poly
			(pts
				(xy -1.524 -1.778) (xy 1.524 -1.778) (xy 1.524 1.778) (xy -1.524 1.778)
			)
			(stroke
				(width 0)
				(type default)
			)
			(fill no)
			(layer "F.CrtYd")
		)
		(fp_poly
			(pts
				(xy -1.524 -1.778) (xy 1.524 -1.778) (xy 1.524 1.778) (xy -1.524 1.778)
			)
			(stroke
				(width 0)
				(type default)
			)
			(fill no)
			(layer "F.Fab")
		)
		(pad "1" smd rect
			(at -0.65024 0.9398 270)
			(size 0.4064 1.016)
			(layers "F.Cu" "F.Mask" "F.Paste")
			(net "GND")
		)
		(pad "2" smd rect
			(at 0 0.9398 270)
			(size 0.4064 1.016)
			(layers "F.Cu" "F.Mask" "F.Paste")
			(net "SW_PWR_R_HDD33")
		)
		(pad "3" smd rect
			(at 0.65024 0.9398 270)
			(size 0.4064 1.016)
			(layers "F.Cu" "F.Mask" "F.Paste")
			(net "SW_HDD_P33")
		)
		(pad "4" smd rect
			(at 0.65024 -0.9398 270)
			(size 0.4064 1.016)
			(layers "F.Cu" "F.Mask" "F.Paste")
			(net "GND")
		)
		(pad "5" smd rect
			(at 0 -0.9398 270)
			(size 0.4064 1.016)
			(layers "F.Cu" "F.Mask" "F.Paste")
			(net "SW_HDD_G33")
		)
		(pad "6" smd rect
			(at -0.65024 -0.9398 270)
			(size 0.4064 1.016)
			(layers "F.Cu" "F.Mask" "F.Paste")
			(net "SW_HDD_R33")
		)
	)
	(footprint ""
		(layer "F.Cu")
		(at 443.398402 -257.89255 -90)
		(property "Reference" "R1255"
			(at 0 0 270)
			(layer "F.SilkS")
			(hide yes)
			(effects
				(font
					(size 1.27 1.27)
				)
			)
		)
		(property "Value" "143KR2F-L-1-GP"
			(at 0.064008 -3.993896 270)
			(unlocked yes)
			(layer "F.Fab")
			(hide yes)
			(effects
				(font
					(size 1.016 1.016)
					(thickness 0.1524)
				)
			)
		)
		(property "Device Type" "R402H16"
			(at 0.064008 -5.517896 270)
			(unlocked yes)
			(layer "F.Fab")
			(hide yes)
			(effects
				(font
					(size 1.016 1.016)
					(thickness 0.1524)
				)
			)
		)
		(duplicate_pad_numbers_are_jumpers no)
		(fp_line
			(start -0.508 -0.9398)
			(end -0.508 0.9398)
			(stroke
				(width 0.1524)
				(type default)
			)
			(layer "F.SilkS")
		)
		(fp_line
			(start 0.508 -0.9398)
			(end -0.508 -0.9398)
			(stroke
				(width 0.1524)
				(type default)
			)
			(layer "F.SilkS")
		)
		(fp_rect
			(start -0.508 0.9398)
			(end 0.508 -0.9398)
			(stroke
				(width 0)
				(type default)
			)
			(fill no)
			(layer "F.CrtYd")
		)
		(fp_rect
			(start -0.508 0.9398)
			(end 0.508 -0.9398)
			(stroke
				(width 0)
				(type default)
			)
			(fill no)
			(layer "F.Fab")
		)
		(pad "1" smd custom
			(at 0 -0.4445 270)
			(size 0.1397 0.1397)
			(layers "F.Cu" "F.Mask" "F.Paste")
			(net "AGND_P5V_C")
			(options
				(clearance outline)
				(anchor circle)
			)
			(primitives
				(gr_poly
					(pts
						(arc
							(start -0.1778 -0.2794)
							(mid -0.249642 -0.249642)
							(end -0.2794 -0.1778)
						)
						(arc
							(start -0.2794 0.1778)
							(mid -0.249642 0.249642)
							(end -0.1778 0.2794)
						)
						(arc
							(start 0.1778 0.2794)
							(mid 0.249642 0.249642)
							(end 0.2794 0.1778)
						)
						(arc
							(start 0.2794 -0.1778)
							(mid 0.249642 -0.249642)
							(end 0.1778 -0.2794)
						)
					)
					(width 0)
					(fill yes)
				)
			)
		)
		(pad "2" smd custom
			(at 0 0.4445 270)
			(size 0.1397 0.1397)
			(layers "F.Cu" "F.Mask" "F.Paste")
			(net "P5V_C_TRIP")
			(options
				(clearance outline)
				(anchor circle)
			)
			(primitives
				(gr_poly
					(pts
						(arc
							(start -0.1778 -0.2794)
							(mid -0.249642 -0.249642)
							(end -0.2794 -0.1778)
						)
						(arc
							(start -0.2794 0.1778)
							(mid -0.249642 0.249642)
							(end -0.1778 0.2794)
						)
						(arc
							(start 0.1778 0.2794)
							(mid 0.249642 0.249642)
							(end 0.2794 0.1778)
						)
						(arc
							(start 0.2794 -0.1778)
							(mid 0.249642 -0.249642)
							(end 0.1778 -0.2794)
						)
					)
					(width 0)
					(fill yes)
				)
			)
		)
	)
	(footprint ""
		(layer "F.Cu")
		(at 35.797998 -176.127918 90)
		(property "Reference" "C198"
			(at 0 0 90)
			(layer "F.SilkS")
			(hide yes)
			(effects
				(font
					(size 1.27 1.27)
				)
			)
		)
		(property "Value" "SCD01U50V2KX-1GP"
			(at 1.1811 -2.7051 90)
			(unlocked yes)
			(layer "F.Fab")
			(hide yes)
			(effects
				(font
					(size 1.016 1.016)
					(thickness 0.1524)
				)
			)
		)
		(property "Device Type" "C402H22"
			(at 1.1811 -4.2291 90)
			(unlocked yes)
			(layer "F.Fab")
			(hide yes)
			(effects
				(font
					(size 1.016 1.016)
					(thickness 0.1524)
				)
			)
		)
		(duplicate_pad_numbers_are_jumpers no)
		(fp_rect
			(start -0.4318 0.9525)
			(end 0.4318 -0.9525)
			(stroke
				(width 0)
				(type default)
			)
			(fill no)
			(layer "F.CrtYd")
		)
		(fp_rect
			(start -0.4318 0.9525)
			(end 0.4318 -0.9525)
			(stroke
				(width 0)
				(type default)
			)
			(fill no)
			(layer "F.Fab")
		)
		(pad "1" smd custom
			(at 0 -0.4445 90)
			(size 0.1524 0.1524)
			(layers "F.Cu" "F.Mask" "F.Paste")
			(net "HDD_PRSNT_12")
			(options
				(clearance outline)
				(anchor circle)
			)
			(primitives
				(gr_poly
					(pts
						(arc
							(start 0.3048 -0.2032)
							(mid 0.275042 -0.275042)
							(end 0.2032 -0.3048)
						)
						(arc
							(start -0.2032 -0.3048)
							(mid -0.275042 -0.275042)
							(end -0.3048 -0.2032)
						)
						(arc
							(start -0.3048 0.2032)
							(mid -0.275042 0.275042)
							(end -0.2032 0.3048)
						)
						(arc
							(start 0.2032 0.3048)
							(mid 0.275042 0.275042)
							(end 0.3048 0.2032)
						)
					)
					(width 0)
					(fill yes)
				)
			)
		)
		(pad "2" smd custom
			(at 0 0.4445 90)
			(size 0.1524 0.1524)
			(layers "F.Cu" "F.Mask" "F.Paste")
			(net "GND")
			(options
				(clearance outline)
				(anchor circle)
			)
			(primitives
				(gr_poly
					(pts
						(arc
							(start 0.3048 -0.2032)
							(mid 0.275042 -0.275042)
							(end 0.2032 -0.3048)
						)
						(arc
							(start -0.2032 -0.3048)
							(mid -0.275042 -0.275042)
							(end -0.3048 -0.2032)
						)
						(arc
							(start -0.3048 0.2032)
							(mid -0.275042 0.275042)
							(end -0.2032 0.3048)
						)
						(arc
							(start 0.2032 0.3048)
							(mid 0.275042 0.275042)
							(end 0.3048 0.2032)
						)
					)
					(width 0)
					(fill yes)
				)
			)
		)
	)
	(footprint ""
		(layer "F.Cu")
		(at 177.711862 -160.272984 90)
		(property "Reference" "R538"
			(at 0 0 90)
			(layer "F.SilkS")
			(hide yes)
			(effects
				(font
					(size 1.27 1.27)
				)
			)
		)
		(property "Value" "0R2J-2-GP"
			(at 0.064008 -3.993896 90)
			(unlocked yes)
			(layer "F.Fab")
			(hide yes)
			(effects
				(font
					(size 1.016 1.016)
					(thickness 0.1524)
				)
			)
		)
		(property "Device Type" "R402H16"
			(at 0.064008 -5.517896 90)
			(unlocked yes)
			(layer "F.Fab")
			(hide yes)
			(effects
				(font
					(size 1.016 1.016)
					(thickness 0.1524)
				)
			)
		)
		(duplicate_pad_numbers_are_jumpers no)
		(fp_line
			(start 0.508 -0.9398)
			(end -0.508 -0.9398)
			(stroke
				(width 0.1524)
				(type default)
			)
			(layer "F.SilkS")
		)
		(fp_line
			(start -0.508 -0.9398)
			(end -0.508 0.9398)
			(stroke
				(width 0.1524)
				(type default)
			)
			(layer "F.SilkS")
		)
		(fp_rect
			(start -0.508 0.9398)
			(end 0.508 -0.9398)
			(stroke
				(width 0)
				(type default)
			)
			(fill no)
			(layer "F.CrtYd")
		)
		(fp_rect
			(start -0.508 0.9398)
			(end 0.508 -0.9398)
			(stroke
				(width 0)
				(type default)
			)
			(fill no)
			(layer "F.Fab")
		)
		(pad "1" smd custom
			(at 0 -0.4445 90)
			(size 0.1397 0.1397)
			(layers "F.Cu" "F.Mask" "F.Paste")
			(net "SW_HDD_G17")
			(options
				(clearance outline)
				(anchor circle)
			)
			(primitives
				(gr_poly
					(pts
						(arc
							(start -0.1778 -0.2794)
							(mid -0.249642 -0.249642)
							(end -0.2794 -0.1778)
						)
						(arc
							(start -0.2794 0.1778)
							(mid -0.249642 0.249642)
							(end -0.1778 0.2794)
						)
						(arc
							(start 0.1778 0.2794)
							(mid 0.249642 0.249642)
							(end 0.2794 0.1778)
						)
						(arc
							(start 0.2794 -0.1778)
							(mid 0.249642 -0.249642)
							(end 0.1778 -0.2794)
						)
					)
					(width 0)
					(fill yes)
				)
			)
		)
		(pad "2" smd custom
			(at 0 0.4445 90)
			(size 0.1397 0.1397)
			(layers "F.Cu" "F.Mask" "F.Paste")
			(net "SW_HDD_R17")
			(options
				(clearance outline)
				(anchor circle)
			)
			(primitives
				(gr_poly
					(pts
						(arc
							(start -0.1778 -0.2794)
							(mid -0.249642 -0.249642)
							(end -0.2794 -0.1778)
						)
						(arc
							(start -0.2794 0.1778)
							(mid -0.249642 0.249642)
							(end -0.1778 0.2794)
						)
						(arc
							(start 0.1778 0.2794)
							(mid 0.249642 0.249642)
							(end 0.2794 0.1778)
						)
						(arc
							(start 0.2794 -0.1778)
							(mid 0.249642 -0.249642)
							(end 0.1778 -0.2794)
						)
					)
					(width 0)
					(fill yes)
				)
			)
		)
	)
	(footprint ""
		(layer "F.Cu")
		(at 77.942948 -289.857942)
		(property "Reference" "Q14"
			(at 0 0 0)
			(layer "F.SilkS")
			(hide yes)
			(effects
				(font
					(size 1.27 1.27)
				)
			)
		)
		(property "Value" "AO4407AL-GP"
			(at -3.707384 -1.5367 0)
			(unlocked yes)
			(layer "F.Fab")
			(hide yes)
			(effects
				(font
					(size 1.016 1.016)
					(thickness 0.1524)
				)
			)
		)
		(property "Device Type" "SOIC8H69"
			(at -3.707384 -3.0607 0)
			(unlocked yes)
			(layer "F.Fab")
			(hide yes)
			(effects
				(font
					(size 1.016 1.016)
					(thickness 0.1524)
				)
			)
		)
		(duplicate_pad_numbers_are_jumpers no)
		(fp_line
			(start -2.7432 -1.4224)
			(end -2.7432 1.4224)
			(stroke
				(width 0.1524)
				(type default)
			)
			(layer "F.SilkS")
		)
		(fp_line
			(start -2.7432 1.4224)
			(end -2.6416 1.4224)
			(stroke
				(width 0.1524)
				(type default)
			)
			(layer "F.SilkS")
		)
		(fp_line
			(start -2.7432 1.4224)
			(end 2.1336 1.4224)
			(stroke
				(width 0.1524)
				(type default)
			)
			(layer "F.SilkS")
		)
		(fp_line
			(start -2.7178 -0.508)
			(end -2.1844 -0.0508)
			(stroke
				(width 0.1524)
				(type default)
			)
			(layer "F.SilkS")
		)
		(fp_line
			(start -2.6289 3.4417)
			(end -2.6289 1.4732)
			(stroke
				(width 0.381)
				(type default)
			)
			(layer "F.SilkS")
		)
		(fp_line
			(start -2.1844 -0.0508)
			(end -2.7178 0.508)
			(stroke
				(width 0.1524)
				(type default)
			)
			(layer "F.SilkS")
		)
		(fp_line
			(start 2.1336 -1.4224)
			(end -2.7432 -1.4224)
			(stroke
				(width 0.1524)
				(type default)
			)
			(layer "F.SilkS")
		)
		(fp_line
			(start 2.1336 1.4224)
			(end 2.1336 -1.4224)
			(stroke
				(width 0.1524)
				(type default)
			)
			(layer "F.SilkS")
		)
		(fp_poly
			(pts
				(xy -2.2098 -1.4224) (xy -2.2098 1.4224) (xy 2.2098 1.4224) (xy 2.2098 -1.4224)
			)
			(stroke
				(width 0)
				(type default)
			)
			(fill yes)
			(layer "F.SilkS")
		)
		(fp_rect
			(start -2.450084 2.999994)
			(end 2.450084 -2.999994)
			(stroke
				(width 0)
				(type default)
			)
			(fill no)
			(layer "F.CrtYd")
		)
		(fp_poly
			(pts
				(xy -2.8194 3.6322) (xy -2.8194 -3.6322) (xy 2.8194 -3.6322) (xy 2.8194 1.18364) (xy 2.450084 1.18364)
				(xy 2.450084 -2.999994) (xy -2.450084 -2.999994) (xy -2.450084 2.999994) (xy 2.450084 2.999994)
				(xy 2.450084 1.18618) (xy 2.8194 1.18618) (xy 2.8194 3.6322)
			)
			(stroke
				(width 0)
				(type default)
			)
			(fill no)
			(layer "F.CrtYd")
		)
		(fp_rect
			(start -2.8194 3.6322)
			(end 2.8194 -3.6322)
			(stroke
				(width 0)
				(type default)
			)
			(fill no)
			(layer "F.Fab")
		)
		(pad "1" smd rect
			(at -1.905 2.54)
			(size 0.635 1.651)
			(layers "F.Cu" "F.Mask" "F.Paste")
			(net "P12V_A")
		)
		(pad "2" smd rect
			(at -0.635 2.54)
			(size 0.635 1.651)
			(layers "F.Cu" "F.Mask" "F.Paste")
			(net "P12V_A")
		)
		(pad "3" smd rect
			(at 0.635 2.54)
			(size 0.635 1.651)
			(layers "F.Cu" "F.Mask" "F.Paste")
			(net "P12V_A")
		)
		(pad "4" smd rect
			(at 1.905 2.54)
			(size 0.635 1.651)
			(layers "F.Cu" "F.Mask" "F.Paste")
			(net "SW_HDD_N2")
		)
		(pad "5" smd rect
			(at 1.905 -2.54)
			(size 0.635 1.651)
			(layers "F.Cu" "F.Mask" "F.Paste")
			(net "P12V_HDD2")
		)
		(pad "6" smd rect
			(at 0.635 -2.54)
			(size 0.635 1.651)
			(layers "F.Cu" "F.Mask" "F.Paste")
			(net "P12V_HDD2")
		)
		(pad "7" smd rect
			(at -0.635 -2.54)
			(size 0.635 1.651)
			(layers "F.Cu" "F.Mask" "F.Paste")
			(net "P12V_HDD2")
		)
		(pad "8" smd rect
			(at -1.905 -2.54)
			(size 0.635 1.651)
			(layers "F.Cu" "F.Mask" "F.Paste")
			(net "P12V_HDD2")
		)
	)
	(footprint ""
		(layer "F.Cu")
		(at 478.832926 -62.270894)
		(property "Reference" "R934"
			(at 0 0 0)
			(layer "F.SilkS")
			(hide yes)
			(effects
				(font
					(size 1.27 1.27)
				)
			)
		)
		(property "Value" "2R6F-GP"
			(at -0.0508 -4.8514 0)
			(unlocked yes)
			(layer "F.Fab")
			(hide yes)
			(effects
				(font
					(size 1.016 1.016)
					(thickness 0.1524)
				)
			)
		)
		(property "Device Type" "R1206H26"
			(at 0 -6.3754 0)
			(unlocked yes)
			(layer "F.Fab")
			(hide yes)
			(effects
				(font
					(size 1.016 1.016)
					(thickness 0.1524)
				)
			)
		)
		(duplicate_pad_numbers_are_jumpers no)
		(fp_line
			(start -1.016 -2.2352)
			(end 1.016 -2.2352)
			(stroke
				(width 0.1524)
				(type default)
			)
			(layer "F.SilkS")
		)
		(fp_line
			(start -1.016 2.2352)
			(end -1.016 -2.2352)
			(stroke
				(width 0.1524)
				(type default)
			)
			(layer "F.SilkS")
		)
		(fp_line
			(start 1.016 -2.2352)
			(end 1.016 2.2352)
			(stroke
				(width 0.1524)
				(type default)
			)
			(layer "F.SilkS")
		)
		(fp_line
			(start 1.016 2.2352)
			(end -1.016 2.2352)
			(stroke
				(width 0.1524)
				(type default)
			)
			(layer "F.SilkS")
		)
		(fp_rect
			(start -1.0922 2.3114)
			(end 1.0922 -2.3114)
			(stroke
				(width 0)
				(type default)
			)
			(fill no)
			(layer "F.CrtYd")
		)
		(fp_poly
			(pts
				(xy -1.0922 -2.3114) (xy 1.0922 -2.3114) (xy 1.0922 2.3114) (xy -1.0922 2.3114)
			)
			(stroke
				(width 0)
				(type default)
			)
			(fill no)
			(layer "F.Fab")
		)
		(pad "1" smd rect
			(at 0 -1.397)
			(size 1.651 1.27)
			(layers "F.Cu" "F.Mask" "F.Paste")
			(net "P5V_HDD35")
		)
		(pad "2" smd rect
			(at 0 1.397)
			(size 1.651 1.27)
			(layers "F.Cu" "F.Mask" "F.Paste")
			(net "5V_PRE_35")
		)
	)
	(footprint ""
		(layer "F.Cu")
		(at 447.834512 -274.219416 -90)
		(property "Reference" "C168"
			(at 0 0 270)
			(layer "F.SilkS")
			(hide yes)
			(effects
				(font
					(size 1.27 1.27)
				)
			)
		)
		(property "Value" "SCD01U16V1KX-GP"
			(at -2.8321 -1.7399 270)
			(unlocked yes)
			(layer "F.Fab")
			(hide yes)
			(effects
				(font
					(size 1.016 1.016)
					(thickness 0.1524)
				)
			)
		)
		(property "Device Type" "C0201H13"
			(at -2.8321 -3.2639 270)
			(unlocked yes)
			(layer "F.Fab")
			(hide yes)
			(effects
				(font
					(size 1.016 1.016)
					(thickness 0.1524)
				)
			)
		)
		(duplicate_pad_numbers_are_jumpers no)
		(fp_rect
			(start -0.2794 0.6477)
			(end 0.2794 -0.6477)
			(stroke
				(width 0)
				(type default)
			)
			(fill no)
			(layer "F.CrtYd")
		)
		(fp_rect
			(start -0.2794 0.6477)
			(end 0.2794 -0.6477)
			(stroke
				(width 0)
				(type default)
			)
			(fill no)
			(layer "F.Fab")
		)
		(pad "1" smd custom
			(at 0 -0.2794 270)
			(size 0.0762 0.0762)
			(layers "F.Cu" "F.Mask" "F.Paste")
			(net "SAS_HDD_RX_N10")
			(options
				(clearance outline)
				(anchor circle)
			)
			(primitives
				(gr_poly
					(pts
						(arc
							(start 0.1524 -0.127)
							(mid 0.137521 -0.162921)
							(end 0.1016 -0.1778)
						)
						(arc
							(start -0.1016 -0.1778)
							(mid -0.137521 -0.162921)
							(end -0.1524 -0.127)
						)
						(arc
							(start -0.1524 0.127)
							(mid -0.137521 0.162921)
							(end -0.1016 0.1778)
						)
						(arc
							(start 0.1016 0.1778)
							(mid 0.137521 0.162921)
							(end 0.1524 0.127)
						)
					)
					(width 0)
					(fill yes)
				)
			)
		)
		(pad "2" smd custom
			(at 0 0.2794 270)
			(size 0.0762 0.0762)
			(layers "F.Cu" "F.Mask" "F.Paste")
			(net "PHY_SCC_A_TO_DRV_A_10_DN")
			(options
				(clearance outline)
				(anchor circle)
			)
			(primitives
				(gr_poly
					(pts
						(arc
							(start 0.1524 -0.127)
							(mid 0.137521 -0.162921)
							(end 0.1016 -0.1778)
						)
						(arc
							(start -0.1016 -0.1778)
							(mid -0.137521 -0.162921)
							(end -0.1524 -0.127)
						)
						(arc
							(start -0.1524 0.127)
							(mid -0.137521 0.162921)
							(end -0.1016 0.1778)
						)
						(arc
							(start 0.1016 0.1778)
							(mid 0.137521 0.162921)
							(end 0.1524 0.127)
						)
					)
					(width 0)
					(fill yes)
				)
			)
		)
	)
	(footprint ""
		(layer "F.Cu")
		(at 368.354102 -62.016894)
		(property "Reference" "Q188"
			(at 0 0 0)
			(layer "F.SilkS")
			(hide yes)
			(effects
				(font
					(size 1.27 1.27)
				)
			)
		)
		(property "Value" "AO4407AL-GP"
			(at -3.707384 -1.5367 0)
			(unlocked yes)
			(layer "F.Fab")
			(hide yes)
			(effects
				(font
					(size 1.016 1.016)
					(thickness 0.1524)
				)
			)
		)
		(property "Device Type" "SOIC8H69"
			(at -3.707384 -3.0607 0)
			(unlocked yes)
			(layer "F.Fab")
			(hide yes)
			(effects
				(font
					(size 1.016 1.016)
					(thickness 0.1524)
				)
			)
		)
		(duplicate_pad_numbers_are_jumpers no)
		(fp_line
			(start -2.7432 -1.4224)
			(end -2.7432 1.4224)
			(stroke
				(width 0.1524)
				(type default)
			)
			(layer "F.SilkS")
		)
		(fp_line
			(start -2.7432 1.4224)
			(end -2.6416 1.4224)
			(stroke
				(width 0.1524)
				(type default)
			)
			(layer "F.SilkS")
		)
		(fp_line
			(start -2.7432 1.4224)
			(end 2.1336 1.4224)
			(stroke
				(width 0.1524)
				(type default)
			)
			(layer "F.SilkS")
		)
		(fp_line
			(start -2.7178 -0.508)
			(end -2.1844 -0.0508)
			(stroke
				(width 0.1524)
				(type default)
			)
			(layer "F.SilkS")
		)
		(fp_line
			(start -2.6289 3.4417)
			(end -2.6289 1.4732)
			(stroke
				(width 0.381)
				(type default)
			)
			(layer "F.SilkS")
		)
		(fp_line
			(start -2.1844 -0.0508)
			(end -2.7178 0.508)
			(stroke
				(width 0.1524)
				(type default)
			)
			(layer "F.SilkS")
		)
		(fp_line
			(start 2.1336 -1.4224)
			(end -2.7432 -1.4224)
			(stroke
				(width 0.1524)
				(type default)
			)
			(layer "F.SilkS")
		)
		(fp_line
			(start 2.1336 1.4224)
			(end 2.1336 -1.4224)
			(stroke
				(width 0.1524)
				(type default)
			)
			(layer "F.SilkS")
		)
		(fp_poly
			(pts
				(xy -2.2098 -1.4224) (xy -2.2098 1.4224) (xy 2.2098 1.4224) (xy 2.2098 -1.4224)
			)
			(stroke
				(width 0)
				(type default)
			)
			(fill yes)
			(layer "F.SilkS")
		)
		(fp_rect
			(start -2.450084 2.999994)
			(end 2.450084 -2.999994)
			(stroke
				(width 0)
				(type default)
			)
			(fill no)
			(layer "F.CrtYd")
		)
		(fp_poly
			(pts
				(xy -2.8194 3.6322) (xy -2.8194 -3.6322) (xy 2.8194 -3.6322) (xy 2.8194 1.18364) (xy 2.450084 1.18364)
				(xy 2.450084 -2.999994) (xy -2.450084 -2.999994) (xy -2.450084 2.999994) (xy 2.450084 2.999994)
				(xy 2.450084 1.18618) (xy 2.8194 1.18618) (xy 2.8194 3.6322)
			)
			(stroke
				(width 0)
				(type default)
			)
			(fill no)
			(layer "F.CrtYd")
		)
		(fp_rect
			(start -2.8194 3.6322)
			(end 2.8194 -3.6322)
			(stroke
				(width 0)
				(type default)
			)
			(fill no)
			(layer "F.Fab")
		)
		(pad "1" smd rect
			(at -1.905 2.54)
			(size 0.635 1.651)
			(layers "F.Cu" "F.Mask" "F.Paste")
			(net "P12V_A")
		)
		(pad "2" smd rect
			(at -0.635 2.54)
			(size 0.635 1.651)
			(layers "F.Cu" "F.Mask" "F.Paste")
			(net "P12V_A")
		)
		(pad "3" smd rect
			(at 0.635 2.54)
			(size 0.635 1.651)
			(layers "F.Cu" "F.Mask" "F.Paste")
			(net "P12V_A")
		)
		(pad "4" smd rect
			(at 1.905 2.54)
			(size 0.635 1.651)
			(layers "F.Cu" "F.Mask" "F.Paste")
			(net "SW_HDD_N31")
		)
		(pad "5" smd rect
			(at 1.905 -2.54)
			(size 0.635 1.651)
			(layers "F.Cu" "F.Mask" "F.Paste")
			(net "P12V_HDD31")
		)
		(pad "6" smd rect
			(at 0.635 -2.54)
			(size 0.635 1.651)
			(layers "F.Cu" "F.Mask" "F.Paste")
			(net "P12V_HDD31")
		)
		(pad "7" smd rect
			(at -0.635 -2.54)
			(size 0.635 1.651)
			(layers "F.Cu" "F.Mask" "F.Paste")
			(net "P12V_HDD31")
		)
		(pad "8" smd rect
			(at -1.905 -2.54)
			(size 0.635 1.651)
			(layers "F.Cu" "F.Mask" "F.Paste")
			(net "P12V_HDD31")
		)
	)
	(footprint ""
		(layer "F.Cu")
		(at 416.284664 -159.219392 -90)
		(property "Reference" "C311"
			(at 0 0 270)
			(layer "F.SilkS")
			(hide yes)
			(effects
				(font
					(size 1.27 1.27)
				)
			)
		)
		(property "Value" "SCD01U16V1KX-GP"
			(at -2.8321 -1.7399 270)
			(unlocked yes)
			(layer "F.Fab")
			(hide yes)
			(effects
				(font
					(size 1.016 1.016)
					(thickness 0.1524)
				)
			)
		)
		(property "Device Type" "C0201H13"
			(at -2.8321 -3.2639 270)
			(unlocked yes)
			(layer "F.Fab")
			(hide yes)
			(effects
				(font
					(size 1.016 1.016)
					(thickness 0.1524)
				)
			)
		)
		(duplicate_pad_numbers_are_jumpers no)
		(fp_rect
			(start -0.2794 0.6477)
			(end 0.2794 -0.6477)
			(stroke
				(width 0)
				(type default)
			)
			(fill no)
			(layer "F.CrtYd")
		)
		(fp_rect
			(start -0.2794 0.6477)
			(end 0.2794 -0.6477)
			(stroke
				(width 0)
				(type default)
			)
			(fill no)
			(layer "F.Fab")
		)
		(pad "1" smd custom
			(at 0 -0.2794 270)
			(size 0.0762 0.0762)
			(layers "F.Cu" "F.Mask" "F.Paste")
			(net "SAS_HDD_RX_N21")
			(options
				(clearance outline)
				(anchor circle)
			)
			(primitives
				(gr_poly
					(pts
						(arc
							(start 0.1524 -0.127)
							(mid 0.137521 -0.162921)
							(end 0.1016 -0.1778)
						)
						(arc
							(start -0.1016 -0.1778)
							(mid -0.137521 -0.162921)
							(end -0.1524 -0.127)
						)
						(arc
							(start -0.1524 0.127)
							(mid -0.137521 0.162921)
							(end -0.1016 0.1778)
						)
						(arc
							(start 0.1016 0.1778)
							(mid 0.137521 0.162921)
							(end 0.1524 0.127)
						)
					)
					(width 0)
					(fill yes)
				)
			)
		)
		(pad "2" smd custom
			(at 0 0.2794 270)
			(size 0.0762 0.0762)
			(layers "F.Cu" "F.Mask" "F.Paste")
			(net "PHY_SCC_A_TO_DRV_A_21_DN")
			(options
				(clearance outline)
				(anchor circle)
			)
			(primitives
				(gr_poly
					(pts
						(arc
							(start 0.1524 -0.127)
							(mid 0.137521 -0.162921)
							(end 0.1016 -0.1778)
						)
						(arc
							(start -0.1016 -0.1778)
							(mid -0.137521 -0.162921)
							(end -0.1524 -0.127)
						)
						(arc
							(start -0.1524 0.127)
							(mid -0.137521 0.162921)
							(end -0.1016 0.1778)
						)
						(arc
							(start 0.1016 0.1778)
							(mid 0.137521 0.162921)
							(end 0.1524 0.127)
						)
					)
					(width 0)
					(fill yes)
				)
			)
		)
	)
	(footprint ""
		(layer "F.Cu")
		(at 368.481102 -275.735542 180)
		(property "Reference" "R305"
			(at 0 0 180)
			(layer "F.SilkS")
			(hide yes)
			(effects
				(font
					(size 1.27 1.27)
				)
			)
		)
		(property "Value" "4K7R2J-2-GP"
			(at 0.064008 -3.993896 180)
			(unlocked yes)
			(layer "F.Fab")
			(hide yes)
			(effects
				(font
					(size 1.016 1.016)
					(thickness 0.1524)
				)
			)
		)
		(property "Device Type" "R402H16"
			(at 0.064008 -5.517896 180)
			(unlocked yes)
			(layer "F.Fab")
			(hide yes)
			(effects
				(font
					(size 1.016 1.016)
					(thickness 0.1524)
				)
			)
		)
		(duplicate_pad_numbers_are_jumpers no)
		(fp_line
			(start 0.508 -0.9398)
			(end -0.508 -0.9398)
			(stroke
				(width 0.1524)
				(type default)
			)
			(layer "F.SilkS")
		)
		(fp_line
			(start -0.508 -0.9398)
			(end -0.508 0.9398)
			(stroke
				(width 0.1524)
				(type default)
			)
			(layer "F.SilkS")
		)
		(fp_rect
			(start -0.508 0.9398)
			(end 0.508 -0.9398)
			(stroke
				(width 0)
				(type default)
			)
			(fill no)
			(layer "F.CrtYd")
		)
		(fp_rect
			(start -0.508 0.9398)
			(end 0.508 -0.9398)
			(stroke
				(width 0)
				(type default)
			)
			(fill no)
			(layer "F.Fab")
		)
		(pad "1" smd custom
			(at 0 -0.4445 180)
			(size 0.1397 0.1397)
			(layers "F.Cu" "F.Mask" "F.Paste")
			(net "P12V_A")
			(options
				(clearance outline)
				(anchor circle)
			)
			(primitives
				(gr_poly
					(pts
						(arc
							(start -0.1778 -0.2794)
							(mid -0.249642 -0.249642)
							(end -0.2794 -0.1778)
						)
						(arc
							(start -0.2794 0.1778)
							(mid -0.249642 0.249642)
							(end -0.1778 0.2794)
						)
						(arc
							(start 0.1778 0.2794)
							(mid 0.249642 0.249642)
							(end 0.2794 0.1778)
						)
						(arc
							(start 0.2794 -0.1778)
							(mid 0.249642 -0.249642)
							(end 0.1778 -0.2794)
						)
					)
					(width 0)
					(fill yes)
				)
			)
		)
		(pad "2" smd custom
			(at 0 0.4445 180)
			(size 0.1397 0.1397)
			(layers "F.Cu" "F.Mask" "F.Paste")
			(net "SW_HDD_R7")
			(options
				(clearance outline)
				(anchor circle)
			)
			(primitives
				(gr_poly
					(pts
						(arc
							(start -0.1778 -0.2794)
							(mid -0.249642 -0.249642)
							(end -0.2794 -0.1778)
						)
						(arc
							(start -0.2794 0.1778)
							(mid -0.249642 0.249642)
							(end -0.1778 0.2794)
						)
						(arc
							(start 0.1778 0.2794)
							(mid 0.249642 0.249642)
							(end 0.2794 0.1778)
						)
						(arc
							(start 0.2794 -0.1778)
							(mid 0.249642 -0.249642)
							(end 0.1778 -0.2794)
						)
					)
					(width 0)
					(fill yes)
				)
			)
		)
	)
	(footprint ""
		(layer "F.Cu")
		(at 263.1186 -284.4292)
		(property "Reference" "R107"
			(at 0 0 0)
			(layer "F.SilkS")
			(hide yes)
			(effects
				(font
					(size 1.27 1.27)
				)
			)
		)
		(property "Value" "4K7R2F-GP"
			(at 0.064008 -3.993896 0)
			(unlocked yes)
			(layer "F.Fab")
			(hide yes)
			(effects
				(font
					(size 1.016 1.016)
					(thickness 0.1524)
				)
			)
		)
		(property "Device Type" "R402H16"
			(at 0.064008 -5.517896 0)
			(unlocked yes)
			(layer "F.Fab")
			(hide yes)
			(effects
				(font
					(size 1.016 1.016)
					(thickness 0.1524)
				)
			)
		)
		(duplicate_pad_numbers_are_jumpers no)
		(fp_line
			(start -0.508 -0.9398)
			(end -0.508 0.9398)
			(stroke
				(width 0.1524)
				(type default)
			)
			(layer "F.SilkS")
		)
		(fp_line
			(start 0.508 -0.9398)
			(end -0.508 -0.9398)
			(stroke
				(width 0.1524)
				(type default)
			)
			(layer "F.SilkS")
		)
		(fp_rect
			(start -0.508 0.9398)
			(end 0.508 -0.9398)
			(stroke
				(width 0)
				(type default)
			)
			(fill no)
			(layer "F.CrtYd")
		)
		(fp_rect
			(start -0.508 0.9398)
			(end 0.508 -0.9398)
			(stroke
				(width 0)
				(type default)
			)
			(fill no)
			(layer "F.Fab")
		)
		(pad "1" smd custom
			(at 0 -0.4445)
			(size 0.1397 0.1397)
			(layers "F.Cu" "F.Mask" "F.Paste")
			(net "P3V3_STBY_A")
			(options
				(clearance outline)
				(anchor circle)
			)
			(primitives
				(gr_poly
					(pts
						(arc
							(start -0.1778 -0.2794)
							(mid -0.249642 -0.249642)
							(end -0.2794 -0.1778)
						)
						(arc
							(start -0.2794 0.1778)
							(mid -0.249642 0.249642)
							(end -0.1778 0.2794)
						)
						(arc
							(start 0.1778 0.2794)
							(mid 0.249642 0.249642)
							(end 0.2794 0.1778)
						)
						(arc
							(start 0.2794 -0.1778)
							(mid 0.249642 -0.249642)
							(end 0.1778 -0.2794)
						)
					)
					(width 0)
					(fill yes)
				)
			)
		)
		(pad "2" smd custom
			(at 0 0.4445)
			(size 0.1397 0.1397)
			(layers "F.Cu" "F.Mask" "F.Paste")
			(net "IO_EXP0_HDD_FAULT_A0")
			(options
				(clearance outline)
				(anchor circle)
			)
			(primitives
				(gr_poly
					(pts
						(arc
							(start -0.1778 -0.2794)
							(mid -0.249642 -0.249642)
							(end -0.2794 -0.1778)
						)
						(arc
							(start -0.2794 0.1778)
							(mid -0.249642 0.249642)
							(end -0.1778 0.2794)
						)
						(arc
							(start 0.1778 0.2794)
							(mid 0.249642 0.249642)
							(end 0.2794 0.1778)
						)
						(arc
							(start 0.2794 -0.1778)
							(mid 0.249642 -0.249642)
							(end 0.1778 -0.2794)
						)
					)
					(width 0)
					(fill yes)
				)
			)
		)
	)
	(footprint ""
		(layer "F.Cu")
		(at 401.80895 -57.851294 90)
		(property "Reference" "C465"
			(at 0 0 90)
			(layer "F.SilkS")
			(hide yes)
			(effects
				(font
					(size 1.27 1.27)
				)
			)
		)
		(property "Value" "SCD033U25V2KX-GP"
			(at 1.1811 -2.7051 90)
			(unlocked yes)
			(layer "F.Fab")
			(hide yes)
			(effects
				(font
					(size 1.016 1.016)
					(thickness 0.1524)
				)
			)
		)
		(property "Device Type" "C402H22"
			(at 1.1811 -4.2291 90)
			(unlocked yes)
			(layer "F.Fab")
			(hide yes)
			(effects
				(font
					(size 1.016 1.016)
					(thickness 0.1524)
				)
			)
		)
		(duplicate_pad_numbers_are_jumpers no)
		(fp_rect
			(start -0.4318 0.9525)
			(end 0.4318 -0.9525)
			(stroke
				(width 0)
				(type default)
			)
			(fill no)
			(layer "F.CrtYd")
		)
		(fp_rect
			(start -0.4318 0.9525)
			(end 0.4318 -0.9525)
			(stroke
				(width 0)
				(type default)
			)
			(fill no)
			(layer "F.Fab")
		)
		(pad "1" smd custom
			(at 0 -0.4445 90)
			(size 0.1524 0.1524)
			(layers "F.Cu" "F.Mask" "F.Paste")
			(net "P12V_A")
			(options
				(clearance outline)
				(anchor circle)
			)
			(primitives
				(gr_poly
					(pts
						(arc
							(start 0.3048 -0.2032)
							(mid 0.275042 -0.275042)
							(end 0.2032 -0.3048)
						)
						(arc
							(start -0.2032 -0.3048)
							(mid -0.275042 -0.275042)
							(end -0.3048 -0.2032)
						)
						(arc
							(start -0.3048 0.2032)
							(mid -0.275042 0.275042)
							(end -0.2032 0.3048)
						)
						(arc
							(start 0.2032 0.3048)
							(mid 0.275042 0.275042)
							(end 0.3048 0.2032)
						)
					)
					(width 0)
					(fill yes)
				)
			)
		)
		(pad "2" smd custom
			(at 0 0.4445 90)
			(size 0.1524 0.1524)
			(layers "F.Cu" "F.Mask" "F.Paste")
			(net "SW_HDD_N32")
			(options
				(clearance outline)
				(anchor circle)
			)
			(primitives
				(gr_poly
					(pts
						(arc
							(start 0.3048 -0.2032)
							(mid 0.275042 -0.275042)
							(end 0.2032 -0.3048)
						)
						(arc
							(start -0.2032 -0.3048)
							(mid -0.275042 -0.275042)
							(end -0.3048 -0.2032)
						)
						(arc
							(start -0.3048 0.2032)
							(mid -0.275042 0.275042)
							(end -0.2032 0.3048)
						)
						(arc
							(start 0.2032 0.3048)
							(mid 0.275042 0.275042)
							(end 0.3048 0.2032)
						)
					)
					(width 0)
					(fill yes)
				)
			)
		)
	)
	(footprint ""
		(layer "F.Cu")
		(at 181.6862 -71.287894)
		(property "Reference" "C421"
			(at 0 0 0)
			(layer "F.SilkS")
			(hide yes)
			(effects
				(font
					(size 1.27 1.27)
				)
			)
		)
		(property "Value" "SC4D7U25V5KX-1-GP"
			(at -0.0762 -6.1214 0)
			(unlocked yes)
			(layer "F.Fab")
			(hide yes)
			(effects
				(font
					(size 1.016 1.016)
					(thickness 0.1524)
				)
			)
		)
		(property "Device Type" "C805H58"
			(at -0.0762 -8.1534 0)
			(unlocked yes)
			(layer "F.Fab")
			(hide yes)
			(effects
				(font
					(size 1.016 1.016)
					(thickness 0.1524)
				)
			)
		)
		(duplicate_pad_numbers_are_jumpers no)
		(fp_line
			(start 0.635 0)
			(end -0.635 0)
			(stroke
				(width 0.508)
				(type default)
			)
			(layer "F.SilkS")
		)
		(fp_rect
			(start -0.9652 1.778)
			(end 0.9652 -1.778)
			(stroke
				(width 0)
				(type default)
			)
			(fill no)
			(layer "F.CrtYd")
		)
		(fp_poly
			(pts
				(xy -0.9652 -1.778) (xy 0.9652 -1.778) (xy 0.9652 1.778) (xy -0.9652 1.778)
			)
			(stroke
				(width 0)
				(type default)
			)
			(fill no)
			(layer "F.Fab")
		)
		(pad "1" smd rect
			(at 0 -0.9652)
			(size 1.397 1.143)
			(layers "F.Cu" "F.Mask" "F.Paste")
			(net "P12V_HDD29")
		)
		(pad "2" smd rect
			(at 0 0.9652)
			(size 1.397 1.143)
			(layers "F.Cu" "F.Mask" "F.Paste")
			(net "GND")
		)
	)
	(footprint ""
		(layer "F.Cu")
		(at 221.742 -365.125 180)
		(property "Reference" "R151"
			(at 0 0 180)
			(layer "F.SilkS")
			(hide yes)
			(effects
				(font
					(size 1.27 1.27)
				)
			)
		)
		(property "Value" "4K7R2F-GP"
			(at 0.064008 -3.993896 180)
			(unlocked yes)
			(layer "F.Fab")
			(hide yes)
			(effects
				(font
					(size 1.016 1.016)
					(thickness 0.1524)
				)
			)
		)
		(property "Device Type" "R402H16"
			(at 0.064008 -5.517896 180)
			(unlocked yes)
			(layer "F.Fab")
			(hide yes)
			(effects
				(font
					(size 1.016 1.016)
					(thickness 0.1524)
				)
			)
		)
		(duplicate_pad_numbers_are_jumpers no)
		(fp_line
			(start 0.508 -0.9398)
			(end -0.508 -0.9398)
			(stroke
				(width 0.1524)
				(type default)
			)
			(layer "F.SilkS")
		)
		(fp_line
			(start -0.508 -0.9398)
			(end -0.508 0.9398)
			(stroke
				(width 0.1524)
				(type default)
			)
			(layer "F.SilkS")
		)
		(fp_rect
			(start -0.508 0.9398)
			(end 0.508 -0.9398)
			(stroke
				(width 0)
				(type default)
			)
			(fill no)
			(layer "F.CrtYd")
		)
		(fp_rect
			(start -0.508 0.9398)
			(end 0.508 -0.9398)
			(stroke
				(width 0)
				(type default)
			)
			(fill no)
			(layer "F.Fab")
		)
		(pad "1" smd custom
			(at 0 -0.4445 180)
			(size 0.1397 0.1397)
			(layers "F.Cu" "F.Mask" "F.Paste")
			(net "P3V3_STBY_B")
			(options
				(clearance outline)
				(anchor circle)
			)
			(primitives
				(gr_poly
					(pts
						(arc
							(start -0.1778 -0.2794)
							(mid -0.249642 -0.249642)
							(end -0.2794 -0.1778)
						)
						(arc
							(start -0.2794 0.1778)
							(mid -0.249642 0.249642)
							(end -0.1778 0.2794)
						)
						(arc
							(start 0.1778 0.2794)
							(mid 0.249642 0.249642)
							(end 0.2794 0.1778)
						)
						(arc
							(start 0.2794 -0.1778)
							(mid 0.249642 -0.249642)
							(end 0.1778 -0.2794)
						)
					)
					(width 0)
					(fill yes)
				)
			)
		)
		(pad "2" smd custom
			(at 0 0.4445 180)
			(size 0.1397 0.1397)
			(layers "F.Cu" "F.Mask" "F.Paste")
			(net "IO_EXP3_HDD_FAULT_A1")
			(options
				(clearance outline)
				(anchor circle)
			)
			(primitives
				(gr_poly
					(pts
						(arc
							(start -0.1778 -0.2794)
							(mid -0.249642 -0.249642)
							(end -0.2794 -0.1778)
						)
						(arc
							(start -0.2794 0.1778)
							(mid -0.249642 0.249642)
							(end -0.1778 0.2794)
						)
						(arc
							(start 0.1778 0.2794)
							(mid 0.249642 0.249642)
							(end 0.2794 0.1778)
						)
						(arc
							(start 0.2794 -0.1778)
							(mid 0.249642 -0.249642)
							(end 0.1778 -0.2794)
						)
					)
					(width 0)
					(fill yes)
				)
			)
		)
	)
	(footprint ""
		(layer "F.Cu")
		(at 299.390308 -24.585676 90)
		(property "Reference" "R1129"
			(at 0 0 90)
			(layer "F.SilkS")
			(hide yes)
			(effects
				(font
					(size 1.27 1.27)
				)
			)
		)
		(property "Value" "100KR2F-L1-GP"
			(at 0.064008 -3.993896 90)
			(unlocked yes)
			(layer "F.Fab")
			(hide yes)
			(effects
				(font
					(size 1.016 1.016)
					(thickness 0.1524)
				)
			)
		)
		(property "Device Type" "R402H16"
			(at 0.064008 -5.517896 90)
			(unlocked yes)
			(layer "F.Fab")
			(hide yes)
			(effects
				(font
					(size 1.016 1.016)
					(thickness 0.1524)
				)
			)
		)
		(duplicate_pad_numbers_are_jumpers no)
		(fp_line
			(start 0.508 -0.9398)
			(end -0.508 -0.9398)
			(stroke
				(width 0.1524)
				(type default)
			)
			(layer "F.SilkS")
		)
		(fp_line
			(start -0.508 -0.9398)
			(end -0.508 0.9398)
			(stroke
				(width 0.1524)
				(type default)
			)
			(layer "F.SilkS")
		)
		(fp_rect
			(start -0.508 0.9398)
			(end 0.508 -0.9398)
			(stroke
				(width 0)
				(type default)
			)
			(fill no)
			(layer "F.CrtYd")
		)
		(fp_rect
			(start -0.508 0.9398)
			(end 0.508 -0.9398)
			(stroke
				(width 0)
				(type default)
			)
			(fill no)
			(layer "F.Fab")
		)
		(pad "1" smd custom
			(at 0 -0.4445 90)
			(size 0.1397 0.1397)
			(layers "F.Cu" "F.Mask" "F.Paste")
			(net "PCIE_COMP_B_TO_IOM_B_RST_4")
			(options
				(clearance outline)
				(anchor circle)
			)
			(primitives
				(gr_poly
					(pts
						(arc
							(start -0.1778 -0.2794)
							(mid -0.249642 -0.249642)
							(end -0.2794 -0.1778)
						)
						(arc
							(start -0.2794 0.1778)
							(mid -0.249642 0.249642)
							(end -0.1778 0.2794)
						)
						(arc
							(start 0.1778 0.2794)
							(mid 0.249642 0.249642)
							(end 0.2794 0.1778)
						)
						(arc
							(start 0.2794 -0.1778)
							(mid 0.249642 -0.249642)
							(end 0.1778 -0.2794)
						)
					)
					(width 0)
					(fill yes)
				)
			)
		)
		(pad "2" smd custom
			(at 0 0.4445 90)
			(size 0.1397 0.1397)
			(layers "F.Cu" "F.Mask" "F.Paste")
			(net "GND")
			(options
				(clearance outline)
				(anchor circle)
			)
			(primitives
				(gr_poly
					(pts
						(arc
							(start -0.1778 -0.2794)
							(mid -0.249642 -0.249642)
							(end -0.2794 -0.1778)
						)
						(arc
							(start -0.2794 0.1778)
							(mid -0.249642 0.249642)
							(end -0.1778 0.2794)
						)
						(arc
							(start 0.1778 0.2794)
							(mid 0.249642 0.249642)
							(end 0.2794 0.1778)
						)
						(arc
							(start 0.2794 -0.1778)
							(mid 0.249642 -0.249642)
							(end 0.1778 -0.2794)
						)
					)
					(width 0)
					(fill yes)
				)
			)
		)
	)
	(footprint ""
		(layer "F.Cu")
		(at 449.06057 -255.199642 -90)
		(property "Reference" "R1252"
			(at 0 0 270)
			(layer "F.SilkS")
			(hide yes)
			(effects
				(font
					(size 1.27 1.27)
				)
			)
		)
		(property "Value" "15KR2F-GP"
			(at 0.064008 -3.993896 270)
			(unlocked yes)
			(layer "F.Fab")
			(hide yes)
			(effects
				(font
					(size 1.016 1.016)
					(thickness 0.1524)
				)
			)
		)
		(property "Device Type" "R402H16"
			(at 0.064008 -5.517896 270)
			(unlocked yes)
			(layer "F.Fab")
			(hide yes)
			(effects
				(font
					(size 1.016 1.016)
					(thickness 0.1524)
				)
			)
		)
		(duplicate_pad_numbers_are_jumpers no)
		(fp_line
			(start -0.508 -0.9398)
			(end -0.508 0.9398)
			(stroke
				(width 0.1524)
				(type default)
			)
			(layer "F.SilkS")
		)
		(fp_line
			(start 0.508 -0.9398)
			(end -0.508 -0.9398)
			(stroke
				(width 0.1524)
				(type default)
			)
			(layer "F.SilkS")
		)
		(fp_rect
			(start -0.508 0.9398)
			(end 0.508 -0.9398)
			(stroke
				(width 0)
				(type default)
			)
			(fill no)
			(layer "F.CrtYd")
		)
		(fp_rect
			(start -0.508 0.9398)
			(end 0.508 -0.9398)
			(stroke
				(width 0)
				(type default)
			)
			(fill no)
			(layer "F.Fab")
		)
		(pad "1" smd custom
			(at 0 -0.4445 270)
			(size 0.1397 0.1397)
			(layers "F.Cu" "F.Mask" "F.Paste")
			(net "P5V_A_3_PGOOD")
			(options
				(clearance outline)
				(anchor circle)
			)
			(primitives
				(gr_poly
					(pts
						(arc
							(start -0.1778 -0.2794)
							(mid -0.249642 -0.249642)
							(end -0.2794 -0.1778)
						)
						(arc
							(start -0.2794 0.1778)
							(mid -0.249642 0.249642)
							(end -0.1778 0.2794)
						)
						(arc
							(start 0.1778 0.2794)
							(mid 0.249642 0.249642)
							(end 0.2794 0.1778)
						)
						(arc
							(start 0.2794 -0.1778)
							(mid 0.249642 -0.249642)
							(end 0.1778 -0.2794)
						)
					)
					(width 0)
					(fill yes)
				)
			)
		)
		(pad "2" smd custom
			(at 0 0.4445 270)
			(size 0.1397 0.1397)
			(layers "F.Cu" "F.Mask" "F.Paste")
			(net "GND")
			(options
				(clearance outline)
				(anchor circle)
			)
			(primitives
				(gr_poly
					(pts
						(arc
							(start -0.1778 -0.2794)
							(mid -0.249642 -0.249642)
							(end -0.2794 -0.1778)
						)
						(arc
							(start -0.2794 0.1778)
							(mid -0.249642 0.249642)
							(end -0.1778 0.2794)
						)
						(arc
							(start 0.1778 0.2794)
							(mid 0.249642 0.249642)
							(end 0.2794 0.1778)
						)
						(arc
							(start 0.2794 -0.1778)
							(mid 0.249642 -0.249642)
							(end 0.1778 -0.2794)
						)
					)
					(width 0)
					(fill yes)
				)
			)
		)
	)
	(footprint ""
		(layer "F.Cu")
		(at 441.349892 -209.399886)
		(property "Reference" "FLED11"
			(at 0 0 0)
			(layer "F.SilkS")
			(hide yes)
			(effects
				(font
					(size 1.27 1.27)
				)
			)
		)
		(property "Value" "LED-BY-19-GP"
			(at -2.132076 1.414018 0)
			(unlocked yes)
			(layer "F.Fab")
			(hide yes)
			(effects
				(font
					(size 1.016 1.016)
					(thickness 0.1524)
				)
			)
		)
		(property "Device Type" "LED-1615-4PH26"
			(at -2.132076 -0.109982 0)
			(unlocked yes)
			(layer "F.Fab")
			(hide yes)
			(effects
				(font
					(size 1.016 1.016)
					(thickness 0.1524)
				)
			)
		)
		(duplicate_pad_numbers_are_jumpers no)
		(fp_line
			(start -1.2954 0.254)
			(end -1.2954 1.6002)
			(stroke
				(width 0.508)
				(type default)
			)
			(layer "F.SilkS")
		)
		(fp_line
			(start -1.2954 1.6002)
			(end 1.2954 1.6002)
			(stroke
				(width 0.508)
				(type default)
			)
			(layer "F.SilkS")
		)
		(fp_line
			(start -1.1176 -1.4224)
			(end 1.1176 -1.4224)
			(stroke
				(width 0.1524)
				(type default)
			)
			(layer "F.SilkS")
		)
		(fp_line
			(start -1.1176 1.4224)
			(end -1.1176 -1.4224)
			(stroke
				(width 0.1524)
				(type default)
			)
			(layer "F.SilkS")
		)
		(fp_line
			(start 1.1176 -1.4224)
			(end 1.1176 1.4224)
			(stroke
				(width 0.1524)
				(type default)
			)
			(layer "F.SilkS")
		)
		(fp_line
			(start 1.1176 1.4224)
			(end -1.1176 1.4224)
			(stroke
				(width 0.1524)
				(type default)
			)
			(layer "F.SilkS")
		)
		(fp_line
			(start 1.2954 1.6002)
			(end 1.2954 0.254)
			(stroke
				(width 0.508)
				(type default)
			)
			(layer "F.SilkS")
		)
		(fp_rect
			(start -0.7493 0.8001)
			(end 0.7493 -0.8001)
			(stroke
				(width 0)
				(type default)
			)
			(fill no)
			(layer "F.CrtYd")
		)
		(fp_poly
			(pts
				(xy -1.3716 1.6764) (xy -1.3716 -1.6764) (xy 1.3716 -1.6764) (xy 1.3716 0.0635) (xy 0.7493 0.0635)
				(xy 0.7493 -0.8001) (xy -0.7493 -0.8001) (xy -0.7493 0.8001) (xy 0.7493 0.8001) (xy 0.7493 0.0762)
				(xy 1.3716 0.0762) (xy 1.3716 1.6764)
			)
			(stroke
				(width 0)
				(type default)
			)
			(fill no)
			(layer "F.CrtYd")
		)
		(fp_rect
			(start -1.3716 1.6764)
			(end 1.3716 -1.6764)
			(stroke
				(width 0)
				(type default)
			)
			(fill no)
			(layer "F.Fab")
		)
		(pad "1" smd rect
			(at 0.50038 -0.73025)
			(size 0.7112 0.8636)
			(layers "F.Cu" "F.Mask" "F.Paste")
			(net "DRV_ACT_10")
		)
		(pad "2" smd rect
			(at -0.50038 -0.73025)
			(size 0.7112 0.8636)
			(layers "F.Cu" "F.Mask" "F.Paste")
			(net "FLT_HDD10")
		)
		(pad "3" smd rect
			(at 0.50038 0.73025)
			(size 0.7112 0.8636)
			(layers "F.Cu" "F.Mask" "F.Paste")
			(net "DRV_ACT_10_N")
		)
		(pad "4" smd rect
			(at -0.50038 0.73025)
			(size 0.7112 0.8636)
			(layers "F.Cu" "F.Mask" "F.Paste")
			(net "FLT_HDD10_N")
		)
	)
	(footprint ""
		(layer "F.Cu")
		(at 392.91895 -189.335918 180)
		(property "Reference" "C307"
			(at 0 0 180)
			(layer "F.SilkS")
			(hide yes)
			(effects
				(font
					(size 1.27 1.27)
				)
			)
		)
		(property "Value" "SC1U25V3KX-GP"
			(at 0 -2.8194 180)
			(unlocked yes)
			(layer "F.Fab")
			(hide yes)
			(effects
				(font
					(size 1.016 1.016)
					(thickness 0.1524)
				)
			)
		)
		(property "Device Type" "C603H36"
			(at 0 -4.3434 180)
			(unlocked yes)
			(layer "F.Fab")
			(hide yes)
			(effects
				(font
					(size 1.016 1.016)
					(thickness 0.1524)
				)
			)
		)
		(duplicate_pad_numbers_are_jumpers no)
		(fp_line
			(start 0.508 0)
			(end -0.508 0)
			(stroke
				(width 0.2032)
				(type default)
			)
			(layer "F.SilkS")
		)
		(fp_rect
			(start -0.5842 1.3335)
			(end 0.5842 -1.3335)
			(stroke
				(width 0)
				(type default)
			)
			(fill no)
			(layer "F.CrtYd")
		)
		(fp_rect
			(start -0.5842 1.3335)
			(end 0.5842 -1.3335)
			(stroke
				(width 0)
				(type default)
			)
			(fill no)
			(layer "F.Fab")
		)
		(pad "1" smd custom
			(at 0 -0.762 180)
			(size 0.2159 0.2159)
			(layers "F.Cu" "F.Mask" "F.Paste")
			(net "P12V_HDD20")
			(options
				(clearance outline)
				(anchor circle)
			)
			(primitives
				(gr_poly
					(pts
						(arc
							(start -0.3302 -0.4318)
							(mid -0.402042 -0.402042)
							(end -0.4318 -0.3302)
						)
						(arc
							(start -0.4318 0.3302)
							(mid -0.402042 0.402042)
							(end -0.3302 0.4318)
						)
						(arc
							(start 0.3302 0.4318)
							(mid 0.402042 0.402042)
							(end 0.4318 0.3302)
						)
						(arc
							(start 0.4318 -0.3302)
							(mid 0.402042 -0.402042)
							(end 0.3302 -0.4318)
						)
					)
					(width 0)
					(fill yes)
				)
			)
		)
		(pad "2" smd custom
			(at 0 0.762 180)
			(size 0.2159 0.2159)
			(layers "F.Cu" "F.Mask" "F.Paste")
			(net "GND")
			(options
				(clearance outline)
				(anchor circle)
			)
			(primitives
				(gr_poly
					(pts
						(arc
							(start -0.3302 -0.4318)
							(mid -0.402042 -0.402042)
							(end -0.4318 -0.3302)
						)
						(arc
							(start -0.4318 0.3302)
							(mid -0.402042 0.402042)
							(end -0.3302 0.4318)
						)
						(arc
							(start 0.3302 0.4318)
							(mid 0.402042 0.402042)
							(end 0.4318 0.3302)
						)
						(arc
							(start 0.4318 -0.3302)
							(mid 0.402042 -0.402042)
							(end 0.3302 -0.4318)
						)
					)
					(width 0)
					(fill yes)
				)
			)
		)
	)
	(footprint ""
		(layer "F.Cu")
		(at 244.725952 -385.759706)
		(property "Reference" "R1139"
			(at 0 0 0)
			(layer "F.SilkS")
			(hide yes)
			(effects
				(font
					(size 1.27 1.27)
				)
			)
		)
		(property "Value" "100R2D-GP"
			(at 0.064008 -3.993896 0)
			(unlocked yes)
			(layer "F.Fab")
			(hide yes)
			(effects
				(font
					(size 1.016 1.016)
					(thickness 0.1524)
				)
			)
		)
		(property "Device Type" "R402H14"
			(at 0.064008 -5.517896 0)
			(unlocked yes)
			(layer "F.Fab")
			(hide yes)
			(effects
				(font
					(size 1.016 1.016)
					(thickness 0.1524)
				)
			)
		)
		(duplicate_pad_numbers_are_jumpers no)
		(fp_line
			(start -0.508 -0.9398)
			(end -0.508 0.9398)
			(stroke
				(width 0.1524)
				(type default)
			)
			(layer "F.SilkS")
		)
		(fp_line
			(start 0.508 -0.9398)
			(end -0.508 -0.9398)
			(stroke
				(width 0.1524)
				(type default)
			)
			(layer "F.SilkS")
		)
		(fp_rect
			(start -0.508 0.9398)
			(end 0.508 -0.9398)
			(stroke
				(width 0)
				(type default)
			)
			(fill no)
			(layer "F.CrtYd")
		)
		(fp_rect
			(start -0.508 0.9398)
			(end 0.508 -0.9398)
			(stroke
				(width 0)
				(type default)
			)
			(fill no)
			(layer "F.Fab")
		)
		(pad "1" smd custom
			(at 0 -0.4445)
			(size 0.1397 0.1397)
			(layers "F.Cu" "F.Mask" "F.Paste")
			(net "MB3_TEMP")
			(options
				(clearance outline)
				(anchor circle)
			)
			(primitives
				(gr_poly
					(pts
						(arc
							(start -0.1778 -0.2794)
							(mid -0.249642 -0.249642)
							(end -0.2794 -0.1778)
						)
						(arc
							(start -0.2794 0.1778)
							(mid -0.249642 0.249642)
							(end -0.1778 0.2794)
						)
						(arc
							(start 0.1778 0.2794)
							(mid 0.249642 0.249642)
							(end 0.2794 0.1778)
						)
						(arc
							(start 0.2794 -0.1778)
							(mid 0.249642 -0.249642)
							(end 0.1778 -0.2794)
						)
					)
					(width 0)
					(fill yes)
				)
			)
		)
		(pad "2" smd custom
			(at 0 0.4445)
			(size 0.1397 0.1397)
			(layers "F.Cu" "F.Mask" "F.Paste")
			(net "MB3_TEMP_B")
			(options
				(clearance outline)
				(anchor circle)
			)
			(primitives
				(gr_poly
					(pts
						(arc
							(start -0.1778 -0.2794)
							(mid -0.249642 -0.249642)
							(end -0.2794 -0.1778)
						)
						(arc
							(start -0.2794 0.1778)
							(mid -0.249642 0.249642)
							(end -0.1778 0.2794)
						)
						(arc
							(start 0.1778 0.2794)
							(mid 0.249642 0.249642)
							(end 0.2794 0.1778)
						)
						(arc
							(start 0.2794 -0.1778)
							(mid 0.249642 -0.249642)
							(end 0.1778 -0.2794)
						)
					)
					(width 0)
					(fill yes)
				)
			)
		)
	)
	(footprint ""
		(layer "F.Cu")
		(at 146.630898 -163.554918 180)
		(property "Reference" "Q97"
			(at 0 0 180)
			(layer "F.SilkS")
			(hide yes)
			(effects
				(font
					(size 1.27 1.27)
				)
			)
		)
		(property "Value" "2N7002KDW-GP"
			(at -2.3622 -8.2042 180)
			(unlocked yes)
			(layer "F.Fab")
			(hide yes)
			(effects
				(font
					(size 1.016 1.016)
					(thickness 0.1524)
				)
			)
		)
		(property "Device Type" "SOT-363H44"
			(at -2.3622 -10.1092 180)
			(unlocked yes)
			(layer "F.Fab")
			(hide yes)
			(effects
				(font
					(size 1.016 1.016)
					(thickness 0.1524)
				)
			)
		)
		(duplicate_pad_numbers_are_jumpers no)
		(fp_line
			(start 1.4478 1.7018)
			(end 1.4478 -1.7018)
			(stroke
				(width 0.1524)
				(type default)
			)
			(layer "F.SilkS")
		)
		(fp_line
			(start 1.4478 -1.7018)
			(end -1.4478 -1.7018)
			(stroke
				(width 0.1524)
				(type default)
			)
			(layer "F.SilkS")
		)
		(fp_line
			(start -1.27 1.524)
			(end -1.27 0.6604)
			(stroke
				(width 0.4826)
				(type default)
			)
			(layer "F.SilkS")
		)
		(fp_line
			(start -1.4478 1.7018)
			(end 1.4478 1.7018)
			(stroke
				(width 0.1524)
				(type default)
			)
			(layer "F.SilkS")
		)
		(fp_line
			(start -1.4478 -1.7018)
			(end -1.4478 1.7018)
			(stroke
				(width 0.1524)
				(type default)
			)
			(layer "F.SilkS")
		)
		(fp_poly
			(pts
				(xy -1.524 -1.778) (xy 1.524 -1.778) (xy 1.524 1.778) (xy -1.524 1.778)
			)
			(stroke
				(width 0)
				(type default)
			)
			(fill no)
			(layer "F.CrtYd")
		)
		(fp_poly
			(pts
				(xy -1.524 -1.778) (xy 1.524 -1.778) (xy 1.524 1.778) (xy -1.524 1.778)
			)
			(stroke
				(width 0)
				(type default)
			)
			(fill no)
			(layer "F.Fab")
		)
		(pad "1" smd rect
			(at -0.65024 0.9398 180)
			(size 0.4064 1.016)
			(layers "F.Cu" "F.Mask" "F.Paste")
			(net "GND")
		)
		(pad "2" smd rect
			(at 0 0.9398 180)
			(size 0.4064 1.016)
			(layers "F.Cu" "F.Mask" "F.Paste")
			(net "SW_PWR_R_HDD16")
		)
		(pad "3" smd rect
			(at 0.65024 0.9398 180)
			(size 0.4064 1.016)
			(layers "F.Cu" "F.Mask" "F.Paste")
			(net "SW_HDD_P16")
		)
		(pad "4" smd rect
			(at 0.65024 -0.9398 180)
			(size 0.4064 1.016)
			(layers "F.Cu" "F.Mask" "F.Paste")
			(net "GND")
		)
		(pad "5" smd rect
			(at 0 -0.9398 180)
			(size 0.4064 1.016)
			(layers "F.Cu" "F.Mask" "F.Paste")
			(net "SW_HDD_G16")
		)
		(pad "6" smd rect
			(at -0.65024 -0.9398 180)
			(size 0.4064 1.016)
			(layers "F.Cu" "F.Mask" "F.Paste")
			(net "SW_HDD_R16")
		)
	)
	(footprint ""
		(layer "F.Cu")
		(at 314.2361 -59.2582 -90)
		(property "Reference" "U42"
			(at 0 0 270)
			(layer "F.SilkS")
			(hide yes)
			(effects
				(font
					(size 1.27 1.27)
				)
			)
		)
		(property "Value" "SNLVC1G126DCKR-GP"
			(at -2.3368 -8.6868 270)
			(unlocked yes)
			(layer "F.Fab")
			(hide yes)
			(effects
				(font
					(size 1.016 1.016)
					(thickness 0.1524)
				)
			)
		)
		(property "Device Type" "SC70-5H44"
			(at -2.3114 -10.414 270)
			(unlocked yes)
			(layer "F.Fab")
			(hide yes)
			(effects
				(font
					(size 1.016 1.016)
					(thickness 0.1524)
				)
			)
		)
		(duplicate_pad_numbers_are_jumpers no)
		(fp_line
			(start -1.27 1.7018)
			(end -1.27 -1.7018)
			(stroke
				(width 0.1524)
				(type default)
			)
			(layer "F.SilkS")
		)
		(fp_line
			(start 1.27 1.7018)
			(end -1.27 1.7018)
			(stroke
				(width 0.1524)
				(type default)
			)
			(layer "F.SilkS")
		)
		(fp_line
			(start -1.27 -1.7018)
			(end 1.27 -1.7018)
			(stroke
				(width 0.1524)
				(type default)
			)
			(layer "F.SilkS")
		)
		(fp_line
			(start 1.27 -1.7018)
			(end 1.27 1.7018)
			(stroke
				(width 0.1524)
				(type default)
			)
			(layer "F.SilkS")
		)
		(fp_line
			(start 0.6604 -1.8034)
			(end 1.3843 -1.8034)
			(stroke
				(width 0.3302)
				(type default)
			)
			(layer "F.SilkS")
		)
		(fp_line
			(start 1.3843 -1.8034)
			(end 1.3843 -1.1176)
			(stroke
				(width 0.3302)
				(type default)
			)
			(layer "F.SilkS")
		)
		(fp_rect
			(start -1.524 1.9558)
			(end 1.524 -1.9558)
			(stroke
				(width 0)
				(type default)
			)
			(fill no)
			(layer "F.CrtYd")
		)
		(fp_poly
			(pts
				(xy -1.524 -1.9558) (xy 1.524 -1.9558) (xy 1.524 1.9558) (xy -1.524 1.9558)
			)
			(stroke
				(width 0)
				(type default)
			)
			(fill no)
			(layer "F.Fab")
		)
		(pad "1" smd rect
			(at 0.65024 -0.8255 270)
			(size 0.4064 1.2192)
			(layers "F.Cu" "F.Mask" "F.Paste")
			(net "P3V3_STBY_B")
		)
		(pad "2" smd rect
			(at 0 -0.8255 270)
			(size 0.4064 1.2192)
			(layers "F.Cu" "F.Mask" "F.Paste")
			(net "SYS_B_RESET_N")
		)
		(pad "3" smd rect
			(at -0.65024 -0.8255 270)
			(size 0.4064 1.2192)
			(layers "F.Cu" "F.Mask" "F.Paste")
			(net "GND")
		)
		(pad "4" smd rect
			(at -0.65024 0.8255 270)
			(size 0.4064 1.2192)
			(layers "F.Cu" "F.Mask" "F.Paste")
			(net "SYS_B_RESET_BUFFER_N")
		)
		(pad "5" smd rect
			(at 0.65024 0.8255 270)
			(size 0.4064 1.2192)
			(layers "F.Cu" "F.Mask" "F.Paste")
			(net "P3V3_STBY_B")
		)
	)
	(footprint ""
		(layer "F.Cu")
		(at 318.77 -62.194694 90)
		(property "Reference" "R820"
			(at 0 0 90)
			(layer "F.SilkS")
			(hide yes)
			(effects
				(font
					(size 1.27 1.27)
				)
			)
		)
		(property "Value" "10KR2F-2-GP"
			(at 0.064008 -3.993896 90)
			(unlocked yes)
			(layer "F.Fab")
			(hide yes)
			(effects
				(font
					(size 1.016 1.016)
					(thickness 0.1524)
				)
			)
		)
		(property "Device Type" "R402H16"
			(at 0.064008 -5.517896 90)
			(unlocked yes)
			(layer "F.Fab")
			(hide yes)
			(effects
				(font
					(size 1.016 1.016)
					(thickness 0.1524)
				)
			)
		)
		(duplicate_pad_numbers_are_jumpers no)
		(fp_line
			(start 0.508 -0.9398)
			(end -0.508 -0.9398)
			(stroke
				(width 0.1524)
				(type default)
			)
			(layer "F.SilkS")
		)
		(fp_line
			(start -0.508 -0.9398)
			(end -0.508 0.9398)
			(stroke
				(width 0.1524)
				(type default)
			)
			(layer "F.SilkS")
		)
		(fp_rect
			(start -0.508 0.9398)
			(end 0.508 -0.9398)
			(stroke
				(width 0)
				(type default)
			)
			(fill no)
			(layer "F.CrtYd")
		)
		(fp_rect
			(start -0.508 0.9398)
			(end 0.508 -0.9398)
			(stroke
				(width 0)
				(type default)
			)
			(fill no)
			(layer "F.Fab")
		)
		(pad "1" smd custom
			(at 0 -0.4445 90)
			(size 0.1397 0.1397)
			(layers "F.Cu" "F.Mask" "F.Paste")
			(net "P3V3_STBY_A")
			(options
				(clearance outline)
				(anchor circle)
			)
			(primitives
				(gr_poly
					(pts
						(arc
							(start -0.1778 -0.2794)
							(mid -0.249642 -0.249642)
							(end -0.2794 -0.1778)
						)
						(arc
							(start -0.2794 0.1778)
							(mid -0.249642 0.249642)
							(end -0.1778 0.2794)
						)
						(arc
							(start 0.1778 0.2794)
							(mid 0.249642 0.249642)
							(end 0.2794 0.1778)
						)
						(arc
							(start 0.2794 -0.1778)
							(mid 0.249642 -0.249642)
							(end 0.1778 -0.2794)
						)
					)
					(width 0)
					(fill yes)
				)
			)
		)
		(pad "2" smd custom
			(at 0 0.4445 90)
			(size 0.1397 0.1397)
			(layers "F.Cu" "F.Mask" "F.Paste")
			(net "HDD_PRSNT_30")
			(options
				(clearance outline)
				(anchor circle)
			)
			(primitives
				(gr_poly
					(pts
						(arc
							(start -0.1778 -0.2794)
							(mid -0.249642 -0.249642)
							(end -0.2794 -0.1778)
						)
						(arc
							(start -0.2794 0.1778)
							(mid -0.249642 0.249642)
							(end -0.1778 0.2794)
						)
						(arc
							(start 0.1778 0.2794)
							(mid 0.249642 0.249642)
							(end 0.2794 0.1778)
						)
						(arc
							(start 0.2794 -0.1778)
							(mid 0.249642 -0.249642)
							(end 0.1778 -0.2794)
						)
					)
					(width 0)
					(fill yes)
				)
			)
		)
	)
	(footprint ""
		(layer "F.Cu")
		(at 98.897948 -62.169294 -90)
		(property "Reference" "R728"
			(at 0 0 270)
			(layer "F.SilkS")
			(hide yes)
			(effects
				(font
					(size 1.27 1.27)
				)
			)
		)
		(property "Value" "10KR2F-2-GP"
			(at 0.064008 -3.993896 270)
			(unlocked yes)
			(layer "F.Fab")
			(hide yes)
			(effects
				(font
					(size 1.016 1.016)
					(thickness 0.1524)
				)
			)
		)
		(property "Device Type" "R402H16"
			(at 0.064008 -5.517896 270)
			(unlocked yes)
			(layer "F.Fab")
			(hide yes)
			(effects
				(font
					(size 1.016 1.016)
					(thickness 0.1524)
				)
			)
		)
		(duplicate_pad_numbers_are_jumpers no)
		(fp_line
			(start -0.508 -0.9398)
			(end -0.508 0.9398)
			(stroke
				(width 0.1524)
				(type default)
			)
			(layer "F.SilkS")
		)
		(fp_line
			(start 0.508 -0.9398)
			(end -0.508 -0.9398)
			(stroke
				(width 0.1524)
				(type default)
			)
			(layer "F.SilkS")
		)
		(fp_rect
			(start -0.508 0.9398)
			(end 0.508 -0.9398)
			(stroke
				(width 0)
				(type default)
			)
			(fill no)
			(layer "F.CrtYd")
		)
		(fp_rect
			(start -0.508 0.9398)
			(end 0.508 -0.9398)
			(stroke
				(width 0)
				(type default)
			)
			(fill no)
			(layer "F.Fab")
		)
		(pad "1" smd custom
			(at 0 -0.4445 270)
			(size 0.1397 0.1397)
			(layers "F.Cu" "F.Mask" "F.Paste")
			(net "P3V3_STBY_A")
			(options
				(clearance outline)
				(anchor circle)
			)
			(primitives
				(gr_poly
					(pts
						(arc
							(start -0.1778 -0.2794)
							(mid -0.249642 -0.249642)
							(end -0.2794 -0.1778)
						)
						(arc
							(start -0.2794 0.1778)
							(mid -0.249642 0.249642)
							(end -0.1778 0.2794)
						)
						(arc
							(start 0.1778 0.2794)
							(mid 0.249642 0.249642)
							(end 0.2794 0.1778)
						)
						(arc
							(start 0.2794 -0.1778)
							(mid 0.249642 -0.249642)
							(end 0.1778 -0.2794)
						)
					)
					(width 0)
					(fill yes)
				)
			)
		)
		(pad "2" smd custom
			(at 0 0.4445 270)
			(size 0.1397 0.1397)
			(layers "F.Cu" "F.Mask" "F.Paste")
			(net "HDD_PRSNT_26")
			(options
				(clearance outline)
				(anchor circle)
			)
			(primitives
				(gr_poly
					(pts
						(arc
							(start -0.1778 -0.2794)
							(mid -0.249642 -0.249642)
							(end -0.2794 -0.1778)
						)
						(arc
							(start -0.2794 0.1778)
							(mid -0.249642 0.249642)
							(end -0.1778 0.2794)
						)
						(arc
							(start 0.1778 0.2794)
							(mid 0.249642 0.249642)
							(end 0.2794 0.1778)
						)
						(arc
							(start 0.2794 -0.1778)
							(mid 0.249642 -0.249642)
							(end 0.1778 -0.2794)
						)
					)
					(width 0)
					(fill yes)
				)
			)
		)
	)
	(footprint ""
		(layer "F.Cu")
		(at 272.542 -336.104992 180)
		(property "Reference" "VIA47"
			(at 0 0 180)
			(layer "F.SilkS")
			(hide yes)
			(effects
				(font
					(size 1.27 1.27)
				)
			)
		)
		(property "Value" "100OHM-8L-1D6MM-L18L16-GP"
			(at -3.7211 -4.5085 180)
			(unlocked yes)
			(layer "F.Fab")
			(hide yes)
			(effects
				(font
					(size 1.016 1.016)
					(thickness 0.1524)
				)
			)
		)
		(property "Device Type" "VIA-PCIE-4P-394076"
			(at -3.7211 -6.0325 180)
			(unlocked yes)
			(layer "F.Fab")
			(hide yes)
			(effects
				(font
					(size 1.016 1.016)
					(thickness 0.1524)
				)
			)
		)
		(duplicate_pad_numbers_are_jumpers no)
		(fp_rect
			(start -1.9685 0.381)
			(end 1.9685 -0.381)
			(stroke
				(width 0)
				(type default)
			)
			(fill no)
			(layer "F.CrtYd")
		)
		(fp_rect
			(start -1.9685 0.381)
			(end 1.9685 -0.381)
			(stroke
				(width 0)
				(type default)
			)
			(fill no)
			(layer "F.Fab")
		)
		(pad "1" thru_hole circle
			(at -1.5875 0 180)
			(size 0.508 0.508)
			(drill 0.254)
			(layers "*.Cu" "*.Mask")
			(remove_unused_layers no)
			(net "GND")
			(clearance 0.127)
			(thermal_gap 0.127)
		)
		(pad "2" thru_hole circle
			(at -0.5715 0 180)
			(size 0.508 0.508)
			(drill 0.254)
			(layers "*.Cu" "*.Mask")
			(remove_unused_layers no)
			(net "PHY_SCC_A_TO_DRV_A_13_DP")
			(clearance 0.127)
			(thermal_gap 0.127)
		)
		(pad "3" thru_hole circle
			(at 0.5715 0 180)
			(size 0.508 0.508)
			(drill 0.254)
			(layers "*.Cu" "*.Mask")
			(remove_unused_layers no)
			(net "PHY_SCC_A_TO_DRV_A_13_DN")
			(clearance 0.127)
			(thermal_gap 0.127)
		)
		(pad "4" thru_hole circle
			(at 1.5875 0 180)
			(size 0.508 0.508)
			(drill 0.254)
			(layers "*.Cu" "*.Mask")
			(remove_unused_layers no)
			(net "GND")
			(clearance 0.127)
			(thermal_gap 0.127)
		)
	)
	(footprint ""
		(layer "F.Cu")
		(at 67.347846 -62.169294 -90)
		(property "Reference" "R705"
			(at 0 0 270)
			(layer "F.SilkS")
			(hide yes)
			(effects
				(font
					(size 1.27 1.27)
				)
			)
		)
		(property "Value" "10KR2F-2-GP"
			(at 0.064008 -3.993896 270)
			(unlocked yes)
			(layer "F.Fab")
			(hide yes)
			(effects
				(font
					(size 1.016 1.016)
					(thickness 0.1524)
				)
			)
		)
		(property "Device Type" "R402H16"
			(at 0.064008 -5.517896 270)
			(unlocked yes)
			(layer "F.Fab")
			(hide yes)
			(effects
				(font
					(size 1.016 1.016)
					(thickness 0.1524)
				)
			)
		)
		(duplicate_pad_numbers_are_jumpers no)
		(fp_line
			(start -0.508 -0.9398)
			(end -0.508 0.9398)
			(stroke
				(width 0.1524)
				(type default)
			)
			(layer "F.SilkS")
		)
		(fp_line
			(start 0.508 -0.9398)
			(end -0.508 -0.9398)
			(stroke
				(width 0.1524)
				(type default)
			)
			(layer "F.SilkS")
		)
		(fp_rect
			(start -0.508 0.9398)
			(end 0.508 -0.9398)
			(stroke
				(width 0)
				(type default)
			)
			(fill no)
			(layer "F.CrtYd")
		)
		(fp_rect
			(start -0.508 0.9398)
			(end 0.508 -0.9398)
			(stroke
				(width 0)
				(type default)
			)
			(fill no)
			(layer "F.Fab")
		)
		(pad "1" smd custom
			(at 0 -0.4445 270)
			(size 0.1397 0.1397)
			(layers "F.Cu" "F.Mask" "F.Paste")
			(net "P3V3_STBY_A")
			(options
				(clearance outline)
				(anchor circle)
			)
			(primitives
				(gr_poly
					(pts
						(arc
							(start -0.1778 -0.2794)
							(mid -0.249642 -0.249642)
							(end -0.2794 -0.1778)
						)
						(arc
							(start -0.2794 0.1778)
							(mid -0.249642 0.249642)
							(end -0.1778 0.2794)
						)
						(arc
							(start 0.1778 0.2794)
							(mid 0.249642 0.249642)
							(end 0.2794 0.1778)
						)
						(arc
							(start 0.2794 -0.1778)
							(mid 0.249642 -0.249642)
							(end 0.1778 -0.2794)
						)
					)
					(width 0)
					(fill yes)
				)
			)
		)
		(pad "2" smd custom
			(at 0 0.4445 270)
			(size 0.1397 0.1397)
			(layers "F.Cu" "F.Mask" "F.Paste")
			(net "HDD_PRSNT_25")
			(options
				(clearance outline)
				(anchor circle)
			)
			(primitives
				(gr_poly
					(pts
						(arc
							(start -0.1778 -0.2794)
							(mid -0.249642 -0.249642)
							(end -0.2794 -0.1778)
						)
						(arc
							(start -0.2794 0.1778)
							(mid -0.249642 0.249642)
							(end -0.1778 0.2794)
						)
						(arc
							(start 0.1778 0.2794)
							(mid 0.249642 0.249642)
							(end 0.2794 0.1778)
						)
						(arc
							(start 0.2794 -0.1778)
							(mid 0.249642 -0.249642)
							(end 0.1778 -0.2794)
						)
					)
					(width 0)
					(fill yes)
				)
			)
		)
	)
	(footprint ""
		(layer "F.Cu")
		(at 222.693992 -344.628978)
		(property "Reference" "R23"
			(at 0 0 0)
			(layer "F.SilkS")
			(hide yes)
			(effects
				(font
					(size 1.27 1.27)
				)
			)
		)
		(property "Value" "4K7R2F-GP"
			(at 0.064008 -3.993896 0)
			(unlocked yes)
			(layer "F.Fab")
			(hide yes)
			(effects
				(font
					(size 1.016 1.016)
					(thickness 0.1524)
				)
			)
		)
		(property "Device Type" "R402H16"
			(at 0.064008 -5.517896 0)
			(unlocked yes)
			(layer "F.Fab")
			(hide yes)
			(effects
				(font
					(size 1.016 1.016)
					(thickness 0.1524)
				)
			)
		)
		(duplicate_pad_numbers_are_jumpers no)
		(fp_line
			(start -0.508 -0.9398)
			(end -0.508 0.9398)
			(stroke
				(width 0.1524)
				(type default)
			)
			(layer "F.SilkS")
		)
		(fp_line
			(start 0.508 -0.9398)
			(end -0.508 -0.9398)
			(stroke
				(width 0.1524)
				(type default)
			)
			(layer "F.SilkS")
		)
		(fp_rect
			(start -0.508 0.9398)
			(end 0.508 -0.9398)
			(stroke
				(width 0)
				(type default)
			)
			(fill no)
			(layer "F.CrtYd")
		)
		(fp_rect
			(start -0.508 0.9398)
			(end 0.508 -0.9398)
			(stroke
				(width 0)
				(type default)
			)
			(fill no)
			(layer "F.Fab")
		)
		(pad "1" smd custom
			(at 0 -0.4445)
			(size 0.1397 0.1397)
			(layers "F.Cu" "F.Mask" "F.Paste")
			(net "P3V3_STBY_A")
			(options
				(clearance outline)
				(anchor circle)
			)
			(primitives
				(gr_poly
					(pts
						(arc
							(start -0.1778 -0.2794)
							(mid -0.249642 -0.249642)
							(end -0.2794 -0.1778)
						)
						(arc
							(start -0.2794 0.1778)
							(mid -0.249642 0.249642)
							(end -0.1778 0.2794)
						)
						(arc
							(start 0.1778 0.2794)
							(mid 0.249642 0.249642)
							(end 0.2794 0.1778)
						)
						(arc
							(start 0.2794 -0.1778)
							(mid 0.249642 -0.249642)
							(end 0.1778 -0.2794)
						)
					)
					(width 0)
					(fill yes)
				)
			)
		)
		(pad "2" smd custom
			(at 0 0.4445)
			(size 0.1397 0.1397)
			(layers "F.Cu" "F.Mask" "F.Paste")
			(net "VOL_SEN_ADDR0")
			(options
				(clearance outline)
				(anchor circle)
			)
			(primitives
				(gr_poly
					(pts
						(arc
							(start -0.1778 -0.2794)
							(mid -0.249642 -0.249642)
							(end -0.2794 -0.1778)
						)
						(arc
							(start -0.2794 0.1778)
							(mid -0.249642 0.249642)
							(end -0.1778 0.2794)
						)
						(arc
							(start 0.1778 0.2794)
							(mid 0.249642 0.249642)
							(end 0.2794 0.1778)
						)
						(arc
							(start 0.2794 -0.1778)
							(mid 0.249642 -0.249642)
							(end 0.1778 -0.2794)
						)
					)
					(width 0)
					(fill yes)
				)
			)
		)
	)
	(footprint ""
		(layer "F.Cu")
		(at 378.7394 -134.8486 90)
		(property "Reference" "R1080"
			(at 0 0 90)
			(layer "F.SilkS")
			(hide yes)
			(effects
				(font
					(size 1.27 1.27)
				)
			)
		)
		(property "Value" "0R0603-PAD-2-GP-U"
			(at 2.1209 -0.1397 90)
			(unlocked yes)
			(layer "F.Fab")
			(hide yes)
			(effects
				(font
					(size 1.016 1.016)
					(thickness 0.1524)
				)
			)
		)
		(property "Device Type" "0R0603-PAD-1-U"
			(at 2.1209 -1.6637 90)
			(unlocked yes)
			(layer "F.Fab")
			(hide yes)
			(effects
				(font
					(size 1.016 1.016)
					(thickness 0.1524)
				)
			)
		)
		(duplicate_pad_numbers_are_jumpers no)
		(fp_rect
			(start -0.5842 1.3335)
			(end 0.5842 -1.3335)
			(stroke
				(width 0)
				(type default)
			)
			(fill no)
			(layer "F.CrtYd")
		)
		(fp_rect
			(start -0.5842 1.3335)
			(end 0.5842 -1.3335)
			(stroke
				(width 0)
				(type default)
			)
			(fill no)
			(layer "F.Fab")
		)
		(pad "1" smd custom
			(at 0 -0.762 90)
			(size 0.2159 0.2159)
			(layers "F.Cu" "F.Mask" "F.Paste")
			(net "AGND_CURRENT_MONOB")
			(options
				(clearance outline)
				(anchor circle)
			)
			(primitives
				(gr_poly
					(pts
						(arc
							(start -0.3302 -0.5842)
							(mid -0.402042 -0.554442)
							(end -0.4318 -0.4826)
						)
						(arc
							(start -0.4318 0.4826)
							(mid -0.402042 0.554442)
							(end -0.3302 0.5842)
						)
						(arc
							(start 0.3302 0.5842)
							(mid 0.402042 0.554442)
							(end 0.4318 0.4826)
						)
						(arc
							(start 0.4318 -0.4826)
							(mid 0.402042 -0.554442)
							(end 0.3302 -0.5842)
						)
					)
					(width 0)
					(fill yes)
				)
			)
		)
		(pad "2" smd custom
			(at 0 0.762 90)
			(size 0.2159 0.2159)
			(layers "F.Cu" "F.Mask" "F.Paste")
			(net "GND")
			(options
				(clearance outline)
				(anchor circle)
			)
			(primitives
				(gr_poly
					(pts
						(arc
							(start -0.4318 0.4826)
							(mid -0.402042 0.554442)
							(end -0.3302 0.5842)
						)
						(arc
							(start 0.3302 0.5842)
							(mid 0.402042 0.554442)
							(end 0.4318 0.4826)
						)
						(arc
							(start 0.4318 -0.4826)
							(mid 0.402042 -0.554442)
							(end 0.3302 -0.5842)
						)
						(arc
							(start -0.3302 -0.5842)
							(mid -0.402042 -0.554442)
							(end -0.4318 -0.4826)
						)
					)
					(width 0)
					(fill yes)
				)
			)
		)
	)
	(footprint ""
		(layer "F.Cu")
		(at 52.234846 -55.285894 180)
		(property "Reference" "Q149"
			(at 0 0 180)
			(layer "F.SilkS")
			(hide yes)
			(effects
				(font
					(size 1.27 1.27)
				)
			)
		)
		(property "Value" "AO4406AL-GP"
			(at -3.707384 -1.5367 180)
			(unlocked yes)
			(layer "F.Fab")
			(hide yes)
			(effects
				(font
					(size 1.016 1.016)
					(thickness 0.1524)
				)
			)
		)
		(property "Device Type" "SOIC8H69"
			(at -3.707384 -3.0607 180)
			(unlocked yes)
			(layer "F.Fab")
			(hide yes)
			(effects
				(font
					(size 1.016 1.016)
					(thickness 0.1524)
				)
			)
		)
		(duplicate_pad_numbers_are_jumpers no)
		(fp_line
			(start 2.1336 1.4224)
			(end 2.1336 -1.4224)
			(stroke
				(width 0.1524)
				(type default)
			)
			(layer "F.SilkS")
		)
		(fp_line
			(start 2.1336 -1.4224)
			(end -2.7432 -1.4224)
			(stroke
				(width 0.1524)
				(type default)
			)
			(layer "F.SilkS")
		)
		(fp_line
			(start -2.1844 -0.0508)
			(end -2.7178 0.508)
			(stroke
				(width 0.1524)
				(type default)
			)
			(layer "F.SilkS")
		)
		(fp_line
			(start -2.6289 3.4417)
			(end -2.6289 1.4732)
			(stroke
				(width 0.381)
				(type default)
			)
			(layer "F.SilkS")
		)
		(fp_line
			(start -2.7178 -0.508)
			(end -2.1844 -0.0508)
			(stroke
				(width 0.1524)
				(type default)
			)
			(layer "F.SilkS")
		)
		(fp_line
			(start -2.7432 1.4224)
			(end 2.1336 1.4224)
			(stroke
				(width 0.1524)
				(type default)
			)
			(layer "F.SilkS")
		)
		(fp_line
			(start -2.7432 1.4224)
			(end -2.6416 1.4224)
			(stroke
				(width 0.1524)
				(type default)
			)
			(layer "F.SilkS")
		)
		(fp_line
			(start -2.7432 -1.4224)
			(end -2.7432 1.4224)
			(stroke
				(width 0.1524)
				(type default)
			)
			(layer "F.SilkS")
		)
		(fp_poly
			(pts
				(xy -2.2098 -1.4224) (xy -2.2098 1.4224) (xy 2.2098 1.4224) (xy 2.2098 -1.4224)
			)
			(stroke
				(width 0)
				(type default)
			)
			(fill yes)
			(layer "F.SilkS")
		)
		(fp_rect
			(start -2.450084 2.999994)
			(end 2.450084 -2.999994)
			(stroke
				(width 0)
				(type default)
			)
			(fill no)
			(layer "F.CrtYd")
		)
		(fp_poly
			(pts
				(xy -2.8194 3.6322) (xy -2.8194 -3.6322) (xy 2.8194 -3.6322) (xy 2.8194 1.18364) (xy 2.450084 1.18364)
				(xy 2.450084 -2.999994) (xy -2.450084 -2.999994) (xy -2.450084 2.999994) (xy 2.450084 2.999994)
				(xy 2.450084 1.18618) (xy 2.8194 1.18618) (xy 2.8194 3.6322)
			)
			(stroke
				(width 0)
				(type default)
			)
			(fill no)
			(layer "F.CrtYd")
		)
		(fp_rect
			(start -2.8194 3.6322)
			(end 2.8194 -3.6322)
			(stroke
				(width 0)
				(type default)
			)
			(fill no)
			(layer "F.Fab")
		)
		(pad "1" smd rect
			(at -1.905 2.54 180)
			(size 0.635 1.651)
			(layers "F.Cu" "F.Mask" "F.Paste")
			(net "P5V_HDD25")
		)
		(pad "2" smd rect
			(at -0.635 2.54 180)
			(size 0.635 1.651)
			(layers "F.Cu" "F.Mask" "F.Paste")
			(net "P5V_HDD25")
		)
		(pad "3" smd rect
			(at 0.635 2.54 180)
			(size 0.635 1.651)
			(layers "F.Cu" "F.Mask" "F.Paste")
			(net "P5V_HDD25")
		)
		(pad "4" smd rect
			(at 1.905 2.54 180)
			(size 0.635 1.651)
			(layers "F.Cu" "F.Mask" "F.Paste")
			(net "SW_HDD_P25")
		)
		(pad "5" smd rect
			(at 1.905 -2.54 180)
			(size 0.635 1.651)
			(layers "F.Cu" "F.Mask" "F.Paste")
			(net "P5V_A_2")
		)
		(pad "6" smd rect
			(at 0.635 -2.54 180)
			(size 0.635 1.651)
			(layers "F.Cu" "F.Mask" "F.Paste")
			(net "P5V_A_2")
		)
		(pad "7" smd rect
			(at -0.635 -2.54 180)
			(size 0.635 1.651)
			(layers "F.Cu" "F.Mask" "F.Paste")
			(net "P5V_A_2")
		)
		(pad "8" smd rect
			(at -1.905 -2.54 180)
			(size 0.635 1.651)
			(layers "F.Cu" "F.Mask" "F.Paste")
			(net "P5V_A_2")
		)
	)
	(footprint ""
		(layer "F.Cu")
		(at 258.694682 -371.88775)
		(property "Reference" "R1174"
			(at 0 0 0)
			(layer "F.SilkS")
			(hide yes)
			(effects
				(font
					(size 1.27 1.27)
				)
			)
		)
		(property "Value" "10R5F-1-GP"
			(at 0 -8.9535 0)
			(unlocked yes)
			(layer "F.Fab")
			(hide yes)
			(effects
				(font
					(size 1.27 1.016)
					(thickness 0.1524)
				)
			)
		)
		(property "Device Type" "R805H24"
			(at 0 -10.6299 0)
			(unlocked yes)
			(layer "F.Fab")
			(hide yes)
			(effects
				(font
					(size 1.27 1.016)
					(thickness 0.1524)
				)
			)
		)
		(duplicate_pad_numbers_are_jumpers no)
		(fp_line
			(start -0.889 -1.7018)
			(end -0.889 0.2794)
			(stroke
				(width 0.1524)
				(type default)
			)
			(layer "F.SilkS")
		)
		(fp_line
			(start -0.889 0.0762)
			(end -0.889 1.7018)
			(stroke
				(width 0.1524)
				(type default)
			)
			(layer "F.SilkS")
		)
		(fp_line
			(start -0.889 1.7018)
			(end 0.889 1.7018)
			(stroke
				(width 0.1524)
				(type default)
			)
			(layer "F.SilkS")
		)
		(fp_line
			(start 0.889 -1.7018)
			(end -0.889 -1.7018)
			(stroke
				(width 0.1524)
				(type default)
			)
			(layer "F.SilkS")
		)
		(fp_line
			(start 0.889 -1.7018)
			(end 0.889 -0.381)
			(stroke
				(width 0.1524)
				(type default)
			)
			(layer "F.SilkS")
		)
		(fp_line
			(start 0.889 1.7018)
			(end 0.889 -0.508)
			(stroke
				(width 0.1524)
				(type default)
			)
			(layer "F.SilkS")
		)
		(fp_poly
			(pts
				(xy 0.9652 -1.778) (xy 0.9652 1.778) (xy -0.9652 1.778) (xy -0.9652 -1.778)
			)
			(stroke
				(width 0)
				(type default)
			)
			(fill no)
			(layer "F.CrtYd")
		)
		(fp_rect
			(start -0.9652 1.778)
			(end 0.9652 -1.778)
			(stroke
				(width 0)
				(type default)
			)
			(fill no)
			(layer "F.Fab")
		)
		(pad "1" smd rect
			(at 0 -0.9652)
			(size 1.397 1.143)
			(layers "F.Cu" "F.Mask" "F.Paste")
			(net "MB3_12V_CTRL_GATE3")
		)
		(pad "2" smd rect
			(at 0 0.9652)
			(size 1.397 1.143)
			(layers "F.Cu" "F.Mask" "F.Paste")
			(net "MB3_CM_GATE_R")
		)
	)
	(footprint ""
		(layer "F.Cu")
		(at 427.898052 -157.585918 180)
		(property "Reference" "R621"
			(at 0 0 180)
			(layer "F.SilkS")
			(hide yes)
			(effects
				(font
					(size 1.27 1.27)
				)
			)
		)
		(property "Value" "1KR2F-3-GP"
			(at 0.064008 -3.993896 180)
			(unlocked yes)
			(layer "F.Fab")
			(hide yes)
			(effects
				(font
					(size 1.016 1.016)
					(thickness 0.1524)
				)
			)
		)
		(property "Device Type" "R402H16"
			(at 0.064008 -5.517896 180)
			(unlocked yes)
			(layer "F.Fab")
			(hide yes)
			(effects
				(font
					(size 1.016 1.016)
					(thickness 0.1524)
				)
			)
		)
		(duplicate_pad_numbers_are_jumpers no)
		(fp_line
			(start 0.508 -0.9398)
			(end -0.508 -0.9398)
			(stroke
				(width 0.1524)
				(type default)
			)
			(layer "F.SilkS")
		)
		(fp_line
			(start -0.508 -0.9398)
			(end -0.508 0.9398)
			(stroke
				(width 0.1524)
				(type default)
			)
			(layer "F.SilkS")
		)
		(fp_rect
			(start -0.508 0.9398)
			(end 0.508 -0.9398)
			(stroke
				(width 0)
				(type default)
			)
			(fill no)
			(layer "F.CrtYd")
		)
		(fp_rect
			(start -0.508 0.9398)
			(end 0.508 -0.9398)
			(stroke
				(width 0)
				(type default)
			)
			(fill no)
			(layer "F.Fab")
		)
		(pad "1" smd custom
			(at 0 -0.4445 180)
			(size 0.1397 0.1397)
			(layers "F.Cu" "F.Mask" "F.Paste")
			(net "P3V3_STBY_A")
			(options
				(clearance outline)
				(anchor circle)
			)
			(primitives
				(gr_poly
					(pts
						(arc
							(start -0.1778 -0.2794)
							(mid -0.249642 -0.249642)
							(end -0.2794 -0.1778)
						)
						(arc
							(start -0.2794 0.1778)
							(mid -0.249642 0.249642)
							(end -0.1778 0.2794)
						)
						(arc
							(start 0.1778 0.2794)
							(mid 0.249642 0.249642)
							(end 0.2794 0.1778)
						)
						(arc
							(start 0.2794 -0.1778)
							(mid 0.249642 -0.249642)
							(end 0.1778 -0.2794)
						)
					)
					(width 0)
					(fill yes)
				)
			)
		)
		(pad "2" smd custom
			(at 0 0.4445 180)
			(size 0.1397 0.1397)
			(layers "F.Cu" "F.Mask" "F.Paste")
			(net "SW_PWR_R_HDD21")
			(options
				(clearance outline)
				(anchor circle)
			)
			(primitives
				(gr_poly
					(pts
						(arc
							(start -0.1778 -0.2794)
							(mid -0.249642 -0.249642)
							(end -0.2794 -0.1778)
						)
						(arc
							(start -0.2794 0.1778)
							(mid -0.249642 0.249642)
							(end -0.1778 0.2794)
						)
						(arc
							(start 0.1778 0.2794)
							(mid 0.249642 0.249642)
							(end 0.2794 0.1778)
						)
						(arc
							(start 0.2794 -0.1778)
							(mid 0.249642 -0.249642)
							(end 0.1778 -0.2794)
						)
					)
					(width 0)
					(fill yes)
				)
			)
		)
	)
	(footprint ""
		(layer "F.Cu")
		(at 334.6196 -272.5928 180)
		(property "Reference" "R279"
			(at 0 0 180)
			(layer "F.SilkS")
			(hide yes)
			(effects
				(font
					(size 1.27 1.27)
				)
			)
		)
		(property "Value" "0R2J-2-GP"
			(at 0.064008 -3.993896 180)
			(unlocked yes)
			(layer "F.Fab")
			(hide yes)
			(effects
				(font
					(size 1.016 1.016)
					(thickness 0.1524)
				)
			)
		)
		(property "Device Type" "R402H16"
			(at 0.064008 -5.517896 180)
			(unlocked yes)
			(layer "F.Fab")
			(hide yes)
			(effects
				(font
					(size 1.016 1.016)
					(thickness 0.1524)
				)
			)
		)
		(duplicate_pad_numbers_are_jumpers no)
		(fp_line
			(start 0.508 -0.9398)
			(end -0.508 -0.9398)
			(stroke
				(width 0.1524)
				(type default)
			)
			(layer "F.SilkS")
		)
		(fp_line
			(start -0.508 -0.9398)
			(end -0.508 0.9398)
			(stroke
				(width 0.1524)
				(type default)
			)
			(layer "F.SilkS")
		)
		(fp_rect
			(start -0.508 0.9398)
			(end 0.508 -0.9398)
			(stroke
				(width 0)
				(type default)
			)
			(fill no)
			(layer "F.CrtYd")
		)
		(fp_rect
			(start -0.508 0.9398)
			(end 0.508 -0.9398)
			(stroke
				(width 0)
				(type default)
			)
			(fill no)
			(layer "F.Fab")
		)
		(pad "1" smd custom
			(at 0 -0.4445 180)
			(size 0.1397 0.1397)
			(layers "F.Cu" "F.Mask" "F.Paste")
			(net "DRIVE_A_6_PWR")
			(options
				(clearance outline)
				(anchor circle)
			)
			(primitives
				(gr_poly
					(pts
						(arc
							(start -0.1778 -0.2794)
							(mid -0.249642 -0.249642)
							(end -0.2794 -0.1778)
						)
						(arc
							(start -0.2794 0.1778)
							(mid -0.249642 0.249642)
							(end -0.1778 0.2794)
						)
						(arc
							(start 0.1778 0.2794)
							(mid 0.249642 0.249642)
							(end 0.2794 0.1778)
						)
						(arc
							(start 0.2794 -0.1778)
							(mid 0.249642 -0.249642)
							(end 0.1778 -0.2794)
						)
					)
					(width 0)
					(fill yes)
				)
			)
		)
		(pad "2" smd custom
			(at 0 0.4445 180)
			(size 0.1397 0.1397)
			(layers "F.Cu" "F.Mask" "F.Paste")
			(net "SW_PWR_R_HDD6")
			(options
				(clearance outline)
				(anchor circle)
			)
			(primitives
				(gr_poly
					(pts
						(arc
							(start -0.1778 -0.2794)
							(mid -0.249642 -0.249642)
							(end -0.2794 -0.1778)
						)
						(arc
							(start -0.2794 0.1778)
							(mid -0.249642 0.249642)
							(end -0.1778 0.2794)
						)
						(arc
							(start 0.1778 0.2794)
							(mid 0.249642 0.249642)
							(end 0.2794 0.1778)
						)
						(arc
							(start 0.2794 -0.1778)
							(mid 0.249642 -0.249642)
							(end 0.1778 -0.2794)
						)
					)
					(width 0)
					(fill yes)
				)
			)
		)
	)
	(footprint ""
		(layer "F.Cu")
		(at 271.0688 -12.4206 90)
		(property "Reference" "TP195"
			(at 0 0 90)
			(layer "F.SilkS")
			(hide yes)
			(effects
				(font
					(size 1.27 1.27)
				)
			)
		)
		(property "Value" "TPAD32-GP"
			(at -0.0508 -1.6764 90)
			(unlocked yes)
			(layer "F.Fab")
			(hide yes)
			(effects
				(font
					(size 1.016 1.016)
					(thickness 0.1524)
				)
			)
		)
		(property "Device Type" "TPAD32"
			(at -0.0508 -3.2004 90)
			(unlocked yes)
			(layer "F.Fab")
			(hide yes)
			(effects
				(font
					(size 1.016 1.016)
					(thickness 0.1524)
				)
			)
		)
		(duplicate_pad_numbers_are_jumpers no)
		(fp_poly
			(pts
				(arc
					(start 0 0.4064)
					(mid 0 -0.4064)
					(end 0 0.4064)
				)
			)
			(stroke
				(width 0)
				(type default)
			)
			(fill no)
			(layer "F.CrtYd")
		)
		(fp_poly
			(pts
				(arc
					(start 0 0.7112)
					(mid 0 -0.7112)
					(end 0 0.7112)
				)
			)
			(stroke
				(width 0)
				(type default)
			)
			(fill no)
			(layer "F.Fab")
		)
		(pad "1" smd circle
			(at 0 0 90)
			(size 0.8128 0.8128)
			(layers "F.Cu" "F.Mask" "F.Paste")
			(net "TP_COMP_B_NCSI_CRSDV")
		)
	)
	(footprint ""
		(layer "F.Cu")
		(at 446.1891 -273.940016 90)
		(property "Reference" "VIA5"
			(at 0 0 90)
			(layer "F.SilkS")
			(hide yes)
			(effects
				(font
					(size 1.27 1.27)
				)
			)
		)
		(property "Value" "100OHM-8L-1D6MM-L18L16-GP"
			(at -3.7211 -4.5085 90)
			(unlocked yes)
			(layer "F.Fab")
			(hide yes)
			(effects
				(font
					(size 1.016 1.016)
					(thickness 0.1524)
				)
			)
		)
		(property "Device Type" "VIA-PCIE-4P-394076"
			(at -3.7211 -6.0325 90)
			(unlocked yes)
			(layer "F.Fab")
			(hide yes)
			(effects
				(font
					(size 1.016 1.016)
					(thickness 0.1524)
				)
			)
		)
		(duplicate_pad_numbers_are_jumpers no)
		(fp_rect
			(start -1.9685 0.381)
			(end 1.9685 -0.381)
			(stroke
				(width 0)
				(type default)
			)
			(fill no)
			(layer "F.CrtYd")
		)
		(fp_rect
			(start -1.9685 0.381)
			(end 1.9685 -0.381)
			(stroke
				(width 0)
				(type default)
			)
			(fill no)
			(layer "F.Fab")
		)
		(pad "1" thru_hole circle
			(at -1.5875 0 90)
			(size 0.508 0.508)
			(drill 0.254)
			(layers "*.Cu" "*.Mask")
			(remove_unused_layers no)
			(net "GND")
			(clearance 0.127)
			(thermal_gap 0.127)
		)
		(pad "2" thru_hole circle
			(at -0.5715 0 90)
			(size 0.508 0.508)
			(drill 0.254)
			(layers "*.Cu" "*.Mask")
			(remove_unused_layers no)
			(net "PHY_SCC_A_TO_DRV_A_10_DP")
			(clearance 0.127)
			(thermal_gap 0.127)
		)
		(pad "3" thru_hole circle
			(at 0.5715 0 90)
			(size 0.508 0.508)
			(drill 0.254)
			(layers "*.Cu" "*.Mask")
			(remove_unused_layers no)
			(net "PHY_SCC_A_TO_DRV_A_10_DN")
			(clearance 0.127)
			(thermal_gap 0.127)
		)
		(pad "4" thru_hole circle
			(at 1.5875 0 90)
			(size 0.508 0.508)
			(drill 0.254)
			(layers "*.Cu" "*.Mask")
			(remove_unused_layers no)
			(net "GND")
			(clearance 0.127)
			(thermal_gap 0.127)
		)
	)
	(footprint ""
		(layer "F.Cu")
		(at 395.83995 -49.596294 90)
		(property "Reference" "C464"
			(at 0 0 90)
			(layer "F.SilkS")
			(hide yes)
			(effects
				(font
					(size 1.27 1.27)
				)
			)
		)
		(property "Value" "SCD033U25V2KX-GP"
			(at 1.1811 -2.7051 90)
			(unlocked yes)
			(layer "F.Fab")
			(hide yes)
			(effects
				(font
					(size 1.016 1.016)
					(thickness 0.1524)
				)
			)
		)
		(property "Device Type" "C402H22"
			(at 1.1811 -4.2291 90)
			(unlocked yes)
			(layer "F.Fab")
			(hide yes)
			(effects
				(font
					(size 1.016 1.016)
					(thickness 0.1524)
				)
			)
		)
		(duplicate_pad_numbers_are_jumpers no)
		(fp_rect
			(start -0.4318 0.9525)
			(end 0.4318 -0.9525)
			(stroke
				(width 0)
				(type default)
			)
			(fill no)
			(layer "F.CrtYd")
		)
		(fp_rect
			(start -0.4318 0.9525)
			(end 0.4318 -0.9525)
			(stroke
				(width 0)
				(type default)
			)
			(fill no)
			(layer "F.Fab")
		)
		(pad "1" smd custom
			(at 0 -0.4445 90)
			(size 0.1524 0.1524)
			(layers "F.Cu" "F.Mask" "F.Paste")
			(net "SW_HDD_P32")
			(options
				(clearance outline)
				(anchor circle)
			)
			(primitives
				(gr_poly
					(pts
						(arc
							(start 0.3048 -0.2032)
							(mid 0.275042 -0.275042)
							(end 0.2032 -0.3048)
						)
						(arc
							(start -0.2032 -0.3048)
							(mid -0.275042 -0.275042)
							(end -0.3048 -0.2032)
						)
						(arc
							(start -0.3048 0.2032)
							(mid -0.275042 0.275042)
							(end -0.2032 0.3048)
						)
						(arc
							(start 0.2032 0.3048)
							(mid 0.275042 0.275042)
							(end 0.3048 0.2032)
						)
					)
					(width 0)
					(fill yes)
				)
			)
		)
		(pad "2" smd custom
			(at 0 0.4445 90)
			(size 0.1524 0.1524)
			(layers "F.Cu" "F.Mask" "F.Paste")
			(net "GND")
			(options
				(clearance outline)
				(anchor circle)
			)
			(primitives
				(gr_poly
					(pts
						(arc
							(start 0.3048 -0.2032)
							(mid 0.275042 -0.275042)
							(end 0.2032 -0.3048)
						)
						(arc
							(start -0.2032 -0.3048)
							(mid -0.275042 -0.275042)
							(end -0.3048 -0.2032)
						)
						(arc
							(start -0.3048 0.2032)
							(mid -0.275042 0.275042)
							(end -0.2032 0.3048)
						)
						(arc
							(start 0.2032 0.3048)
							(mid 0.275042 0.275042)
							(end 0.3048 0.2032)
						)
					)
					(width 0)
					(fill yes)
				)
			)
		)
	)
	(footprint ""
		(layer "F.Cu")
		(at 434.168042 -130.336036 -90)
		(property "Reference" "R542"
			(at 0 0 270)
			(layer "F.SilkS")
			(hide yes)
			(effects
				(font
					(size 1.27 1.27)
				)
			)
		)
		(property "Value" "4K7R2J-2-GP"
			(at 0.064008 -3.993896 270)
			(unlocked yes)
			(layer "F.Fab")
			(hide yes)
			(effects
				(font
					(size 1.016 1.016)
					(thickness 0.1524)
				)
			)
		)
		(property "Device Type" "R402H16"
			(at 0.064008 -5.517896 270)
			(unlocked yes)
			(layer "F.Fab")
			(hide yes)
			(effects
				(font
					(size 1.016 1.016)
					(thickness 0.1524)
				)
			)
		)
		(duplicate_pad_numbers_are_jumpers no)
		(fp_line
			(start -0.508 -0.9398)
			(end -0.508 0.9398)
			(stroke
				(width 0.1524)
				(type default)
			)
			(layer "F.SilkS")
		)
		(fp_line
			(start 0.508 -0.9398)
			(end -0.508 -0.9398)
			(stroke
				(width 0.1524)
				(type default)
			)
			(layer "F.SilkS")
		)
		(fp_rect
			(start -0.508 0.9398)
			(end 0.508 -0.9398)
			(stroke
				(width 0)
				(type default)
			)
			(fill no)
			(layer "F.CrtYd")
		)
		(fp_rect
			(start -0.508 0.9398)
			(end 0.508 -0.9398)
			(stroke
				(width 0)
				(type default)
			)
			(fill no)
			(layer "F.Fab")
		)
		(pad "1" smd custom
			(at 0 -0.4445 270)
			(size 0.1397 0.1397)
			(layers "F.Cu" "F.Mask" "F.Paste")
			(net "DRIVE_A_22_ACT")
			(options
				(clearance outline)
				(anchor circle)
			)
			(primitives
				(gr_poly
					(pts
						(arc
							(start -0.1778 -0.2794)
							(mid -0.249642 -0.249642)
							(end -0.2794 -0.1778)
						)
						(arc
							(start -0.2794 0.1778)
							(mid -0.249642 0.249642)
							(end -0.1778 0.2794)
						)
						(arc
							(start 0.1778 0.2794)
							(mid 0.249642 0.249642)
							(end 0.2794 0.1778)
						)
						(arc
							(start 0.2794 -0.1778)
							(mid 0.249642 -0.249642)
							(end 0.1778 -0.2794)
						)
					)
					(width 0)
					(fill yes)
				)
			)
		)
		(pad "2" smd custom
			(at 0 0.4445 270)
			(size 0.1397 0.1397)
			(layers "F.Cu" "F.Mask" "F.Paste")
			(net "GND")
			(options
				(clearance outline)
				(anchor circle)
			)
			(primitives
				(gr_poly
					(pts
						(arc
							(start -0.1778 -0.2794)
							(mid -0.249642 -0.249642)
							(end -0.2794 -0.1778)
						)
						(arc
							(start -0.2794 0.1778)
							(mid -0.249642 0.249642)
							(end -0.1778 0.2794)
						)
						(arc
							(start 0.1778 0.2794)
							(mid 0.249642 0.249642)
							(end 0.2794 0.1778)
						)
						(arc
							(start 0.2794 -0.1778)
							(mid 0.249642 -0.249642)
							(end 0.1778 -0.2794)
						)
					)
					(width 0)
					(fill yes)
				)
			)
		)
	)
	(footprint ""
		(layer "F.Cu")
		(at 113.065052 -242.25377)
		(property "Reference" "R220"
			(at 0 0 0)
			(layer "F.SilkS")
			(hide yes)
			(effects
				(font
					(size 1.27 1.27)
				)
			)
		)
		(property "Value" "91R3F-1-GP"
			(at -0.0254 -2.5146 0)
			(unlocked yes)
			(layer "F.Fab")
			(hide yes)
			(effects
				(font
					(size 1.016 1.016)
					(thickness 0.1524)
				)
			)
		)
		(property "Device Type" "R603H22"
			(at -0.0254 -4.0386 0)
			(unlocked yes)
			(layer "F.Fab")
			(hide yes)
			(effects
				(font
					(size 1.016 1.016)
					(thickness 0.1524)
				)
			)
		)
		(duplicate_pad_numbers_are_jumpers no)
		(fp_line
			(start -0.4826 0)
			(end -0.2032 0)
			(stroke
				(width 0.2032)
				(type default)
			)
			(layer "F.SilkS")
		)
		(fp_line
			(start 0.2032 0)
			(end 0.4826 0)
			(stroke
				(width 0.2032)
				(type default)
			)
			(layer "F.SilkS")
		)
		(fp_rect
			(start -0.5842 1.3335)
			(end 0.5842 -1.3335)
			(stroke
				(width 0)
				(type default)
			)
			(fill no)
			(layer "F.CrtYd")
		)
		(fp_rect
			(start -0.5842 1.3335)
			(end 0.5842 -1.3335)
			(stroke
				(width 0)
				(type default)
			)
			(fill no)
			(layer "F.Fab")
		)
		(pad "1" smd custom
			(at 0 -0.762)
			(size 0.2159 0.2159)
			(layers "F.Cu" "F.Mask" "F.Paste")
			(net "P5V_A_1")
			(options
				(clearance outline)
				(anchor circle)
			)
			(primitives
				(gr_poly
					(pts
						(arc
							(start -0.3302 -0.4318)
							(mid -0.402042 -0.402042)
							(end -0.4318 -0.3302)
						)
						(arc
							(start -0.4318 0.3302)
							(mid -0.402042 0.402042)
							(end -0.3302 0.4318)
						)
						(arc
							(start 0.3302 0.4318)
							(mid 0.402042 0.402042)
							(end 0.4318 0.3302)
						)
						(arc
							(start 0.4318 -0.3302)
							(mid 0.402042 -0.402042)
							(end 0.3302 -0.4318)
						)
					)
					(width 0)
					(fill yes)
				)
			)
		)
		(pad "2" smd custom
			(at 0 0.762)
			(size 0.2159 0.2159)
			(layers "F.Cu" "F.Mask" "F.Paste")
			(net "DRV_ACT_3")
			(options
				(clearance outline)
				(anchor circle)
			)
			(primitives
				(gr_poly
					(pts
						(arc
							(start -0.3302 -0.4318)
							(mid -0.402042 -0.402042)
							(end -0.4318 -0.3302)
						)
						(arc
							(start -0.4318 0.3302)
							(mid -0.402042 0.402042)
							(end -0.3302 0.4318)
						)
						(arc
							(start 0.3302 0.4318)
							(mid 0.402042 0.402042)
							(end 0.4318 0.3302)
						)
						(arc
							(start 0.4318 -0.3302)
							(mid 0.402042 -0.402042)
							(end 0.3302 -0.4318)
						)
					)
					(width 0)
					(fill yes)
				)
			)
		)
	)
	(footprint ""
		(layer "F.Cu")
		(at 429.549052 -52.872894 -90)
		(property "Reference" "Q197"
			(at 0 0 270)
			(layer "F.SilkS")
			(hide yes)
			(effects
				(font
					(size 1.27 1.27)
				)
			)
		)
		(property "Value" "AO4406AL-GP"
			(at -3.707384 -1.5367 270)
			(unlocked yes)
			(layer "F.Fab")
			(hide yes)
			(effects
				(font
					(size 1.016 1.016)
					(thickness 0.1524)
				)
			)
		)
		(property "Device Type" "SOIC8H69"
			(at -3.707384 -3.0607 270)
			(unlocked yes)
			(layer "F.Fab")
			(hide yes)
			(effects
				(font
					(size 1.016 1.016)
					(thickness 0.1524)
				)
			)
		)
		(duplicate_pad_numbers_are_jumpers no)
		(fp_line
			(start -2.6289 3.4417)
			(end -2.6289 1.4732)
			(stroke
				(width 0.381)
				(type default)
			)
			(layer "F.SilkS")
		)
		(fp_line
			(start -2.7432 1.4224)
			(end -2.6416 1.4224)
			(stroke
				(width 0.1524)
				(type default)
			)
			(layer "F.SilkS")
		)
		(fp_line
			(start -2.7432 1.4224)
			(end 2.1336 1.4224)
			(stroke
				(width 0.1524)
				(type default)
			)
			(layer "F.SilkS")
		)
		(fp_line
			(start 2.1336 1.4224)
			(end 2.1336 -1.4224)
			(stroke
				(width 0.1524)
				(type default)
			)
			(layer "F.SilkS")
		)
		(fp_line
			(start -2.1844 -0.0508)
			(end -2.7178 0.508)
			(stroke
				(width 0.1524)
				(type default)
			)
			(layer "F.SilkS")
		)
		(fp_line
			(start -2.7178 -0.508)
			(end -2.1844 -0.0508)
			(stroke
				(width 0.1524)
				(type default)
			)
			(layer "F.SilkS")
		)
		(fp_line
			(start -2.7432 -1.4224)
			(end -2.7432 1.4224)
			(stroke
				(width 0.1524)
				(type default)
			)
			(layer "F.SilkS")
		)
		(fp_line
			(start 2.1336 -1.4224)
			(end -2.7432 -1.4224)
			(stroke
				(width 0.1524)
				(type default)
			)
			(layer "F.SilkS")
		)
		(fp_poly
			(pts
				(xy -2.2098 -1.4224) (xy -2.2098 1.4224) (xy 2.2098 1.4224) (xy 2.2098 -1.4224)
			)
			(stroke
				(width 0)
				(type default)
			)
			(fill yes)
			(layer "F.SilkS")
		)
		(fp_rect
			(start -2.450084 2.999994)
			(end 2.450084 -2.999994)
			(stroke
				(width 0)
				(type default)
			)
			(fill no)
			(layer "F.CrtYd")
		)
		(fp_poly
			(pts
				(xy -2.8194 3.6322) (xy -2.8194 -3.6322) (xy 2.8194 -3.6322) (xy 2.8194 1.18364) (xy 2.450084 1.18364)
				(xy 2.450084 -2.999994) (xy -2.450084 -2.999994) (xy -2.450084 2.999994) (xy 2.450084 2.999994)
				(xy 2.450084 1.18618) (xy 2.8194 1.18618) (xy 2.8194 3.6322)
			)
			(stroke
				(width 0)
				(type default)
			)
			(fill no)
			(layer "F.CrtYd")
		)
		(fp_rect
			(start -2.8194 3.6322)
			(end 2.8194 -3.6322)
			(stroke
				(width 0)
				(type default)
			)
			(fill no)
			(layer "F.Fab")
		)
		(pad "1" smd rect
			(at -1.905 2.54 270)
			(size 0.635 1.651)
			(layers "F.Cu" "F.Mask" "F.Paste")
			(net "P5V_HDD33")
		)
		(pad "2" smd rect
			(at -0.635 2.54 270)
			(size 0.635 1.651)
			(layers "F.Cu" "F.Mask" "F.Paste")
			(net "P5V_HDD33")
		)
		(pad "3" smd rect
			(at 0.635 2.54 270)
			(size 0.635 1.651)
			(layers "F.Cu" "F.Mask" "F.Paste")
			(net "P5V_HDD33")
		)
		(pad "4" smd rect
			(at 1.905 2.54 270)
			(size 0.635 1.651)
			(layers "F.Cu" "F.Mask" "F.Paste")
			(net "SW_HDD_P33")
		)
		(pad "5" smd rect
			(at 1.905 -2.54 270)
			(size 0.635 1.651)
			(layers "F.Cu" "F.Mask" "F.Paste")
			(net "P5V_A_4")
		)
		(pad "6" smd rect
			(at 0.635 -2.54 270)
			(size 0.635 1.651)
			(layers "F.Cu" "F.Mask" "F.Paste")
			(net "P5V_A_4")
		)
		(pad "7" smd rect
			(at -0.635 -2.54 270)
			(size 0.635 1.651)
			(layers "F.Cu" "F.Mask" "F.Paste")
			(net "P5V_A_4")
		)
		(pad "8" smd rect
			(at -1.905 -2.54 270)
			(size 0.635 1.651)
			(layers "F.Cu" "F.Mask" "F.Paste")
			(net "P5V_A_4")
		)
	)
	(footprint ""
		(layer "F.Cu")
		(at 415.909252 -291.127942 -90)
		(property "Reference" "C163"
			(at 0 0 270)
			(layer "F.SilkS")
			(hide yes)
			(effects
				(font
					(size 1.27 1.27)
				)
			)
		)
		(property "Value" "SCD01U50V2KX-1GP"
			(at 1.1811 -2.7051 270)
			(unlocked yes)
			(layer "F.Fab")
			(hide yes)
			(effects
				(font
					(size 1.016 1.016)
					(thickness 0.1524)
				)
			)
		)
		(property "Device Type" "C402H22"
			(at 1.1811 -4.2291 270)
			(unlocked yes)
			(layer "F.Fab")
			(hide yes)
			(effects
				(font
					(size 1.016 1.016)
					(thickness 0.1524)
				)
			)
		)
		(duplicate_pad_numbers_are_jumpers no)
		(fp_rect
			(start -0.4318 0.9525)
			(end 0.4318 -0.9525)
			(stroke
				(width 0)
				(type default)
			)
			(fill no)
			(layer "F.CrtYd")
		)
		(fp_rect
			(start -0.4318 0.9525)
			(end 0.4318 -0.9525)
			(stroke
				(width 0)
				(type default)
			)
			(fill no)
			(layer "F.Fab")
		)
		(pad "1" smd custom
			(at 0 -0.4445 270)
			(size 0.1524 0.1524)
			(layers "F.Cu" "F.Mask" "F.Paste")
			(net "HDD_PRSNT_9")
			(options
				(clearance outline)
				(anchor circle)
			)
			(primitives
				(gr_poly
					(pts
						(arc
							(start 0.3048 -0.2032)
							(mid 0.275042 -0.275042)
							(end 0.2032 -0.3048)
						)
						(arc
							(start -0.2032 -0.3048)
							(mid -0.275042 -0.275042)
							(end -0.3048 -0.2032)
						)
						(arc
							(start -0.3048 0.2032)
							(mid -0.275042 0.275042)
							(end -0.2032 0.3048)
						)
						(arc
							(start 0.2032 0.3048)
							(mid 0.275042 0.275042)
							(end 0.3048 0.2032)
						)
					)
					(width 0)
					(fill yes)
				)
			)
		)
		(pad "2" smd custom
			(at 0 0.4445 270)
			(size 0.1524 0.1524)
			(layers "F.Cu" "F.Mask" "F.Paste")
			(net "GND")
			(options
				(clearance outline)
				(anchor circle)
			)
			(primitives
				(gr_poly
					(pts
						(arc
							(start 0.3048 -0.2032)
							(mid 0.275042 -0.275042)
							(end 0.2032 -0.3048)
						)
						(arc
							(start -0.2032 -0.3048)
							(mid -0.275042 -0.275042)
							(end -0.3048 -0.2032)
						)
						(arc
							(start -0.3048 0.2032)
							(mid -0.275042 0.275042)
							(end -0.2032 0.3048)
						)
						(arc
							(start 0.2032 0.3048)
							(mid 0.275042 0.275042)
							(end 0.3048 0.2032)
						)
					)
					(width 0)
					(fill yes)
				)
			)
		)
	)
	(footprint ""
		(layer "F.Cu")
		(at 396.34795 -42.585894 180)
		(property "Reference" "R874"
			(at 0 0 180)
			(layer "F.SilkS")
			(hide yes)
			(effects
				(font
					(size 1.27 1.27)
				)
			)
		)
		(property "Value" "100KR2F-L1-GP"
			(at 0.064008 -3.993896 180)
			(unlocked yes)
			(layer "F.Fab")
			(hide yes)
			(effects
				(font
					(size 1.016 1.016)
					(thickness 0.1524)
				)
			)
		)
		(property "Device Type" "R402H16"
			(at 0.064008 -5.517896 180)
			(unlocked yes)
			(layer "F.Fab")
			(hide yes)
			(effects
				(font
					(size 1.016 1.016)
					(thickness 0.1524)
				)
			)
		)
		(duplicate_pad_numbers_are_jumpers no)
		(fp_line
			(start 0.508 -0.9398)
			(end -0.508 -0.9398)
			(stroke
				(width 0.1524)
				(type default)
			)
			(layer "F.SilkS")
		)
		(fp_line
			(start -0.508 -0.9398)
			(end -0.508 0.9398)
			(stroke
				(width 0.1524)
				(type default)
			)
			(layer "F.SilkS")
		)
		(fp_rect
			(start -0.508 0.9398)
			(end 0.508 -0.9398)
			(stroke
				(width 0)
				(type default)
			)
			(fill no)
			(layer "F.CrtYd")
		)
		(fp_rect
			(start -0.508 0.9398)
			(end 0.508 -0.9398)
			(stroke
				(width 0)
				(type default)
			)
			(fill no)
			(layer "F.Fab")
		)
		(pad "1" smd custom
			(at 0 -0.4445 180)
			(size 0.1397 0.1397)
			(layers "F.Cu" "F.Mask" "F.Paste")
			(net "P3V3_STBY_A")
			(options
				(clearance outline)
				(anchor circle)
			)
			(primitives
				(gr_poly
					(pts
						(arc
							(start -0.1778 -0.2794)
							(mid -0.249642 -0.249642)
							(end -0.2794 -0.1778)
						)
						(arc
							(start -0.2794 0.1778)
							(mid -0.249642 0.249642)
							(end -0.1778 0.2794)
						)
						(arc
							(start 0.1778 0.2794)
							(mid 0.249642 0.249642)
							(end 0.2794 0.1778)
						)
						(arc
							(start 0.2794 -0.1778)
							(mid 0.249642 -0.249642)
							(end 0.1778 -0.2794)
						)
					)
					(width 0)
					(fill yes)
				)
			)
		)
		(pad "2" smd custom
			(at 0 0.4445 180)
			(size 0.1397 0.1397)
			(layers "F.Cu" "F.Mask" "F.Paste")
			(net "SW_PWR_R_HDD32")
			(options
				(clearance outline)
				(anchor circle)
			)
			(primitives
				(gr_poly
					(pts
						(arc
							(start -0.1778 -0.2794)
							(mid -0.249642 -0.249642)
							(end -0.2794 -0.1778)
						)
						(arc
							(start -0.2794 0.1778)
							(mid -0.249642 0.249642)
							(end -0.1778 0.2794)
						)
						(arc
							(start 0.1778 0.2794)
							(mid 0.249642 0.249642)
							(end 0.2794 0.1778)
						)
						(arc
							(start 0.2794 -0.1778)
							(mid 0.249642 -0.249642)
							(end 0.1778 -0.2794)
						)
					)
					(width 0)
					(fill yes)
				)
			)
		)
	)
	(footprint ""
		(layer "F.Cu")
		(at 253.414276 -248.87936)
		(property "Reference" "R54"
			(at 0 0 0)
			(layer "F.SilkS")
			(hide yes)
			(effects
				(font
					(size 1.27 1.27)
				)
			)
		)
		(property "Value" "4K7R2F-GP"
			(at 0.064008 -3.993896 0)
			(unlocked yes)
			(layer "F.Fab")
			(hide yes)
			(effects
				(font
					(size 1.016 1.016)
					(thickness 0.1524)
				)
			)
		)
		(property "Device Type" "R402H16"
			(at 0.064008 -5.517896 0)
			(unlocked yes)
			(layer "F.Fab")
			(hide yes)
			(effects
				(font
					(size 1.016 1.016)
					(thickness 0.1524)
				)
			)
		)
		(duplicate_pad_numbers_are_jumpers no)
		(fp_line
			(start -0.508 -0.9398)
			(end -0.508 0.9398)
			(stroke
				(width 0.1524)
				(type default)
			)
			(layer "F.SilkS")
		)
		(fp_line
			(start 0.508 -0.9398)
			(end -0.508 -0.9398)
			(stroke
				(width 0.1524)
				(type default)
			)
			(layer "F.SilkS")
		)
		(fp_rect
			(start -0.508 0.9398)
			(end 0.508 -0.9398)
			(stroke
				(width 0)
				(type default)
			)
			(fill no)
			(layer "F.CrtYd")
		)
		(fp_rect
			(start -0.508 0.9398)
			(end 0.508 -0.9398)
			(stroke
				(width 0)
				(type default)
			)
			(fill no)
			(layer "F.Fab")
		)
		(pad "1" smd custom
			(at 0 -0.4445)
			(size 0.1397 0.1397)
			(layers "F.Cu" "F.Mask" "F.Paste")
			(net "IO_EXP6_A1")
			(options
				(clearance outline)
				(anchor circle)
			)
			(primitives
				(gr_poly
					(pts
						(arc
							(start -0.1778 -0.2794)
							(mid -0.249642 -0.249642)
							(end -0.2794 -0.1778)
						)
						(arc
							(start -0.2794 0.1778)
							(mid -0.249642 0.249642)
							(end -0.1778 0.2794)
						)
						(arc
							(start 0.1778 0.2794)
							(mid 0.249642 0.249642)
							(end 0.2794 0.1778)
						)
						(arc
							(start 0.2794 -0.1778)
							(mid 0.249642 -0.249642)
							(end 0.1778 -0.2794)
						)
					)
					(width 0)
					(fill yes)
				)
			)
		)
		(pad "2" smd custom
			(at 0 0.4445)
			(size 0.1397 0.1397)
			(layers "F.Cu" "F.Mask" "F.Paste")
			(net "GND")
			(options
				(clearance outline)
				(anchor circle)
			)
			(primitives
				(gr_poly
					(pts
						(arc
							(start -0.1778 -0.2794)
							(mid -0.249642 -0.249642)
							(end -0.2794 -0.1778)
						)
						(arc
							(start -0.2794 0.1778)
							(mid -0.249642 0.249642)
							(end -0.1778 0.2794)
						)
						(arc
							(start 0.1778 0.2794)
							(mid 0.249642 0.249642)
							(end 0.2794 0.1778)
						)
						(arc
							(start 0.2794 -0.1778)
							(mid 0.249642 -0.249642)
							(end 0.1778 -0.2794)
						)
					)
					(width 0)
					(fill yes)
				)
			)
		)
	)
	(footprint ""
		(layer "F.Cu")
		(at 174.625 -276.649942 180)
		(property "Reference" "D5"
			(at 0 0 180)
			(layer "F.SilkS")
			(hide yes)
			(effects
				(font
					(size 1.27 1.27)
				)
			)
		)
		(property "Value" "RB551V30-GP"
			(at 0 -6.7818 180)
			(unlocked yes)
			(layer "F.Fab")
			(hide yes)
			(effects
				(font
					(size 1.016 1.016)
					(thickness 0.1524)
				)
			)
		)
		(property "Device Type" "SOD323AKH38"
			(at 0 -8.6868 180)
			(unlocked yes)
			(layer "F.Fab")
			(hide yes)
			(effects
				(font
					(size 1.016 1.016)
					(thickness 0.1524)
				)
			)
		)
		(duplicate_pad_numbers_are_jumpers no)
		(fp_line
			(start 0.889 2.159)
			(end -0.889 2.159)
			(stroke
				(width 0.1524)
				(type default)
			)
			(layer "F.SilkS")
		)
		(fp_line
			(start 0.889 -1.9304)
			(end 0.889 2.159)
			(stroke
				(width 0.1524)
				(type default)
			)
			(layer "F.SilkS")
		)
		(fp_line
			(start 0.762 2.0574)
			(end -0.762 2.0574)
			(stroke
				(width 0.508)
				(type default)
			)
			(layer "F.SilkS")
		)
		(fp_line
			(start -0.889 2.159)
			(end -0.889 -1.9304)
			(stroke
				(width 0.1524)
				(type default)
			)
			(layer "F.SilkS")
		)
		(fp_line
			(start -0.889 -1.9304)
			(end 0.889 -1.9304)
			(stroke
				(width 0.1524)
				(type default)
			)
			(layer "F.SilkS")
		)
		(fp_rect
			(start -1.016 2.3114)
			(end 1.016 -2.0066)
			(stroke
				(width 0)
				(type default)
			)
			(fill no)
			(layer "F.CrtYd")
		)
		(fp_poly
			(pts
				(xy -1.016 -2.0066) (xy 1.016 -2.0066) (xy 1.016 2.3114) (xy -1.016 2.3114)
			)
			(stroke
				(width 0)
				(type default)
			)
			(fill no)
			(layer "F.Fab")
		)
		(pad "A" smd rect
			(at 0 -1.143 180)
			(size 0.5588 1.016)
			(layers "F.Cu" "F.Mask" "F.Paste")
			(net "SW_HDD_R5")
		)
		(pad "K" smd rect
			(at 0 1.143 180)
			(size 0.5588 1.016)
			(layers "F.Cu" "F.Mask" "F.Paste")
			(net "SW_HDD_N5")
		)
	)
	(footprint ""
		(layer "F.Cu")
		(at 272.542 -310.90489 180)
		(property "Reference" "VIA65"
			(at 0 0 180)
			(layer "F.SilkS")
			(hide yes)
			(effects
				(font
					(size 1.27 1.27)
				)
			)
		)
		(property "Value" "100OHM-8L-1D6MM-L18L16-GP"
			(at -3.7211 -4.5085 180)
			(unlocked yes)
			(layer "F.Fab")
			(hide yes)
			(effects
				(font
					(size 1.016 1.016)
					(thickness 0.1524)
				)
			)
		)
		(property "Device Type" "VIA-PCIE-4P-394076"
			(at -3.7211 -6.0325 180)
			(unlocked yes)
			(layer "F.Fab")
			(hide yes)
			(effects
				(font
					(size 1.016 1.016)
					(thickness 0.1524)
				)
			)
		)
		(duplicate_pad_numbers_are_jumpers no)
		(fp_rect
			(start -1.9685 0.381)
			(end 1.9685 -0.381)
			(stroke
				(width 0)
				(type default)
			)
			(fill no)
			(layer "F.CrtYd")
		)
		(fp_rect
			(start -1.9685 0.381)
			(end 1.9685 -0.381)
			(stroke
				(width 0)
				(type default)
			)
			(fill no)
			(layer "F.Fab")
		)
		(pad "1" thru_hole circle
			(at -1.5875 0 180)
			(size 0.508 0.508)
			(drill 0.254)
			(layers "*.Cu" "*.Mask")
			(remove_unused_layers no)
			(net "GND")
			(clearance 0.127)
			(thermal_gap 0.127)
		)
		(pad "2" thru_hole circle
			(at -0.5715 0 180)
			(size 0.508 0.508)
			(drill 0.254)
			(layers "*.Cu" "*.Mask")
			(remove_unused_layers no)
			(net "PHY_SCC_A_TO_DRV_A_27_DP")
			(clearance 0.127)
			(thermal_gap 0.127)
		)
		(pad "3" thru_hole circle
			(at 0.5715 0 180)
			(size 0.508 0.508)
			(drill 0.254)
			(layers "*.Cu" "*.Mask")
			(remove_unused_layers no)
			(net "PHY_SCC_A_TO_DRV_A_27_DN")
			(clearance 0.127)
			(thermal_gap 0.127)
		)
		(pad "4" thru_hole circle
			(at 1.5875 0 180)
			(size 0.508 0.508)
			(drill 0.254)
			(layers "*.Cu" "*.Mask")
			(remove_unused_layers no)
			(net "GND")
			(clearance 0.127)
			(thermal_gap 0.127)
		)
	)
	(footprint ""
		(layer "F.Cu")
		(at 273.812 -272.288 180)
		(property "Reference" "R117"
			(at 0 0 180)
			(layer "F.SilkS")
			(hide yes)
			(effects
				(font
					(size 1.27 1.27)
				)
			)
		)
		(property "Value" "4K7R2F-GP"
			(at 0.064008 -3.993896 180)
			(unlocked yes)
			(layer "F.Fab")
			(hide yes)
			(effects
				(font
					(size 1.016 1.016)
					(thickness 0.1524)
				)
			)
		)
		(property "Device Type" "R402H16"
			(at 0.064008 -5.517896 180)
			(unlocked yes)
			(layer "F.Fab")
			(hide yes)
			(effects
				(font
					(size 1.016 1.016)
					(thickness 0.1524)
				)
			)
		)
		(duplicate_pad_numbers_are_jumpers no)
		(fp_line
			(start 0.508 -0.9398)
			(end -0.508 -0.9398)
			(stroke
				(width 0.1524)
				(type default)
			)
			(layer "F.SilkS")
		)
		(fp_line
			(start -0.508 -0.9398)
			(end -0.508 0.9398)
			(stroke
				(width 0.1524)
				(type default)
			)
			(layer "F.SilkS")
		)
		(fp_rect
			(start -0.508 0.9398)
			(end 0.508 -0.9398)
			(stroke
				(width 0)
				(type default)
			)
			(fill no)
			(layer "F.CrtYd")
		)
		(fp_rect
			(start -0.508 0.9398)
			(end 0.508 -0.9398)
			(stroke
				(width 0)
				(type default)
			)
			(fill no)
			(layer "F.Fab")
		)
		(pad "1" smd custom
			(at 0 -0.4445 180)
			(size 0.1397 0.1397)
			(layers "F.Cu" "F.Mask" "F.Paste")
			(net "P3V3_STBY_A")
			(options
				(clearance outline)
				(anchor circle)
			)
			(primitives
				(gr_poly
					(pts
						(arc
							(start -0.1778 -0.2794)
							(mid -0.249642 -0.249642)
							(end -0.2794 -0.1778)
						)
						(arc
							(start -0.2794 0.1778)
							(mid -0.249642 0.249642)
							(end -0.1778 0.2794)
						)
						(arc
							(start 0.1778 0.2794)
							(mid 0.249642 0.249642)
							(end 0.2794 0.1778)
						)
						(arc
							(start 0.2794 -0.1778)
							(mid 0.249642 -0.249642)
							(end 0.1778 -0.2794)
						)
					)
					(width 0)
					(fill yes)
				)
			)
		)
		(pad "2" smd custom
			(at 0 0.4445 180)
			(size 0.1397 0.1397)
			(layers "F.Cu" "F.Mask" "F.Paste")
			(net "IO_EXP1_HDD_FAULT_A1")
			(options
				(clearance outline)
				(anchor circle)
			)
			(primitives
				(gr_poly
					(pts
						(arc
							(start -0.1778 -0.2794)
							(mid -0.249642 -0.249642)
							(end -0.2794 -0.1778)
						)
						(arc
							(start -0.2794 0.1778)
							(mid -0.249642 0.249642)
							(end -0.1778 0.2794)
						)
						(arc
							(start 0.1778 0.2794)
							(mid 0.249642 0.249642)
							(end 0.2794 0.1778)
						)
						(arc
							(start 0.2794 -0.1778)
							(mid 0.249642 -0.249642)
							(end 0.1778 -0.2794)
						)
					)
					(width 0)
					(fill yes)
				)
			)
		)
	)
	(footprint ""
		(layer "F.Cu")
		(at 22.970998 -44.871894 -90)
		(property "Reference" "R693"
			(at 0 0 270)
			(layer "F.SilkS")
			(hide yes)
			(effects
				(font
					(size 1.27 1.27)
				)
			)
		)
		(property "Value" "0R2J-2-GP"
			(at 0.064008 -3.993896 270)
			(unlocked yes)
			(layer "F.Fab")
			(hide yes)
			(effects
				(font
					(size 1.016 1.016)
					(thickness 0.1524)
				)
			)
		)
		(property "Device Type" "R402H16"
			(at 0.064008 -5.517896 270)
			(unlocked yes)
			(layer "F.Fab")
			(hide yes)
			(effects
				(font
					(size 1.016 1.016)
					(thickness 0.1524)
				)
			)
		)
		(duplicate_pad_numbers_are_jumpers no)
		(fp_line
			(start -0.508 -0.9398)
			(end -0.508 0.9398)
			(stroke
				(width 0.1524)
				(type default)
			)
			(layer "F.SilkS")
		)
		(fp_line
			(start 0.508 -0.9398)
			(end -0.508 -0.9398)
			(stroke
				(width 0.1524)
				(type default)
			)
			(layer "F.SilkS")
		)
		(fp_rect
			(start -0.508 0.9398)
			(end 0.508 -0.9398)
			(stroke
				(width 0)
				(type default)
			)
			(fill no)
			(layer "F.CrtYd")
		)
		(fp_rect
			(start -0.508 0.9398)
			(end 0.508 -0.9398)
			(stroke
				(width 0)
				(type default)
			)
			(fill no)
			(layer "F.Fab")
		)
		(pad "1" smd custom
			(at 0 -0.4445 270)
			(size 0.1397 0.1397)
			(layers "F.Cu" "F.Mask" "F.Paste")
			(net "DRIVE_A_24_PWR")
			(options
				(clearance outline)
				(anchor circle)
			)
			(primitives
				(gr_poly
					(pts
						(arc
							(start -0.1778 -0.2794)
							(mid -0.249642 -0.249642)
							(end -0.2794 -0.1778)
						)
						(arc
							(start -0.2794 0.1778)
							(mid -0.249642 0.249642)
							(end -0.1778 0.2794)
						)
						(arc
							(start 0.1778 0.2794)
							(mid 0.249642 0.249642)
							(end 0.2794 0.1778)
						)
						(arc
							(start 0.2794 -0.1778)
							(mid 0.249642 -0.249642)
							(end 0.1778 -0.2794)
						)
					)
					(width 0)
					(fill yes)
				)
			)
		)
		(pad "2" smd custom
			(at 0 0.4445 270)
			(size 0.1397 0.1397)
			(layers "F.Cu" "F.Mask" "F.Paste")
			(net "SW_PWR_R_HDD24")
			(options
				(clearance outline)
				(anchor circle)
			)
			(primitives
				(gr_poly
					(pts
						(arc
							(start -0.1778 -0.2794)
							(mid -0.249642 -0.249642)
							(end -0.2794 -0.1778)
						)
						(arc
							(start -0.2794 0.1778)
							(mid -0.249642 0.249642)
							(end -0.1778 0.2794)
						)
						(arc
							(start 0.1778 0.2794)
							(mid 0.249642 0.249642)
							(end 0.2794 0.1778)
						)
						(arc
							(start 0.2794 -0.1778)
							(mid 0.249642 -0.249642)
							(end 0.1778 -0.2794)
						)
					)
					(width 0)
					(fill yes)
				)
			)
		)
	)
	(footprint ""
		(layer "F.Cu")
		(at 219.856558 -9.457436 90)
		(property "Reference" "C46"
			(at 0 0 90)
			(layer "F.SilkS")
			(hide yes)
			(effects
				(font
					(size 1.27 1.27)
				)
			)
		)
		(property "Value" "SC1U16V3KX-5GP"
			(at 0 -2.8194 90)
			(unlocked yes)
			(layer "F.Fab")
			(hide yes)
			(effects
				(font
					(size 1.016 1.016)
					(thickness 0.1524)
				)
			)
		)
		(property "Device Type" "C603H36"
			(at 0 -4.3434 90)
			(unlocked yes)
			(layer "F.Fab")
			(hide yes)
			(effects
				(font
					(size 1.016 1.016)
					(thickness 0.1524)
				)
			)
		)
		(duplicate_pad_numbers_are_jumpers no)
		(fp_line
			(start 0.508 0)
			(end -0.508 0)
			(stroke
				(width 0.2032)
				(type default)
			)
			(layer "F.SilkS")
		)
		(fp_rect
			(start -0.5842 1.3335)
			(end 0.5842 -1.3335)
			(stroke
				(width 0)
				(type default)
			)
			(fill no)
			(layer "F.CrtYd")
		)
		(fp_rect
			(start -0.5842 1.3335)
			(end 0.5842 -1.3335)
			(stroke
				(width 0)
				(type default)
			)
			(fill no)
			(layer "F.Fab")
		)
		(pad "1" smd custom
			(at 0 -0.762 90)
			(size 0.2159 0.2159)
			(layers "F.Cu" "F.Mask" "F.Paste")
			(net "P5V_A_2")
			(options
				(clearance outline)
				(anchor circle)
			)
			(primitives
				(gr_poly
					(pts
						(arc
							(start -0.3302 -0.4318)
							(mid -0.402042 -0.402042)
							(end -0.4318 -0.3302)
						)
						(arc
							(start -0.4318 0.3302)
							(mid -0.402042 0.402042)
							(end -0.3302 0.4318)
						)
						(arc
							(start 0.3302 0.4318)
							(mid 0.402042 0.402042)
							(end 0.4318 0.3302)
						)
						(arc
							(start 0.4318 -0.3302)
							(mid 0.402042 -0.402042)
							(end 0.3302 -0.4318)
						)
					)
					(width 0)
					(fill yes)
				)
			)
		)
		(pad "2" smd custom
			(at 0 0.762 90)
			(size 0.2159 0.2159)
			(layers "F.Cu" "F.Mask" "F.Paste")
			(net "GND")
			(options
				(clearance outline)
				(anchor circle)
			)
			(primitives
				(gr_poly
					(pts
						(arc
							(start -0.3302 -0.4318)
							(mid -0.402042 -0.402042)
							(end -0.4318 -0.3302)
						)
						(arc
							(start -0.4318 0.3302)
							(mid -0.402042 0.402042)
							(end -0.3302 0.4318)
						)
						(arc
							(start 0.3302 0.4318)
							(mid 0.402042 0.402042)
							(end 0.4318 0.3302)
						)
						(arc
							(start 0.4318 -0.3302)
							(mid 0.402042 -0.402042)
							(end 0.3302 -0.4318)
						)
					)
					(width 0)
					(fill yes)
				)
			)
		)
	)
	(footprint ""
		(layer "F.Cu")
		(at 67.728846 -295.064942 90)
		(property "Reference" "R155"
			(at 0 0 90)
			(layer "F.SilkS")
			(hide yes)
			(effects
				(font
					(size 1.27 1.27)
				)
			)
		)
		(property "Value" "220R3F-1-GP"
			(at -0.0254 -2.5146 90)
			(unlocked yes)
			(layer "F.Fab")
			(hide yes)
			(effects
				(font
					(size 1.016 1.016)
					(thickness 0.1524)
				)
			)
		)
		(property "Device Type" "R603H22"
			(at -0.0254 -4.0386 90)
			(unlocked yes)
			(layer "F.Fab")
			(hide yes)
			(effects
				(font
					(size 1.016 1.016)
					(thickness 0.1524)
				)
			)
		)
		(duplicate_pad_numbers_are_jumpers no)
		(fp_line
			(start 0.2032 0)
			(end 0.4826 0)
			(stroke
				(width 0.2032)
				(type default)
			)
			(layer "F.SilkS")
		)
		(fp_line
			(start -0.4826 0)
			(end -0.2032 0)
			(stroke
				(width 0.2032)
				(type default)
			)
			(layer "F.SilkS")
		)
		(fp_rect
			(start -0.5842 1.3335)
			(end 0.5842 -1.3335)
			(stroke
				(width 0)
				(type default)
			)
			(fill no)
			(layer "F.CrtYd")
		)
		(fp_rect
			(start -0.5842 1.3335)
			(end 0.5842 -1.3335)
			(stroke
				(width 0)
				(type default)
			)
			(fill no)
			(layer "F.Fab")
		)
		(pad "1" smd custom
			(at 0 -0.762 90)
			(size 0.2159 0.2159)
			(layers "F.Cu" "F.Mask" "F.Paste")
			(net "HDD_PRSNT_1")
			(options
				(clearance outline)
				(anchor circle)
			)
			(primitives
				(gr_poly
					(pts
						(arc
							(start -0.3302 -0.4318)
							(mid -0.402042 -0.402042)
							(end -0.4318 -0.3302)
						)
						(arc
							(start -0.4318 0.3302)
							(mid -0.402042 0.402042)
							(end -0.3302 0.4318)
						)
						(arc
							(start 0.3302 0.4318)
							(mid 0.402042 0.402042)
							(end 0.4318 0.3302)
						)
						(arc
							(start 0.4318 -0.3302)
							(mid 0.402042 -0.402042)
							(end 0.3302 -0.4318)
						)
					)
					(width 0)
					(fill yes)
				)
			)
		)
		(pad "2" smd custom
			(at 0 0.762 90)
			(size 0.2159 0.2159)
			(layers "F.Cu" "F.Mask" "F.Paste")
			(net "DRIVE_A_1_INS")
			(options
				(clearance outline)
				(anchor circle)
			)
			(primitives
				(gr_poly
					(pts
						(arc
							(start -0.3302 -0.4318)
							(mid -0.402042 -0.402042)
							(end -0.4318 -0.3302)
						)
						(arc
							(start -0.4318 0.3302)
							(mid -0.402042 0.402042)
							(end -0.3302 0.4318)
						)
						(arc
							(start 0.3302 0.4318)
							(mid 0.402042 0.402042)
							(end 0.4318 0.3302)
						)
						(arc
							(start 0.4318 -0.3302)
							(mid 0.402042 -0.402042)
							(end 0.3302 -0.4318)
						)
					)
					(width 0)
					(fill yes)
				)
			)
		)
	)
	(footprint ""
		(layer "F.Cu")
		(at 28.200096 -172.909992 -90)
		(property "Reference" "HDDSAS12"
			(at 0 0 270)
			(layer "F.SilkS")
			(hide yes)
			(effects
				(font
					(size 1.27 1.27)
				)
			)
		)
		(property "Value" "SKT-SAS15P-14P-45-GP"
			(at -20.7645 -8.9789 270)
			(unlocked yes)
			(layer "F.Fab")
			(hide yes)
			(effects
				(font
					(size 1.016 1.016)
					(thickness 0.1524)
				)
			)
		)
		(property "Device Type" "10120818-001C-TRLF"
			(at -20.7645 -10.5029 270)
			(unlocked yes)
			(layer "F.Fab")
			(hide yes)
			(effects
				(font
					(size 1.016 1.016)
					(thickness 0.1524)
				)
			)
		)
		(duplicate_pad_numbers_are_jumpers no)
		(fp_line
			(start 1.651 4.2926)
			(end 1.651 3.0099)
			(stroke
				(width 0.1524)
				(type default)
			)
			(layer "F.SilkS")
		)
		(fp_line
			(start 8.509 4.2926)
			(end 1.651 4.2926)
			(stroke
				(width 0.1524)
				(type default)
			)
			(layer "F.SilkS")
		)
		(fp_line
			(start -23.4188 3.0099)
			(end -23.4188 -3.2512)
			(stroke
				(width 0.1524)
				(type default)
			)
			(layer "F.SilkS")
		)
		(fp_line
			(start 1.651 3.0099)
			(end -23.4188 3.0099)
			(stroke
				(width 0.1524)
				(type default)
			)
			(layer "F.SilkS")
		)
		(fp_line
			(start 8.509 3.0099)
			(end 8.509 4.2926)
			(stroke
				(width 0.1524)
				(type default)
			)
			(layer "F.SilkS")
		)
		(fp_line
			(start 23.4188 3.0099)
			(end 8.509 3.0099)
			(stroke
				(width 0.1524)
				(type default)
			)
			(layer "F.SilkS")
		)
		(fp_line
			(start -23.4188 -3.2512)
			(end 23.4188 -3.2512)
			(stroke
				(width 0.1524)
				(type default)
			)
			(layer "F.SilkS")
		)
		(fp_line
			(start 23.4188 -3.2512)
			(end 23.4188 3.0099)
			(stroke
				(width 0.1524)
				(type default)
			)
			(layer "F.SilkS")
		)
		(fp_line
			(start 15.5067 -3.3401)
			(end 16.2687 -3.3401)
			(stroke
				(width 0.3302)
				(type default)
			)
			(layer "F.SilkS")
		)
		(fp_poly
			(pts
				(xy 15.868904 -3.230372) (xy 16.503904 -3.865372) (xy 15.233904 -3.865372)
			)
			(stroke
				(width 0)
				(type default)
			)
			(fill yes)
			(layer "F.SilkS")
		)
		(fp_poly
			(pts
				(xy -22.8727 -2.7559) (xy 22.8727 -2.7559) (xy 22.8727 2.7559) (xy 8.255 2.7559) (xy 8.255 3.5179)
				(xy 1.905 3.5179) (xy 1.905 2.7559) (xy -22.8727 2.7559)
			)
			(stroke
				(width 0)
				(type default)
			)
			(fill no)
			(layer "F.CrtYd")
		)
		(fp_poly
			(pts
				(xy 1.397 4.5466) (xy 1.397 3.2639) (xy -23.6728 3.2639) (xy -23.6728 -3.5052) (xy 23.6728 -3.5052)
				(xy 23.6728 -0.00635) (xy 22.8727 -0.00635) (xy 22.8727 -2.7559) (xy -22.8727 -2.7559) (xy -22.8727 2.7559)
				(xy 1.905 2.7559) (xy 1.905 3.5179) (xy 8.255 3.5179) (xy 8.255 2.7559) (xy 22.8727 2.7559) (xy 22.8727 0.00635)
				(xy 23.6728 0.00635) (xy 23.6728 3.2639) (xy 8.763 3.2639) (xy 8.763 4.5466)
			)
			(stroke
				(width 0)
				(type default)
			)
			(fill no)
			(layer "F.CrtYd")
		)
		(fp_poly
			(pts
				(xy 1.397 4.5466) (xy 1.397 3.2639) (xy -23.6728 3.2639) (xy -23.6728 -3.5052) (xy 23.6728 -3.5052)
				(xy 23.6728 3.2639) (xy 8.763 3.2639) (xy 8.763 4.5466)
			)
			(stroke
				(width 0)
				(type default)
			)
			(fill no)
			(layer "F.Fab")
		)
		(pad "" np_thru_hole circle
			(at -18.874994 0 270)
			(size 0.254 0.254)
			(drill 1.3462)
			(layers "*.Cu" "*.Mask")
			(clearance 0.9017)
			(thermal_gap 0.9017)
		)
		(pad "" np_thru_hole circle
			(at 18.874994 0 270)
			(size 0.254 0.254)
			(drill 0.9398)
			(layers "*.Cu" "*.Mask")
			(clearance 0.6985)
			(thermal_gap 0.6985)
		)
		(pad "G1" smd rect
			(at 21.874988 0 270)
			(size 2.5908 2.5908)
			(layers "F.Cu" "F.Mask" "F.Paste")
			(net "GND")
		)
		(pad "G2" smd rect
			(at -21.874988 0 270)
			(size 2.5908 2.5908)
			(layers "F.Cu" "F.Mask" "F.Paste")
			(net "GND")
		)
		(pad "P1" smd rect
			(at 1.905 -1.82499 270)
			(size 0.6096 2.3622)
			(layers "F.Cu" "F.Mask" "F.Paste")
			(net "Net_2156")
		)
		(pad "P2" smd rect
			(at 0.635 -1.82499 270)
			(size 0.6096 2.3622)
			(layers "F.Cu" "F.Mask" "F.Paste")
			(net "Net_2157")
		)
		(pad "P3" smd rect
			(at -0.635 -1.82499 270)
			(size 0.6096 2.3622)
			(layers "F.Cu" "F.Mask" "F.Paste")
			(net "Net_2158")
		)
		(pad "P4" smd rect
			(at -1.905 -1.82499 270)
			(size 0.6096 2.3622)
			(layers "F.Cu" "F.Mask" "F.Paste")
			(net "GND")
		)
		(pad "P5" smd rect
			(at -3.175 -1.82499 270)
			(size 0.6096 2.3622)
			(layers "F.Cu" "F.Mask" "F.Paste")
			(net "HDD_PRSNT_12")
		)
		(pad "P6" smd rect
			(at -4.445 -1.82499 270)
			(size 0.6096 2.3622)
			(layers "F.Cu" "F.Mask" "F.Paste")
			(net "GND")
		)
		(pad "P7" smd rect
			(at -5.715 -1.82499 270)
			(size 0.6096 2.3622)
			(layers "F.Cu" "F.Mask" "F.Paste")
			(net "5V_PRE_12")
		)
		(pad "P8" smd rect
			(at -6.985 -1.82499 270)
			(size 0.6096 2.3622)
			(layers "F.Cu" "F.Mask" "F.Paste")
			(net "P5V_HDD12")
		)
		(pad "P9" smd rect
			(at -8.255 -1.82499 270)
			(size 0.6096 2.3622)
			(layers "F.Cu" "F.Mask" "F.Paste")
			(net "P5V_HDD12")
		)
		(pad "P10" smd rect
			(at -9.525 -1.82499 270)
			(size 0.6096 2.3622)
			(layers "F.Cu" "F.Mask" "F.Paste")
			(net "GND")
		)
		(pad "P11" smd rect
			(at -10.795 -1.82499 270)
			(size 0.6096 2.3622)
			(layers "F.Cu" "F.Mask" "F.Paste")
			(net "ACT_HDD_12")
		)
		(pad "P12" smd rect
			(at -12.065 -1.82499 270)
			(size 0.6096 2.3622)
			(layers "F.Cu" "F.Mask" "F.Paste")
			(net "GND")
		)
		(pad "P13" smd rect
			(at -13.335 -1.82499 270)
			(size 0.6096 2.3622)
			(layers "F.Cu" "F.Mask" "F.Paste")
			(net "12V_PRE_12")
		)
		(pad "P14" smd rect
			(at -14.605 -1.82499 270)
			(size 0.6096 2.3622)
			(layers "F.Cu" "F.Mask" "F.Paste")
			(net "P12V_HDD12")
		)
		(pad "P15" smd rect
			(at -15.875 -1.82499 270)
			(size 0.6096 2.3622)
			(layers "F.Cu" "F.Mask" "F.Paste")
			(net "P12V_HDD12")
		)
		(pad "S1" smd rect
			(at 15.875 -1.82499 270)
			(size 0.6096 2.3622)
			(layers "F.Cu" "F.Mask" "F.Paste")
			(net "GND")
		)
		(pad "S2" smd rect
			(at 14.605 -1.82499 270)
			(size 0.6096 2.3622)
			(layers "F.Cu" "F.Mask" "F.Paste")
			(net "SAS_HDD_RX_P12")
		)
		(pad "S3" smd rect
			(at 13.335 -1.82499 270)
			(size 0.6096 2.3622)
			(layers "F.Cu" "F.Mask" "F.Paste")
			(net "SAS_HDD_RX_N12")
		)
		(pad "S4" smd rect
			(at 12.065 -1.82499 270)
			(size 0.6096 2.3622)
			(layers "F.Cu" "F.Mask" "F.Paste")
			(net "GND")
		)
		(pad "S5" smd rect
			(at 10.795 -1.82499 270)
			(size 0.6096 2.3622)
			(layers "F.Cu" "F.Mask" "F.Paste")
			(net "PHY_DRV_A_TO_SCC_A_12_DN")
		)
		(pad "S6" smd rect
			(at 9.525 -1.82499 270)
			(size 0.6096 2.3622)
			(layers "F.Cu" "F.Mask" "F.Paste")
			(net "PHY_DRV_A_TO_SCC_A_12_DP")
		)
		(pad "S7" smd rect
			(at 8.255 -1.82499 270)
			(size 0.6096 2.3622)
			(layers "F.Cu" "F.Mask" "F.Paste")
			(net "GND")
		)
		(pad "S8" smd rect
			(at 7.480046 2.845054 270)
			(size 0.508 2.3622)
			(layers "F.Cu" "F.Mask" "F.Paste")
			(net "GND")
		)
		(pad "S9" smd rect
			(at 6.679946 2.845054 270)
			(size 0.508 2.3622)
			(layers "F.Cu" "F.Mask" "F.Paste")
			(net "Net_449")
		)
		(pad "S10" smd rect
			(at 5.8801 2.845054 270)
			(size 0.508 2.3622)
			(layers "F.Cu" "F.Mask" "F.Paste")
			(net "Net_341")
		)
		(pad "S11" smd rect
			(at 5.08 2.845054 270)
			(size 0.508 2.3622)
			(layers "F.Cu" "F.Mask" "F.Paste")
			(net "GND")
		)
		(pad "S12" smd rect
			(at 4.2799 2.845054 270)
			(size 0.508 2.3622)
			(layers "F.Cu" "F.Mask" "F.Paste")
			(net "Net_377")
		)
		(pad "S13" smd rect
			(at 3.480054 2.845054 270)
			(size 0.508 2.3622)
			(layers "F.Cu" "F.Mask" "F.Paste")
			(net "Net_413")
		)
		(pad "S14" smd rect
			(at 2.679954 2.845054 270)
			(size 0.508 2.3622)
			(layers "F.Cu" "F.Mask" "F.Paste")
			(net "GND")
		)
		(zone
			(layer "F.Cu")
			(hatch none 0.5)
			(connect_pads
				(clearance 0)
			)
			(min_thickness 0.25)
			(keepout
				(tracks allowed)
				(vias not_allowed)
				(pads allowed)
				(copperpour not_allowed)
				(footprints allowed)
			)
			(placement
				(enabled no)
				(sheetname "")
			)
			(fill
				(thermal_gap 0.5)
				(thermal_bridge_width 0.5)
				(island_removal_mode 0)
			)
			(polygon
				(pts
					(xy 31.857696 -189.648592) (xy 24.783796 -189.648592) (xy 24.783796 -196.582792) (xy 25.888696 -196.582792)
					(xy 25.888696 -192.467992) (xy 30.511496 -192.467992) (xy 30.511496 -196.582792) (xy 31.857696 -196.582792)
				)
			)
		)
		(zone
			(layer "F.Cu")
			(hatch none 0.5)
			(connect_pads
				(clearance 0)
			)
			(min_thickness 0.25)
			(keepout
				(tracks not_allowed)
				(vias allowed)
				(pads allowed)
				(copperpour not_allowed)
				(footprints allowed)
			)
			(placement
				(enabled no)
				(sheetname "")
			)
			(fill
				(thermal_gap 0.5)
				(thermal_bridge_width 0.5)
				(island_removal_mode 0)
			)
			(polygon
				(pts
					(xy 31.857696 -189.648592) (xy 24.783796 -189.648592) (xy 24.783796 -196.582792) (xy 25.888696 -196.582792)
					(xy 25.888696 -192.467992) (xy 30.511496 -192.467992) (xy 30.511496 -196.582792) (xy 31.857696 -196.582792)
				)
			)
		)
		(zone
			(layer "F.Cu")
			(hatch none 0.5)
			(connect_pads
				(clearance 0)
			)
			(min_thickness 0.25)
			(keepout
				(tracks allowed)
				(vias not_allowed)
				(pads allowed)
				(copperpour not_allowed)
				(footprints allowed)
			)
			(placement
				(enabled no)
				(sheetname "")
			)
			(fill
				(thermal_gap 0.5)
				(thermal_bridge_width 0.5)
				(island_removal_mode 0)
			)
			(polygon
				(pts
					(xy 31.857696 -156.171392) (xy 24.783796 -156.171392) (xy 24.783796 -149.237192) (xy 25.888696 -149.237192)
					(xy 25.888696 -153.351992) (xy 30.511496 -153.351992) (xy 30.511496 -149.237192) (xy 31.857696 -149.237192)
				)
			)
		)
		(zone
			(layer "F.Cu")
			(hatch none 0.5)
			(connect_pads
				(clearance 0)
			)
			(min_thickness 0.25)
			(keepout
				(tracks not_allowed)
				(vias allowed)
				(pads allowed)
				(copperpour not_allowed)
				(footprints allowed)
			)
			(placement
				(enabled no)
				(sheetname "")
			)
			(fill
				(thermal_gap 0.5)
				(thermal_bridge_width 0.5)
				(island_removal_mode 0)
			)
			(polygon
				(pts
					(xy 31.857696 -156.171392) (xy 24.783796 -156.171392) (xy 24.783796 -149.237192) (xy 25.888696 -149.237192)
					(xy 25.888696 -153.351992) (xy 30.511496 -153.351992) (xy 30.511496 -149.237192) (xy 31.857696 -149.237192)
				)
			)
		)
		(zone
			(layers "F.Cu" "B.Cu" "In1.Cu" "In2.Cu" "In3.Cu" "In4.Cu" "In5.Cu" "In6.Cu"
				"In7.Cu" "In8.Cu" "In9.Cu" "In10.Cu"
			)
			(hatch none 0.5)
			(connect_pads
				(clearance 0)
			)
			(min_thickness 0.25)
			(keepout
				(tracks not_allowed)
				(vias allowed)
				(pads allowed)
				(copperpour not_allowed)
				(footprints allowed)
			)
			(placement
				(enabled no)
				(sheetname "")
			)
			(fill
				(thermal_gap 0.5)
				(thermal_bridge_width 0.5)
				(island_removal_mode 0)
			)
			(polygon
				(pts
					(arc
						(start 28.974796 -154.034998)
						(mid 27.425396 -154.034998)
						(end 28.974796 -154.034998)
					)
				)
			)
		)
		(zone
			(layers "F.Cu" "B.Cu" "In1.Cu" "In2.Cu" "In3.Cu" "In4.Cu" "In5.Cu" "In6.Cu"
				"In7.Cu" "In8.Cu" "In9.Cu" "In10.Cu"
			)
			(hatch none 0.5)
			(connect_pads
				(clearance 0)
			)
			(min_thickness 0.25)
			(keepout
				(tracks not_allowed)
				(vias allowed)
				(pads allowed)
				(copperpour not_allowed)
				(footprints allowed)
			)
			(placement
				(enabled no)
				(sheetname "")
			)
			(fill
				(thermal_gap 0.5)
				(thermal_bridge_width 0.5)
				(island_removal_mode 0)
			)
			(polygon
				(pts
					(arc
						(start 29.177996 -191.784986)
						(mid 27.222196 -191.784986)
						(end 29.177996 -191.784986)
					)
				)
			)
		)
	)
	(footprint ""
		(layer "F.Cu")
		(at 406.9588 -282.6766)
		(property "Reference" "R329"
			(at 0 0 0)
			(layer "F.SilkS")
			(hide yes)
			(effects
				(font
					(size 1.27 1.27)
				)
			)
		)
		(property "Value" "300KR2F-GP"
			(at 0.064008 -3.993896 0)
			(unlocked yes)
			(layer "F.Fab")
			(hide yes)
			(effects
				(font
					(size 1.016 1.016)
					(thickness 0.1524)
				)
			)
		)
		(property "Device Type" "R402H16"
			(at 0.064008 -5.517896 0)
			(unlocked yes)
			(layer "F.Fab")
			(hide yes)
			(effects
				(font
					(size 1.016 1.016)
					(thickness 0.1524)
				)
			)
		)
		(duplicate_pad_numbers_are_jumpers no)
		(fp_line
			(start -0.508 -0.9398)
			(end -0.508 0.9398)
			(stroke
				(width 0.1524)
				(type default)
			)
			(layer "F.SilkS")
		)
		(fp_line
			(start 0.508 -0.9398)
			(end -0.508 -0.9398)
			(stroke
				(width 0.1524)
				(type default)
			)
			(layer "F.SilkS")
		)
		(fp_rect
			(start -0.508 0.9398)
			(end 0.508 -0.9398)
			(stroke
				(width 0)
				(type default)
			)
			(fill no)
			(layer "F.CrtYd")
		)
		(fp_rect
			(start -0.508 0.9398)
			(end 0.508 -0.9398)
			(stroke
				(width 0)
				(type default)
			)
			(fill no)
			(layer "F.Fab")
		)
		(pad "1" smd custom
			(at 0 -0.4445)
			(size 0.1397 0.1397)
			(layers "F.Cu" "F.Mask" "F.Paste")
			(net "SW_HDD_N8")
			(options
				(clearance outline)
				(anchor circle)
			)
			(primitives
				(gr_poly
					(pts
						(arc
							(start -0.1778 -0.2794)
							(mid -0.249642 -0.249642)
							(end -0.2794 -0.1778)
						)
						(arc
							(start -0.2794 0.1778)
							(mid -0.249642 0.249642)
							(end -0.1778 0.2794)
						)
						(arc
							(start 0.1778 0.2794)
							(mid 0.249642 0.249642)
							(end 0.2794 0.1778)
						)
						(arc
							(start 0.2794 -0.1778)
							(mid 0.249642 -0.249642)
							(end 0.1778 -0.2794)
						)
					)
					(width 0)
					(fill yes)
				)
			)
		)
		(pad "2" smd custom
			(at 0 0.4445)
			(size 0.1397 0.1397)
			(layers "F.Cu" "F.Mask" "F.Paste")
			(net "P12V_A")
			(options
				(clearance outline)
				(anchor circle)
			)
			(primitives
				(gr_poly
					(pts
						(arc
							(start -0.1778 -0.2794)
							(mid -0.249642 -0.249642)
							(end -0.2794 -0.1778)
						)
						(arc
							(start -0.2794 0.1778)
							(mid -0.249642 0.249642)
							(end -0.1778 0.2794)
						)
						(arc
							(start 0.1778 0.2794)
							(mid 0.249642 0.249642)
							(end 0.2794 0.1778)
						)
						(arc
							(start 0.2794 -0.1778)
							(mid 0.249642 -0.249642)
							(end 0.1778 -0.2794)
						)
					)
					(width 0)
					(fill yes)
				)
			)
		)
	)
	(footprint ""
		(layer "F.Cu")
		(at 255.0414 18.219928 180)
		(property "Reference" "R638"
			(at 0 0 180)
			(layer "F.SilkS")
			(hide yes)
			(effects
				(font
					(size 1.27 1.27)
				)
			)
		)
		(property "Value" "10KR2F-2-GP"
			(at 0.064008 -3.993896 180)
			(unlocked yes)
			(layer "F.Fab")
			(hide yes)
			(effects
				(font
					(size 1.016 1.016)
					(thickness 0.1524)
				)
			)
		)
		(property "Device Type" "R402H16"
			(at 0.064008 -5.517896 180)
			(unlocked yes)
			(layer "F.Fab")
			(hide yes)
			(effects
				(font
					(size 1.016 1.016)
					(thickness 0.1524)
				)
			)
		)
		(duplicate_pad_numbers_are_jumpers no)
		(fp_line
			(start 0.508 -0.9398)
			(end -0.508 -0.9398)
			(stroke
				(width 0.1524)
				(type default)
			)
			(layer "F.SilkS")
		)
		(fp_line
			(start -0.508 -0.9398)
			(end -0.508 0.9398)
			(stroke
				(width 0.1524)
				(type default)
			)
			(layer "F.SilkS")
		)
		(fp_rect
			(start -0.508 0.9398)
			(end 0.508 -0.9398)
			(stroke
				(width 0)
				(type default)
			)
			(fill no)
			(layer "F.CrtYd")
		)
		(fp_rect
			(start -0.508 0.9398)
			(end 0.508 -0.9398)
			(stroke
				(width 0)
				(type default)
			)
			(fill no)
			(layer "F.Fab")
		)
		(pad "1" smd custom
			(at 0 -0.4445 180)
			(size 0.1397 0.1397)
			(layers "F.Cu" "F.Mask" "F.Paste")
			(net "P3V3_STBY_A")
			(options
				(clearance outline)
				(anchor circle)
			)
			(primitives
				(gr_poly
					(pts
						(arc
							(start -0.1778 -0.2794)
							(mid -0.249642 -0.249642)
							(end -0.2794 -0.1778)
						)
						(arc
							(start -0.2794 0.1778)
							(mid -0.249642 0.249642)
							(end -0.1778 0.2794)
						)
						(arc
							(start 0.1778 0.2794)
							(mid 0.249642 0.249642)
							(end 0.2794 0.1778)
						)
						(arc
							(start 0.2794 -0.1778)
							(mid 0.249642 -0.249642)
							(end 0.1778 -0.2794)
						)
					)
					(width 0)
					(fill yes)
				)
			)
		)
		(pad "2" smd custom
			(at 0 0.4445 180)
			(size 0.1397 0.1397)
			(layers "F.Cu" "F.Mask" "F.Paste")
			(net "SCC_A_PWR_LED")
			(options
				(clearance outline)
				(anchor circle)
			)
			(primitives
				(gr_poly
					(pts
						(arc
							(start -0.1778 -0.2794)
							(mid -0.249642 -0.249642)
							(end -0.2794 -0.1778)
						)
						(arc
							(start -0.2794 0.1778)
							(mid -0.249642 0.249642)
							(end -0.1778 0.2794)
						)
						(arc
							(start 0.1778 0.2794)
							(mid 0.249642 0.249642)
							(end 0.2794 0.1778)
						)
						(arc
							(start 0.2794 -0.1778)
							(mid 0.249642 -0.249642)
							(end 0.1778 -0.2794)
						)
					)
					(width 0)
					(fill yes)
				)
			)
		)
	)
	(footprint ""
		(layer "F.Cu")
		(at 285.623 -272.3134)
		(property "Reference" "R127"
			(at 0 0 0)
			(layer "F.SilkS")
			(hide yes)
			(effects
				(font
					(size 1.27 1.27)
				)
			)
		)
		(property "Value" "4K7R2F-GP"
			(at 0.064008 -3.993896 0)
			(unlocked yes)
			(layer "F.Fab")
			(hide yes)
			(effects
				(font
					(size 1.016 1.016)
					(thickness 0.1524)
				)
			)
		)
		(property "Device Type" "R402H16"
			(at 0.064008 -5.517896 0)
			(unlocked yes)
			(layer "F.Fab")
			(hide yes)
			(effects
				(font
					(size 1.016 1.016)
					(thickness 0.1524)
				)
			)
		)
		(duplicate_pad_numbers_are_jumpers no)
		(fp_line
			(start -0.508 -0.9398)
			(end -0.508 0.9398)
			(stroke
				(width 0.1524)
				(type default)
			)
			(layer "F.SilkS")
		)
		(fp_line
			(start 0.508 -0.9398)
			(end -0.508 -0.9398)
			(stroke
				(width 0.1524)
				(type default)
			)
			(layer "F.SilkS")
		)
		(fp_rect
			(start -0.508 0.9398)
			(end 0.508 -0.9398)
			(stroke
				(width 0)
				(type default)
			)
			(fill no)
			(layer "F.CrtYd")
		)
		(fp_rect
			(start -0.508 0.9398)
			(end 0.508 -0.9398)
			(stroke
				(width 0)
				(type default)
			)
			(fill no)
			(layer "F.Fab")
		)
		(pad "1" smd custom
			(at 0 -0.4445)
			(size 0.1397 0.1397)
			(layers "F.Cu" "F.Mask" "F.Paste")
			(net "IO_EXP2_HDD_FAULT_A2")
			(options
				(clearance outline)
				(anchor circle)
			)
			(primitives
				(gr_poly
					(pts
						(arc
							(start -0.1778 -0.2794)
							(mid -0.249642 -0.249642)
							(end -0.2794 -0.1778)
						)
						(arc
							(start -0.2794 0.1778)
							(mid -0.249642 0.249642)
							(end -0.1778 0.2794)
						)
						(arc
							(start 0.1778 0.2794)
							(mid 0.249642 0.249642)
							(end 0.2794 0.1778)
						)
						(arc
							(start 0.2794 -0.1778)
							(mid 0.249642 -0.249642)
							(end 0.1778 -0.2794)
						)
					)
					(width 0)
					(fill yes)
				)
			)
		)
		(pad "2" smd custom
			(at 0 0.4445)
			(size 0.1397 0.1397)
			(layers "F.Cu" "F.Mask" "F.Paste")
			(net "GND")
			(options
				(clearance outline)
				(anchor circle)
			)
			(primitives
				(gr_poly
					(pts
						(arc
							(start -0.1778 -0.2794)
							(mid -0.249642 -0.249642)
							(end -0.2794 -0.1778)
						)
						(arc
							(start -0.2794 0.1778)
							(mid -0.249642 0.249642)
							(end -0.1778 0.2794)
						)
						(arc
							(start 0.1778 0.2794)
							(mid 0.249642 0.249642)
							(end 0.2794 0.1778)
						)
						(arc
							(start 0.2794 -0.1778)
							(mid 0.249642 -0.249642)
							(end 0.1778 -0.2794)
						)
					)
					(width 0)
					(fill yes)
				)
			)
		)
	)
	(footprint ""
		(layer "F.Cu")
		(at 368.862102 -277.792942 90)
		(property "Reference" "D7"
			(at 0 0 90)
			(layer "F.SilkS")
			(hide yes)
			(effects
				(font
					(size 1.27 1.27)
				)
			)
		)
		(property "Value" "RB551V30-GP"
			(at 0 -6.7818 90)
			(unlocked yes)
			(layer "F.Fab")
			(hide yes)
			(effects
				(font
					(size 1.016 1.016)
					(thickness 0.1524)
				)
			)
		)
		(property "Device Type" "SOD323AKH38"
			(at 0 -8.6868 90)
			(unlocked yes)
			(layer "F.Fab")
			(hide yes)
			(effects
				(font
					(size 1.016 1.016)
					(thickness 0.1524)
				)
			)
		)
		(duplicate_pad_numbers_are_jumpers no)
		(fp_line
			(start 0.889 -1.9304)
			(end 0.889 2.159)
			(stroke
				(width 0.1524)
				(type default)
			)
			(layer "F.SilkS")
		)
		(fp_line
			(start -0.889 -1.9304)
			(end 0.889 -1.9304)
			(stroke
				(width 0.1524)
				(type default)
			)
			(layer "F.SilkS")
		)
		(fp_line
			(start 0.762 2.0574)
			(end -0.762 2.0574)
			(stroke
				(width 0.508)
				(type default)
			)
			(layer "F.SilkS")
		)
		(fp_line
			(start 0.889 2.159)
			(end -0.889 2.159)
			(stroke
				(width 0.1524)
				(type default)
			)
			(layer "F.SilkS")
		)
		(fp_line
			(start -0.889 2.159)
			(end -0.889 -1.9304)
			(stroke
				(width 0.1524)
				(type default)
			)
			(layer "F.SilkS")
		)
		(fp_rect
			(start -1.016 2.3114)
			(end 1.016 -2.0066)
			(stroke
				(width 0)
				(type default)
			)
			(fill no)
			(layer "F.CrtYd")
		)
		(fp_poly
			(pts
				(xy -1.016 -2.0066) (xy 1.016 -2.0066) (xy 1.016 2.3114) (xy -1.016 2.3114)
			)
			(stroke
				(width 0)
				(type default)
			)
			(fill no)
			(layer "F.Fab")
		)
		(pad "A" smd rect
			(at 0 -1.143 90)
			(size 0.5588 1.016)
			(layers "F.Cu" "F.Mask" "F.Paste")
			(net "SW_HDD_R7")
		)
		(pad "K" smd rect
			(at 0 1.143 90)
			(size 0.5588 1.016)
			(layers "F.Cu" "F.Mask" "F.Paste")
			(net "SW_HDD_N7")
		)
	)
	(footprint ""
		(layer "F.Cu")
		(at 77.942948 -169.523918 90)
		(property "Reference" "C231"
			(at 0 0 90)
			(layer "F.SilkS")
			(hide yes)
			(effects
				(font
					(size 1.27 1.27)
				)
			)
		)
		(property "Value" "SCD033U25V2KX-GP"
			(at 1.1811 -2.7051 90)
			(unlocked yes)
			(layer "F.Fab")
			(hide yes)
			(effects
				(font
					(size 1.016 1.016)
					(thickness 0.1524)
				)
			)
		)
		(property "Device Type" "C402H22"
			(at 1.1811 -4.2291 90)
			(unlocked yes)
			(layer "F.Fab")
			(hide yes)
			(effects
				(font
					(size 1.016 1.016)
					(thickness 0.1524)
				)
			)
		)
		(duplicate_pad_numbers_are_jumpers no)
		(fp_rect
			(start -0.4318 0.9525)
			(end 0.4318 -0.9525)
			(stroke
				(width 0)
				(type default)
			)
			(fill no)
			(layer "F.CrtYd")
		)
		(fp_rect
			(start -0.4318 0.9525)
			(end 0.4318 -0.9525)
			(stroke
				(width 0)
				(type default)
			)
			(fill no)
			(layer "F.Fab")
		)
		(pad "1" smd custom
			(at 0 -0.4445 90)
			(size 0.1524 0.1524)
			(layers "F.Cu" "F.Mask" "F.Paste")
			(net "P12V_A")
			(options
				(clearance outline)
				(anchor circle)
			)
			(primitives
				(gr_poly
					(pts
						(arc
							(start 0.3048 -0.2032)
							(mid 0.275042 -0.275042)
							(end 0.2032 -0.3048)
						)
						(arc
							(start -0.2032 -0.3048)
							(mid -0.275042 -0.275042)
							(end -0.3048 -0.2032)
						)
						(arc
							(start -0.3048 0.2032)
							(mid -0.275042 0.275042)
							(end -0.2032 0.3048)
						)
						(arc
							(start 0.2032 0.3048)
							(mid 0.275042 0.275042)
							(end 0.3048 0.2032)
						)
					)
					(width 0)
					(fill yes)
				)
			)
		)
		(pad "2" smd custom
			(at 0 0.4445 90)
			(size 0.1524 0.1524)
			(layers "F.Cu" "F.Mask" "F.Paste")
			(net "SW_HDD_N14")
			(options
				(clearance outline)
				(anchor circle)
			)
			(primitives
				(gr_poly
					(pts
						(arc
							(start 0.3048 -0.2032)
							(mid 0.275042 -0.275042)
							(end 0.2032 -0.3048)
						)
						(arc
							(start -0.2032 -0.3048)
							(mid -0.275042 -0.275042)
							(end -0.3048 -0.2032)
						)
						(arc
							(start -0.3048 0.2032)
							(mid -0.275042 0.275042)
							(end -0.2032 0.3048)
						)
						(arc
							(start 0.2032 0.3048)
							(mid 0.275042 0.275042)
							(end 0.3048 0.2032)
						)
					)
					(width 0)
					(fill yes)
				)
			)
		)
	)
	(footprint ""
		(layer "F.Cu")
		(at 330.67498 -207.79994)
		(property "Reference" ""
			(at 0 0 0)
			(layer "F.SilkS")
			(hide yes)
			(effects
				(font
					(size 1.27 1.27)
				)
			)
		)
		(property "Value" "*"
			(at -8.398764 -8.057642 0)
			(unlocked yes)
			(layer "F.Fab")
			(hide yes)
			(effects
				(font
					(size 1.016 1.016)
					(thickness 0.1524)
				)
			)
		)
		(duplicate_pad_numbers_are_jumpers no)
		(fp_poly
			(pts
				(arc
					(start 7.3152 0)
					(mid 0 7.3152)
					(end -7.3152 0)
				)
				(arc
					(start -7.3152 -5.9944)
					(mid 0 -13.3096)
					(end 7.3152 -5.9944)
				)
			)
			(stroke
				(width 0)
				(type default)
			)
			(fill no)
			(layer "B.CrtYd")
		)
		(fp_poly
			(pts
				(arc
					(start 7.3152 0)
					(mid 0 7.3152)
					(end -7.3152 0)
				)
				(arc
					(start -7.3152 -5.9944)
					(mid 0 -13.3096)
					(end 7.3152 -5.9944)
				)
			)
			(stroke
				(width 0)
				(type default)
			)
			(fill no)
			(layer "F.CrtYd")
		)
		(fp_poly
			(pts
				(arc
					(start 7.3152 0)
					(mid 0 7.3152)
					(end -7.3152 0)
				)
				(arc
					(start -7.3152 -5.9944)
					(mid 0 -13.3096)
					(end 7.3152 -5.9944)
				)
			)
			(stroke
				(width 0)
				(type default)
			)
			(fill no)
			(layer "B.Fab")
		)
		(fp_poly
			(pts
				(arc
					(start 7.3152 0)
					(mid 0 7.3152)
					(end -7.3152 0)
				)
				(arc
					(start -7.3152 -5.9944)
					(mid 0 -13.3096)
					(end 7.3152 -5.9944)
				)
			)
			(stroke
				(width 0)
				(type default)
			)
			(fill no)
			(layer "F.Fab")
		)
		(pad "1" thru_hole oval
			(at 0 0)
			(size 14.0208 20.0152)
			(drill 0.0254
				(offset 0 -2.9972)
			)
			(layers "*.Cu" "*.Mask")
			(remove_unused_layers no)
			(net "Net_100")
			(clearance -1.002284)
			(thermal_gap 0.1524)
			(padstack
				(mode front_inner_back)
				(layer "Inner"
					(shape custom)
					(size 2.928012 2.928012)
					(options
						(anchor circle)
					)
					(primitives
						(gr_poly
							(pts
								(arc
									(start 4.571746 -2.084324)
									(mid 0.000333 7.430372)
									(end -4.571492 -2.084324)
								)
								(arc
									(start -4.571492 -2.084324)
									(mid -3.570296 -3.611977)
									(end -2.875026 -5.30098)
								)
								(arc
									(start -2.875026 -5.30098)
									(mid 0.000217 -7.43089)
									(end 2.87528 -5.30098)
								)
								(arc
									(start 2.87528 -5.30098)
									(mid 3.570511 -3.611956)
									(end 4.571746 -2.084324)
								)
							)
							(width 0)
							(fill yes)
						)
					)
					(clearance 0.1524)
				)
				(layer "B.Cu"
					(shape oval)
					(size 14.0208 20.0152)
					(offset 0 -2.9972)
					(clearance -1.002284)
				)
			)
		)
		(zone
			(layers "F.Cu" "B.Cu" "In1.Cu" "In2.Cu" "In3.Cu" "In4.Cu" "In5.Cu" "In6.Cu"
				"In7.Cu" "In8.Cu" "In9.Cu" "In10.Cu"
			)
			(hatch none 0.5)
			(connect_pads
				(clearance 0)
			)
			(min_thickness 0.25)
			(keepout
				(tracks not_allowed)
				(vias allowed)
				(pads allowed)
				(copperpour not_allowed)
				(footprints allowed)
			)
			(placement
				(enabled no)
				(sheetname "")
			)
			(fill
				(thermal_gap 0.5)
				(thermal_bridge_width 0.5)
				(island_removal_mode 0)
			)
			(polygon
				(pts
					(arc
						(start 323.66458 -213.79434)
						(mid 330.67498 -220.80474)
						(end 337.68538 -213.79434)
					)
					(arc
						(start 337.68538 -207.79994)
						(mid 330.67498 -200.78954)
						(end 323.66458 -207.79994)
					)
				)
			)
		)
	)
	(footprint ""
		(layer "F.Cu")
		(at 367.287302 -160.735518 180)
		(property "Reference" "R584"
			(at 0 0 180)
			(layer "F.SilkS")
			(hide yes)
			(effects
				(font
					(size 1.27 1.27)
				)
			)
		)
		(property "Value" "0R2J-2-GP"
			(at 0.064008 -3.993896 180)
			(unlocked yes)
			(layer "F.Fab")
			(hide yes)
			(effects
				(font
					(size 1.016 1.016)
					(thickness 0.1524)
				)
			)
		)
		(property "Device Type" "R402H16"
			(at 0.064008 -5.517896 180)
			(unlocked yes)
			(layer "F.Fab")
			(hide yes)
			(effects
				(font
					(size 1.016 1.016)
					(thickness 0.1524)
				)
			)
		)
		(duplicate_pad_numbers_are_jumpers no)
		(fp_line
			(start 0.508 -0.9398)
			(end -0.508 -0.9398)
			(stroke
				(width 0.1524)
				(type default)
			)
			(layer "F.SilkS")
		)
		(fp_line
			(start -0.508 -0.9398)
			(end -0.508 0.9398)
			(stroke
				(width 0.1524)
				(type default)
			)
			(layer "F.SilkS")
		)
		(fp_rect
			(start -0.508 0.9398)
			(end 0.508 -0.9398)
			(stroke
				(width 0)
				(type default)
			)
			(fill no)
			(layer "F.CrtYd")
		)
		(fp_rect
			(start -0.508 0.9398)
			(end 0.508 -0.9398)
			(stroke
				(width 0)
				(type default)
			)
			(fill no)
			(layer "F.Fab")
		)
		(pad "1" smd custom
			(at 0 -0.4445 180)
			(size 0.1397 0.1397)
			(layers "F.Cu" "F.Mask" "F.Paste")
			(net "SW_HDD_G19")
			(options
				(clearance outline)
				(anchor circle)
			)
			(primitives
				(gr_poly
					(pts
						(arc
							(start -0.1778 -0.2794)
							(mid -0.249642 -0.249642)
							(end -0.2794 -0.1778)
						)
						(arc
							(start -0.2794 0.1778)
							(mid -0.249642 0.249642)
							(end -0.1778 0.2794)
						)
						(arc
							(start 0.1778 0.2794)
							(mid 0.249642 0.249642)
							(end 0.2794 0.1778)
						)
						(arc
							(start 0.2794 -0.1778)
							(mid 0.249642 -0.249642)
							(end 0.1778 -0.2794)
						)
					)
					(width 0)
					(fill yes)
				)
			)
		)
		(pad "2" smd custom
			(at 0 0.4445 180)
			(size 0.1397 0.1397)
			(layers "F.Cu" "F.Mask" "F.Paste")
			(net "SW_HDD_R19")
			(options
				(clearance outline)
				(anchor circle)
			)
			(primitives
				(gr_poly
					(pts
						(arc
							(start -0.1778 -0.2794)
							(mid -0.249642 -0.249642)
							(end -0.2794 -0.1778)
						)
						(arc
							(start -0.2794 0.1778)
							(mid -0.249642 0.249642)
							(end -0.1778 0.2794)
						)
						(arc
							(start 0.1778 0.2794)
							(mid 0.249642 0.249642)
							(end 0.2794 0.1778)
						)
						(arc
							(start 0.2794 -0.1778)
							(mid 0.249642 -0.249642)
							(end 0.1778 -0.2794)
						)
					)
					(width 0)
					(fill yes)
				)
			)
		)
	)
	(footprint ""
		(layer "F.Cu")
		(at 20.430998 -292.778942 -90)
		(property "Reference" "C508"
			(at 0 0 270)
			(layer "F.SilkS")
			(hide yes)
			(effects
				(font
					(size 1.27 1.27)
				)
			)
		)
		(property "Value" "SC1U16V3KX-5GP"
			(at 0 -2.8194 270)
			(unlocked yes)
			(layer "F.Fab")
			(hide yes)
			(effects
				(font
					(size 1.016 1.016)
					(thickness 0.1524)
				)
			)
		)
		(property "Device Type" "C603H36"
			(at 0 -4.3434 270)
			(unlocked yes)
			(layer "F.Fab")
			(hide yes)
			(effects
				(font
					(size 1.016 1.016)
					(thickness 0.1524)
				)
			)
		)
		(duplicate_pad_numbers_are_jumpers no)
		(fp_line
			(start 0.508 0)
			(end -0.508 0)
			(stroke
				(width 0.2032)
				(type default)
			)
			(layer "F.SilkS")
		)
		(fp_rect
			(start -0.5842 1.3335)
			(end 0.5842 -1.3335)
			(stroke
				(width 0)
				(type default)
			)
			(fill no)
			(layer "F.CrtYd")
		)
		(fp_rect
			(start -0.5842 1.3335)
			(end 0.5842 -1.3335)
			(stroke
				(width 0)
				(type default)
			)
			(fill no)
			(layer "F.Fab")
		)
		(pad "1" smd custom
			(at 0 -0.762 270)
			(size 0.2159 0.2159)
			(layers "F.Cu" "F.Mask" "F.Paste")
			(net "P5V_HDD0")
			(options
				(clearance outline)
				(anchor circle)
			)
			(primitives
				(gr_poly
					(pts
						(arc
							(start -0.3302 -0.4318)
							(mid -0.402042 -0.402042)
							(end -0.4318 -0.3302)
						)
						(arc
							(start -0.4318 0.3302)
							(mid -0.402042 0.402042)
							(end -0.3302 0.4318)
						)
						(arc
							(start 0.3302 0.4318)
							(mid 0.402042 0.402042)
							(end 0.4318 0.3302)
						)
						(arc
							(start 0.4318 -0.3302)
							(mid 0.402042 -0.402042)
							(end 0.3302 -0.4318)
						)
					)
					(width 0)
					(fill yes)
				)
			)
		)
		(pad "2" smd custom
			(at 0 0.762 270)
			(size 0.2159 0.2159)
			(layers "F.Cu" "F.Mask" "F.Paste")
			(net "GND")
			(options
				(clearance outline)
				(anchor circle)
			)
			(primitives
				(gr_poly
					(pts
						(arc
							(start -0.3302 -0.4318)
							(mid -0.402042 -0.402042)
							(end -0.4318 -0.3302)
						)
						(arc
							(start -0.4318 0.3302)
							(mid -0.402042 0.402042)
							(end -0.3302 0.4318)
						)
						(arc
							(start 0.3302 0.4318)
							(mid 0.402042 0.402042)
							(end 0.4318 0.3302)
						)
						(arc
							(start 0.4318 -0.3302)
							(mid 0.402042 -0.402042)
							(end 0.3302 -0.4318)
						)
					)
					(width 0)
					(fill yes)
				)
			)
		)
	)
	(footprint ""
		(layer "F.Cu")
		(at 466.870796 -277.03653 180)
		(property "Reference" "R400"
			(at 0 0 180)
			(layer "F.SilkS")
			(hide yes)
			(effects
				(font
					(size 1.27 1.27)
				)
			)
		)
		(property "Value" "0R2J-2-GP"
			(at 0.064008 -3.993896 180)
			(unlocked yes)
			(layer "F.Fab")
			(hide yes)
			(effects
				(font
					(size 1.016 1.016)
					(thickness 0.1524)
				)
			)
		)
		(property "Device Type" "R402H16"
			(at 0.064008 -5.517896 180)
			(unlocked yes)
			(layer "F.Fab")
			(hide yes)
			(effects
				(font
					(size 1.016 1.016)
					(thickness 0.1524)
				)
			)
		)
		(duplicate_pad_numbers_are_jumpers no)
		(fp_line
			(start 0.508 -0.9398)
			(end -0.508 -0.9398)
			(stroke
				(width 0.1524)
				(type default)
			)
			(layer "F.SilkS")
		)
		(fp_line
			(start -0.508 -0.9398)
			(end -0.508 0.9398)
			(stroke
				(width 0.1524)
				(type default)
			)
			(layer "F.SilkS")
		)
		(fp_rect
			(start -0.508 0.9398)
			(end 0.508 -0.9398)
			(stroke
				(width 0)
				(type default)
			)
			(fill no)
			(layer "F.CrtYd")
		)
		(fp_rect
			(start -0.508 0.9398)
			(end 0.508 -0.9398)
			(stroke
				(width 0)
				(type default)
			)
			(fill no)
			(layer "F.Fab")
		)
		(pad "1" smd custom
			(at 0 -0.4445 180)
			(size 0.1397 0.1397)
			(layers "F.Cu" "F.Mask" "F.Paste")
			(net "SW_HDD_G11")
			(options
				(clearance outline)
				(anchor circle)
			)
			(primitives
				(gr_poly
					(pts
						(arc
							(start -0.1778 -0.2794)
							(mid -0.249642 -0.249642)
							(end -0.2794 -0.1778)
						)
						(arc
							(start -0.2794 0.1778)
							(mid -0.249642 0.249642)
							(end -0.1778 0.2794)
						)
						(arc
							(start 0.1778 0.2794)
							(mid 0.249642 0.249642)
							(end 0.2794 0.1778)
						)
						(arc
							(start 0.2794 -0.1778)
							(mid 0.249642 -0.249642)
							(end 0.1778 -0.2794)
						)
					)
					(width 0)
					(fill yes)
				)
			)
		)
		(pad "2" smd custom
			(at 0 0.4445 180)
			(size 0.1397 0.1397)
			(layers "F.Cu" "F.Mask" "F.Paste")
			(net "SW_HDD_R11")
			(options
				(clearance outline)
				(anchor circle)
			)
			(primitives
				(gr_poly
					(pts
						(arc
							(start -0.1778 -0.2794)
							(mid -0.249642 -0.249642)
							(end -0.2794 -0.1778)
						)
						(arc
							(start -0.2794 0.1778)
							(mid -0.249642 0.249642)
							(end -0.1778 0.2794)
						)
						(arc
							(start 0.1778 0.2794)
							(mid 0.249642 0.249642)
							(end 0.2794 0.1778)
						)
						(arc
							(start 0.2794 -0.1778)
							(mid 0.249642 -0.249642)
							(end 0.1778 -0.2794)
						)
					)
					(width 0)
					(fill yes)
				)
			)
		)
	)
	(footprint ""
		(layer "F.Cu")
		(at 426.120052 -176.127918 -90)
		(property "Reference" "R612"
			(at 0 0 270)
			(layer "F.SilkS")
			(hide yes)
			(effects
				(font
					(size 1.27 1.27)
				)
			)
		)
		(property "Value" "2R6F-GP"
			(at -0.0508 -4.8514 270)
			(unlocked yes)
			(layer "F.Fab")
			(hide yes)
			(effects
				(font
					(size 1.016 1.016)
					(thickness 0.1524)
				)
			)
		)
		(property "Device Type" "R1206H26"
			(at 0 -6.3754 270)
			(unlocked yes)
			(layer "F.Fab")
			(hide yes)
			(effects
				(font
					(size 1.016 1.016)
					(thickness 0.1524)
				)
			)
		)
		(duplicate_pad_numbers_are_jumpers no)
		(fp_line
			(start -1.016 2.2352)
			(end -1.016 -2.2352)
			(stroke
				(width 0.1524)
				(type default)
			)
			(layer "F.SilkS")
		)
		(fp_line
			(start 1.016 2.2352)
			(end -1.016 2.2352)
			(stroke
				(width 0.1524)
				(type default)
			)
			(layer "F.SilkS")
		)
		(fp_line
			(start -1.016 -2.2352)
			(end 1.016 -2.2352)
			(stroke
				(width 0.1524)
				(type default)
			)
			(layer "F.SilkS")
		)
		(fp_line
			(start 1.016 -2.2352)
			(end 1.016 2.2352)
			(stroke
				(width 0.1524)
				(type default)
			)
			(layer "F.SilkS")
		)
		(fp_rect
			(start -1.0922 2.3114)
			(end 1.0922 -2.3114)
			(stroke
				(width 0)
				(type default)
			)
			(fill no)
			(layer "F.CrtYd")
		)
		(fp_poly
			(pts
				(xy -1.0922 -2.3114) (xy 1.0922 -2.3114) (xy 1.0922 2.3114) (xy -1.0922 2.3114)
			)
			(stroke
				(width 0)
				(type default)
			)
			(fill no)
			(layer "F.Fab")
		)
		(pad "1" smd rect
			(at 0 -1.397 270)
			(size 1.651 1.27)
			(layers "F.Cu" "F.Mask" "F.Paste")
			(net "P5V_HDD21")
		)
		(pad "2" smd rect
			(at 0 1.397 270)
			(size 1.651 1.27)
			(layers "F.Cu" "F.Mask" "F.Paste")
			(net "5V_PRE_21")
		)
	)
	(footprint ""
		(layer "F.Cu")
		(at 224.572322 -129.51587 -90)
		(property "Reference" "TP204"
			(at 0 0 270)
			(layer "F.SilkS")
			(hide yes)
			(effects
				(font
					(size 1.27 1.27)
				)
			)
		)
		(property "Value" "TPAD32-GP"
			(at -0.0508 -1.6764 270)
			(unlocked yes)
			(layer "F.Fab")
			(hide yes)
			(effects
				(font
					(size 1.016 1.016)
					(thickness 0.1524)
				)
			)
		)
		(property "Device Type" "TPAD32"
			(at -0.0508 -3.2004 270)
			(unlocked yes)
			(layer "F.Fab")
			(hide yes)
			(effects
				(font
					(size 1.016 1.016)
					(thickness 0.1524)
				)
			)
		)
		(duplicate_pad_numbers_are_jumpers no)
		(fp_poly
			(pts
				(arc
					(start 0 -0.4064)
					(mid 0 0.4064)
					(end 0 -0.4064)
				)
			)
			(stroke
				(width 0)
				(type default)
			)
			(fill no)
			(layer "F.CrtYd")
		)
		(fp_poly
			(pts
				(arc
					(start 0 -0.7112)
					(mid 0 0.7112)
					(end 0 -0.7112)
				)
			)
			(stroke
				(width 0)
				(type default)
			)
			(fill no)
			(layer "F.Fab")
		)
		(pad "1" smd circle
			(at 0 0 270)
			(size 0.8128 0.8128)
			(layers "F.Cu" "F.Mask" "F.Paste")
			(net "TP_COMP_A_SATA_P0_TX_DN")
		)
	)
	(footprint ""
		(layer "F.Cu")
		(at 447.421 -183.007 -90)
		(property "Reference" "R636"
			(at 0 0 270)
			(layer "F.SilkS")
			(hide yes)
			(effects
				(font
					(size 1.27 1.27)
				)
			)
		)
		(property "Value" "10KR2F-2-GP"
			(at 0.064008 -3.993896 270)
			(unlocked yes)
			(layer "F.Fab")
			(hide yes)
			(effects
				(font
					(size 1.016 1.016)
					(thickness 0.1524)
				)
			)
		)
		(property "Device Type" "R402H16"
			(at 0.064008 -5.517896 270)
			(unlocked yes)
			(layer "F.Fab")
			(hide yes)
			(effects
				(font
					(size 1.016 1.016)
					(thickness 0.1524)
				)
			)
		)
		(duplicate_pad_numbers_are_jumpers no)
		(fp_line
			(start -0.508 -0.9398)
			(end -0.508 0.9398)
			(stroke
				(width 0.1524)
				(type default)
			)
			(layer "F.SilkS")
		)
		(fp_line
			(start 0.508 -0.9398)
			(end -0.508 -0.9398)
			(stroke
				(width 0.1524)
				(type default)
			)
			(layer "F.SilkS")
		)
		(fp_rect
			(start -0.508 0.9398)
			(end 0.508 -0.9398)
			(stroke
				(width 0)
				(type default)
			)
			(fill no)
			(layer "F.CrtYd")
		)
		(fp_rect
			(start -0.508 0.9398)
			(end 0.508 -0.9398)
			(stroke
				(width 0)
				(type default)
			)
			(fill no)
			(layer "F.Fab")
		)
		(pad "1" smd custom
			(at 0 -0.4445 270)
			(size 0.1397 0.1397)
			(layers "F.Cu" "F.Mask" "F.Paste")
			(net "P3V3_STBY_A")
			(options
				(clearance outline)
				(anchor circle)
			)
			(primitives
				(gr_poly
					(pts
						(arc
							(start -0.1778 -0.2794)
							(mid -0.249642 -0.249642)
							(end -0.2794 -0.1778)
						)
						(arc
							(start -0.2794 0.1778)
							(mid -0.249642 0.249642)
							(end -0.1778 0.2794)
						)
						(arc
							(start 0.1778 0.2794)
							(mid 0.249642 0.249642)
							(end 0.2794 0.1778)
						)
						(arc
							(start 0.2794 -0.1778)
							(mid 0.249642 -0.249642)
							(end 0.1778 -0.2794)
						)
					)
					(width 0)
					(fill yes)
				)
			)
		)
		(pad "2" smd custom
			(at 0 0.4445 270)
			(size 0.1397 0.1397)
			(layers "F.Cu" "F.Mask" "F.Paste")
			(net "HDD_PRSNT_22")
			(options
				(clearance outline)
				(anchor circle)
			)
			(primitives
				(gr_poly
					(pts
						(arc
							(start -0.1778 -0.2794)
							(mid -0.249642 -0.249642)
							(end -0.2794 -0.1778)
						)
						(arc
							(start -0.2794 0.1778)
							(mid -0.249642 0.249642)
							(end -0.1778 0.2794)
						)
						(arc
							(start 0.1778 0.2794)
							(mid 0.249642 0.249642)
							(end 0.2794 0.1778)
						)
						(arc
							(start 0.2794 -0.1778)
							(mid 0.249642 -0.249642)
							(end 0.1778 -0.2794)
						)
					)
					(width 0)
					(fill yes)
				)
			)
		)
	)
	(footprint ""
		(layer "F.Cu")
		(at 349.812102 -291.127942 -90)
		(property "Reference" "C136"
			(at 0 0 270)
			(layer "F.SilkS")
			(hide yes)
			(effects
				(font
					(size 1.27 1.27)
				)
			)
		)
		(property "Value" "SCD01U50V2KX-1GP"
			(at 1.1811 -2.7051 270)
			(unlocked yes)
			(layer "F.Fab")
			(hide yes)
			(effects
				(font
					(size 1.016 1.016)
					(thickness 0.1524)
				)
			)
		)
		(property "Device Type" "C402H22"
			(at 1.1811 -4.2291 270)
			(unlocked yes)
			(layer "F.Fab")
			(hide yes)
			(effects
				(font
					(size 1.016 1.016)
					(thickness 0.1524)
				)
			)
		)
		(duplicate_pad_numbers_are_jumpers no)
		(fp_rect
			(start -0.4318 0.9525)
			(end 0.4318 -0.9525)
			(stroke
				(width 0)
				(type default)
			)
			(fill no)
			(layer "F.CrtYd")
		)
		(fp_rect
			(start -0.4318 0.9525)
			(end 0.4318 -0.9525)
			(stroke
				(width 0)
				(type default)
			)
			(fill no)
			(layer "F.Fab")
		)
		(pad "1" smd custom
			(at 0 -0.4445 270)
			(size 0.1524 0.1524)
			(layers "F.Cu" "F.Mask" "F.Paste")
			(net "HDD_PRSNT_7")
			(options
				(clearance outline)
				(anchor circle)
			)
			(primitives
				(gr_poly
					(pts
						(arc
							(start 0.3048 -0.2032)
							(mid 0.275042 -0.275042)
							(end 0.2032 -0.3048)
						)
						(arc
							(start -0.2032 -0.3048)
							(mid -0.275042 -0.275042)
							(end -0.3048 -0.2032)
						)
						(arc
							(start -0.3048 0.2032)
							(mid -0.275042 0.275042)
							(end -0.2032 0.3048)
						)
						(arc
							(start 0.2032 0.3048)
							(mid 0.275042 0.275042)
							(end 0.3048 0.2032)
						)
					)
					(width 0)
					(fill yes)
				)
			)
		)
		(pad "2" smd custom
			(at 0 0.4445 270)
			(size 0.1524 0.1524)
			(layers "F.Cu" "F.Mask" "F.Paste")
			(net "GND")
			(options
				(clearance outline)
				(anchor circle)
			)
			(primitives
				(gr_poly
					(pts
						(arc
							(start 0.3048 -0.2032)
							(mid 0.275042 -0.275042)
							(end 0.2032 -0.3048)
						)
						(arc
							(start -0.2032 -0.3048)
							(mid -0.275042 -0.275042)
							(end -0.3048 -0.2032)
						)
						(arc
							(start -0.3048 0.2032)
							(mid -0.275042 0.275042)
							(end -0.2032 0.3048)
						)
						(arc
							(start 0.2032 0.3048)
							(mid 0.275042 0.275042)
							(end 0.3048 0.2032)
						)
					)
					(width 0)
					(fill yes)
				)
			)
		)
	)
	(footprint ""
		(layer "F.Cu")
		(at 86.924134 -16.94053 -90)
		(property "Reference" "U28"
			(at 0 0 270)
			(layer "F.SilkS")
			(hide yes)
			(effects
				(font
					(size 1.27 1.27)
				)
			)
		)
		(property "Value" "74LVC1G32DC-1GP"
			(at -2.3368 -8.6868 270)
			(unlocked yes)
			(layer "F.Fab")
			(hide yes)
			(effects
				(font
					(size 1.016 1.016)
					(thickness 0.1524)
				)
			)
		)
		(property "Device Type" "SC70-5H44"
			(at -2.3114 -10.414 270)
			(unlocked yes)
			(layer "F.Fab")
			(hide yes)
			(effects
				(font
					(size 1.016 1.016)
					(thickness 0.1524)
				)
			)
		)
		(duplicate_pad_numbers_are_jumpers no)
		(fp_line
			(start -1.27 1.7018)
			(end -1.27 -1.7018)
			(stroke
				(width 0.1524)
				(type default)
			)
			(layer "F.SilkS")
		)
		(fp_line
			(start 1.27 1.7018)
			(end -1.27 1.7018)
			(stroke
				(width 0.1524)
				(type default)
			)
			(layer "F.SilkS")
		)
		(fp_line
			(start -1.27 -1.7018)
			(end 1.27 -1.7018)
			(stroke
				(width 0.1524)
				(type default)
			)
			(layer "F.SilkS")
		)
		(fp_line
			(start 1.27 -1.7018)
			(end 1.27 1.7018)
			(stroke
				(width 0.1524)
				(type default)
			)
			(layer "F.SilkS")
		)
		(fp_line
			(start 0.6604 -1.8034)
			(end 1.3843 -1.8034)
			(stroke
				(width 0.3302)
				(type default)
			)
			(layer "F.SilkS")
		)
		(fp_line
			(start 1.3843 -1.8034)
			(end 1.3843 -1.1176)
			(stroke
				(width 0.3302)
				(type default)
			)
			(layer "F.SilkS")
		)
		(fp_rect
			(start -1.524 1.9558)
			(end 1.524 -1.9558)
			(stroke
				(width 0)
				(type default)
			)
			(fill no)
			(layer "F.CrtYd")
		)
		(fp_poly
			(pts
				(xy -1.524 -1.9558) (xy 1.524 -1.9558) (xy 1.524 1.9558) (xy -1.524 1.9558)
			)
			(stroke
				(width 0)
				(type default)
			)
			(fill no)
			(layer "F.Fab")
		)
		(pad "1" smd rect
			(at 0.65024 -0.8255 270)
			(size 0.4064 1.2192)
			(layers "F.Cu" "F.Mask" "F.Paste")
			(net "COMP_A_PRI_INS_N")
		)
		(pad "2" smd rect
			(at 0 -0.8255 270)
			(size 0.4064 1.2192)
			(layers "F.Cu" "F.Mask" "F.Paste")
			(net "COMP_A_SEC_INS_N")
		)
		(pad "3" smd rect
			(at -0.65024 -0.8255 270)
			(size 0.4064 1.2192)
			(layers "F.Cu" "F.Mask" "F.Paste")
			(net "GND")
		)
		(pad "4" smd rect
			(at -0.65024 0.8255 270)
			(size 0.4064 1.2192)
			(layers "F.Cu" "F.Mask" "F.Paste")
			(net "COMP_A_INS_N")
		)
		(pad "5" smd rect
			(at 0.65024 0.8255 270)
			(size 0.4064 1.2192)
			(layers "F.Cu" "F.Mask" "F.Paste")
			(net "P3V3_STBY_A")
		)
	)
	(footprint ""
		(layer "F.Cu")
		(at 127.399796 -290.061142 90)
		(property "Reference" "C84"
			(at 0 0 90)
			(layer "F.SilkS")
			(hide yes)
			(effects
				(font
					(size 1.27 1.27)
				)
			)
		)
		(property "Value" "SCD01U50V2KX-1GP"
			(at 1.1811 -2.7051 90)
			(unlocked yes)
			(layer "F.Fab")
			(hide yes)
			(effects
				(font
					(size 1.016 1.016)
					(thickness 0.1524)
				)
			)
		)
		(property "Device Type" "C402H22"
			(at 1.1811 -4.2291 90)
			(unlocked yes)
			(layer "F.Fab")
			(hide yes)
			(effects
				(font
					(size 1.016 1.016)
					(thickness 0.1524)
				)
			)
		)
		(duplicate_pad_numbers_are_jumpers no)
		(fp_rect
			(start -0.4318 0.9525)
			(end 0.4318 -0.9525)
			(stroke
				(width 0)
				(type default)
			)
			(fill no)
			(layer "F.CrtYd")
		)
		(fp_rect
			(start -0.4318 0.9525)
			(end 0.4318 -0.9525)
			(stroke
				(width 0)
				(type default)
			)
			(fill no)
			(layer "F.Fab")
		)
		(pad "1" smd custom
			(at 0 -0.4445 90)
			(size 0.1524 0.1524)
			(layers "F.Cu" "F.Mask" "F.Paste")
			(net "HDD_PRSNT_3")
			(options
				(clearance outline)
				(anchor circle)
			)
			(primitives
				(gr_poly
					(pts
						(arc
							(start 0.3048 -0.2032)
							(mid 0.275042 -0.275042)
							(end 0.2032 -0.3048)
						)
						(arc
							(start -0.2032 -0.3048)
							(mid -0.275042 -0.275042)
							(end -0.3048 -0.2032)
						)
						(arc
							(start -0.3048 0.2032)
							(mid -0.275042 0.275042)
							(end -0.2032 0.3048)
						)
						(arc
							(start 0.2032 0.3048)
							(mid 0.275042 0.275042)
							(end 0.3048 0.2032)
						)
					)
					(width 0)
					(fill yes)
				)
			)
		)
		(pad "2" smd custom
			(at 0 0.4445 90)
			(size 0.1524 0.1524)
			(layers "F.Cu" "F.Mask" "F.Paste")
			(net "GND")
			(options
				(clearance outline)
				(anchor circle)
			)
			(primitives
				(gr_poly
					(pts
						(arc
							(start 0.3048 -0.2032)
							(mid 0.275042 -0.275042)
							(end 0.2032 -0.3048)
						)
						(arc
							(start -0.2032 -0.3048)
							(mid -0.275042 -0.275042)
							(end -0.3048 -0.2032)
						)
						(arc
							(start -0.3048 0.2032)
							(mid -0.275042 0.275042)
							(end -0.2032 0.3048)
						)
						(arc
							(start 0.2032 0.3048)
							(mid 0.275042 0.275042)
							(end 0.3048 0.2032)
						)
					)
					(width 0)
					(fill yes)
				)
			)
		)
	)
	(footprint ""
		(layer "F.Cu")
		(at 426.755052 -160.252918 -90)
		(property "Reference" "Q127"
			(at 0 0 270)
			(layer "F.SilkS")
			(hide yes)
			(effects
				(font
					(size 1.27 1.27)
				)
			)
		)
		(property "Value" "2N7002KDW-GP"
			(at -2.3622 -8.2042 270)
			(unlocked yes)
			(layer "F.Fab")
			(hide yes)
			(effects
				(font
					(size 1.016 1.016)
					(thickness 0.1524)
				)
			)
		)
		(property "Device Type" "SOT-363H44"
			(at -2.3622 -10.1092 270)
			(unlocked yes)
			(layer "F.Fab")
			(hide yes)
			(effects
				(font
					(size 1.016 1.016)
					(thickness 0.1524)
				)
			)
		)
		(duplicate_pad_numbers_are_jumpers no)
		(fp_line
			(start -1.4478 1.7018)
			(end 1.4478 1.7018)
			(stroke
				(width 0.1524)
				(type default)
			)
			(layer "F.SilkS")
		)
		(fp_line
			(start 1.4478 1.7018)
			(end 1.4478 -1.7018)
			(stroke
				(width 0.1524)
				(type default)
			)
			(layer "F.SilkS")
		)
		(fp_line
			(start -1.27 1.524)
			(end -1.27 0.6604)
			(stroke
				(width 0.4826)
				(type default)
			)
			(layer "F.SilkS")
		)
		(fp_line
			(start -1.4478 -1.7018)
			(end -1.4478 1.7018)
			(stroke
				(width 0.1524)
				(type default)
			)
			(layer "F.SilkS")
		)
		(fp_line
			(start 1.4478 -1.7018)
			(end -1.4478 -1.7018)
			(stroke
				(width 0.1524)
				(type default)
			)
			(layer "F.SilkS")
		)
		(fp_poly
			(pts
				(xy -1.524 -1.778) (xy 1.524 -1.778) (xy 1.524 1.778) (xy -1.524 1.778)
			)
			(stroke
				(width 0)
				(type default)
			)
			(fill no)
			(layer "F.CrtYd")
		)
		(fp_poly
			(pts
				(xy -1.524 -1.778) (xy 1.524 -1.778) (xy 1.524 1.778) (xy -1.524 1.778)
			)
			(stroke
				(width 0)
				(type default)
			)
			(fill no)
			(layer "F.Fab")
		)
		(pad "1" smd rect
			(at -0.65024 0.9398 270)
			(size 0.4064 1.016)
			(layers "F.Cu" "F.Mask" "F.Paste")
			(net "GND")
		)
		(pad "2" smd rect
			(at 0 0.9398 270)
			(size 0.4064 1.016)
			(layers "F.Cu" "F.Mask" "F.Paste")
			(net "SW_PWR_R_HDD21")
		)
		(pad "3" smd rect
			(at 0.65024 0.9398 270)
			(size 0.4064 1.016)
			(layers "F.Cu" "F.Mask" "F.Paste")
			(net "SW_HDD_P21")
		)
		(pad "4" smd rect
			(at 0.65024 -0.9398 270)
			(size 0.4064 1.016)
			(layers "F.Cu" "F.Mask" "F.Paste")
			(net "GND")
		)
		(pad "5" smd rect
			(at 0 -0.9398 270)
			(size 0.4064 1.016)
			(layers "F.Cu" "F.Mask" "F.Paste")
			(net "SW_HDD_G21")
		)
		(pad "6" smd rect
			(at -0.65024 -0.9398 270)
			(size 0.4064 1.016)
			(layers "F.Cu" "F.Mask" "F.Paste")
			(net "SW_HDD_R21")
		)
	)
	(footprint ""
		(layer "F.Cu")
		(at 20.684998 -285.285942 180)
		(property "Reference" "Q215"
			(at 0 0 180)
			(layer "F.SilkS")
			(hide yes)
			(effects
				(font
					(size 1.27 1.27)
				)
			)
		)
		(property "Value" "AO4406AL-GP"
			(at -3.707384 -1.5367 180)
			(unlocked yes)
			(layer "F.Fab")
			(hide yes)
			(effects
				(font
					(size 1.016 1.016)
					(thickness 0.1524)
				)
			)
		)
		(property "Device Type" "SOIC8H69"
			(at -3.707384 -3.0607 180)
			(unlocked yes)
			(layer "F.Fab")
			(hide yes)
			(effects
				(font
					(size 1.016 1.016)
					(thickness 0.1524)
				)
			)
		)
		(duplicate_pad_numbers_are_jumpers no)
		(fp_line
			(start 2.1336 1.4224)
			(end 2.1336 -1.4224)
			(stroke
				(width 0.1524)
				(type default)
			)
			(layer "F.SilkS")
		)
		(fp_line
			(start 2.1336 -1.4224)
			(end -2.7432 -1.4224)
			(stroke
				(width 0.1524)
				(type default)
			)
			(layer "F.SilkS")
		)
		(fp_line
			(start -2.1844 -0.0508)
			(end -2.7178 0.508)
			(stroke
				(width 0.1524)
				(type default)
			)
			(layer "F.SilkS")
		)
		(fp_line
			(start -2.6289 3.4417)
			(end -2.6289 1.4732)
			(stroke
				(width 0.381)
				(type default)
			)
			(layer "F.SilkS")
		)
		(fp_line
			(start -2.7178 -0.508)
			(end -2.1844 -0.0508)
			(stroke
				(width 0.1524)
				(type default)
			)
			(layer "F.SilkS")
		)
		(fp_line
			(start -2.7432 1.4224)
			(end 2.1336 1.4224)
			(stroke
				(width 0.1524)
				(type default)
			)
			(layer "F.SilkS")
		)
		(fp_line
			(start -2.7432 1.4224)
			(end -2.6416 1.4224)
			(stroke
				(width 0.1524)
				(type default)
			)
			(layer "F.SilkS")
		)
		(fp_line
			(start -2.7432 -1.4224)
			(end -2.7432 1.4224)
			(stroke
				(width 0.1524)
				(type default)
			)
			(layer "F.SilkS")
		)
		(fp_poly
			(pts
				(xy -2.2098 -1.4224) (xy -2.2098 1.4224) (xy 2.2098 1.4224) (xy 2.2098 -1.4224)
			)
			(stroke
				(width 0)
				(type default)
			)
			(fill yes)
			(layer "F.SilkS")
		)
		(fp_rect
			(start -2.450084 2.999994)
			(end 2.450084 -2.999994)
			(stroke
				(width 0)
				(type default)
			)
			(fill no)
			(layer "F.CrtYd")
		)
		(fp_poly
			(pts
				(xy -2.8194 3.6322) (xy -2.8194 -3.6322) (xy 2.8194 -3.6322) (xy 2.8194 1.18364) (xy 2.450084 1.18364)
				(xy 2.450084 -2.999994) (xy -2.450084 -2.999994) (xy -2.450084 2.999994) (xy 2.450084 2.999994)
				(xy 2.450084 1.18618) (xy 2.8194 1.18618) (xy 2.8194 3.6322)
			)
			(stroke
				(width 0)
				(type default)
			)
			(fill no)
			(layer "F.CrtYd")
		)
		(fp_rect
			(start -2.8194 3.6322)
			(end 2.8194 -3.6322)
			(stroke
				(width 0)
				(type default)
			)
			(fill no)
			(layer "F.Fab")
		)
		(pad "1" smd rect
			(at -1.905 2.54 180)
			(size 0.635 1.651)
			(layers "F.Cu" "F.Mask" "F.Paste")
			(net "P5V_HDD0")
		)
		(pad "2" smd rect
			(at -0.635 2.54 180)
			(size 0.635 1.651)
			(layers "F.Cu" "F.Mask" "F.Paste")
			(net "P5V_HDD0")
		)
		(pad "3" smd rect
			(at 0.635 2.54 180)
			(size 0.635 1.651)
			(layers "F.Cu" "F.Mask" "F.Paste")
			(net "P5V_HDD0")
		)
		(pad "4" smd rect
			(at 1.905 2.54 180)
			(size 0.635 1.651)
			(layers "F.Cu" "F.Mask" "F.Paste")
			(net "SW_HDD_P0")
		)
		(pad "5" smd rect
			(at 1.905 -2.54 180)
			(size 0.635 1.651)
			(layers "F.Cu" "F.Mask" "F.Paste")
			(net "P5V_A_1")
		)
		(pad "6" smd rect
			(at 0.635 -2.54 180)
			(size 0.635 1.651)
			(layers "F.Cu" "F.Mask" "F.Paste")
			(net "P5V_A_1")
		)
		(pad "7" smd rect
			(at -0.635 -2.54 180)
			(size 0.635 1.651)
			(layers "F.Cu" "F.Mask" "F.Paste")
			(net "P5V_A_1")
		)
		(pad "8" smd rect
			(at -1.905 -2.54 180)
			(size 0.635 1.651)
			(layers "F.Cu" "F.Mask" "F.Paste")
			(net "P5V_A_1")
		)
	)
	(footprint ""
		(layer "F.Cu")
		(at 144.700498 -45.633894)
		(property "Reference" "R791"
			(at 0 0 0)
			(layer "F.SilkS")
			(hide yes)
			(effects
				(font
					(size 1.27 1.27)
				)
			)
		)
		(property "Value" "0R2J-2-GP"
			(at 0.064008 -3.993896 0)
			(unlocked yes)
			(layer "F.Fab")
			(hide yes)
			(effects
				(font
					(size 1.016 1.016)
					(thickness 0.1524)
				)
			)
		)
		(property "Device Type" "R402H16"
			(at 0.064008 -5.517896 0)
			(unlocked yes)
			(layer "F.Fab")
			(hide yes)
			(effects
				(font
					(size 1.016 1.016)
					(thickness 0.1524)
				)
			)
		)
		(duplicate_pad_numbers_are_jumpers no)
		(fp_line
			(start -0.508 -0.9398)
			(end -0.508 0.9398)
			(stroke
				(width 0.1524)
				(type default)
			)
			(layer "F.SilkS")
		)
		(fp_line
			(start 0.508 -0.9398)
			(end -0.508 -0.9398)
			(stroke
				(width 0.1524)
				(type default)
			)
			(layer "F.SilkS")
		)
		(fp_rect
			(start -0.508 0.9398)
			(end 0.508 -0.9398)
			(stroke
				(width 0)
				(type default)
			)
			(fill no)
			(layer "F.CrtYd")
		)
		(fp_rect
			(start -0.508 0.9398)
			(end 0.508 -0.9398)
			(stroke
				(width 0)
				(type default)
			)
			(fill no)
			(layer "F.Fab")
		)
		(pad "1" smd custom
			(at 0 -0.4445)
			(size 0.1397 0.1397)
			(layers "F.Cu" "F.Mask" "F.Paste")
			(net "SW_HDD_G28")
			(options
				(clearance outline)
				(anchor circle)
			)
			(primitives
				(gr_poly
					(pts
						(arc
							(start -0.1778 -0.2794)
							(mid -0.249642 -0.249642)
							(end -0.2794 -0.1778)
						)
						(arc
							(start -0.2794 0.1778)
							(mid -0.249642 0.249642)
							(end -0.1778 0.2794)
						)
						(arc
							(start 0.1778 0.2794)
							(mid 0.249642 0.249642)
							(end 0.2794 0.1778)
						)
						(arc
							(start 0.2794 -0.1778)
							(mid 0.249642 -0.249642)
							(end 0.1778 -0.2794)
						)
					)
					(width 0)
					(fill yes)
				)
			)
		)
		(pad "2" smd custom
			(at 0 0.4445)
			(size 0.1397 0.1397)
			(layers "F.Cu" "F.Mask" "F.Paste")
			(net "SW_HDD_R28")
			(options
				(clearance outline)
				(anchor circle)
			)
			(primitives
				(gr_poly
					(pts
						(arc
							(start -0.1778 -0.2794)
							(mid -0.249642 -0.249642)
							(end -0.2794 -0.1778)
						)
						(arc
							(start -0.2794 0.1778)
							(mid -0.249642 0.249642)
							(end -0.1778 0.2794)
						)
						(arc
							(start 0.1778 0.2794)
							(mid 0.249642 0.249642)
							(end 0.2794 0.1778)
						)
						(arc
							(start 0.2794 -0.1778)
							(mid 0.249642 -0.249642)
							(end 0.1778 -0.2794)
						)
					)
					(width 0)
					(fill yes)
				)
			)
		)
	)
	(footprint ""
		(layer "F.Cu")
		(at 443.848744 -245.278656 -90)
		(property "Reference" "R494"
			(at 0 0 270)
			(layer "F.SilkS")
			(hide yes)
			(effects
				(font
					(size 1.27 1.27)
				)
			)
		)
		(property "Value" "4K7R2J-2-GP"
			(at 0.064008 -3.993896 270)
			(unlocked yes)
			(layer "F.Fab")
			(hide yes)
			(effects
				(font
					(size 1.016 1.016)
					(thickness 0.1524)
				)
			)
		)
		(property "Device Type" "R402H16"
			(at 0.064008 -5.517896 270)
			(unlocked yes)
			(layer "F.Fab")
			(hide yes)
			(effects
				(font
					(size 1.016 1.016)
					(thickness 0.1524)
				)
			)
		)
		(duplicate_pad_numbers_are_jumpers no)
		(fp_line
			(start -0.508 -0.9398)
			(end -0.508 0.9398)
			(stroke
				(width 0.1524)
				(type default)
			)
			(layer "F.SilkS")
		)
		(fp_line
			(start 0.508 -0.9398)
			(end -0.508 -0.9398)
			(stroke
				(width 0.1524)
				(type default)
			)
			(layer "F.SilkS")
		)
		(fp_rect
			(start -0.508 0.9398)
			(end 0.508 -0.9398)
			(stroke
				(width 0)
				(type default)
			)
			(fill no)
			(layer "F.CrtYd")
		)
		(fp_rect
			(start -0.508 0.9398)
			(end 0.508 -0.9398)
			(stroke
				(width 0)
				(type default)
			)
			(fill no)
			(layer "F.Fab")
		)
		(pad "1" smd custom
			(at 0 -0.4445 270)
			(size 0.1397 0.1397)
			(layers "F.Cu" "F.Mask" "F.Paste")
			(net "DRIVE_A_10_ACT")
			(options
				(clearance outline)
				(anchor circle)
			)
			(primitives
				(gr_poly
					(pts
						(arc
							(start -0.1778 -0.2794)
							(mid -0.249642 -0.249642)
							(end -0.2794 -0.1778)
						)
						(arc
							(start -0.2794 0.1778)
							(mid -0.249642 0.249642)
							(end -0.1778 0.2794)
						)
						(arc
							(start 0.1778 0.2794)
							(mid 0.249642 0.249642)
							(end 0.2794 0.1778)
						)
						(arc
							(start 0.2794 -0.1778)
							(mid 0.249642 -0.249642)
							(end 0.1778 -0.2794)
						)
					)
					(width 0)
					(fill yes)
				)
			)
		)
		(pad "2" smd custom
			(at 0 0.4445 270)
			(size 0.1397 0.1397)
			(layers "F.Cu" "F.Mask" "F.Paste")
			(net "GND")
			(options
				(clearance outline)
				(anchor circle)
			)
			(primitives
				(gr_poly
					(pts
						(arc
							(start -0.1778 -0.2794)
							(mid -0.249642 -0.249642)
							(end -0.2794 -0.1778)
						)
						(arc
							(start -0.2794 0.1778)
							(mid -0.249642 0.249642)
							(end -0.1778 0.2794)
						)
						(arc
							(start 0.1778 0.2794)
							(mid 0.249642 0.249642)
							(end 0.2794 0.1778)
						)
						(arc
							(start 0.2794 -0.1778)
							(mid 0.249642 -0.249642)
							(end 0.1778 -0.2794)
						)
					)
					(width 0)
					(fill yes)
				)
			)
		)
	)
	(footprint ""
		(layer "F.Cu")
		(at 335.788 -275.735542 180)
		(property "Reference" "R285"
			(at 0 0 180)
			(layer "F.SilkS")
			(hide yes)
			(effects
				(font
					(size 1.27 1.27)
				)
			)
		)
		(property "Value" "0R2J-2-GP"
			(at 0.064008 -3.993896 180)
			(unlocked yes)
			(layer "F.Fab")
			(hide yes)
			(effects
				(font
					(size 1.016 1.016)
					(thickness 0.1524)
				)
			)
		)
		(property "Device Type" "R402H16"
			(at 0.064008 -5.517896 180)
			(unlocked yes)
			(layer "F.Fab")
			(hide yes)
			(effects
				(font
					(size 1.016 1.016)
					(thickness 0.1524)
				)
			)
		)
		(duplicate_pad_numbers_are_jumpers no)
		(fp_line
			(start 0.508 -0.9398)
			(end -0.508 -0.9398)
			(stroke
				(width 0.1524)
				(type default)
			)
			(layer "F.SilkS")
		)
		(fp_line
			(start -0.508 -0.9398)
			(end -0.508 0.9398)
			(stroke
				(width 0.1524)
				(type default)
			)
			(layer "F.SilkS")
		)
		(fp_rect
			(start -0.508 0.9398)
			(end 0.508 -0.9398)
			(stroke
				(width 0)
				(type default)
			)
			(fill no)
			(layer "F.CrtYd")
		)
		(fp_rect
			(start -0.508 0.9398)
			(end 0.508 -0.9398)
			(stroke
				(width 0)
				(type default)
			)
			(fill no)
			(layer "F.Fab")
		)
		(pad "1" smd custom
			(at 0 -0.4445 180)
			(size 0.1397 0.1397)
			(layers "F.Cu" "F.Mask" "F.Paste")
			(net "SW_HDD_G6")
			(options
				(clearance outline)
				(anchor circle)
			)
			(primitives
				(gr_poly
					(pts
						(arc
							(start -0.1778 -0.2794)
							(mid -0.249642 -0.249642)
							(end -0.2794 -0.1778)
						)
						(arc
							(start -0.2794 0.1778)
							(mid -0.249642 0.249642)
							(end -0.1778 0.2794)
						)
						(arc
							(start 0.1778 0.2794)
							(mid 0.249642 0.249642)
							(end 0.2794 0.1778)
						)
						(arc
							(start 0.2794 -0.1778)
							(mid 0.249642 -0.249642)
							(end 0.1778 -0.2794)
						)
					)
					(width 0)
					(fill yes)
				)
			)
		)
		(pad "2" smd custom
			(at 0 0.4445 180)
			(size 0.1397 0.1397)
			(layers "F.Cu" "F.Mask" "F.Paste")
			(net "SW_HDD_R6")
			(options
				(clearance outline)
				(anchor circle)
			)
			(primitives
				(gr_poly
					(pts
						(arc
							(start -0.1778 -0.2794)
							(mid -0.249642 -0.249642)
							(end -0.2794 -0.1778)
						)
						(arc
							(start -0.2794 0.1778)
							(mid -0.249642 0.249642)
							(end -0.1778 0.2794)
						)
						(arc
							(start 0.1778 0.2794)
							(mid 0.249642 0.249642)
							(end 0.2794 0.1778)
						)
						(arc
							(start 0.2794 -0.1778)
							(mid 0.249642 -0.249642)
							(end 0.1778 -0.2794)
						)
					)
					(width 0)
					(fill yes)
				)
			)
		)
	)
	(footprint ""
		(layer "F.Cu")
		(at 378.249942 -94.400116)
		(property "Reference" "FLED21"
			(at 0 0 0)
			(layer "F.SilkS")
			(hide yes)
			(effects
				(font
					(size 1.27 1.27)
				)
			)
		)
		(property "Value" "LED-BY-19-GP"
			(at -2.132076 1.414018 0)
			(unlocked yes)
			(layer "F.Fab")
			(hide yes)
			(effects
				(font
					(size 1.016 1.016)
					(thickness 0.1524)
				)
			)
		)
		(property "Device Type" "LED-1615-4PH26"
			(at -2.132076 -0.109982 0)
			(unlocked yes)
			(layer "F.Fab")
			(hide yes)
			(effects
				(font
					(size 1.016 1.016)
					(thickness 0.1524)
				)
			)
		)
		(duplicate_pad_numbers_are_jumpers no)
		(fp_line
			(start -1.2954 0.254)
			(end -1.2954 1.6002)
			(stroke
				(width 0.508)
				(type default)
			)
			(layer "F.SilkS")
		)
		(fp_line
			(start -1.2954 1.6002)
			(end 1.2954 1.6002)
			(stroke
				(width 0.508)
				(type default)
			)
			(layer "F.SilkS")
		)
		(fp_line
			(start -1.1176 -1.4224)
			(end 1.1176 -1.4224)
			(stroke
				(width 0.1524)
				(type default)
			)
			(layer "F.SilkS")
		)
		(fp_line
			(start -1.1176 1.4224)
			(end -1.1176 -1.4224)
			(stroke
				(width 0.1524)
				(type default)
			)
			(layer "F.SilkS")
		)
		(fp_line
			(start 1.1176 -1.4224)
			(end 1.1176 1.4224)
			(stroke
				(width 0.1524)
				(type default)
			)
			(layer "F.SilkS")
		)
		(fp_line
			(start 1.1176 1.4224)
			(end -1.1176 1.4224)
			(stroke
				(width 0.1524)
				(type default)
			)
			(layer "F.SilkS")
		)
		(fp_line
			(start 1.2954 1.6002)
			(end 1.2954 0.254)
			(stroke
				(width 0.508)
				(type default)
			)
			(layer "F.SilkS")
		)
		(fp_rect
			(start -0.7493 0.8001)
			(end 0.7493 -0.8001)
			(stroke
				(width 0)
				(type default)
			)
			(fill no)
			(layer "F.CrtYd")
		)
		(fp_poly
			(pts
				(xy -1.3716 1.6764) (xy -1.3716 -1.6764) (xy 1.3716 -1.6764) (xy 1.3716 0.0635) (xy 0.7493 0.0635)
				(xy 0.7493 -0.8001) (xy -0.7493 -0.8001) (xy -0.7493 0.8001) (xy 0.7493 0.8001) (xy 0.7493 0.0762)
				(xy 1.3716 0.0762) (xy 1.3716 1.6764)
			)
			(stroke
				(width 0)
				(type default)
			)
			(fill no)
			(layer "F.CrtYd")
		)
		(fp_rect
			(start -1.3716 1.6764)
			(end 1.3716 -1.6764)
			(stroke
				(width 0)
				(type default)
			)
			(fill no)
			(layer "F.Fab")
		)
		(pad "1" smd rect
			(at 0.50038 -0.73025)
			(size 0.7112 0.8636)
			(layers "F.Cu" "F.Mask" "F.Paste")
			(net "DRV_ACT_20")
		)
		(pad "2" smd rect
			(at -0.50038 -0.73025)
			(size 0.7112 0.8636)
			(layers "F.Cu" "F.Mask" "F.Paste")
			(net "FLT_HDD20")
		)
		(pad "3" smd rect
			(at 0.50038 0.73025)
			(size 0.7112 0.8636)
			(layers "F.Cu" "F.Mask" "F.Paste")
			(net "DRV_ACT_20_N")
		)
		(pad "4" smd rect
			(at -0.50038 0.73025)
			(size 0.7112 0.8636)
			(layers "F.Cu" "F.Mask" "F.Paste")
			(net "FLT_HDD20_N")
		)
	)
	(footprint ""
		(layer "F.Cu")
		(at 377.594876 -242.25377)
		(property "Reference" "R247"
			(at 0 0 0)
			(layer "F.SilkS")
			(hide yes)
			(effects
				(font
					(size 1.27 1.27)
				)
			)
		)
		(property "Value" "130R3F-GP"
			(at -0.0254 -2.5146 0)
			(unlocked yes)
			(layer "F.Fab")
			(hide yes)
			(effects
				(font
					(size 1.016 1.016)
					(thickness 0.1524)
				)
			)
		)
		(property "Device Type" "R603H22"
			(at -0.0254 -4.0386 0)
			(unlocked yes)
			(layer "F.Fab")
			(hide yes)
			(effects
				(font
					(size 1.016 1.016)
					(thickness 0.1524)
				)
			)
		)
		(duplicate_pad_numbers_are_jumpers no)
		(fp_line
			(start -0.4826 0)
			(end -0.2032 0)
			(stroke
				(width 0.2032)
				(type default)
			)
			(layer "F.SilkS")
		)
		(fp_line
			(start 0.2032 0)
			(end 0.4826 0)
			(stroke
				(width 0.2032)
				(type default)
			)
			(layer "F.SilkS")
		)
		(fp_rect
			(start -0.5842 1.3335)
			(end 0.5842 -1.3335)
			(stroke
				(width 0)
				(type default)
			)
			(fill no)
			(layer "F.CrtYd")
		)
		(fp_rect
			(start -0.5842 1.3335)
			(end 0.5842 -1.3335)
			(stroke
				(width 0)
				(type default)
			)
			(fill no)
			(layer "F.Fab")
		)
		(pad "1" smd custom
			(at 0 -0.762)
			(size 0.2159 0.2159)
			(layers "F.Cu" "F.Mask" "F.Paste")
			(net "P5V_A_3")
			(options
				(clearance outline)
				(anchor circle)
			)
			(primitives
				(gr_poly
					(pts
						(arc
							(start -0.3302 -0.4318)
							(mid -0.402042 -0.402042)
							(end -0.4318 -0.3302)
						)
						(arc
							(start -0.4318 0.3302)
							(mid -0.402042 0.402042)
							(end -0.3302 0.4318)
						)
						(arc
							(start 0.3302 0.4318)
							(mid 0.402042 0.402042)
							(end 0.4318 0.3302)
						)
						(arc
							(start 0.4318 -0.3302)
							(mid 0.402042 -0.402042)
							(end 0.3302 -0.4318)
						)
					)
					(width 0)
					(fill yes)
				)
			)
		)
		(pad "2" smd custom
			(at 0 0.762)
			(size 0.2159 0.2159)
			(layers "F.Cu" "F.Mask" "F.Paste")
			(net "FLT_HDD8")
			(options
				(clearance outline)
				(anchor circle)
			)
			(primitives
				(gr_poly
					(pts
						(arc
							(start -0.3302 -0.4318)
							(mid -0.402042 -0.402042)
							(end -0.4318 -0.3302)
						)
						(arc
							(start -0.4318 0.3302)
							(mid -0.402042 0.402042)
							(end -0.3302 0.4318)
						)
						(arc
							(start 0.3302 0.4318)
							(mid 0.402042 0.402042)
							(end 0.4318 0.3302)
						)
						(arc
							(start 0.4318 -0.3302)
							(mid 0.402042 -0.402042)
							(end 0.3302 -0.4318)
						)
					)
					(width 0)
					(fill yes)
				)
			)
		)
	)
	(footprint ""
		(layer "F.Cu")
		(at 315.016388 -242.745768 180)
		(property "Reference" "Q269"
			(at 0 0 180)
			(layer "F.SilkS")
			(hide yes)
			(effects
				(font
					(size 1.27 1.27)
				)
			)
		)
		(property "Value" "SSM3K324R-GP"
			(at 0.127 -8.9662 180)
			(unlocked yes)
			(layer "F.Fab")
			(hide yes)
			(effects
				(font
					(size 1.016 1.016)
					(thickness 0.1524)
				)
			)
		)
		(property "Device Type" "SOT23DGS2D4H35"
			(at 0.127 -10.4902 180)
			(unlocked yes)
			(layer "F.Fab")
			(hide yes)
			(effects
				(font
					(size 1.016 1.016)
					(thickness 0.1524)
				)
			)
		)
		(duplicate_pad_numbers_are_jumpers no)
		(fp_line
			(start 1.651 1.778)
			(end 1.651 -1.778)
			(stroke
				(width 0.1524)
				(type default)
			)
			(layer "F.SilkS")
		)
		(fp_line
			(start 1.651 -1.778)
			(end -1.651 -1.778)
			(stroke
				(width 0.1524)
				(type default)
			)
			(layer "F.SilkS")
		)
		(fp_line
			(start -1.651 1.778)
			(end 1.651 1.778)
			(stroke
				(width 0.1524)
				(type default)
			)
			(layer "F.SilkS")
		)
		(fp_line
			(start -1.651 -1.778)
			(end -1.651 1.778)
			(stroke
				(width 0.1524)
				(type default)
			)
			(layer "F.SilkS")
		)
		(fp_poly
			(pts
				(xy -1.778 1.8796) (xy -1.778 -1.8796) (xy 1.778 -1.8796) (xy 1.778 1.8796)
			)
			(stroke
				(width 0)
				(type default)
			)
			(fill no)
			(layer "F.CrtYd")
		)
		(fp_poly
			(pts
				(xy -1.778 1.8796) (xy -1.778 -1.8796) (xy 1.778 -1.8796) (xy 1.778 1.8796)
			)
			(stroke
				(width 0)
				(type default)
			)
			(fill no)
			(layer "F.Fab")
		)
		(pad "D" smd custom
			(at 0 -0.9525 180)
			(size 0.1905 0.1905)
			(layers "F.Cu" "F.Mask" "F.Paste")
			(net "DRV_ACT_6_N")
			(options
				(clearance outline)
				(anchor circle)
			)
			(primitives
				(gr_poly
					(pts
						(arc
							(start -0.1778 0.5715)
							(mid -0.321484 0.511984)
							(end -0.381 0.3683)
						)
						(arc
							(start -0.381 -0.3683)
							(mid -0.321484 -0.511984)
							(end -0.1778 -0.5715)
						)
						(arc
							(start 0.1778 -0.5715)
							(mid 0.321484 -0.511984)
							(end 0.381 -0.3683)
						)
						(arc
							(start 0.381 0.3683)
							(mid 0.321484 0.511984)
							(end 0.1778 0.5715)
						)
					)
					(width 0)
					(fill yes)
				)
			)
		)
		(pad "G" smd custom
			(at -0.98425 0.9525 180)
			(size 0.1905 0.1905)
			(layers "F.Cu" "F.Mask" "F.Paste")
			(net "DRIVE_A_6_ACT")
			(options
				(clearance outline)
				(anchor circle)
			)
			(primitives
				(gr_poly
					(pts
						(arc
							(start -0.1778 0.5715)
							(mid -0.321484 0.511984)
							(end -0.381 0.3683)
						)
						(arc
							(start -0.381 -0.3683)
							(mid -0.321484 -0.511984)
							(end -0.1778 -0.5715)
						)
						(arc
							(start 0.1778 -0.5715)
							(mid 0.321484 -0.511984)
							(end 0.381 -0.3683)
						)
						(arc
							(start 0.381 0.3683)
							(mid 0.321484 0.511984)
							(end 0.1778 0.5715)
						)
					)
					(width 0)
					(fill yes)
				)
			)
		)
		(pad "S" smd custom
			(at 0.98425 0.9525 180)
			(size 0.1905 0.1905)
			(layers "F.Cu" "F.Mask" "F.Paste")
			(net "GND")
			(options
				(clearance outline)
				(anchor circle)
			)
			(primitives
				(gr_poly
					(pts
						(arc
							(start -0.1778 0.5715)
							(mid -0.321484 0.511984)
							(end -0.381 0.3683)
						)
						(arc
							(start -0.381 -0.3683)
							(mid -0.321484 -0.511984)
							(end -0.1778 -0.5715)
						)
						(arc
							(start 0.1778 -0.5715)
							(mid 0.321484 -0.511984)
							(end 0.381 -0.3683)
						)
						(arc
							(start 0.381 0.3683)
							(mid 0.321484 0.511984)
							(end 0.1778 0.5715)
						)
					)
					(width 0)
					(fill yes)
				)
			)
		)
	)
	(footprint ""
		(layer "F.Cu")
		(at 286.7406 -272.3134 180)
		(property "Reference" "R121"
			(at 0 0 180)
			(layer "F.SilkS")
			(hide yes)
			(effects
				(font
					(size 1.27 1.27)
				)
			)
		)
		(property "Value" "4K7R2F-GP"
			(at 0.064008 -3.993896 180)
			(unlocked yes)
			(layer "F.Fab")
			(hide yes)
			(effects
				(font
					(size 1.016 1.016)
					(thickness 0.1524)
				)
			)
		)
		(property "Device Type" "R402H16"
			(at 0.064008 -5.517896 180)
			(unlocked yes)
			(layer "F.Fab")
			(hide yes)
			(effects
				(font
					(size 1.016 1.016)
					(thickness 0.1524)
				)
			)
		)
		(duplicate_pad_numbers_are_jumpers no)
		(fp_line
			(start 0.508 -0.9398)
			(end -0.508 -0.9398)
			(stroke
				(width 0.1524)
				(type default)
			)
			(layer "F.SilkS")
		)
		(fp_line
			(start -0.508 -0.9398)
			(end -0.508 0.9398)
			(stroke
				(width 0.1524)
				(type default)
			)
			(layer "F.SilkS")
		)
		(fp_rect
			(start -0.508 0.9398)
			(end 0.508 -0.9398)
			(stroke
				(width 0)
				(type default)
			)
			(fill no)
			(layer "F.CrtYd")
		)
		(fp_rect
			(start -0.508 0.9398)
			(end 0.508 -0.9398)
			(stroke
				(width 0)
				(type default)
			)
			(fill no)
			(layer "F.Fab")
		)
		(pad "1" smd custom
			(at 0 -0.4445 180)
			(size 0.1397 0.1397)
			(layers "F.Cu" "F.Mask" "F.Paste")
			(net "P3V3_STBY_A")
			(options
				(clearance outline)
				(anchor circle)
			)
			(primitives
				(gr_poly
					(pts
						(arc
							(start -0.1778 -0.2794)
							(mid -0.249642 -0.249642)
							(end -0.2794 -0.1778)
						)
						(arc
							(start -0.2794 0.1778)
							(mid -0.249642 0.249642)
							(end -0.1778 0.2794)
						)
						(arc
							(start 0.1778 0.2794)
							(mid 0.249642 0.249642)
							(end 0.2794 0.1778)
						)
						(arc
							(start 0.2794 -0.1778)
							(mid 0.249642 -0.249642)
							(end 0.1778 -0.2794)
						)
					)
					(width 0)
					(fill yes)
				)
			)
		)
		(pad "2" smd custom
			(at 0 0.4445 180)
			(size 0.1397 0.1397)
			(layers "F.Cu" "F.Mask" "F.Paste")
			(net "IO_EXP2_HDD_FAULT_A2")
			(options
				(clearance outline)
				(anchor circle)
			)
			(primitives
				(gr_poly
					(pts
						(arc
							(start -0.1778 -0.2794)
							(mid -0.249642 -0.249642)
							(end -0.2794 -0.1778)
						)
						(arc
							(start -0.2794 0.1778)
							(mid -0.249642 0.249642)
							(end -0.1778 0.2794)
						)
						(arc
							(start 0.1778 0.2794)
							(mid 0.249642 0.249642)
							(end 0.2794 0.1778)
						)
						(arc
							(start 0.2794 -0.1778)
							(mid 0.249642 -0.249642)
							(end 0.1778 -0.2794)
						)
					)
					(width 0)
					(fill yes)
				)
			)
		)
	)
	(footprint ""
		(layer "F.Cu")
		(at 16.874998 -46.649894 180)
		(property "Reference" "D24"
			(at 0 0 180)
			(layer "F.SilkS")
			(hide yes)
			(effects
				(font
					(size 1.27 1.27)
				)
			)
		)
		(property "Value" "RB551V30-GP"
			(at 0 -6.7818 180)
			(unlocked yes)
			(layer "F.Fab")
			(hide yes)
			(effects
				(font
					(size 1.016 1.016)
					(thickness 0.1524)
				)
			)
		)
		(property "Device Type" "SOD323AKH38"
			(at 0 -8.6868 180)
			(unlocked yes)
			(layer "F.Fab")
			(hide yes)
			(effects
				(font
					(size 1.016 1.016)
					(thickness 0.1524)
				)
			)
		)
		(duplicate_pad_numbers_are_jumpers no)
		(fp_line
			(start 0.889 2.159)
			(end -0.889 2.159)
			(stroke
				(width 0.1524)
				(type default)
			)
			(layer "F.SilkS")
		)
		(fp_line
			(start 0.889 -1.9304)
			(end 0.889 2.159)
			(stroke
				(width 0.1524)
				(type default)
			)
			(layer "F.SilkS")
		)
		(fp_line
			(start 0.762 2.0574)
			(end -0.762 2.0574)
			(stroke
				(width 0.508)
				(type default)
			)
			(layer "F.SilkS")
		)
		(fp_line
			(start -0.889 2.159)
			(end -0.889 -1.9304)
			(stroke
				(width 0.1524)
				(type default)
			)
			(layer "F.SilkS")
		)
		(fp_line
			(start -0.889 -1.9304)
			(end 0.889 -1.9304)
			(stroke
				(width 0.1524)
				(type default)
			)
			(layer "F.SilkS")
		)
		(fp_rect
			(start -1.016 2.3114)
			(end 1.016 -2.0066)
			(stroke
				(width 0)
				(type default)
			)
			(fill no)
			(layer "F.CrtYd")
		)
		(fp_poly
			(pts
				(xy -1.016 -2.0066) (xy 1.016 -2.0066) (xy 1.016 2.3114) (xy -1.016 2.3114)
			)
			(stroke
				(width 0)
				(type default)
			)
			(fill no)
			(layer "F.Fab")
		)
		(pad "A" smd rect
			(at 0 -1.143 180)
			(size 0.5588 1.016)
			(layers "F.Cu" "F.Mask" "F.Paste")
			(net "SW_HDD_R24")
		)
		(pad "K" smd rect
			(at 0 1.143 180)
			(size 0.5588 1.016)
			(layers "F.Cu" "F.Mask" "F.Paste")
			(net "SW_HDD_N24")
		)
	)
	(footprint ""
		(layer "F.Cu")
		(at 475.149926 -176.000918 -90)
		(property "Reference" "C340"
			(at 0 0 270)
			(layer "F.SilkS")
			(hide yes)
			(effects
				(font
					(size 1.27 1.27)
				)
			)
		)
		(property "Value" "SC10U16V6KX-2GP"
			(at -0.0762 -5.1308 270)
			(unlocked yes)
			(layer "F.Fab")
			(hide yes)
			(effects
				(font
					(size 1.016 1.016)
					(thickness 0.1524)
				)
			)
		)
		(property "Device Type" "C1206H71"
			(at -0.127 -6.6548 270)
			(unlocked yes)
			(layer "F.Fab")
			(hide yes)
			(effects
				(font
					(size 1.016 1.016)
					(thickness 0.1524)
				)
			)
		)
		(duplicate_pad_numbers_are_jumpers no)
		(fp_line
			(start -1.016 2.2352)
			(end -1.016 0.8382)
			(stroke
				(width 0.1524)
				(type default)
			)
			(layer "F.SilkS")
		)
		(fp_line
			(start 1.016 2.2352)
			(end -1.016 2.2352)
			(stroke
				(width 0.1524)
				(type default)
			)
			(layer "F.SilkS")
		)
		(fp_line
			(start 1.016 0.8382)
			(end 1.016 2.2352)
			(stroke
				(width 0.1524)
				(type default)
			)
			(layer "F.SilkS")
		)
		(fp_line
			(start -1.016 -0.8382)
			(end -1.016 -2.2352)
			(stroke
				(width 0.1524)
				(type default)
			)
			(layer "F.SilkS")
		)
		(fp_line
			(start -1.016 -2.2352)
			(end 1.016 -2.2352)
			(stroke
				(width 0.1524)
				(type default)
			)
			(layer "F.SilkS")
		)
		(fp_line
			(start 1.016 -2.2352)
			(end 1.016 -0.8382)
			(stroke
				(width 0.1524)
				(type default)
			)
			(layer "F.SilkS")
		)
		(fp_rect
			(start -1.0922 2.3114)
			(end 1.0922 -2.3114)
			(stroke
				(width 0)
				(type default)
			)
			(fill no)
			(layer "F.CrtYd")
		)
		(fp_poly
			(pts
				(xy 1.0922 -2.3114) (xy 1.0922 2.3114) (xy -1.0922 2.3114) (xy -1.0922 -2.3114)
			)
			(stroke
				(width 0)
				(type default)
			)
			(fill no)
			(layer "F.Fab")
		)
		(pad "1" smd rect
			(at 0 -1.397 270)
			(size 1.651 1.27)
			(layers "F.Cu" "F.Mask" "F.Paste")
			(net "P5V_HDD23")
		)
		(pad "2" smd rect
			(at 0 1.397 270)
			(size 1.651 1.27)
			(layers "F.Cu" "F.Mask" "F.Paste")
			(net "GND")
		)
	)
	(footprint ""
		(layer "F.Cu")
		(at 396.686786 -299.539914 -90)
		(property "Reference" "R317"
			(at 0 0 270)
			(layer "F.SilkS")
			(hide yes)
			(effects
				(font
					(size 1.27 1.27)
				)
			)
		)
		(property "Value" "2R6F-GP"
			(at -0.0508 -4.8514 270)
			(unlocked yes)
			(layer "F.Fab")
			(hide yes)
			(effects
				(font
					(size 1.016 1.016)
					(thickness 0.1524)
				)
			)
		)
		(property "Device Type" "R1206H26"
			(at 0 -6.3754 270)
			(unlocked yes)
			(layer "F.Fab")
			(hide yes)
			(effects
				(font
					(size 1.016 1.016)
					(thickness 0.1524)
				)
			)
		)
		(duplicate_pad_numbers_are_jumpers no)
		(fp_line
			(start -1.016 2.2352)
			(end -1.016 -2.2352)
			(stroke
				(width 0.1524)
				(type default)
			)
			(layer "F.SilkS")
		)
		(fp_line
			(start 1.016 2.2352)
			(end -1.016 2.2352)
			(stroke
				(width 0.1524)
				(type default)
			)
			(layer "F.SilkS")
		)
		(fp_line
			(start -1.016 -2.2352)
			(end 1.016 -2.2352)
			(stroke
				(width 0.1524)
				(type default)
			)
			(layer "F.SilkS")
		)
		(fp_line
			(start 1.016 -2.2352)
			(end 1.016 2.2352)
			(stroke
				(width 0.1524)
				(type default)
			)
			(layer "F.SilkS")
		)
		(fp_rect
			(start -1.0922 2.3114)
			(end 1.0922 -2.3114)
			(stroke
				(width 0)
				(type default)
			)
			(fill no)
			(layer "F.CrtYd")
		)
		(fp_poly
			(pts
				(xy -1.0922 -2.3114) (xy 1.0922 -2.3114) (xy 1.0922 2.3114) (xy -1.0922 2.3114)
			)
			(stroke
				(width 0)
				(type default)
			)
			(fill no)
			(layer "F.Fab")
		)
		(pad "1" smd rect
			(at 0 -1.397 270)
			(size 1.651 1.27)
			(layers "F.Cu" "F.Mask" "F.Paste")
			(net "P12V_HDD8")
		)
		(pad "2" smd rect
			(at 0 1.397 270)
			(size 1.651 1.27)
			(layers "F.Cu" "F.Mask" "F.Paste")
			(net "12V_PRE_8")
		)
	)
	(footprint ""
		(layer "F.Cu")
		(at 414.639252 -43.939968 90)
		(property "Reference" "VIA14"
			(at 0 0 90)
			(layer "F.SilkS")
			(hide yes)
			(effects
				(font
					(size 1.27 1.27)
				)
			)
		)
		(property "Value" "100OHM-8L-1D6MM-L18L16-GP"
			(at -3.7211 -4.5085 90)
			(unlocked yes)
			(layer "F.Fab")
			(hide yes)
			(effects
				(font
					(size 1.016 1.016)
					(thickness 0.1524)
				)
			)
		)
		(property "Device Type" "VIA-PCIE-4P-394076"
			(at -3.7211 -6.0325 90)
			(unlocked yes)
			(layer "F.Fab")
			(hide yes)
			(effects
				(font
					(size 1.016 1.016)
					(thickness 0.1524)
				)
			)
		)
		(duplicate_pad_numbers_are_jumpers no)
		(fp_rect
			(start -1.9685 0.381)
			(end 1.9685 -0.381)
			(stroke
				(width 0)
				(type default)
			)
			(fill no)
			(layer "F.CrtYd")
		)
		(fp_rect
			(start -1.9685 0.381)
			(end 1.9685 -0.381)
			(stroke
				(width 0)
				(type default)
			)
			(fill no)
			(layer "F.Fab")
		)
		(pad "1" thru_hole circle
			(at -1.5875 0 90)
			(size 0.508 0.508)
			(drill 0.254)
			(layers "*.Cu" "*.Mask")
			(remove_unused_layers no)
			(net "GND")
			(clearance 0.127)
			(thermal_gap 0.127)
		)
		(pad "2" thru_hole circle
			(at -0.5715 0 90)
			(size 0.508 0.508)
			(drill 0.254)
			(layers "*.Cu" "*.Mask")
			(remove_unused_layers no)
			(net "PHY_SCC_A_TO_DRV_A_33_DP")
			(clearance 0.127)
			(thermal_gap 0.127)
		)
		(pad "3" thru_hole circle
			(at 0.5715 0 90)
			(size 0.508 0.508)
			(drill 0.254)
			(layers "*.Cu" "*.Mask")
			(remove_unused_layers no)
			(net "PHY_SCC_A_TO_DRV_A_33_DN")
			(clearance 0.127)
			(thermal_gap 0.127)
		)
		(pad "4" thru_hole circle
			(at 1.5875 0 90)
			(size 0.508 0.508)
			(drill 0.254)
			(layers "*.Cu" "*.Mask")
			(remove_unused_layers no)
			(net "GND")
			(clearance 0.127)
			(thermal_gap 0.127)
		)
	)
	(footprint ""
		(layer "F.Cu")
		(at 469.942926 -54.523894 90)
		(property "Reference" "C504"
			(at 0 0 90)
			(layer "F.SilkS")
			(hide yes)
			(effects
				(font
					(size 1.27 1.27)
				)
			)
		)
		(property "Value" "SCD033U25V2KX-GP"
			(at 1.1811 -2.7051 90)
			(unlocked yes)
			(layer "F.Fab")
			(hide yes)
			(effects
				(font
					(size 1.016 1.016)
					(thickness 0.1524)
				)
			)
		)
		(property "Device Type" "C402H22"
			(at 1.1811 -4.2291 90)
			(unlocked yes)
			(layer "F.Fab")
			(hide yes)
			(effects
				(font
					(size 1.016 1.016)
					(thickness 0.1524)
				)
			)
		)
		(duplicate_pad_numbers_are_jumpers no)
		(fp_rect
			(start -0.4318 0.9525)
			(end 0.4318 -0.9525)
			(stroke
				(width 0)
				(type default)
			)
			(fill no)
			(layer "F.CrtYd")
		)
		(fp_rect
			(start -0.4318 0.9525)
			(end 0.4318 -0.9525)
			(stroke
				(width 0)
				(type default)
			)
			(fill no)
			(layer "F.Fab")
		)
		(pad "1" smd custom
			(at 0 -0.4445 90)
			(size 0.1524 0.1524)
			(layers "F.Cu" "F.Mask" "F.Paste")
			(net "P12V_A")
			(options
				(clearance outline)
				(anchor circle)
			)
			(primitives
				(gr_poly
					(pts
						(arc
							(start 0.3048 -0.2032)
							(mid 0.275042 -0.275042)
							(end 0.2032 -0.3048)
						)
						(arc
							(start -0.2032 -0.3048)
							(mid -0.275042 -0.275042)
							(end -0.3048 -0.2032)
						)
						(arc
							(start -0.3048 0.2032)
							(mid -0.275042 0.275042)
							(end -0.2032 0.3048)
						)
						(arc
							(start 0.2032 0.3048)
							(mid 0.275042 0.275042)
							(end 0.3048 0.2032)
						)
					)
					(width 0)
					(fill yes)
				)
			)
		)
		(pad "2" smd custom
			(at 0 0.4445 90)
			(size 0.1524 0.1524)
			(layers "F.Cu" "F.Mask" "F.Paste")
			(net "SW_HDD_N35")
			(options
				(clearance outline)
				(anchor circle)
			)
			(primitives
				(gr_poly
					(pts
						(arc
							(start 0.3048 -0.2032)
							(mid 0.275042 -0.275042)
							(end 0.2032 -0.3048)
						)
						(arc
							(start -0.2032 -0.3048)
							(mid -0.275042 -0.275042)
							(end -0.3048 -0.2032)
						)
						(arc
							(start -0.3048 0.2032)
							(mid -0.275042 0.275042)
							(end -0.2032 0.3048)
						)
						(arc
							(start 0.2032 0.3048)
							(mid 0.275042 0.275042)
							(end 0.3048 0.2032)
						)
					)
					(width 0)
					(fill yes)
				)
			)
		)
	)
	(footprint ""
		(layer "F.Cu")
		(at 7.347204 -169.549572 90)
		(property "Reference" "R145"
			(at 0 0 90)
			(layer "F.SilkS")
			(hide yes)
			(effects
				(font
					(size 1.27 1.27)
				)
			)
		)
		(property "Value" "4K7R2J-2-GP"
			(at 0.064008 -3.993896 90)
			(unlocked yes)
			(layer "F.Fab")
			(hide yes)
			(effects
				(font
					(size 1.016 1.016)
					(thickness 0.1524)
				)
			)
		)
		(property "Device Type" "R402H16"
			(at 0.064008 -5.517896 90)
			(unlocked yes)
			(layer "F.Fab")
			(hide yes)
			(effects
				(font
					(size 1.016 1.016)
					(thickness 0.1524)
				)
			)
		)
		(duplicate_pad_numbers_are_jumpers no)
		(fp_line
			(start 0.508 -0.9398)
			(end -0.508 -0.9398)
			(stroke
				(width 0.1524)
				(type default)
			)
			(layer "F.SilkS")
		)
		(fp_line
			(start -0.508 -0.9398)
			(end -0.508 0.9398)
			(stroke
				(width 0.1524)
				(type default)
			)
			(layer "F.SilkS")
		)
		(fp_rect
			(start -0.508 0.9398)
			(end 0.508 -0.9398)
			(stroke
				(width 0)
				(type default)
			)
			(fill no)
			(layer "F.CrtYd")
		)
		(fp_rect
			(start -0.508 0.9398)
			(end 0.508 -0.9398)
			(stroke
				(width 0)
				(type default)
			)
			(fill no)
			(layer "F.Fab")
		)
		(pad "1" smd custom
			(at 0 -0.4445 90)
			(size 0.1397 0.1397)
			(layers "F.Cu" "F.Mask" "F.Paste")
			(net "DRIVE_A_0_ACT")
			(options
				(clearance outline)
				(anchor circle)
			)
			(primitives
				(gr_poly
					(pts
						(arc
							(start -0.1778 -0.2794)
							(mid -0.249642 -0.249642)
							(end -0.2794 -0.1778)
						)
						(arc
							(start -0.2794 0.1778)
							(mid -0.249642 0.249642)
							(end -0.1778 0.2794)
						)
						(arc
							(start 0.1778 0.2794)
							(mid 0.249642 0.249642)
							(end 0.2794 0.1778)
						)
						(arc
							(start 0.2794 -0.1778)
							(mid 0.249642 -0.249642)
							(end 0.1778 -0.2794)
						)
					)
					(width 0)
					(fill yes)
				)
			)
		)
		(pad "2" smd custom
			(at 0 0.4445 90)
			(size 0.1397 0.1397)
			(layers "F.Cu" "F.Mask" "F.Paste")
			(net "GND")
			(options
				(clearance outline)
				(anchor circle)
			)
			(primitives
				(gr_poly
					(pts
						(arc
							(start -0.1778 -0.2794)
							(mid -0.249642 -0.249642)
							(end -0.2794 -0.1778)
						)
						(arc
							(start -0.2794 0.1778)
							(mid -0.249642 0.249642)
							(end -0.1778 0.2794)
						)
						(arc
							(start 0.1778 0.2794)
							(mid 0.249642 0.249642)
							(end 0.2794 0.1778)
						)
						(arc
							(start 0.2794 -0.1778)
							(mid 0.249642 -0.249642)
							(end 0.1778 -0.2794)
						)
					)
					(width 0)
					(fill yes)
				)
			)
		)
	)
	(footprint ""
		(layer "F.Cu")
		(at 153.232866 -137.879074 -90)
		(property "Reference" "R1078"
			(at 0 0 270)
			(layer "F.SilkS")
			(hide yes)
			(effects
				(font
					(size 1.27 1.27)
				)
			)
		)
		(property "Value" "10R2F-L-GP"
			(at 0.064008 -3.993896 270)
			(unlocked yes)
			(layer "F.Fab")
			(hide yes)
			(effects
				(font
					(size 1.016 1.016)
					(thickness 0.1524)
				)
			)
		)
		(property "Device Type" "R402H14"
			(at 0.064008 -5.517896 270)
			(unlocked yes)
			(layer "F.Fab")
			(hide yes)
			(effects
				(font
					(size 1.016 1.016)
					(thickness 0.1524)
				)
			)
		)
		(duplicate_pad_numbers_are_jumpers no)
		(fp_line
			(start -0.508 -0.9398)
			(end -0.508 0.9398)
			(stroke
				(width 0.1524)
				(type default)
			)
			(layer "F.SilkS")
		)
		(fp_line
			(start 0.508 -0.9398)
			(end -0.508 -0.9398)
			(stroke
				(width 0.1524)
				(type default)
			)
			(layer "F.SilkS")
		)
		(fp_rect
			(start -0.508 0.9398)
			(end 0.508 -0.9398)
			(stroke
				(width 0)
				(type default)
			)
			(fill no)
			(layer "F.CrtYd")
		)
		(fp_rect
			(start -0.508 0.9398)
			(end 0.508 -0.9398)
			(stroke
				(width 0)
				(type default)
			)
			(fill no)
			(layer "F.Fab")
		)
		(pad "1" smd custom
			(at 0 -0.4445 270)
			(size 0.1397 0.1397)
			(layers "F.Cu" "F.Mask" "F.Paste")
			(net "MB0_CM_SENSE_R1_P")
			(options
				(clearance outline)
				(anchor circle)
			)
			(primitives
				(gr_poly
					(pts
						(arc
							(start -0.1778 -0.2794)
							(mid -0.249642 -0.249642)
							(end -0.2794 -0.1778)
						)
						(arc
							(start -0.2794 0.1778)
							(mid -0.249642 0.249642)
							(end -0.1778 0.2794)
						)
						(arc
							(start 0.1778 0.2794)
							(mid 0.249642 0.249642)
							(end 0.2794 0.1778)
						)
						(arc
							(start 0.2794 -0.1778)
							(mid 0.249642 -0.249642)
							(end 0.1778 -0.2794)
						)
					)
					(width 0)
					(fill yes)
				)
			)
		)
		(pad "2" smd custom
			(at 0 0.4445 270)
			(size 0.1397 0.1397)
			(layers "F.Cu" "F.Mask" "F.Paste")
			(net "MB0_HS_SENSE_P")
			(options
				(clearance outline)
				(anchor circle)
			)
			(primitives
				(gr_poly
					(pts
						(arc
							(start -0.1778 -0.2794)
							(mid -0.249642 -0.249642)
							(end -0.2794 -0.1778)
						)
						(arc
							(start -0.2794 0.1778)
							(mid -0.249642 0.249642)
							(end -0.1778 0.2794)
						)
						(arc
							(start 0.1778 0.2794)
							(mid 0.249642 0.249642)
							(end 0.2794 0.1778)
						)
						(arc
							(start 0.2794 -0.1778)
							(mid 0.249642 -0.249642)
							(end 0.1778 -0.2794)
						)
					)
					(width 0)
					(fill yes)
				)
			)
		)
	)
	(footprint ""
		(layer "F.Cu")
		(at 230.7844 -383.0574 -90)
		(property "Reference" "R1144"
			(at 0 0 270)
			(layer "F.SilkS")
			(hide yes)
			(effects
				(font
					(size 1.27 1.27)
				)
			)
		)
		(property "Value" "0R2J-2-GP"
			(at 0.064008 -3.993896 270)
			(unlocked yes)
			(layer "F.Fab")
			(hide yes)
			(effects
				(font
					(size 1.016 1.016)
					(thickness 0.1524)
				)
			)
		)
		(property "Device Type" "R402H16"
			(at 0.064008 -5.517896 270)
			(unlocked yes)
			(layer "F.Fab")
			(hide yes)
			(effects
				(font
					(size 1.016 1.016)
					(thickness 0.1524)
				)
			)
		)
		(duplicate_pad_numbers_are_jumpers no)
		(fp_line
			(start -0.508 -0.9398)
			(end -0.508 0.9398)
			(stroke
				(width 0.1524)
				(type default)
			)
			(layer "F.SilkS")
		)
		(fp_line
			(start 0.508 -0.9398)
			(end -0.508 -0.9398)
			(stroke
				(width 0.1524)
				(type default)
			)
			(layer "F.SilkS")
		)
		(fp_rect
			(start -0.508 0.9398)
			(end 0.508 -0.9398)
			(stroke
				(width 0)
				(type default)
			)
			(fill no)
			(layer "F.CrtYd")
		)
		(fp_rect
			(start -0.508 0.9398)
			(end 0.508 -0.9398)
			(stroke
				(width 0)
				(type default)
			)
			(fill no)
			(layer "F.Fab")
		)
		(pad "1" smd custom
			(at 0 -0.4445 270)
			(size 0.1397 0.1397)
			(layers "F.Cu" "F.Mask" "F.Paste")
			(net "MB3_SCL_R")
			(options
				(clearance outline)
				(anchor circle)
			)
			(primitives
				(gr_poly
					(pts
						(arc
							(start -0.1778 -0.2794)
							(mid -0.249642 -0.249642)
							(end -0.2794 -0.1778)
						)
						(arc
							(start -0.2794 0.1778)
							(mid -0.249642 0.249642)
							(end -0.1778 0.2794)
						)
						(arc
							(start 0.1778 0.2794)
							(mid 0.249642 0.249642)
							(end 0.2794 0.1778)
						)
						(arc
							(start 0.2794 -0.1778)
							(mid 0.249642 -0.249642)
							(end 0.1778 -0.2794)
						)
					)
					(width 0)
					(fill yes)
				)
			)
		)
		(pad "2" smd custom
			(at 0 0.4445 270)
			(size 0.1397 0.1397)
			(layers "F.Cu" "F.Mask" "F.Paste")
			(net "I2C_DPB_A_SCL_BUF")
			(options
				(clearance outline)
				(anchor circle)
			)
			(primitives
				(gr_poly
					(pts
						(arc
							(start -0.1778 -0.2794)
							(mid -0.249642 -0.249642)
							(end -0.2794 -0.1778)
						)
						(arc
							(start -0.2794 0.1778)
							(mid -0.249642 0.249642)
							(end -0.1778 0.2794)
						)
						(arc
							(start 0.1778 0.2794)
							(mid 0.249642 0.249642)
							(end 0.2794 0.1778)
						)
						(arc
							(start 0.2794 -0.1778)
							(mid 0.249642 -0.249642)
							(end 0.1778 -0.2794)
						)
					)
					(width 0)
					(fill yes)
				)
			)
		)
	)
	(footprint ""
		(layer "F.Cu")
		(at 219.878402 -213.754462)
		(property "Reference" "C57"
			(at 0 0 0)
			(layer "F.SilkS")
			(hide yes)
			(effects
				(font
					(size 1.27 1.27)
				)
			)
		)
		(property "Value" "SC1U16V3KX-5GP"
			(at 0 -2.8194 0)
			(unlocked yes)
			(layer "F.Fab")
			(hide yes)
			(effects
				(font
					(size 1.016 1.016)
					(thickness 0.1524)
				)
			)
		)
		(property "Device Type" "C603H36"
			(at 0 -4.3434 0)
			(unlocked yes)
			(layer "F.Fab")
			(hide yes)
			(effects
				(font
					(size 1.016 1.016)
					(thickness 0.1524)
				)
			)
		)
		(duplicate_pad_numbers_are_jumpers no)
		(fp_line
			(start 0.508 0)
			(end -0.508 0)
			(stroke
				(width 0.2032)
				(type default)
			)
			(layer "F.SilkS")
		)
		(fp_rect
			(start -0.5842 1.3335)
			(end 0.5842 -1.3335)
			(stroke
				(width 0)
				(type default)
			)
			(fill no)
			(layer "F.CrtYd")
		)
		(fp_rect
			(start -0.5842 1.3335)
			(end 0.5842 -1.3335)
			(stroke
				(width 0)
				(type default)
			)
			(fill no)
			(layer "F.Fab")
		)
		(pad "1" smd custom
			(at 0 -0.762)
			(size 0.2159 0.2159)
			(layers "F.Cu" "F.Mask" "F.Paste")
			(net "P3V3_STBY_A")
			(options
				(clearance outline)
				(anchor circle)
			)
			(primitives
				(gr_poly
					(pts
						(arc
							(start -0.3302 -0.4318)
							(mid -0.402042 -0.402042)
							(end -0.4318 -0.3302)
						)
						(arc
							(start -0.4318 0.3302)
							(mid -0.402042 0.402042)
							(end -0.3302 0.4318)
						)
						(arc
							(start 0.3302 0.4318)
							(mid 0.402042 0.402042)
							(end 0.4318 0.3302)
						)
						(arc
							(start 0.4318 -0.3302)
							(mid 0.402042 -0.402042)
							(end 0.3302 -0.4318)
						)
					)
					(width 0)
					(fill yes)
				)
			)
		)
		(pad "2" smd custom
			(at 0 0.762)
			(size 0.2159 0.2159)
			(layers "F.Cu" "F.Mask" "F.Paste")
			(net "GND")
			(options
				(clearance outline)
				(anchor circle)
			)
			(primitives
				(gr_poly
					(pts
						(arc
							(start -0.3302 -0.4318)
							(mid -0.402042 -0.402042)
							(end -0.4318 -0.3302)
						)
						(arc
							(start -0.4318 0.3302)
							(mid -0.402042 0.402042)
							(end -0.3302 0.4318)
						)
						(arc
							(start 0.3302 0.4318)
							(mid 0.402042 0.402042)
							(end 0.4318 0.3302)
						)
						(arc
							(start 0.4318 -0.3302)
							(mid 0.402042 -0.402042)
							(end 0.3302 -0.4318)
						)
					)
					(width 0)
					(fill yes)
				)
			)
		)
	)
	(footprint ""
		(layer "F.Cu")
		(at 149.196298 -44.871894 -90)
		(property "Reference" "R785"
			(at 0 0 270)
			(layer "F.SilkS")
			(hide yes)
			(effects
				(font
					(size 1.27 1.27)
				)
			)
		)
		(property "Value" "0R2J-2-GP"
			(at 0.064008 -3.993896 270)
			(unlocked yes)
			(layer "F.Fab")
			(hide yes)
			(effects
				(font
					(size 1.016 1.016)
					(thickness 0.1524)
				)
			)
		)
		(property "Device Type" "R402H16"
			(at 0.064008 -5.517896 270)
			(unlocked yes)
			(layer "F.Fab")
			(hide yes)
			(effects
				(font
					(size 1.016 1.016)
					(thickness 0.1524)
				)
			)
		)
		(duplicate_pad_numbers_are_jumpers no)
		(fp_line
			(start -0.508 -0.9398)
			(end -0.508 0.9398)
			(stroke
				(width 0.1524)
				(type default)
			)
			(layer "F.SilkS")
		)
		(fp_line
			(start 0.508 -0.9398)
			(end -0.508 -0.9398)
			(stroke
				(width 0.1524)
				(type default)
			)
			(layer "F.SilkS")
		)
		(fp_rect
			(start -0.508 0.9398)
			(end 0.508 -0.9398)
			(stroke
				(width 0)
				(type default)
			)
			(fill no)
			(layer "F.CrtYd")
		)
		(fp_rect
			(start -0.508 0.9398)
			(end 0.508 -0.9398)
			(stroke
				(width 0)
				(type default)
			)
			(fill no)
			(layer "F.Fab")
		)
		(pad "1" smd custom
			(at 0 -0.4445 270)
			(size 0.1397 0.1397)
			(layers "F.Cu" "F.Mask" "F.Paste")
			(net "DRIVE_A_28_PWR")
			(options
				(clearance outline)
				(anchor circle)
			)
			(primitives
				(gr_poly
					(pts
						(arc
							(start -0.1778 -0.2794)
							(mid -0.249642 -0.249642)
							(end -0.2794 -0.1778)
						)
						(arc
							(start -0.2794 0.1778)
							(mid -0.249642 0.249642)
							(end -0.1778 0.2794)
						)
						(arc
							(start 0.1778 0.2794)
							(mid 0.249642 0.249642)
							(end 0.2794 0.1778)
						)
						(arc
							(start 0.2794 -0.1778)
							(mid 0.249642 -0.249642)
							(end 0.1778 -0.2794)
						)
					)
					(width 0)
					(fill yes)
				)
			)
		)
		(pad "2" smd custom
			(at 0 0.4445 270)
			(size 0.1397 0.1397)
			(layers "F.Cu" "F.Mask" "F.Paste")
			(net "SW_PWR_R_HDD28")
			(options
				(clearance outline)
				(anchor circle)
			)
			(primitives
				(gr_poly
					(pts
						(arc
							(start -0.1778 -0.2794)
							(mid -0.249642 -0.249642)
							(end -0.2794 -0.1778)
						)
						(arc
							(start -0.2794 0.1778)
							(mid -0.249642 0.249642)
							(end -0.1778 0.2794)
						)
						(arc
							(start 0.1778 0.2794)
							(mid 0.249642 0.249642)
							(end 0.2794 0.1778)
						)
						(arc
							(start 0.2794 -0.1778)
							(mid 0.249642 -0.249642)
							(end 0.1778 -0.2794)
						)
					)
					(width 0)
					(fill yes)
				)
			)
		)
	)
	(footprint ""
		(layer "F.Cu")
		(at 28.200096 -57.909968 -90)
		(property "Reference" "HDDSAS24"
			(at 0 0 270)
			(layer "F.SilkS")
			(hide yes)
			(effects
				(font
					(size 1.27 1.27)
				)
			)
		)
		(property "Value" "SKT-SAS15P-14P-45-GP"
			(at -20.7645 -8.9789 270)
			(unlocked yes)
			(layer "F.Fab")
			(hide yes)
			(effects
				(font
					(size 1.016 1.016)
					(thickness 0.1524)
				)
			)
		)
		(property "Device Type" "10120818-001C-TRLF"
			(at -20.7645 -10.5029 270)
			(unlocked yes)
			(layer "F.Fab")
			(hide yes)
			(effects
				(font
					(size 1.016 1.016)
					(thickness 0.1524)
				)
			)
		)
		(duplicate_pad_numbers_are_jumpers no)
		(fp_line
			(start 1.651 4.2926)
			(end 1.651 3.0099)
			(stroke
				(width 0.1524)
				(type default)
			)
			(layer "F.SilkS")
		)
		(fp_line
			(start 8.509 4.2926)
			(end 1.651 4.2926)
			(stroke
				(width 0.1524)
				(type default)
			)
			(layer "F.SilkS")
		)
		(fp_line
			(start -23.4188 3.0099)
			(end -23.4188 -3.2512)
			(stroke
				(width 0.1524)
				(type default)
			)
			(layer "F.SilkS")
		)
		(fp_line
			(start 1.651 3.0099)
			(end -23.4188 3.0099)
			(stroke
				(width 0.1524)
				(type default)
			)
			(layer "F.SilkS")
		)
		(fp_line
			(start 8.509 3.0099)
			(end 8.509 4.2926)
			(stroke
				(width 0.1524)
				(type default)
			)
			(layer "F.SilkS")
		)
		(fp_line
			(start 23.4188 3.0099)
			(end 8.509 3.0099)
			(stroke
				(width 0.1524)
				(type default)
			)
			(layer "F.SilkS")
		)
		(fp_line
			(start -23.4188 -3.2512)
			(end 23.4188 -3.2512)
			(stroke
				(width 0.1524)
				(type default)
			)
			(layer "F.SilkS")
		)
		(fp_line
			(start 23.4188 -3.2512)
			(end 23.4188 3.0099)
			(stroke
				(width 0.1524)
				(type default)
			)
			(layer "F.SilkS")
		)
		(fp_line
			(start 15.5067 -3.3401)
			(end 16.2687 -3.3401)
			(stroke
				(width 0.3302)
				(type default)
			)
			(layer "F.SilkS")
		)
		(fp_poly
			(pts
				(xy 15.868904 -3.230372) (xy 16.503904 -3.865372) (xy 15.233904 -3.865372)
			)
			(stroke
				(width 0)
				(type default)
			)
			(fill yes)
			(layer "F.SilkS")
		)
		(fp_poly
			(pts
				(xy -22.8727 -2.7559) (xy 22.8727 -2.7559) (xy 22.8727 2.7559) (xy 8.255 2.7559) (xy 8.255 3.5179)
				(xy 1.905 3.5179) (xy 1.905 2.7559) (xy -22.8727 2.7559)
			)
			(stroke
				(width 0)
				(type default)
			)
			(fill no)
			(layer "F.CrtYd")
		)
		(fp_poly
			(pts
				(xy 1.397 4.5466) (xy 1.397 3.2639) (xy -23.6728 3.2639) (xy -23.6728 -3.5052) (xy 23.6728 -3.5052)
				(xy 23.6728 -0.00635) (xy 22.8727 -0.00635) (xy 22.8727 -2.7559) (xy -22.8727 -2.7559) (xy -22.8727 2.7559)
				(xy 1.905 2.7559) (xy 1.905 3.5179) (xy 8.255 3.5179) (xy 8.255 2.7559) (xy 22.8727 2.7559) (xy 22.8727 0.00635)
				(xy 23.6728 0.00635) (xy 23.6728 3.2639) (xy 8.763 3.2639) (xy 8.763 4.5466)
			)
			(stroke
				(width 0)
				(type default)
			)
			(fill no)
			(layer "F.CrtYd")
		)
		(fp_poly
			(pts
				(xy 1.397 4.5466) (xy 1.397 3.2639) (xy -23.6728 3.2639) (xy -23.6728 -3.5052) (xy 23.6728 -3.5052)
				(xy 23.6728 3.2639) (xy 8.763 3.2639) (xy 8.763 4.5466)
			)
			(stroke
				(width 0)
				(type default)
			)
			(fill no)
			(layer "F.Fab")
		)
		(pad "" np_thru_hole circle
			(at -18.874994 0 270)
			(size 0.254 0.254)
			(drill 1.3462)
			(layers "*.Cu" "*.Mask")
			(clearance 0.9017)
			(thermal_gap 0.9017)
		)
		(pad "" np_thru_hole circle
			(at 18.874994 0 270)
			(size 0.254 0.254)
			(drill 0.9398)
			(layers "*.Cu" "*.Mask")
			(clearance 0.6985)
			(thermal_gap 0.6985)
		)
		(pad "G1" smd rect
			(at 21.874988 0 270)
			(size 2.5908 2.5908)
			(layers "F.Cu" "F.Mask" "F.Paste")
			(net "GND")
		)
		(pad "G2" smd rect
			(at -21.874988 0 270)
			(size 2.5908 2.5908)
			(layers "F.Cu" "F.Mask" "F.Paste")
			(net "GND")
		)
		(pad "P1" smd rect
			(at 1.905 -1.82499 270)
			(size 0.6096 2.3622)
			(layers "F.Cu" "F.Mask" "F.Paste")
			(net "Net_2091")
		)
		(pad "P2" smd rect
			(at 0.635 -1.82499 270)
			(size 0.6096 2.3622)
			(layers "F.Cu" "F.Mask" "F.Paste")
			(net "Net_2092")
		)
		(pad "P3" smd rect
			(at -0.635 -1.82499 270)
			(size 0.6096 2.3622)
			(layers "F.Cu" "F.Mask" "F.Paste")
			(net "Net_2093")
		)
		(pad "P4" smd rect
			(at -1.905 -1.82499 270)
			(size 0.6096 2.3622)
			(layers "F.Cu" "F.Mask" "F.Paste")
			(net "GND")
		)
		(pad "P5" smd rect
			(at -3.175 -1.82499 270)
			(size 0.6096 2.3622)
			(layers "F.Cu" "F.Mask" "F.Paste")
			(net "HDD_PRSNT_24")
		)
		(pad "P6" smd rect
			(at -4.445 -1.82499 270)
			(size 0.6096 2.3622)
			(layers "F.Cu" "F.Mask" "F.Paste")
			(net "GND")
		)
		(pad "P7" smd rect
			(at -5.715 -1.82499 270)
			(size 0.6096 2.3622)
			(layers "F.Cu" "F.Mask" "F.Paste")
			(net "5V_PRE_24")
		)
		(pad "P8" smd rect
			(at -6.985 -1.82499 270)
			(size 0.6096 2.3622)
			(layers "F.Cu" "F.Mask" "F.Paste")
			(net "P5V_HDD24")
		)
		(pad "P9" smd rect
			(at -8.255 -1.82499 270)
			(size 0.6096 2.3622)
			(layers "F.Cu" "F.Mask" "F.Paste")
			(net "P5V_HDD24")
		)
		(pad "P10" smd rect
			(at -9.525 -1.82499 270)
			(size 0.6096 2.3622)
			(layers "F.Cu" "F.Mask" "F.Paste")
			(net "GND")
		)
		(pad "P11" smd rect
			(at -10.795 -1.82499 270)
			(size 0.6096 2.3622)
			(layers "F.Cu" "F.Mask" "F.Paste")
			(net "ACT_HDD_24")
		)
		(pad "P12" smd rect
			(at -12.065 -1.82499 270)
			(size 0.6096 2.3622)
			(layers "F.Cu" "F.Mask" "F.Paste")
			(net "GND")
		)
		(pad "P13" smd rect
			(at -13.335 -1.82499 270)
			(size 0.6096 2.3622)
			(layers "F.Cu" "F.Mask" "F.Paste")
			(net "12V_PRE_24")
		)
		(pad "P14" smd rect
			(at -14.605 -1.82499 270)
			(size 0.6096 2.3622)
			(layers "F.Cu" "F.Mask" "F.Paste")
			(net "P12V_HDD24")
		)
		(pad "P15" smd rect
			(at -15.875 -1.82499 270)
			(size 0.6096 2.3622)
			(layers "F.Cu" "F.Mask" "F.Paste")
			(net "P12V_HDD24")
		)
		(pad "S1" smd rect
			(at 15.875 -1.82499 270)
			(size 0.6096 2.3622)
			(layers "F.Cu" "F.Mask" "F.Paste")
			(net "GND")
		)
		(pad "S2" smd rect
			(at 14.605 -1.82499 270)
			(size 0.6096 2.3622)
			(layers "F.Cu" "F.Mask" "F.Paste")
			(net "SAS_HDD_RX_P24")
		)
		(pad "S3" smd rect
			(at 13.335 -1.82499 270)
			(size 0.6096 2.3622)
			(layers "F.Cu" "F.Mask" "F.Paste")
			(net "SAS_HDD_RX_N24")
		)
		(pad "S4" smd rect
			(at 12.065 -1.82499 270)
			(size 0.6096 2.3622)
			(layers "F.Cu" "F.Mask" "F.Paste")
			(net "GND")
		)
		(pad "S5" smd rect
			(at 10.795 -1.82499 270)
			(size 0.6096 2.3622)
			(layers "F.Cu" "F.Mask" "F.Paste")
			(net "PHY_DRV_A_TO_SCC_A_24_DN")
		)
		(pad "S6" smd rect
			(at 9.525 -1.82499 270)
			(size 0.6096 2.3622)
			(layers "F.Cu" "F.Mask" "F.Paste")
			(net "PHY_DRV_A_TO_SCC_A_24_DP")
		)
		(pad "S7" smd rect
			(at 8.255 -1.82499 270)
			(size 0.6096 2.3622)
			(layers "F.Cu" "F.Mask" "F.Paste")
			(net "GND")
		)
		(pad "S8" smd rect
			(at 7.480046 2.845054 270)
			(size 0.508 2.3622)
			(layers "F.Cu" "F.Mask" "F.Paste")
			(net "GND")
		)
		(pad "S9" smd rect
			(at 6.679946 2.845054 270)
			(size 0.508 2.3622)
			(layers "F.Cu" "F.Mask" "F.Paste")
			(net "Net_462")
		)
		(pad "S10" smd rect
			(at 5.8801 2.845054 270)
			(size 0.508 2.3622)
			(layers "F.Cu" "F.Mask" "F.Paste")
			(net "Net_354")
		)
		(pad "S11" smd rect
			(at 5.08 2.845054 270)
			(size 0.508 2.3622)
			(layers "F.Cu" "F.Mask" "F.Paste")
			(net "GND")
		)
		(pad "S12" smd rect
			(at 4.2799 2.845054 270)
			(size 0.508 2.3622)
			(layers "F.Cu" "F.Mask" "F.Paste")
			(net "Net_390")
		)
		(pad "S13" smd rect
			(at 3.480054 2.845054 270)
			(size 0.508 2.3622)
			(layers "F.Cu" "F.Mask" "F.Paste")
			(net "Net_426")
		)
		(pad "S14" smd rect
			(at 2.679954 2.845054 270)
			(size 0.508 2.3622)
			(layers "F.Cu" "F.Mask" "F.Paste")
			(net "GND")
		)
		(zone
			(layer "F.Cu")
			(hatch none 0.5)
			(connect_pads
				(clearance 0)
			)
			(min_thickness 0.25)
			(keepout
				(tracks not_allowed)
				(vias allowed)
				(pads allowed)
				(copperpour not_allowed)
				(footprints allowed)
			)
			(placement
				(enabled no)
				(sheetname "")
			)
			(fill
				(thermal_gap 0.5)
				(thermal_bridge_width 0.5)
				(island_removal_mode 0)
			)
			(polygon
				(pts
					(xy 31.857696 -74.648568) (xy 24.783796 -74.648568) (xy 24.783796 -81.582768) (xy 25.888696 -81.582768)
					(xy 25.888696 -77.467968) (xy 30.511496 -77.467968) (xy 30.511496 -81.582768) (xy 31.857696 -81.582768)
				)
			)
		)
		(zone
			(layer "F.Cu")
			(hatch none 0.5)
			(connect_pads
				(clearance 0)
			)
			(min_thickness 0.25)
			(keepout
				(tracks allowed)
				(vias not_allowed)
				(pads allowed)
				(copperpour not_allowed)
				(footprints allowed)
			)
			(placement
				(enabled no)
				(sheetname "")
			)
			(fill
				(thermal_gap 0.5)
				(thermal_bridge_width 0.5)
				(island_removal_mode 0)
			)
			(polygon
				(pts
					(xy 31.857696 -74.648568) (xy 24.783796 -74.648568) (xy 24.783796 -81.582768) (xy 25.888696 -81.582768)
					(xy 25.888696 -77.467968) (xy 30.511496 -77.467968) (xy 30.511496 -81.582768) (xy 31.857696 -81.582768)
				)
			)
		)
		(zone
			(layer "F.Cu")
			(hatch none 0.5)
			(connect_pads
				(clearance 0)
			)
			(min_thickness 0.25)
			(keepout
				(tracks allowed)
				(vias not_allowed)
				(pads allowed)
				(copperpour not_allowed)
				(footprints allowed)
			)
			(placement
				(enabled no)
				(sheetname "")
			)
			(fill
				(thermal_gap 0.5)
				(thermal_bridge_width 0.5)
				(island_removal_mode 0)
			)
			(polygon
				(pts
					(xy 31.857696 -41.171368) (xy 24.783796 -41.171368) (xy 24.783796 -34.237168) (xy 25.888696 -34.237168)
					(xy 25.888696 -38.351968) (xy 30.511496 -38.351968) (xy 30.511496 -34.237168) (xy 31.857696 -34.237168)
				)
			)
		)
		(zone
			(layer "F.Cu")
			(hatch none 0.5)
			(connect_pads
				(clearance 0)
			)
			(min_thickness 0.25)
			(keepout
				(tracks not_allowed)
				(vias allowed)
				(pads allowed)
				(copperpour not_allowed)
				(footprints allowed)
			)
			(placement
				(enabled no)
				(sheetname "")
			)
			(fill
				(thermal_gap 0.5)
				(thermal_bridge_width 0.5)
				(island_removal_mode 0)
			)
			(polygon
				(pts
					(xy 31.857696 -41.171368) (xy 24.783796 -41.171368) (xy 24.783796 -34.237168) (xy 25.888696 -34.237168)
					(xy 25.888696 -38.351968) (xy 30.511496 -38.351968) (xy 30.511496 -34.237168) (xy 31.857696 -34.237168)
				)
			)
		)
		(zone
			(layers "F.Cu" "B.Cu" "In1.Cu" "In2.Cu" "In3.Cu" "In4.Cu" "In5.Cu" "In6.Cu"
				"In7.Cu" "In8.Cu" "In9.Cu" "In10.Cu"
			)
			(hatch none 0.5)
			(connect_pads
				(clearance 0)
			)
			(min_thickness 0.25)
			(keepout
				(tracks not_allowed)
				(vias allowed)
				(pads allowed)
				(copperpour not_allowed)
				(footprints allowed)
			)
			(placement
				(enabled no)
				(sheetname "")
			)
			(fill
				(thermal_gap 0.5)
				(thermal_bridge_width 0.5)
				(island_removal_mode 0)
			)
			(polygon
				(pts
					(arc
						(start 28.974796 -39.034974)
						(mid 27.425396 -39.034974)
						(end 28.974796 -39.034974)
					)
				)
			)
		)
		(zone
			(layers "F.Cu" "B.Cu" "In1.Cu" "In2.Cu" "In3.Cu" "In4.Cu" "In5.Cu" "In6.Cu"
				"In7.Cu" "In8.Cu" "In9.Cu" "In10.Cu"
			)
			(hatch none 0.5)
			(connect_pads
				(clearance 0)
			)
			(min_thickness 0.25)
			(keepout
				(tracks not_allowed)
				(vias allowed)
				(pads allowed)
				(copperpour not_allowed)
				(footprints allowed)
			)
			(placement
				(enabled no)
				(sheetname "")
			)
			(fill
				(thermal_gap 0.5)
				(thermal_bridge_width 0.5)
				(island_removal_mode 0)
			)
			(polygon
				(pts
					(arc
						(start 29.177996 -76.784962)
						(mid 27.222196 -76.784962)
						(end 29.177996 -76.784962)
					)
				)
			)
		)
	)
	(footprint ""
		(layer "F.Cu")
		(at 469.904318 -164.295074 90)
		(property "Reference" "R675"
			(at 0 0 90)
			(layer "F.SilkS")
			(hide yes)
			(effects
				(font
					(size 1.27 1.27)
				)
			)
		)
		(property "Value" "200KR2F-L-GP"
			(at 0.064008 -3.993896 90)
			(unlocked yes)
			(layer "F.Fab")
			(hide yes)
			(effects
				(font
					(size 1.016 1.016)
					(thickness 0.1524)
				)
			)
		)
		(property "Device Type" "R402H16"
			(at 0.064008 -5.517896 90)
			(unlocked yes)
			(layer "F.Fab")
			(hide yes)
			(effects
				(font
					(size 1.016 1.016)
					(thickness 0.1524)
				)
			)
		)
		(duplicate_pad_numbers_are_jumpers no)
		(fp_line
			(start 0.508 -0.9398)
			(end -0.508 -0.9398)
			(stroke
				(width 0.1524)
				(type default)
			)
			(layer "F.SilkS")
		)
		(fp_line
			(start -0.508 -0.9398)
			(end -0.508 0.9398)
			(stroke
				(width 0.1524)
				(type default)
			)
			(layer "F.SilkS")
		)
		(fp_rect
			(start -0.508 0.9398)
			(end 0.508 -0.9398)
			(stroke
				(width 0)
				(type default)
			)
			(fill no)
			(layer "F.CrtYd")
		)
		(fp_rect
			(start -0.508 0.9398)
			(end 0.508 -0.9398)
			(stroke
				(width 0)
				(type default)
			)
			(fill no)
			(layer "F.Fab")
		)
		(pad "1" smd custom
			(at 0 -0.4445 90)
			(size 0.1397 0.1397)
			(layers "F.Cu" "F.Mask" "F.Paste")
			(net "SW_HDD_R23")
			(options
				(clearance outline)
				(anchor circle)
			)
			(primitives
				(gr_poly
					(pts
						(arc
							(start -0.1778 -0.2794)
							(mid -0.249642 -0.249642)
							(end -0.2794 -0.1778)
						)
						(arc
							(start -0.2794 0.1778)
							(mid -0.249642 0.249642)
							(end -0.1778 0.2794)
						)
						(arc
							(start 0.1778 0.2794)
							(mid 0.249642 0.249642)
							(end 0.2794 0.1778)
						)
						(arc
							(start 0.2794 -0.1778)
							(mid 0.249642 -0.249642)
							(end 0.1778 -0.2794)
						)
					)
					(width 0)
					(fill yes)
				)
			)
		)
		(pad "2" smd custom
			(at 0 0.4445 90)
			(size 0.1397 0.1397)
			(layers "F.Cu" "F.Mask" "F.Paste")
			(net "SW_HDD_N23")
			(options
				(clearance outline)
				(anchor circle)
			)
			(primitives
				(gr_poly
					(pts
						(arc
							(start -0.1778 -0.2794)
							(mid -0.249642 -0.249642)
							(end -0.2794 -0.1778)
						)
						(arc
							(start -0.2794 0.1778)
							(mid -0.249642 0.249642)
							(end -0.1778 0.2794)
						)
						(arc
							(start 0.1778 0.2794)
							(mid 0.249642 0.249642)
							(end 0.2794 0.1778)
						)
						(arc
							(start 0.2794 -0.1778)
							(mid 0.249642 -0.249642)
							(end 0.1778 -0.2794)
						)
					)
					(width 0)
					(fill yes)
				)
			)
		)
	)
	(footprint ""
		(layer "F.Cu")
		(at 467.469982 -279.816814)
		(property "Reference" "R397"
			(at 0 0 0)
			(layer "F.SilkS")
			(hide yes)
			(effects
				(font
					(size 1.27 1.27)
				)
			)
		)
		(property "Value" "4K7R2J-2-GP"
			(at 0.064008 -3.993896 0)
			(unlocked yes)
			(layer "F.Fab")
			(hide yes)
			(effects
				(font
					(size 1.016 1.016)
					(thickness 0.1524)
				)
			)
		)
		(property "Device Type" "R402H16"
			(at 0.064008 -5.517896 0)
			(unlocked yes)
			(layer "F.Fab")
			(hide yes)
			(effects
				(font
					(size 1.016 1.016)
					(thickness 0.1524)
				)
			)
		)
		(duplicate_pad_numbers_are_jumpers no)
		(fp_line
			(start -0.508 -0.9398)
			(end -0.508 0.9398)
			(stroke
				(width 0.1524)
				(type default)
			)
			(layer "F.SilkS")
		)
		(fp_line
			(start 0.508 -0.9398)
			(end -0.508 -0.9398)
			(stroke
				(width 0.1524)
				(type default)
			)
			(layer "F.SilkS")
		)
		(fp_rect
			(start -0.508 0.9398)
			(end 0.508 -0.9398)
			(stroke
				(width 0)
				(type default)
			)
			(fill no)
			(layer "F.CrtYd")
		)
		(fp_rect
			(start -0.508 0.9398)
			(end 0.508 -0.9398)
			(stroke
				(width 0)
				(type default)
			)
			(fill no)
			(layer "F.Fab")
		)
		(pad "1" smd custom
			(at 0 -0.4445)
			(size 0.1397 0.1397)
			(layers "F.Cu" "F.Mask" "F.Paste")
			(net "P12V_A")
			(options
				(clearance outline)
				(anchor circle)
			)
			(primitives
				(gr_poly
					(pts
						(arc
							(start -0.1778 -0.2794)
							(mid -0.249642 -0.249642)
							(end -0.2794 -0.1778)
						)
						(arc
							(start -0.2794 0.1778)
							(mid -0.249642 0.249642)
							(end -0.1778 0.2794)
						)
						(arc
							(start 0.1778 0.2794)
							(mid 0.249642 0.249642)
							(end 0.2794 0.1778)
						)
						(arc
							(start 0.2794 -0.1778)
							(mid 0.249642 -0.249642)
							(end 0.1778 -0.2794)
						)
					)
					(width 0)
					(fill yes)
				)
			)
		)
		(pad "2" smd custom
			(at 0 0.4445)
			(size 0.1397 0.1397)
			(layers "F.Cu" "F.Mask" "F.Paste")
			(net "SW_HDD_R11")
			(options
				(clearance outline)
				(anchor circle)
			)
			(primitives
				(gr_poly
					(pts
						(arc
							(start -0.1778 -0.2794)
							(mid -0.249642 -0.249642)
							(end -0.2794 -0.1778)
						)
						(arc
							(start -0.2794 0.1778)
							(mid -0.249642 0.249642)
							(end -0.1778 0.2794)
						)
						(arc
							(start 0.1778 0.2794)
							(mid 0.249642 0.249642)
							(end 0.2794 0.1778)
						)
						(arc
							(start 0.2794 -0.1778)
							(mid 0.249642 -0.249642)
							(end 0.1778 -0.2794)
						)
					)
					(width 0)
					(fill yes)
				)
			)
		)
	)
	(footprint ""
		(layer "F.Cu")
		(at 55.282846 -292.270942)
		(property "Reference" "R152"
			(at 0 0 0)
			(layer "F.SilkS")
			(hide yes)
			(effects
				(font
					(size 1.27 1.27)
				)
			)
		)
		(property "Value" "2R6F-GP"
			(at -0.0508 -4.8514 0)
			(unlocked yes)
			(layer "F.Fab")
			(hide yes)
			(effects
				(font
					(size 1.016 1.016)
					(thickness 0.1524)
				)
			)
		)
		(property "Device Type" "R1206H26"
			(at 0 -6.3754 0)
			(unlocked yes)
			(layer "F.Fab")
			(hide yes)
			(effects
				(font
					(size 1.016 1.016)
					(thickness 0.1524)
				)
			)
		)
		(duplicate_pad_numbers_are_jumpers no)
		(fp_line
			(start -1.016 -2.2352)
			(end 1.016 -2.2352)
			(stroke
				(width 0.1524)
				(type default)
			)
			(layer "F.SilkS")
		)
		(fp_line
			(start -1.016 2.2352)
			(end -1.016 -2.2352)
			(stroke
				(width 0.1524)
				(type default)
			)
			(layer "F.SilkS")
		)
		(fp_line
			(start 1.016 -2.2352)
			(end 1.016 2.2352)
			(stroke
				(width 0.1524)
				(type default)
			)
			(layer "F.SilkS")
		)
		(fp_line
			(start 1.016 2.2352)
			(end -1.016 2.2352)
			(stroke
				(width 0.1524)
				(type default)
			)
			(layer "F.SilkS")
		)
		(fp_rect
			(start -1.0922 2.3114)
			(end 1.0922 -2.3114)
			(stroke
				(width 0)
				(type default)
			)
			(fill no)
			(layer "F.CrtYd")
		)
		(fp_poly
			(pts
				(xy -1.0922 -2.3114) (xy 1.0922 -2.3114) (xy 1.0922 2.3114) (xy -1.0922 2.3114)
			)
			(stroke
				(width 0)
				(type default)
			)
			(fill no)
			(layer "F.Fab")
		)
		(pad "1" smd rect
			(at 0 -1.397)
			(size 1.651 1.27)
			(layers "F.Cu" "F.Mask" "F.Paste")
			(net "P5V_HDD1")
		)
		(pad "2" smd rect
			(at 0 1.397)
			(size 1.651 1.27)
			(layers "F.Cu" "F.Mask" "F.Paste")
			(net "5V_PRE_1")
		)
	)
	(footprint ""
		(layer "F.Cu")
		(at 16.824198 -168.152318 -90)
		(property "Reference" "C204"
			(at 0 0 270)
			(layer "F.SilkS")
			(hide yes)
			(effects
				(font
					(size 1.27 1.27)
				)
			)
		)
		(property "Value" "SCD033U25V2KX-GP"
			(at 1.1811 -2.7051 270)
			(unlocked yes)
			(layer "F.Fab")
			(hide yes)
			(effects
				(font
					(size 1.016 1.016)
					(thickness 0.1524)
				)
			)
		)
		(property "Device Type" "C402H22"
			(at 1.1811 -4.2291 270)
			(unlocked yes)
			(layer "F.Fab")
			(hide yes)
			(effects
				(font
					(size 1.016 1.016)
					(thickness 0.1524)
				)
			)
		)
		(duplicate_pad_numbers_are_jumpers no)
		(fp_rect
			(start -0.4318 0.9525)
			(end 0.4318 -0.9525)
			(stroke
				(width 0)
				(type default)
			)
			(fill no)
			(layer "F.CrtYd")
		)
		(fp_rect
			(start -0.4318 0.9525)
			(end 0.4318 -0.9525)
			(stroke
				(width 0)
				(type default)
			)
			(fill no)
			(layer "F.Fab")
		)
		(pad "1" smd custom
			(at 0 -0.4445 270)
			(size 0.1524 0.1524)
			(layers "F.Cu" "F.Mask" "F.Paste")
			(net "SW_HDD_P12")
			(options
				(clearance outline)
				(anchor circle)
			)
			(primitives
				(gr_poly
					(pts
						(arc
							(start 0.3048 -0.2032)
							(mid 0.275042 -0.275042)
							(end 0.2032 -0.3048)
						)
						(arc
							(start -0.2032 -0.3048)
							(mid -0.275042 -0.275042)
							(end -0.3048 -0.2032)
						)
						(arc
							(start -0.3048 0.2032)
							(mid -0.275042 0.275042)
							(end -0.2032 0.3048)
						)
						(arc
							(start 0.2032 0.3048)
							(mid 0.275042 0.275042)
							(end 0.3048 0.2032)
						)
					)
					(width 0)
					(fill yes)
				)
			)
		)
		(pad "2" smd custom
			(at 0 0.4445 270)
			(size 0.1524 0.1524)
			(layers "F.Cu" "F.Mask" "F.Paste")
			(net "GND")
			(options
				(clearance outline)
				(anchor circle)
			)
			(primitives
				(gr_poly
					(pts
						(arc
							(start 0.3048 -0.2032)
							(mid 0.275042 -0.275042)
							(end 0.2032 -0.3048)
						)
						(arc
							(start -0.2032 -0.3048)
							(mid -0.275042 -0.275042)
							(end -0.3048 -0.2032)
						)
						(arc
							(start -0.3048 0.2032)
							(mid -0.275042 0.275042)
							(end -0.2032 0.3048)
						)
						(arc
							(start 0.2032 0.3048)
							(mid 0.275042 0.275042)
							(end 0.3048 0.2032)
						)
					)
					(width 0)
					(fill yes)
				)
			)
		)
	)
	(footprint ""
		(layer "F.Cu")
		(at 276.2758 11.8618)
		(property "Reference" "D44"
			(at 0 0 0)
			(layer "F.SilkS")
			(hide yes)
			(effects
				(font
					(size 1.27 1.27)
				)
			)
		)
		(property "Value" "MMPZ5228BPT-GP"
			(at 0 -6.7818 0)
			(unlocked yes)
			(layer "F.Fab")
			(hide yes)
			(effects
				(font
					(size 1.016 1.016)
					(thickness 0.1524)
				)
			)
		)
		(property "Device Type" "SOD323AKH40"
			(at 0 -8.6868 0)
			(unlocked yes)
			(layer "F.Fab")
			(hide yes)
			(effects
				(font
					(size 1.016 1.016)
					(thickness 0.1524)
				)
			)
		)
		(duplicate_pad_numbers_are_jumpers no)
		(fp_line
			(start -0.889 -1.9304)
			(end 0.889 -1.9304)
			(stroke
				(width 0.1524)
				(type default)
			)
			(layer "F.SilkS")
		)
		(fp_line
			(start -0.889 2.159)
			(end -0.889 -1.9304)
			(stroke
				(width 0.1524)
				(type default)
			)
			(layer "F.SilkS")
		)
		(fp_line
			(start 0.762 2.0574)
			(end -0.762 2.0574)
			(stroke
				(width 0.508)
				(type default)
			)
			(layer "F.SilkS")
		)
		(fp_line
			(start 0.889 -1.9304)
			(end 0.889 2.159)
			(stroke
				(width 0.1524)
				(type default)
			)
			(layer "F.SilkS")
		)
		(fp_line
			(start 0.889 2.159)
			(end -0.889 2.159)
			(stroke
				(width 0.1524)
				(type default)
			)
			(layer "F.SilkS")
		)
		(fp_rect
			(start -1.016 2.3114)
			(end 1.016 -2.0066)
			(stroke
				(width 0)
				(type default)
			)
			(fill no)
			(layer "F.CrtYd")
		)
		(fp_poly
			(pts
				(xy -1.016 -2.0066) (xy 1.016 -2.0066) (xy 1.016 2.3114) (xy -1.016 2.3114)
			)
			(stroke
				(width 0)
				(type default)
			)
			(fill no)
			(layer "F.Fab")
		)
		(pad "A" smd rect
			(at 0 -1.143)
			(size 0.5588 1.016)
			(layers "F.Cu" "F.Mask" "F.Paste")
			(net "GND")
		)
		(pad "K" smd rect
			(at 0 1.143)
			(size 0.5588 1.016)
			(layers "F.Cu" "F.Mask" "F.Paste")
			(net "VCCP")
		)
	)
	(footprint ""
		(layer "F.Cu")
		(at 325.550022 -57.909968 -90)
		(property "Reference" "HDDSAS30"
			(at 0 0 270)
			(layer "F.SilkS")
			(hide yes)
			(effects
				(font
					(size 1.27 1.27)
				)
			)
		)
		(property "Value" "SKT-SAS15P-14P-45-GP"
			(at -20.7645 -8.9789 270)
			(unlocked yes)
			(layer "F.Fab")
			(hide yes)
			(effects
				(font
					(size 1.016 1.016)
					(thickness 0.1524)
				)
			)
		)
		(property "Device Type" "10120818-001C-TRLF"
			(at -20.7645 -10.5029 270)
			(unlocked yes)
			(layer "F.Fab")
			(hide yes)
			(effects
				(font
					(size 1.016 1.016)
					(thickness 0.1524)
				)
			)
		)
		(duplicate_pad_numbers_are_jumpers no)
		(fp_line
			(start 1.651 4.2926)
			(end 1.651 3.0099)
			(stroke
				(width 0.1524)
				(type default)
			)
			(layer "F.SilkS")
		)
		(fp_line
			(start 8.509 4.2926)
			(end 1.651 4.2926)
			(stroke
				(width 0.1524)
				(type default)
			)
			(layer "F.SilkS")
		)
		(fp_line
			(start -23.4188 3.0099)
			(end -23.4188 -3.2512)
			(stroke
				(width 0.1524)
				(type default)
			)
			(layer "F.SilkS")
		)
		(fp_line
			(start 1.651 3.0099)
			(end -23.4188 3.0099)
			(stroke
				(width 0.1524)
				(type default)
			)
			(layer "F.SilkS")
		)
		(fp_line
			(start 8.509 3.0099)
			(end 8.509 4.2926)
			(stroke
				(width 0.1524)
				(type default)
			)
			(layer "F.SilkS")
		)
		(fp_line
			(start 23.4188 3.0099)
			(end 8.509 3.0099)
			(stroke
				(width 0.1524)
				(type default)
			)
			(layer "F.SilkS")
		)
		(fp_line
			(start -23.4188 -3.2512)
			(end 23.4188 -3.2512)
			(stroke
				(width 0.1524)
				(type default)
			)
			(layer "F.SilkS")
		)
		(fp_line
			(start 23.4188 -3.2512)
			(end 23.4188 3.0099)
			(stroke
				(width 0.1524)
				(type default)
			)
			(layer "F.SilkS")
		)
		(fp_line
			(start 15.5067 -3.3401)
			(end 16.2687 -3.3401)
			(stroke
				(width 0.3302)
				(type default)
			)
			(layer "F.SilkS")
		)
		(fp_poly
			(pts
				(xy 15.868904 -3.230372) (xy 16.503904 -3.865372) (xy 15.233904 -3.865372)
			)
			(stroke
				(width 0)
				(type default)
			)
			(fill yes)
			(layer "F.SilkS")
		)
		(fp_poly
			(pts
				(xy -22.8727 -2.7559) (xy 22.8727 -2.7559) (xy 22.8727 2.7559) (xy 8.255 2.7559) (xy 8.255 3.5179)
				(xy 1.905 3.5179) (xy 1.905 2.7559) (xy -22.8727 2.7559)
			)
			(stroke
				(width 0)
				(type default)
			)
			(fill no)
			(layer "F.CrtYd")
		)
		(fp_poly
			(pts
				(xy 1.397 4.5466) (xy 1.397 3.2639) (xy -23.6728 3.2639) (xy -23.6728 -3.5052) (xy 23.6728 -3.5052)
				(xy 23.6728 -0.00635) (xy 22.8727 -0.00635) (xy 22.8727 -2.7559) (xy -22.8727 -2.7559) (xy -22.8727 2.7559)
				(xy 1.905 2.7559) (xy 1.905 3.5179) (xy 8.255 3.5179) (xy 8.255 2.7559) (xy 22.8727 2.7559) (xy 22.8727 0.00635)
				(xy 23.6728 0.00635) (xy 23.6728 3.2639) (xy 8.763 3.2639) (xy 8.763 4.5466)
			)
			(stroke
				(width 0)
				(type default)
			)
			(fill no)
			(layer "F.CrtYd")
		)
		(fp_poly
			(pts
				(xy 1.397 4.5466) (xy 1.397 3.2639) (xy -23.6728 3.2639) (xy -23.6728 -3.5052) (xy 23.6728 -3.5052)
				(xy 23.6728 3.2639) (xy 8.763 3.2639) (xy 8.763 4.5466)
			)
			(stroke
				(width 0)
				(type default)
			)
			(fill no)
			(layer "F.Fab")
		)
		(pad "" np_thru_hole circle
			(at -18.874994 0 270)
			(size 0.254 0.254)
			(drill 1.3462)
			(layers "*.Cu" "*.Mask")
			(clearance 0.9017)
			(thermal_gap 0.9017)
		)
		(pad "" np_thru_hole circle
			(at 18.874994 0 270)
			(size 0.254 0.254)
			(drill 0.9398)
			(layers "*.Cu" "*.Mask")
			(clearance 0.6985)
			(thermal_gap 0.6985)
		)
		(pad "G1" smd rect
			(at 21.874988 0 270)
			(size 2.5908 2.5908)
			(layers "F.Cu" "F.Mask" "F.Paste")
			(net "GND")
		)
		(pad "G2" smd rect
			(at -21.874988 0 270)
			(size 2.5908 2.5908)
			(layers "F.Cu" "F.Mask" "F.Paste")
			(net "GND")
		)
		(pad "P1" smd rect
			(at 1.905 -1.82499 270)
			(size 0.6096 2.3622)
			(layers "F.Cu" "F.Mask" "F.Paste")
			(net "Net_2056")
		)
		(pad "P2" smd rect
			(at 0.635 -1.82499 270)
			(size 0.6096 2.3622)
			(layers "F.Cu" "F.Mask" "F.Paste")
			(net "Net_2057")
		)
		(pad "P3" smd rect
			(at -0.635 -1.82499 270)
			(size 0.6096 2.3622)
			(layers "F.Cu" "F.Mask" "F.Paste")
			(net "Net_2058")
		)
		(pad "P4" smd rect
			(at -1.905 -1.82499 270)
			(size 0.6096 2.3622)
			(layers "F.Cu" "F.Mask" "F.Paste")
			(net "GND")
		)
		(pad "P5" smd rect
			(at -3.175 -1.82499 270)
			(size 0.6096 2.3622)
			(layers "F.Cu" "F.Mask" "F.Paste")
			(net "HDD_PRSNT_30")
		)
		(pad "P6" smd rect
			(at -4.445 -1.82499 270)
			(size 0.6096 2.3622)
			(layers "F.Cu" "F.Mask" "F.Paste")
			(net "GND")
		)
		(pad "P7" smd rect
			(at -5.715 -1.82499 270)
			(size 0.6096 2.3622)
			(layers "F.Cu" "F.Mask" "F.Paste")
			(net "5V_PRE_30")
		)
		(pad "P8" smd rect
			(at -6.985 -1.82499 270)
			(size 0.6096 2.3622)
			(layers "F.Cu" "F.Mask" "F.Paste")
			(net "P5V_HDD30")
		)
		(pad "P9" smd rect
			(at -8.255 -1.82499 270)
			(size 0.6096 2.3622)
			(layers "F.Cu" "F.Mask" "F.Paste")
			(net "P5V_HDD30")
		)
		(pad "P10" smd rect
			(at -9.525 -1.82499 270)
			(size 0.6096 2.3622)
			(layers "F.Cu" "F.Mask" "F.Paste")
			(net "GND")
		)
		(pad "P11" smd rect
			(at -10.795 -1.82499 270)
			(size 0.6096 2.3622)
			(layers "F.Cu" "F.Mask" "F.Paste")
			(net "ACT_HDD_30")
		)
		(pad "P12" smd rect
			(at -12.065 -1.82499 270)
			(size 0.6096 2.3622)
			(layers "F.Cu" "F.Mask" "F.Paste")
			(net "GND")
		)
		(pad "P13" smd rect
			(at -13.335 -1.82499 270)
			(size 0.6096 2.3622)
			(layers "F.Cu" "F.Mask" "F.Paste")
			(net "12V_PRE_30")
		)
		(pad "P14" smd rect
			(at -14.605 -1.82499 270)
			(size 0.6096 2.3622)
			(layers "F.Cu" "F.Mask" "F.Paste")
			(net "P12V_HDD30")
		)
		(pad "P15" smd rect
			(at -15.875 -1.82499 270)
			(size 0.6096 2.3622)
			(layers "F.Cu" "F.Mask" "F.Paste")
			(net "P12V_HDD30")
		)
		(pad "S1" smd rect
			(at 15.875 -1.82499 270)
			(size 0.6096 2.3622)
			(layers "F.Cu" "F.Mask" "F.Paste")
			(net "GND")
		)
		(pad "S2" smd rect
			(at 14.605 -1.82499 270)
			(size 0.6096 2.3622)
			(layers "F.Cu" "F.Mask" "F.Paste")
			(net "SAS_HDD_RX_P30")
		)
		(pad "S3" smd rect
			(at 13.335 -1.82499 270)
			(size 0.6096 2.3622)
			(layers "F.Cu" "F.Mask" "F.Paste")
			(net "SAS_HDD_RX_N30")
		)
		(pad "S4" smd rect
			(at 12.065 -1.82499 270)
			(size 0.6096 2.3622)
			(layers "F.Cu" "F.Mask" "F.Paste")
			(net "GND")
		)
		(pad "S5" smd rect
			(at 10.795 -1.82499 270)
			(size 0.6096 2.3622)
			(layers "F.Cu" "F.Mask" "F.Paste")
			(net "PHY_DRV_A_TO_SCC_A_30_DN")
		)
		(pad "S6" smd rect
			(at 9.525 -1.82499 270)
			(size 0.6096 2.3622)
			(layers "F.Cu" "F.Mask" "F.Paste")
			(net "PHY_DRV_A_TO_SCC_A_30_DP")
		)
		(pad "S7" smd rect
			(at 8.255 -1.82499 270)
			(size 0.6096 2.3622)
			(layers "F.Cu" "F.Mask" "F.Paste")
			(net "GND")
		)
		(pad "S8" smd rect
			(at 7.480046 2.845054 270)
			(size 0.508 2.3622)
			(layers "F.Cu" "F.Mask" "F.Paste")
			(net "GND")
		)
		(pad "S9" smd rect
			(at 6.679946 2.845054 270)
			(size 0.508 2.3622)
			(layers "F.Cu" "F.Mask" "F.Paste")
			(net "Net_469")
		)
		(pad "S10" smd rect
			(at 5.8801 2.845054 270)
			(size 0.508 2.3622)
			(layers "F.Cu" "F.Mask" "F.Paste")
			(net "Net_361")
		)
		(pad "S11" smd rect
			(at 5.08 2.845054 270)
			(size 0.508 2.3622)
			(layers "F.Cu" "F.Mask" "F.Paste")
			(net "GND")
		)
		(pad "S12" smd rect
			(at 4.2799 2.845054 270)
			(size 0.508 2.3622)
			(layers "F.Cu" "F.Mask" "F.Paste")
			(net "Net_397")
		)
		(pad "S13" smd rect
			(at 3.480054 2.845054 270)
			(size 0.508 2.3622)
			(layers "F.Cu" "F.Mask" "F.Paste")
			(net "Net_433")
		)
		(pad "S14" smd rect
			(at 2.679954 2.845054 270)
			(size 0.508 2.3622)
			(layers "F.Cu" "F.Mask" "F.Paste")
			(net "GND")
		)
		(zone
			(layer "F.Cu")
			(hatch none 0.5)
			(connect_pads
				(clearance 0)
			)
			(min_thickness 0.25)
			(keepout
				(tracks allowed)
				(vias not_allowed)
				(pads allowed)
				(copperpour not_allowed)
				(footprints allowed)
			)
			(placement
				(enabled no)
				(sheetname "")
			)
			(fill
				(thermal_gap 0.5)
				(thermal_bridge_width 0.5)
				(island_removal_mode 0)
			)
			(polygon
				(pts
					(xy 329.207622 -74.648568) (xy 322.133722 -74.648568) (xy 322.133722 -81.582768) (xy 323.238622 -81.582768)
					(xy 323.238622 -77.467968) (xy 327.861422 -77.467968) (xy 327.861422 -81.582768) (xy 329.207622 -81.582768)
				)
			)
		)
		(zone
			(layer "F.Cu")
			(hatch none 0.5)
			(connect_pads
				(clearance 0)
			)
			(min_thickness 0.25)
			(keepout
				(tracks not_allowed)
				(vias allowed)
				(pads allowed)
				(copperpour not_allowed)
				(footprints allowed)
			)
			(placement
				(enabled no)
				(sheetname "")
			)
			(fill
				(thermal_gap 0.5)
				(thermal_bridge_width 0.5)
				(island_removal_mode 0)
			)
			(polygon
				(pts
					(xy 329.207622 -74.648568) (xy 322.133722 -74.648568) (xy 322.133722 -81.582768) (xy 323.238622 -81.582768)
					(xy 323.238622 -77.467968) (xy 327.861422 -77.467968) (xy 327.861422 -81.582768) (xy 329.207622 -81.582768)
				)
			)
		)
		(zone
			(layer "F.Cu")
			(hatch none 0.5)
			(connect_pads
				(clearance 0)
			)
			(min_thickness 0.25)
			(keepout
				(tracks allowed)
				(vias not_allowed)
				(pads allowed)
				(copperpour not_allowed)
				(footprints allowed)
			)
			(placement
				(enabled no)
				(sheetname "")
			)
			(fill
				(thermal_gap 0.5)
				(thermal_bridge_width 0.5)
				(island_removal_mode 0)
			)
			(polygon
				(pts
					(xy 329.207622 -41.171368) (xy 322.133722 -41.171368) (xy 322.133722 -34.237168) (xy 323.238622 -34.237168)
					(xy 323.238622 -38.351968) (xy 327.861422 -38.351968) (xy 327.861422 -34.237168) (xy 329.207622 -34.237168)
				)
			)
		)
		(zone
			(layer "F.Cu")
			(hatch none 0.5)
			(connect_pads
				(clearance 0)
			)
			(min_thickness 0.25)
			(keepout
				(tracks not_allowed)
				(vias allowed)
				(pads allowed)
				(copperpour not_allowed)
				(footprints allowed)
			)
			(placement
				(enabled no)
				(sheetname "")
			)
			(fill
				(thermal_gap 0.5)
				(thermal_bridge_width 0.5)
				(island_removal_mode 0)
			)
			(polygon
				(pts
					(xy 329.207622 -41.171368) (xy 322.133722 -41.171368) (xy 322.133722 -34.237168) (xy 323.238622 -34.237168)
					(xy 323.238622 -38.351968) (xy 327.861422 -38.351968) (xy 327.861422 -34.237168) (xy 329.207622 -34.237168)
				)
			)
		)
		(zone
			(layers "F.Cu" "B.Cu" "In1.Cu" "In2.Cu" "In3.Cu" "In4.Cu" "In5.Cu" "In6.Cu"
				"In7.Cu" "In8.Cu" "In9.Cu" "In10.Cu"
			)
			(hatch none 0.5)
			(connect_pads
				(clearance 0)
			)
			(min_thickness 0.25)
			(keepout
				(tracks not_allowed)
				(vias allowed)
				(pads allowed)
				(copperpour not_allowed)
				(footprints allowed)
			)
			(placement
				(enabled no)
				(sheetname "")
			)
			(fill
				(thermal_gap 0.5)
				(thermal_bridge_width 0.5)
				(island_removal_mode 0)
			)
			(polygon
				(pts
					(arc
						(start 326.324722 -39.034974)
						(mid 324.775322 -39.034974)
						(end 326.324722 -39.034974)
					)
				)
			)
		)
		(zone
			(layers "F.Cu" "B.Cu" "In1.Cu" "In2.Cu" "In3.Cu" "In4.Cu" "In5.Cu" "In6.Cu"
				"In7.Cu" "In8.Cu" "In9.Cu" "In10.Cu"
			)
			(hatch none 0.5)
			(connect_pads
				(clearance 0)
			)
			(min_thickness 0.25)
			(keepout
				(tracks not_allowed)
				(vias allowed)
				(pads allowed)
				(copperpour not_allowed)
				(footprints allowed)
			)
			(placement
				(enabled no)
				(sheetname "")
			)
			(fill
				(thermal_gap 0.5)
				(thermal_bridge_width 0.5)
				(island_removal_mode 0)
			)
			(polygon
				(pts
					(arc
						(start 326.527922 -76.784962)
						(mid 324.572122 -76.784962)
						(end 326.527922 -76.784962)
					)
				)
			)
		)
	)
	(footprint ""
		(layer "F.Cu")
		(at 427.390052 -279.596342 90)
		(property "Reference" "C165"
			(at 0 0 90)
			(layer "F.SilkS")
			(hide yes)
			(effects
				(font
					(size 1.27 1.27)
				)
			)
		)
		(property "Value" "SCD033U25V2KX-GP"
			(at 1.1811 -2.7051 90)
			(unlocked yes)
			(layer "F.Fab")
			(hide yes)
			(effects
				(font
					(size 1.016 1.016)
					(thickness 0.1524)
				)
			)
		)
		(property "Device Type" "C402H22"
			(at 1.1811 -4.2291 90)
			(unlocked yes)
			(layer "F.Fab")
			(hide yes)
			(effects
				(font
					(size 1.016 1.016)
					(thickness 0.1524)
				)
			)
		)
		(duplicate_pad_numbers_are_jumpers no)
		(fp_rect
			(start -0.4318 0.9525)
			(end 0.4318 -0.9525)
			(stroke
				(width 0)
				(type default)
			)
			(fill no)
			(layer "F.CrtYd")
		)
		(fp_rect
			(start -0.4318 0.9525)
			(end 0.4318 -0.9525)
			(stroke
				(width 0)
				(type default)
			)
			(fill no)
			(layer "F.Fab")
		)
		(pad "1" smd custom
			(at 0 -0.4445 90)
			(size 0.1524 0.1524)
			(layers "F.Cu" "F.Mask" "F.Paste")
			(net "SW_HDD_P9")
			(options
				(clearance outline)
				(anchor circle)
			)
			(primitives
				(gr_poly
					(pts
						(arc
							(start 0.3048 -0.2032)
							(mid 0.275042 -0.275042)
							(end 0.2032 -0.3048)
						)
						(arc
							(start -0.2032 -0.3048)
							(mid -0.275042 -0.275042)
							(end -0.3048 -0.2032)
						)
						(arc
							(start -0.3048 0.2032)
							(mid -0.275042 0.275042)
							(end -0.2032 0.3048)
						)
						(arc
							(start 0.2032 0.3048)
							(mid 0.275042 0.275042)
							(end 0.3048 0.2032)
						)
					)
					(width 0)
					(fill yes)
				)
			)
		)
		(pad "2" smd custom
			(at 0 0.4445 90)
			(size 0.1524 0.1524)
			(layers "F.Cu" "F.Mask" "F.Paste")
			(net "GND")
			(options
				(clearance outline)
				(anchor circle)
			)
			(primitives
				(gr_poly
					(pts
						(arc
							(start 0.3048 -0.2032)
							(mid 0.275042 -0.275042)
							(end 0.2032 -0.3048)
						)
						(arc
							(start -0.2032 -0.3048)
							(mid -0.275042 -0.275042)
							(end -0.3048 -0.2032)
						)
						(arc
							(start -0.3048 0.2032)
							(mid -0.275042 0.275042)
							(end -0.2032 0.3048)
						)
						(arc
							(start 0.2032 0.3048)
							(mid 0.275042 0.275042)
							(end 0.3048 0.2032)
						)
					)
					(width 0)
					(fill yes)
				)
			)
		)
	)
	(footprint ""
		(layer "F.Cu")
		(at 272.34007 -9.901428 180)
		(property "Reference" "TP192"
			(at 0 0 180)
			(layer "F.SilkS")
			(hide yes)
			(effects
				(font
					(size 1.27 1.27)
				)
			)
		)
		(property "Value" "TPAD32-GP"
			(at -0.0508 -1.6764 180)
			(unlocked yes)
			(layer "F.Fab")
			(hide yes)
			(effects
				(font
					(size 1.016 1.016)
					(thickness 0.1524)
				)
			)
		)
		(property "Device Type" "TPAD32"
			(at -0.0508 -3.2004 180)
			(unlocked yes)
			(layer "F.Fab")
			(hide yes)
			(effects
				(font
					(size 1.016 1.016)
					(thickness 0.1524)
				)
			)
		)
		(duplicate_pad_numbers_are_jumpers no)
		(fp_poly
			(pts
				(arc
					(start -0.4064 0)
					(mid 0.4064 0)
					(end -0.4064 0)
				)
			)
			(stroke
				(width 0)
				(type default)
			)
			(fill no)
			(layer "F.CrtYd")
		)
		(fp_poly
			(pts
				(arc
					(start -0.7112 0)
					(mid 0.7112 0)
					(end -0.7112 0)
				)
			)
			(stroke
				(width 0)
				(type default)
			)
			(fill no)
			(layer "F.Fab")
		)
		(pad "1" smd circle
			(at 0 0 180)
			(size 0.8128 0.8128)
			(layers "F.Cu" "F.Mask" "F.Paste")
			(net "TP_COMP_B_NCSI_TXD0")
		)
	)
	(footprint ""
		(layer "F.Cu")
		(at 471.924126 -168.126918 -90)
		(property "Reference" "C347"
			(at 0 0 270)
			(layer "F.SilkS")
			(hide yes)
			(effects
				(font
					(size 1.27 1.27)
				)
			)
		)
		(property "Value" "SCD033U25V2KX-GP"
			(at 1.1811 -2.7051 270)
			(unlocked yes)
			(layer "F.Fab")
			(hide yes)
			(effects
				(font
					(size 1.016 1.016)
					(thickness 0.1524)
				)
			)
		)
		(property "Device Type" "C402H22"
			(at 1.1811 -4.2291 270)
			(unlocked yes)
			(layer "F.Fab")
			(hide yes)
			(effects
				(font
					(size 1.016 1.016)
					(thickness 0.1524)
				)
			)
		)
		(duplicate_pad_numbers_are_jumpers no)
		(fp_rect
			(start -0.4318 0.9525)
			(end 0.4318 -0.9525)
			(stroke
				(width 0)
				(type default)
			)
			(fill no)
			(layer "F.CrtYd")
		)
		(fp_rect
			(start -0.4318 0.9525)
			(end 0.4318 -0.9525)
			(stroke
				(width 0)
				(type default)
			)
			(fill no)
			(layer "F.Fab")
		)
		(pad "1" smd custom
			(at 0 -0.4445 270)
			(size 0.1524 0.1524)
			(layers "F.Cu" "F.Mask" "F.Paste")
			(net "SW_HDD_P23")
			(options
				(clearance outline)
				(anchor circle)
			)
			(primitives
				(gr_poly
					(pts
						(arc
							(start 0.3048 -0.2032)
							(mid 0.275042 -0.275042)
							(end 0.2032 -0.3048)
						)
						(arc
							(start -0.2032 -0.3048)
							(mid -0.275042 -0.275042)
							(end -0.3048 -0.2032)
						)
						(arc
							(start -0.3048 0.2032)
							(mid -0.275042 0.275042)
							(end -0.2032 0.3048)
						)
						(arc
							(start 0.2032 0.3048)
							(mid 0.275042 0.275042)
							(end 0.3048 0.2032)
						)
					)
					(width 0)
					(fill yes)
				)
			)
		)
		(pad "2" smd custom
			(at 0 0.4445 270)
			(size 0.1524 0.1524)
			(layers "F.Cu" "F.Mask" "F.Paste")
			(net "GND")
			(options
				(clearance outline)
				(anchor circle)
			)
			(primitives
				(gr_poly
					(pts
						(arc
							(start 0.3048 -0.2032)
							(mid 0.275042 -0.275042)
							(end 0.2032 -0.3048)
						)
						(arc
							(start -0.2032 -0.3048)
							(mid -0.275042 -0.275042)
							(end -0.3048 -0.2032)
						)
						(arc
							(start -0.3048 0.2032)
							(mid -0.275042 0.275042)
							(end -0.2032 0.3048)
						)
						(arc
							(start 0.2032 0.3048)
							(mid 0.275042 0.275042)
							(end 0.3048 0.2032)
						)
					)
					(width 0)
					(fill yes)
				)
			)
		)
	)
	(footprint ""
		(layer "F.Cu")
		(at 134.283196 -292.804342 90)
		(property "Reference" "C79"
			(at 0 0 90)
			(layer "F.SilkS")
			(hide yes)
			(effects
				(font
					(size 1.27 1.27)
				)
			)
		)
		(property "Value" "SC1U16V3KX-5GP"
			(at 0 -2.8194 90)
			(unlocked yes)
			(layer "F.Fab")
			(hide yes)
			(effects
				(font
					(size 1.016 1.016)
					(thickness 0.1524)
				)
			)
		)
		(property "Device Type" "C603H36"
			(at 0 -4.3434 90)
			(unlocked yes)
			(layer "F.Fab")
			(hide yes)
			(effects
				(font
					(size 1.016 1.016)
					(thickness 0.1524)
				)
			)
		)
		(duplicate_pad_numbers_are_jumpers no)
		(fp_line
			(start 0.508 0)
			(end -0.508 0)
			(stroke
				(width 0.2032)
				(type default)
			)
			(layer "F.SilkS")
		)
		(fp_rect
			(start -0.5842 1.3335)
			(end 0.5842 -1.3335)
			(stroke
				(width 0)
				(type default)
			)
			(fill no)
			(layer "F.CrtYd")
		)
		(fp_rect
			(start -0.5842 1.3335)
			(end 0.5842 -1.3335)
			(stroke
				(width 0)
				(type default)
			)
			(fill no)
			(layer "F.Fab")
		)
		(pad "1" smd custom
			(at 0 -0.762 90)
			(size 0.2159 0.2159)
			(layers "F.Cu" "F.Mask" "F.Paste")
			(net "P5V_HDD3")
			(options
				(clearance outline)
				(anchor circle)
			)
			(primitives
				(gr_poly
					(pts
						(arc
							(start -0.3302 -0.4318)
							(mid -0.402042 -0.402042)
							(end -0.4318 -0.3302)
						)
						(arc
							(start -0.4318 0.3302)
							(mid -0.402042 0.402042)
							(end -0.3302 0.4318)
						)
						(arc
							(start 0.3302 0.4318)
							(mid 0.402042 0.402042)
							(end 0.4318 0.3302)
						)
						(arc
							(start 0.4318 -0.3302)
							(mid 0.402042 -0.402042)
							(end 0.3302 -0.4318)
						)
					)
					(width 0)
					(fill yes)
				)
			)
		)
		(pad "2" smd custom
			(at 0 0.762 90)
			(size 0.2159 0.2159)
			(layers "F.Cu" "F.Mask" "F.Paste")
			(net "GND")
			(options
				(clearance outline)
				(anchor circle)
			)
			(primitives
				(gr_poly
					(pts
						(arc
							(start -0.3302 -0.4318)
							(mid -0.402042 -0.402042)
							(end -0.4318 -0.3302)
						)
						(arc
							(start -0.4318 0.3302)
							(mid -0.402042 0.402042)
							(end -0.3302 0.4318)
						)
						(arc
							(start 0.3302 0.4318)
							(mid 0.402042 0.402042)
							(end 0.4318 0.3302)
						)
						(arc
							(start 0.4318 -0.3302)
							(mid 0.402042 -0.402042)
							(end 0.3302 -0.4318)
						)
					)
					(width 0)
					(fill yes)
				)
			)
		)
	)
	(footprint ""
		(layer "F.Cu")
		(at 349.565722 -146.435826)
		(property "Reference" "C565"
			(at 0 0 0)
			(layer "F.SilkS")
			(hide yes)
			(effects
				(font
					(size 1.27 1.27)
				)
			)
		)
		(property "Value" "SCD1U25V2KX-2-GP"
			(at 1.1811 -2.7051 0)
			(unlocked yes)
			(layer "F.Fab")
			(hide yes)
			(effects
				(font
					(size 1.016 1.016)
					(thickness 0.1524)
				)
			)
		)
		(property "Device Type" "C402H22"
			(at 1.1811 -4.2291 0)
			(unlocked yes)
			(layer "F.Fab")
			(hide yes)
			(effects
				(font
					(size 1.016 1.016)
					(thickness 0.1524)
				)
			)
		)
		(duplicate_pad_numbers_are_jumpers no)
		(fp_rect
			(start -0.4318 0.9525)
			(end 0.4318 -0.9525)
			(stroke
				(width 0)
				(type default)
			)
			(fill no)
			(layer "F.CrtYd")
		)
		(fp_rect
			(start -0.4318 0.9525)
			(end 0.4318 -0.9525)
			(stroke
				(width 0)
				(type default)
			)
			(fill no)
			(layer "F.Fab")
		)
		(pad "1" smd custom
			(at 0 -0.4445)
			(size 0.1524 0.1524)
			(layers "F.Cu" "F.Mask" "F.Paste")
			(net "P12V_B")
			(options
				(clearance outline)
				(anchor circle)
			)
			(primitives
				(gr_poly
					(pts
						(arc
							(start 0.3048 -0.2032)
							(mid 0.275042 -0.275042)
							(end 0.2032 -0.3048)
						)
						(arc
							(start -0.2032 -0.3048)
							(mid -0.275042 -0.275042)
							(end -0.3048 -0.2032)
						)
						(arc
							(start -0.3048 0.2032)
							(mid -0.275042 0.275042)
							(end -0.2032 0.3048)
						)
						(arc
							(start 0.2032 0.3048)
							(mid 0.275042 0.275042)
							(end 0.3048 0.2032)
						)
					)
					(width 0)
					(fill yes)
				)
			)
		)
		(pad "2" smd custom
			(at 0 0.4445)
			(size 0.1524 0.1524)
			(layers "F.Cu" "F.Mask" "F.Paste")
			(net "GND")
			(options
				(clearance outline)
				(anchor circle)
			)
			(primitives
				(gr_poly
					(pts
						(arc
							(start 0.3048 -0.2032)
							(mid 0.275042 -0.275042)
							(end 0.2032 -0.3048)
						)
						(arc
							(start -0.2032 -0.3048)
							(mid -0.275042 -0.275042)
							(end -0.3048 -0.2032)
						)
						(arc
							(start -0.3048 0.2032)
							(mid -0.275042 0.275042)
							(end -0.2032 0.3048)
						)
						(arc
							(start 0.2032 0.3048)
							(mid 0.275042 0.275042)
							(end 0.3048 0.2032)
						)
					)
					(width 0)
					(fill yes)
				)
			)
		)
	)
	(footprint ""
		(layer "F.Cu")
		(at 190.8048 -53.2384 90)
		(property "Reference" "C423"
			(at 0 0 90)
			(layer "F.SilkS")
			(hide yes)
			(effects
				(font
					(size 1.27 1.27)
				)
			)
		)
		(property "Value" "SCD01U50V2KX-1GP"
			(at 1.1811 -2.7051 90)
			(unlocked yes)
			(layer "F.Fab")
			(hide yes)
			(effects
				(font
					(size 1.016 1.016)
					(thickness 0.1524)
				)
			)
		)
		(property "Device Type" "C402H22"
			(at 1.1811 -4.2291 90)
			(unlocked yes)
			(layer "F.Fab")
			(hide yes)
			(effects
				(font
					(size 1.016 1.016)
					(thickness 0.1524)
				)
			)
		)
		(duplicate_pad_numbers_are_jumpers no)
		(fp_rect
			(start -0.4318 0.9525)
			(end 0.4318 -0.9525)
			(stroke
				(width 0)
				(type default)
			)
			(fill no)
			(layer "F.CrtYd")
		)
		(fp_rect
			(start -0.4318 0.9525)
			(end 0.4318 -0.9525)
			(stroke
				(width 0)
				(type default)
			)
			(fill no)
			(layer "F.Fab")
		)
		(pad "1" smd custom
			(at 0 -0.4445 90)
			(size 0.1524 0.1524)
			(layers "F.Cu" "F.Mask" "F.Paste")
			(net "HDD_PRSNT_29")
			(options
				(clearance outline)
				(anchor circle)
			)
			(primitives
				(gr_poly
					(pts
						(arc
							(start 0.3048 -0.2032)
							(mid 0.275042 -0.275042)
							(end 0.2032 -0.3048)
						)
						(arc
							(start -0.2032 -0.3048)
							(mid -0.275042 -0.275042)
							(end -0.3048 -0.2032)
						)
						(arc
							(start -0.3048 0.2032)
							(mid -0.275042 0.275042)
							(end -0.2032 0.3048)
						)
						(arc
							(start 0.2032 0.3048)
							(mid 0.275042 0.275042)
							(end 0.3048 0.2032)
						)
					)
					(width 0)
					(fill yes)
				)
			)
		)
		(pad "2" smd custom
			(at 0 0.4445 90)
			(size 0.1524 0.1524)
			(layers "F.Cu" "F.Mask" "F.Paste")
			(net "GND")
			(options
				(clearance outline)
				(anchor circle)
			)
			(primitives
				(gr_poly
					(pts
						(arc
							(start 0.3048 -0.2032)
							(mid 0.275042 -0.275042)
							(end 0.2032 -0.3048)
						)
						(arc
							(start -0.2032 -0.3048)
							(mid -0.275042 -0.275042)
							(end -0.3048 -0.2032)
						)
						(arc
							(start -0.3048 0.2032)
							(mid -0.275042 0.275042)
							(end -0.2032 0.3048)
						)
						(arc
							(start 0.2032 0.3048)
							(mid 0.275042 0.275042)
							(end 0.3048 0.2032)
						)
					)
					(width 0)
					(fill yes)
				)
			)
		)
	)
	(footprint ""
		(layer "F.Cu")
		(at 116.121942 -275.291804 90)
		(property "Reference" "Q19"
			(at 0 0 90)
			(layer "F.SilkS")
			(hide yes)
			(effects
				(font
					(size 1.27 1.27)
				)
			)
		)
		(property "Value" "2N7002KDW-GP"
			(at -2.3622 -8.2042 90)
			(unlocked yes)
			(layer "F.Fab")
			(hide yes)
			(effects
				(font
					(size 1.016 1.016)
					(thickness 0.1524)
				)
			)
		)
		(property "Device Type" "SOT-363H44"
			(at -2.3622 -10.1092 90)
			(unlocked yes)
			(layer "F.Fab")
			(hide yes)
			(effects
				(font
					(size 1.016 1.016)
					(thickness 0.1524)
				)
			)
		)
		(duplicate_pad_numbers_are_jumpers no)
		(fp_line
			(start 1.4478 -1.7018)
			(end -1.4478 -1.7018)
			(stroke
				(width 0.1524)
				(type default)
			)
			(layer "F.SilkS")
		)
		(fp_line
			(start -1.4478 -1.7018)
			(end -1.4478 1.7018)
			(stroke
				(width 0.1524)
				(type default)
			)
			(layer "F.SilkS")
		)
		(fp_line
			(start -1.27 1.524)
			(end -1.27 0.6604)
			(stroke
				(width 0.4826)
				(type default)
			)
			(layer "F.SilkS")
		)
		(fp_line
			(start 1.4478 1.7018)
			(end 1.4478 -1.7018)
			(stroke
				(width 0.1524)
				(type default)
			)
			(layer "F.SilkS")
		)
		(fp_line
			(start -1.4478 1.7018)
			(end 1.4478 1.7018)
			(stroke
				(width 0.1524)
				(type default)
			)
			(layer "F.SilkS")
		)
		(fp_poly
			(pts
				(xy -1.524 -1.778) (xy 1.524 -1.778) (xy 1.524 1.778) (xy -1.524 1.778)
			)
			(stroke
				(width 0)
				(type default)
			)
			(fill no)
			(layer "F.CrtYd")
		)
		(fp_poly
			(pts
				(xy -1.524 -1.778) (xy 1.524 -1.778) (xy 1.524 1.778) (xy -1.524 1.778)
			)
			(stroke
				(width 0)
				(type default)
			)
			(fill no)
			(layer "F.Fab")
		)
		(pad "1" smd rect
			(at -0.65024 0.9398 90)
			(size 0.4064 1.016)
			(layers "F.Cu" "F.Mask" "F.Paste")
			(net "GND")
		)
		(pad "2" smd rect
			(at 0 0.9398 90)
			(size 0.4064 1.016)
			(layers "F.Cu" "F.Mask" "F.Paste")
			(net "SW_PWR_R_HDD3")
		)
		(pad "3" smd rect
			(at 0.65024 0.9398 90)
			(size 0.4064 1.016)
			(layers "F.Cu" "F.Mask" "F.Paste")
			(net "SW_HDD_P3")
		)
		(pad "4" smd rect
			(at 0.65024 -0.9398 90)
			(size 0.4064 1.016)
			(layers "F.Cu" "F.Mask" "F.Paste")
			(net "GND")
		)
		(pad "5" smd rect
			(at 0 -0.9398 90)
			(size 0.4064 1.016)
			(layers "F.Cu" "F.Mask" "F.Paste")
			(net "SW_HDD_G3")
		)
		(pad "6" smd rect
			(at -0.65024 -0.9398 90)
			(size 0.4064 1.016)
			(layers "F.Cu" "F.Mask" "F.Paste")
			(net "SW_HDD_R3")
		)
	)
	(footprint ""
		(layer "F.Cu")
		(at 384.734562 -158.660592 -90)
		(property "Reference" "C299"
			(at 0 0 270)
			(layer "F.SilkS")
			(hide yes)
			(effects
				(font
					(size 1.27 1.27)
				)
			)
		)
		(property "Value" "SCD01U16V1KX-GP"
			(at -2.8321 -1.7399 270)
			(unlocked yes)
			(layer "F.Fab")
			(hide yes)
			(effects
				(font
					(size 1.016 1.016)
					(thickness 0.1524)
				)
			)
		)
		(property "Device Type" "C0201H13"
			(at -2.8321 -3.2639 270)
			(unlocked yes)
			(layer "F.Fab")
			(hide yes)
			(effects
				(font
					(size 1.016 1.016)
					(thickness 0.1524)
				)
			)
		)
		(duplicate_pad_numbers_are_jumpers no)
		(fp_rect
			(start -0.2794 0.6477)
			(end 0.2794 -0.6477)
			(stroke
				(width 0)
				(type default)
			)
			(fill no)
			(layer "F.CrtYd")
		)
		(fp_rect
			(start -0.2794 0.6477)
			(end 0.2794 -0.6477)
			(stroke
				(width 0)
				(type default)
			)
			(fill no)
			(layer "F.Fab")
		)
		(pad "1" smd custom
			(at 0 -0.2794 270)
			(size 0.0762 0.0762)
			(layers "F.Cu" "F.Mask" "F.Paste")
			(net "SAS_HDD_RX_P20")
			(options
				(clearance outline)
				(anchor circle)
			)
			(primitives
				(gr_poly
					(pts
						(arc
							(start 0.1524 -0.127)
							(mid 0.137521 -0.162921)
							(end 0.1016 -0.1778)
						)
						(arc
							(start -0.1016 -0.1778)
							(mid -0.137521 -0.162921)
							(end -0.1524 -0.127)
						)
						(arc
							(start -0.1524 0.127)
							(mid -0.137521 0.162921)
							(end -0.1016 0.1778)
						)
						(arc
							(start 0.1016 0.1778)
							(mid 0.137521 0.162921)
							(end 0.1524 0.127)
						)
					)
					(width 0)
					(fill yes)
				)
			)
		)
		(pad "2" smd custom
			(at 0 0.2794 270)
			(size 0.0762 0.0762)
			(layers "F.Cu" "F.Mask" "F.Paste")
			(net "PHY_SCC_A_TO_DRV_A_20_DP")
			(options
				(clearance outline)
				(anchor circle)
			)
			(primitives
				(gr_poly
					(pts
						(arc
							(start 0.1524 -0.127)
							(mid 0.137521 -0.162921)
							(end 0.1016 -0.1778)
						)
						(arc
							(start -0.1016 -0.1778)
							(mid -0.137521 -0.162921)
							(end -0.1524 -0.127)
						)
						(arc
							(start -0.1524 0.127)
							(mid -0.137521 0.162921)
							(end -0.1016 0.1778)
						)
						(arc
							(start 0.1016 0.1778)
							(mid 0.137521 0.162921)
							(end 0.1524 0.127)
						)
					)
					(width 0)
					(fill yes)
				)
			)
		)
	)
	(footprint ""
		(layer "F.Cu")
		(at 237.996476 -349.211392)
		(property "Reference" "R27"
			(at 0 0 0)
			(layer "F.SilkS")
			(hide yes)
			(effects
				(font
					(size 1.27 1.27)
				)
			)
		)
		(property "Value" "7K32R2F-GP"
			(at 0.064008 -3.993896 0)
			(unlocked yes)
			(layer "F.Fab")
			(hide yes)
			(effects
				(font
					(size 1.016 1.016)
					(thickness 0.1524)
				)
			)
		)
		(property "Device Type" "R402H16"
			(at 0.064008 -5.517896 0)
			(unlocked yes)
			(layer "F.Fab")
			(hide yes)
			(effects
				(font
					(size 1.016 1.016)
					(thickness 0.1524)
				)
			)
		)
		(duplicate_pad_numbers_are_jumpers no)
		(fp_line
			(start -0.508 -0.9398)
			(end -0.508 0.9398)
			(stroke
				(width 0.1524)
				(type default)
			)
			(layer "F.SilkS")
		)
		(fp_line
			(start 0.508 -0.9398)
			(end -0.508 -0.9398)
			(stroke
				(width 0.1524)
				(type default)
			)
			(layer "F.SilkS")
		)
		(fp_rect
			(start -0.508 0.9398)
			(end 0.508 -0.9398)
			(stroke
				(width 0)
				(type default)
			)
			(fill no)
			(layer "F.CrtYd")
		)
		(fp_rect
			(start -0.508 0.9398)
			(end 0.508 -0.9398)
			(stroke
				(width 0)
				(type default)
			)
			(fill no)
			(layer "F.Fab")
		)
		(pad "1" smd custom
			(at 0 -0.4445)
			(size 0.1397 0.1397)
			(layers "F.Cu" "F.Mask" "F.Paste")
			(net "P3V3_STBY_A")
			(options
				(clearance outline)
				(anchor circle)
			)
			(primitives
				(gr_poly
					(pts
						(arc
							(start -0.1778 -0.2794)
							(mid -0.249642 -0.249642)
							(end -0.2794 -0.1778)
						)
						(arc
							(start -0.2794 0.1778)
							(mid -0.249642 0.249642)
							(end -0.1778 0.2794)
						)
						(arc
							(start 0.1778 0.2794)
							(mid 0.249642 0.249642)
							(end 0.2794 0.1778)
						)
						(arc
							(start 0.2794 -0.1778)
							(mid 0.249642 -0.249642)
							(end 0.1778 -0.2794)
						)
					)
					(width 0)
					(fill yes)
				)
			)
		)
		(pad "2" smd custom
			(at 0 0.4445)
			(size 0.1397 0.1397)
			(layers "F.Cu" "F.Mask" "F.Paste")
			(net "P3V3_SENSE")
			(options
				(clearance outline)
				(anchor circle)
			)
			(primitives
				(gr_poly
					(pts
						(arc
							(start -0.1778 -0.2794)
							(mid -0.249642 -0.249642)
							(end -0.2794 -0.1778)
						)
						(arc
							(start -0.2794 0.1778)
							(mid -0.249642 0.249642)
							(end -0.1778 0.2794)
						)
						(arc
							(start 0.1778 0.2794)
							(mid 0.249642 0.249642)
							(end 0.2794 0.1778)
						)
						(arc
							(start 0.2794 -0.1778)
							(mid 0.249642 -0.249642)
							(end 0.1778 -0.2794)
						)
					)
					(width 0)
					(fill yes)
				)
			)
		)
	)
	(footprint ""
		(layer "F.Cu")
		(at 353.184714 -273.660616 -90)
		(property "Reference" "C130"
			(at 0 0 270)
			(layer "F.SilkS")
			(hide yes)
			(effects
				(font
					(size 1.27 1.27)
				)
			)
		)
		(property "Value" "SCD01U16V1KX-GP"
			(at -2.8321 -1.7399 270)
			(unlocked yes)
			(layer "F.Fab")
			(hide yes)
			(effects
				(font
					(size 1.016 1.016)
					(thickness 0.1524)
				)
			)
		)
		(property "Device Type" "C0201H13"
			(at -2.8321 -3.2639 270)
			(unlocked yes)
			(layer "F.Fab")
			(hide yes)
			(effects
				(font
					(size 1.016 1.016)
					(thickness 0.1524)
				)
			)
		)
		(duplicate_pad_numbers_are_jumpers no)
		(fp_rect
			(start -0.2794 0.6477)
			(end 0.2794 -0.6477)
			(stroke
				(width 0)
				(type default)
			)
			(fill no)
			(layer "F.CrtYd")
		)
		(fp_rect
			(start -0.2794 0.6477)
			(end 0.2794 -0.6477)
			(stroke
				(width 0)
				(type default)
			)
			(fill no)
			(layer "F.Fab")
		)
		(pad "1" smd custom
			(at 0 -0.2794 270)
			(size 0.0762 0.0762)
			(layers "F.Cu" "F.Mask" "F.Paste")
			(net "SAS_HDD_RX_P7")
			(options
				(clearance outline)
				(anchor circle)
			)
			(primitives
				(gr_poly
					(pts
						(arc
							(start 0.1524 -0.127)
							(mid 0.137521 -0.162921)
							(end 0.1016 -0.1778)
						)
						(arc
							(start -0.1016 -0.1778)
							(mid -0.137521 -0.162921)
							(end -0.1524 -0.127)
						)
						(arc
							(start -0.1524 0.127)
							(mid -0.137521 0.162921)
							(end -0.1016 0.1778)
						)
						(arc
							(start 0.1016 0.1778)
							(mid 0.137521 0.162921)
							(end 0.1524 0.127)
						)
					)
					(width 0)
					(fill yes)
				)
			)
		)
		(pad "2" smd custom
			(at 0 0.2794 270)
			(size 0.0762 0.0762)
			(layers "F.Cu" "F.Mask" "F.Paste")
			(net "PHY_SCC_A_TO_DRV_A_7_DP")
			(options
				(clearance outline)
				(anchor circle)
			)
			(primitives
				(gr_poly
					(pts
						(arc
							(start 0.1524 -0.127)
							(mid 0.137521 -0.162921)
							(end 0.1016 -0.1778)
						)
						(arc
							(start -0.1016 -0.1778)
							(mid -0.137521 -0.162921)
							(end -0.1524 -0.127)
						)
						(arc
							(start -0.1524 0.127)
							(mid -0.137521 0.162921)
							(end -0.1016 0.1778)
						)
						(arc
							(start 0.1016 0.1778)
							(mid 0.137521 0.162921)
							(end 0.1524 0.127)
						)
					)
					(width 0)
					(fill yes)
				)
			)
		)
	)
	(footprint ""
		(layer "F.Cu")
		(at 263.09828 14.44117)
		(property "Reference" "U34"
			(at 0 0 0)
			(layer "F.SilkS")
			(hide yes)
			(effects
				(font
					(size 1.27 1.27)
				)
			)
		)
		(property "Value" "TPS2065DBVT-GP"
			(at 0 -5.1308 0)
			(unlocked yes)
			(layer "F.Fab")
			(hide yes)
			(effects
				(font
					(size 1.016 1.016)
					(thickness 0.1524)
				)
			)
		)
		(property "Device Type" "SOT-23-5H58"
			(at 0 -6.7564 0)
			(unlocked yes)
			(layer "F.Fab")
			(hide yes)
			(effects
				(font
					(size 1.016 1.016)
					(thickness 0.1524)
				)
			)
		)
		(duplicate_pad_numbers_are_jumpers no)
		(fp_line
			(start -1.778 -2.286)
			(end -1.778 2.286)
			(stroke
				(width 0.1524)
				(type default)
			)
			(layer "F.SilkS")
		)
		(fp_line
			(start -1.778 2.286)
			(end -0.254 2.286)
			(stroke
				(width 0.1524)
				(type default)
			)
			(layer "F.SilkS")
		)
		(fp_line
			(start -1.778 2.286)
			(end 1.778 2.286)
			(stroke
				(width 0.1524)
				(type default)
			)
			(layer "F.SilkS")
		)
		(fp_line
			(start -1.7272 2.2352)
			(end -1.7272 0.762)
			(stroke
				(width 0.3302)
				(type default)
			)
			(layer "F.SilkS")
		)
		(fp_line
			(start -0.7112 2.2352)
			(end -1.7272 2.2352)
			(stroke
				(width 0.3302)
				(type default)
			)
			(layer "F.SilkS")
		)
		(fp_line
			(start -0.254 2.286)
			(end 1.778 2.286)
			(stroke
				(width 0.1524)
				(type default)
			)
			(layer "F.SilkS")
		)
		(fp_line
			(start 1.778 -2.286)
			(end -1.778 -2.286)
			(stroke
				(width 0.1524)
				(type default)
			)
			(layer "F.SilkS")
		)
		(fp_line
			(start 1.778 2.286)
			(end 1.778 -2.286)
			(stroke
				(width 0.1524)
				(type default)
			)
			(layer "F.SilkS")
		)
		(fp_poly
			(pts
				(xy -0.9652 2.4384) (xy -1.3208 2.794) (xy -0.6096 2.794)
			)
			(stroke
				(width 0)
				(type default)
			)
			(fill yes)
			(layer "F.SilkS")
		)
		(fp_rect
			(start -1.778 2.286)
			(end 1.778 -2.286)
			(stroke
				(width 0)
				(type default)
			)
			(fill no)
			(layer "F.CrtYd")
		)
		(fp_rect
			(start -1.778 2.286)
			(end 1.778 -2.286)
			(stroke
				(width 0)
				(type default)
			)
			(fill no)
			(layer "F.Fab")
		)
		(pad "1" smd rect
			(at -0.94996 1.143)
			(size 0.508 1.524)
			(layers "F.Cu" "F.Mask" "F.Paste")
			(net "P5V_USB_A")
		)
		(pad "2" smd rect
			(at 0 1.143)
			(size 0.508 1.524)
			(layers "F.Cu" "F.Mask" "F.Paste")
			(net "GND")
		)
		(pad "3" smd rect
			(at 0.94996 1.143)
			(size 0.508 1.524)
			(layers "F.Cu" "F.Mask" "F.Paste")
			(net "USB_OCS_N1")
		)
		(pad "4" smd rect
			(at 0.94996 -1.143)
			(size 0.508 1.524)
			(layers "F.Cu" "F.Mask" "F.Paste")
			(net "USB_EN_1")
		)
		(pad "5" smd rect
			(at -0.94996 -1.143)
			(size 0.508 1.524)
			(layers "F.Cu" "F.Mask" "F.Paste")
			(net "P5V_A_2")
		)
	)
	(footprint ""
		(layer "F.Cu")
		(at 190.213488 -274.219416 90)
		(property "Reference" "C103"
			(at 0 0 90)
			(layer "F.SilkS")
			(hide yes)
			(effects
				(font
					(size 1.27 1.27)
				)
			)
		)
		(property "Value" "SCD01U16V1KX-GP"
			(at -2.8321 -1.7399 90)
			(unlocked yes)
			(layer "F.Fab")
			(hide yes)
			(effects
				(font
					(size 1.016 1.016)
					(thickness 0.1524)
				)
			)
		)
		(property "Device Type" "C0201H13"
			(at -2.8321 -3.2639 90)
			(unlocked yes)
			(layer "F.Fab")
			(hide yes)
			(effects
				(font
					(size 1.016 1.016)
					(thickness 0.1524)
				)
			)
		)
		(duplicate_pad_numbers_are_jumpers no)
		(fp_rect
			(start -0.2794 0.6477)
			(end 0.2794 -0.6477)
			(stroke
				(width 0)
				(type default)
			)
			(fill no)
			(layer "F.CrtYd")
		)
		(fp_rect
			(start -0.2794 0.6477)
			(end 0.2794 -0.6477)
			(stroke
				(width 0)
				(type default)
			)
			(fill no)
			(layer "F.Fab")
		)
		(pad "1" smd custom
			(at 0 -0.2794 90)
			(size 0.0762 0.0762)
			(layers "F.Cu" "F.Mask" "F.Paste")
			(net "SAS_HDD_RX_N5")
			(options
				(clearance outline)
				(anchor circle)
			)
			(primitives
				(gr_poly
					(pts
						(arc
							(start 0.1524 -0.127)
							(mid 0.137521 -0.162921)
							(end 0.1016 -0.1778)
						)
						(arc
							(start -0.1016 -0.1778)
							(mid -0.137521 -0.162921)
							(end -0.1524 -0.127)
						)
						(arc
							(start -0.1524 0.127)
							(mid -0.137521 0.162921)
							(end -0.1016 0.1778)
						)
						(arc
							(start 0.1016 0.1778)
							(mid 0.137521 0.162921)
							(end 0.1524 0.127)
						)
					)
					(width 0)
					(fill yes)
				)
			)
		)
		(pad "2" smd custom
			(at 0 0.2794 90)
			(size 0.0762 0.0762)
			(layers "F.Cu" "F.Mask" "F.Paste")
			(net "PHY_SCC_A_TO_DRV_A_5_DN")
			(options
				(clearance outline)
				(anchor circle)
			)
			(primitives
				(gr_poly
					(pts
						(arc
							(start 0.1524 -0.127)
							(mid 0.137521 -0.162921)
							(end 0.1016 -0.1778)
						)
						(arc
							(start -0.1016 -0.1778)
							(mid -0.137521 -0.162921)
							(end -0.1524 -0.127)
						)
						(arc
							(start -0.1524 0.127)
							(mid -0.137521 0.162921)
							(end -0.1016 0.1778)
						)
						(arc
							(start 0.1016 0.1778)
							(mid 0.137521 0.162921)
							(end 0.1524 0.127)
						)
					)
					(width 0)
					(fill yes)
				)
			)
		)
	)
	(footprint ""
		(layer "F.Cu")
		(at 175.550068 -94.400116)
		(property "Reference" "FLED18"
			(at 0 0 0)
			(layer "F.SilkS")
			(hide yes)
			(effects
				(font
					(size 1.27 1.27)
				)
			)
		)
		(property "Value" "LED-BY-19-GP"
			(at -2.132076 1.414018 0)
			(unlocked yes)
			(layer "F.Fab")
			(hide yes)
			(effects
				(font
					(size 1.016 1.016)
					(thickness 0.1524)
				)
			)
		)
		(property "Device Type" "LED-1615-4PH26"
			(at -2.132076 -0.109982 0)
			(unlocked yes)
			(layer "F.Fab")
			(hide yes)
			(effects
				(font
					(size 1.016 1.016)
					(thickness 0.1524)
				)
			)
		)
		(duplicate_pad_numbers_are_jumpers no)
		(fp_line
			(start -1.2954 0.254)
			(end -1.2954 1.6002)
			(stroke
				(width 0.508)
				(type default)
			)
			(layer "F.SilkS")
		)
		(fp_line
			(start -1.2954 1.6002)
			(end 1.2954 1.6002)
			(stroke
				(width 0.508)
				(type default)
			)
			(layer "F.SilkS")
		)
		(fp_line
			(start -1.1176 -1.4224)
			(end 1.1176 -1.4224)
			(stroke
				(width 0.1524)
				(type default)
			)
			(layer "F.SilkS")
		)
		(fp_line
			(start -1.1176 1.4224)
			(end -1.1176 -1.4224)
			(stroke
				(width 0.1524)
				(type default)
			)
			(layer "F.SilkS")
		)
		(fp_line
			(start 1.1176 -1.4224)
			(end 1.1176 1.4224)
			(stroke
				(width 0.1524)
				(type default)
			)
			(layer "F.SilkS")
		)
		(fp_line
			(start 1.1176 1.4224)
			(end -1.1176 1.4224)
			(stroke
				(width 0.1524)
				(type default)
			)
			(layer "F.SilkS")
		)
		(fp_line
			(start 1.2954 1.6002)
			(end 1.2954 0.254)
			(stroke
				(width 0.508)
				(type default)
			)
			(layer "F.SilkS")
		)
		(fp_rect
			(start -0.7493 0.8001)
			(end 0.7493 -0.8001)
			(stroke
				(width 0)
				(type default)
			)
			(fill no)
			(layer "F.CrtYd")
		)
		(fp_poly
			(pts
				(xy -1.3716 1.6764) (xy -1.3716 -1.6764) (xy 1.3716 -1.6764) (xy 1.3716 0.0635) (xy 0.7493 0.0635)
				(xy 0.7493 -0.8001) (xy -0.7493 -0.8001) (xy -0.7493 0.8001) (xy 0.7493 0.8001) (xy 0.7493 0.0762)
				(xy 1.3716 0.0762) (xy 1.3716 1.6764)
			)
			(stroke
				(width 0)
				(type default)
			)
			(fill no)
			(layer "F.CrtYd")
		)
		(fp_rect
			(start -1.3716 1.6764)
			(end 1.3716 -1.6764)
			(stroke
				(width 0)
				(type default)
			)
			(fill no)
			(layer "F.Fab")
		)
		(pad "1" smd rect
			(at 0.50038 -0.73025)
			(size 0.7112 0.8636)
			(layers "F.Cu" "F.Mask" "F.Paste")
			(net "DRV_ACT_17")
		)
		(pad "2" smd rect
			(at -0.50038 -0.73025)
			(size 0.7112 0.8636)
			(layers "F.Cu" "F.Mask" "F.Paste")
			(net "FLT_HDD17")
		)
		(pad "3" smd rect
			(at 0.50038 0.73025)
			(size 0.7112 0.8636)
			(layers "F.Cu" "F.Mask" "F.Paste")
			(net "DRV_ACT_17_N")
		)
		(pad "4" smd rect
			(at -0.50038 0.73025)
			(size 0.7112 0.8636)
			(layers "F.Cu" "F.Mask" "F.Paste")
			(net "FLT_HDD17_N")
		)
	)
	(footprint ""
		(layer "F.Cu")
		(at 333.586836 -184.450228 -90)
		(property "Reference" "R545"
			(at 0 0 270)
			(layer "F.SilkS")
			(hide yes)
			(effects
				(font
					(size 1.27 1.27)
				)
			)
		)
		(property "Value" "2R6F-GP"
			(at -0.0508 -4.8514 270)
			(unlocked yes)
			(layer "F.Fab")
			(hide yes)
			(effects
				(font
					(size 1.016 1.016)
					(thickness 0.1524)
				)
			)
		)
		(property "Device Type" "R1206H26"
			(at 0 -6.3754 270)
			(unlocked yes)
			(layer "F.Fab")
			(hide yes)
			(effects
				(font
					(size 1.016 1.016)
					(thickness 0.1524)
				)
			)
		)
		(duplicate_pad_numbers_are_jumpers no)
		(fp_line
			(start -1.016 2.2352)
			(end -1.016 -2.2352)
			(stroke
				(width 0.1524)
				(type default)
			)
			(layer "F.SilkS")
		)
		(fp_line
			(start 1.016 2.2352)
			(end -1.016 2.2352)
			(stroke
				(width 0.1524)
				(type default)
			)
			(layer "F.SilkS")
		)
		(fp_line
			(start -1.016 -2.2352)
			(end 1.016 -2.2352)
			(stroke
				(width 0.1524)
				(type default)
			)
			(layer "F.SilkS")
		)
		(fp_line
			(start 1.016 -2.2352)
			(end 1.016 2.2352)
			(stroke
				(width 0.1524)
				(type default)
			)
			(layer "F.SilkS")
		)
		(fp_rect
			(start -1.0922 2.3114)
			(end 1.0922 -2.3114)
			(stroke
				(width 0)
				(type default)
			)
			(fill no)
			(layer "F.CrtYd")
		)
		(fp_poly
			(pts
				(xy -1.0922 -2.3114) (xy 1.0922 -2.3114) (xy 1.0922 2.3114) (xy -1.0922 2.3114)
			)
			(stroke
				(width 0)
				(type default)
			)
			(fill no)
			(layer "F.Fab")
		)
		(pad "1" smd rect
			(at 0 -1.397 270)
			(size 1.651 1.27)
			(layers "F.Cu" "F.Mask" "F.Paste")
			(net "P12V_HDD18")
		)
		(pad "2" smd rect
			(at 0 1.397 270)
			(size 1.651 1.27)
			(layers "F.Cu" "F.Mask" "F.Paste")
			(net "12V_PRE_18")
		)
	)
	(footprint ""
		(layer "F.Cu")
		(at 49.349914 -209.399886)
		(property "Reference" "FLED2"
			(at 0 0 0)
			(layer "F.SilkS")
			(hide yes)
			(effects
				(font
					(size 1.27 1.27)
				)
			)
		)
		(property "Value" "LED-BY-19-GP"
			(at -2.132076 1.414018 0)
			(unlocked yes)
			(layer "F.Fab")
			(hide yes)
			(effects
				(font
					(size 1.016 1.016)
					(thickness 0.1524)
				)
			)
		)
		(property "Device Type" "LED-1615-4PH26"
			(at -2.132076 -0.109982 0)
			(unlocked yes)
			(layer "F.Fab")
			(hide yes)
			(effects
				(font
					(size 1.016 1.016)
					(thickness 0.1524)
				)
			)
		)
		(duplicate_pad_numbers_are_jumpers no)
		(fp_line
			(start -1.2954 0.254)
			(end -1.2954 1.6002)
			(stroke
				(width 0.508)
				(type default)
			)
			(layer "F.SilkS")
		)
		(fp_line
			(start -1.2954 1.6002)
			(end 1.2954 1.6002)
			(stroke
				(width 0.508)
				(type default)
			)
			(layer "F.SilkS")
		)
		(fp_line
			(start -1.1176 -1.4224)
			(end 1.1176 -1.4224)
			(stroke
				(width 0.1524)
				(type default)
			)
			(layer "F.SilkS")
		)
		(fp_line
			(start -1.1176 1.4224)
			(end -1.1176 -1.4224)
			(stroke
				(width 0.1524)
				(type default)
			)
			(layer "F.SilkS")
		)
		(fp_line
			(start 1.1176 -1.4224)
			(end 1.1176 1.4224)
			(stroke
				(width 0.1524)
				(type default)
			)
			(layer "F.SilkS")
		)
		(fp_line
			(start 1.1176 1.4224)
			(end -1.1176 1.4224)
			(stroke
				(width 0.1524)
				(type default)
			)
			(layer "F.SilkS")
		)
		(fp_line
			(start 1.2954 1.6002)
			(end 1.2954 0.254)
			(stroke
				(width 0.508)
				(type default)
			)
			(layer "F.SilkS")
		)
		(fp_rect
			(start -0.7493 0.8001)
			(end 0.7493 -0.8001)
			(stroke
				(width 0)
				(type default)
			)
			(fill no)
			(layer "F.CrtYd")
		)
		(fp_poly
			(pts
				(xy -1.3716 1.6764) (xy -1.3716 -1.6764) (xy 1.3716 -1.6764) (xy 1.3716 0.0635) (xy 0.7493 0.0635)
				(xy 0.7493 -0.8001) (xy -0.7493 -0.8001) (xy -0.7493 0.8001) (xy 0.7493 0.8001) (xy 0.7493 0.0762)
				(xy 1.3716 0.0762) (xy 1.3716 1.6764)
			)
			(stroke
				(width 0)
				(type default)
			)
			(fill no)
			(layer "F.CrtYd")
		)
		(fp_rect
			(start -1.3716 1.6764)
			(end 1.3716 -1.6764)
			(stroke
				(width 0)
				(type default)
			)
			(fill no)
			(layer "F.Fab")
		)
		(pad "1" smd rect
			(at 0.50038 -0.73025)
			(size 0.7112 0.8636)
			(layers "F.Cu" "F.Mask" "F.Paste")
			(net "DRV_ACT_1")
		)
		(pad "2" smd rect
			(at -0.50038 -0.73025)
			(size 0.7112 0.8636)
			(layers "F.Cu" "F.Mask" "F.Paste")
			(net "FLT_HDD1")
		)
		(pad "3" smd rect
			(at 0.50038 0.73025)
			(size 0.7112 0.8636)
			(layers "F.Cu" "F.Mask" "F.Paste")
			(net "DRV_ACT_1_N")
		)
		(pad "4" smd rect
			(at -0.50038 0.73025)
			(size 0.7112 0.8636)
			(layers "F.Cu" "F.Mask" "F.Paste")
			(net "FLT_HDD1_N")
		)
	)
	(footprint ""
		(layer "F.Cu")
		(at 267.18641 -131.636262 -90)
		(property "Reference" "TP185"
			(at 0 0 270)
			(layer "F.SilkS")
			(hide yes)
			(effects
				(font
					(size 1.27 1.27)
				)
			)
		)
		(property "Value" "TPAD32-GP"
			(at -0.0508 -1.6764 270)
			(unlocked yes)
			(layer "F.Fab")
			(hide yes)
			(effects
				(font
					(size 1.016 1.016)
					(thickness 0.1524)
				)
			)
		)
		(property "Device Type" "TPAD32"
			(at -0.0508 -3.2004 270)
			(unlocked yes)
			(layer "F.Fab")
			(hide yes)
			(effects
				(font
					(size 1.016 1.016)
					(thickness 0.1524)
				)
			)
		)
		(duplicate_pad_numbers_are_jumpers no)
		(fp_poly
			(pts
				(arc
					(start 0 -0.4064)
					(mid 0 0.4064)
					(end 0 -0.4064)
				)
			)
			(stroke
				(width 0)
				(type default)
			)
			(fill no)
			(layer "F.CrtYd")
		)
		(fp_poly
			(pts
				(arc
					(start 0 -0.7112)
					(mid 0 0.7112)
					(end 0 -0.7112)
				)
			)
			(stroke
				(width 0)
				(type default)
			)
			(fill no)
			(layer "F.Fab")
		)
		(pad "1" smd circle
			(at 0 0 270)
			(size 0.8128 0.8128)
			(layers "F.Cu" "F.Mask" "F.Paste")
			(net "TP_COMP_B_SATA_P0_RX_DP")
		)
	)
	(footprint ""
		(layer "F.Cu")
		(at 67.1068 -298.704)
		(property "Reference" "TP7"
			(at 0 0 0)
			(layer "F.SilkS")
			(hide yes)
			(effects
				(font
					(size 1.27 1.27)
				)
			)
		)
		(property "Value" "TPAD32-GP"
			(at -0.0508 -1.6764 0)
			(unlocked yes)
			(layer "F.Fab")
			(hide yes)
			(effects
				(font
					(size 1.016 1.016)
					(thickness 0.1524)
				)
			)
		)
		(property "Device Type" "TPAD32"
			(at -0.0508 -3.2004 0)
			(unlocked yes)
			(layer "F.Fab")
			(hide yes)
			(effects
				(font
					(size 1.016 1.016)
					(thickness 0.1524)
				)
			)
		)
		(duplicate_pad_numbers_are_jumpers no)
		(fp_poly
			(pts
				(arc
					(start 0.4064 0)
					(mid -0.4064 0)
					(end 0.4064 0)
				)
			)
			(stroke
				(width 0)
				(type default)
			)
			(fill no)
			(layer "F.CrtYd")
		)
		(fp_poly
			(pts
				(arc
					(start 0.7112 0)
					(mid -0.7112 0)
					(end 0.7112 0)
				)
			)
			(stroke
				(width 0)
				(type default)
			)
			(fill no)
			(layer "F.Fab")
		)
		(pad "1" smd circle
			(at 0 0)
			(size 0.8128 0.8128)
			(layers "F.Cu" "F.Mask" "F.Paste")
			(net "ACT_HDD_1")
		)
	)
	(footprint ""
		(layer "F.Cu")
		(at 224.14103 -357.961438)
		(property "Reference" "R426"
			(at 0 0 0)
			(layer "F.SilkS")
			(hide yes)
			(effects
				(font
					(size 1.27 1.27)
				)
			)
		)
		(property "Value" "1KR2F-3-GP"
			(at 0.064008 -3.993896 0)
			(unlocked yes)
			(layer "F.Fab")
			(hide yes)
			(effects
				(font
					(size 1.016 1.016)
					(thickness 0.1524)
				)
			)
		)
		(property "Device Type" "R402H16"
			(at 0.064008 -5.517896 0)
			(unlocked yes)
			(layer "F.Fab")
			(hide yes)
			(effects
				(font
					(size 1.016 1.016)
					(thickness 0.1524)
				)
			)
		)
		(duplicate_pad_numbers_are_jumpers no)
		(fp_line
			(start -0.508 -0.9398)
			(end -0.508 0.9398)
			(stroke
				(width 0.1524)
				(type default)
			)
			(layer "F.SilkS")
		)
		(fp_line
			(start 0.508 -0.9398)
			(end -0.508 -0.9398)
			(stroke
				(width 0.1524)
				(type default)
			)
			(layer "F.SilkS")
		)
		(fp_rect
			(start -0.508 0.9398)
			(end 0.508 -0.9398)
			(stroke
				(width 0)
				(type default)
			)
			(fill no)
			(layer "F.CrtYd")
		)
		(fp_rect
			(start -0.508 0.9398)
			(end 0.508 -0.9398)
			(stroke
				(width 0)
				(type default)
			)
			(fill no)
			(layer "F.Fab")
		)
		(pad "1" smd custom
			(at 0 -0.4445)
			(size 0.1397 0.1397)
			(layers "F.Cu" "F.Mask" "F.Paste")
			(net "P3V3_STBY_A")
			(options
				(clearance outline)
				(anchor circle)
			)
			(primitives
				(gr_poly
					(pts
						(arc
							(start -0.1778 -0.2794)
							(mid -0.249642 -0.249642)
							(end -0.2794 -0.1778)
						)
						(arc
							(start -0.2794 0.1778)
							(mid -0.249642 0.249642)
							(end -0.1778 0.2794)
						)
						(arc
							(start 0.1778 0.2794)
							(mid 0.249642 0.249642)
							(end 0.2794 0.1778)
						)
						(arc
							(start 0.2794 -0.1778)
							(mid 0.249642 -0.249642)
							(end 0.1778 -0.2794)
						)
					)
					(width 0)
					(fill yes)
				)
			)
		)
		(pad "2" smd custom
			(at 0 0.4445)
			(size 0.1397 0.1397)
			(layers "F.Cu" "F.Mask" "F.Paste")
			(net "I2C_CLIP_A_SCL")
			(options
				(clearance outline)
				(anchor circle)
			)
			(primitives
				(gr_poly
					(pts
						(arc
							(start -0.1778 -0.2794)
							(mid -0.249642 -0.249642)
							(end -0.2794 -0.1778)
						)
						(arc
							(start -0.2794 0.1778)
							(mid -0.249642 0.249642)
							(end -0.1778 0.2794)
						)
						(arc
							(start 0.1778 0.2794)
							(mid 0.249642 0.249642)
							(end 0.2794 0.1778)
						)
						(arc
							(start 0.2794 -0.1778)
							(mid 0.249642 -0.249642)
							(end 0.1778 -0.2794)
						)
					)
					(width 0)
					(fill yes)
				)
			)
		)
	)
	(footprint ""
		(layer "F.Cu")
		(at 351.539302 -158.939992 90)
		(property "Reference" "VIA8"
			(at 0 0 90)
			(layer "F.SilkS")
			(hide yes)
			(effects
				(font
					(size 1.27 1.27)
				)
			)
		)
		(property "Value" "100OHM-8L-1D6MM-L18L16-GP"
			(at -3.7211 -4.5085 90)
			(unlocked yes)
			(layer "F.Fab")
			(hide yes)
			(effects
				(font
					(size 1.016 1.016)
					(thickness 0.1524)
				)
			)
		)
		(property "Device Type" "VIA-PCIE-4P-394076"
			(at -3.7211 -6.0325 90)
			(unlocked yes)
			(layer "F.Fab")
			(hide yes)
			(effects
				(font
					(size 1.016 1.016)
					(thickness 0.1524)
				)
			)
		)
		(duplicate_pad_numbers_are_jumpers no)
		(fp_rect
			(start -1.9685 0.381)
			(end 1.9685 -0.381)
			(stroke
				(width 0)
				(type default)
			)
			(fill no)
			(layer "F.CrtYd")
		)
		(fp_rect
			(start -1.9685 0.381)
			(end 1.9685 -0.381)
			(stroke
				(width 0)
				(type default)
			)
			(fill no)
			(layer "F.Fab")
		)
		(pad "1" thru_hole circle
			(at -1.5875 0 90)
			(size 0.508 0.508)
			(drill 0.254)
			(layers "*.Cu" "*.Mask")
			(remove_unused_layers no)
			(net "GND")
			(clearance 0.127)
			(thermal_gap 0.127)
		)
		(pad "2" thru_hole circle
			(at -0.5715 0 90)
			(size 0.508 0.508)
			(drill 0.254)
			(layers "*.Cu" "*.Mask")
			(remove_unused_layers no)
			(net "PHY_SCC_A_TO_DRV_A_19_DP")
			(clearance 0.127)
			(thermal_gap 0.127)
		)
		(pad "3" thru_hole circle
			(at 0.5715 0 90)
			(size 0.508 0.508)
			(drill 0.254)
			(layers "*.Cu" "*.Mask")
			(remove_unused_layers no)
			(net "PHY_SCC_A_TO_DRV_A_19_DN")
			(clearance 0.127)
			(thermal_gap 0.127)
		)
		(pad "4" thru_hole circle
			(at 1.5875 0 90)
			(size 0.508 0.508)
			(drill 0.254)
			(layers "*.Cu" "*.Mask")
			(remove_unused_layers no)
			(net "GND")
			(clearance 0.127)
			(thermal_gap 0.127)
		)
	)
	(footprint ""
		(layer "F.Cu")
		(at 314.471304 -245.357142 -90)
		(property "Reference" "R477"
			(at 0 0 270)
			(layer "F.SilkS")
			(hide yes)
			(effects
				(font
					(size 1.27 1.27)
				)
			)
		)
		(property "Value" "4K7R2J-2-GP"
			(at 0.064008 -3.993896 270)
			(unlocked yes)
			(layer "F.Fab")
			(hide yes)
			(effects
				(font
					(size 1.016 1.016)
					(thickness 0.1524)
				)
			)
		)
		(property "Device Type" "R402H16"
			(at 0.064008 -5.517896 270)
			(unlocked yes)
			(layer "F.Fab")
			(hide yes)
			(effects
				(font
					(size 1.016 1.016)
					(thickness 0.1524)
				)
			)
		)
		(duplicate_pad_numbers_are_jumpers no)
		(fp_line
			(start -0.508 -0.9398)
			(end -0.508 0.9398)
			(stroke
				(width 0.1524)
				(type default)
			)
			(layer "F.SilkS")
		)
		(fp_line
			(start 0.508 -0.9398)
			(end -0.508 -0.9398)
			(stroke
				(width 0.1524)
				(type default)
			)
			(layer "F.SilkS")
		)
		(fp_rect
			(start -0.508 0.9398)
			(end 0.508 -0.9398)
			(stroke
				(width 0)
				(type default)
			)
			(fill no)
			(layer "F.CrtYd")
		)
		(fp_rect
			(start -0.508 0.9398)
			(end 0.508 -0.9398)
			(stroke
				(width 0)
				(type default)
			)
			(fill no)
			(layer "F.Fab")
		)
		(pad "1" smd custom
			(at 0 -0.4445 270)
			(size 0.1397 0.1397)
			(layers "F.Cu" "F.Mask" "F.Paste")
			(net "DRIVE_A_6_ACT")
			(options
				(clearance outline)
				(anchor circle)
			)
			(primitives
				(gr_poly
					(pts
						(arc
							(start -0.1778 -0.2794)
							(mid -0.249642 -0.249642)
							(end -0.2794 -0.1778)
						)
						(arc
							(start -0.2794 0.1778)
							(mid -0.249642 0.249642)
							(end -0.1778 0.2794)
						)
						(arc
							(start 0.1778 0.2794)
							(mid 0.249642 0.249642)
							(end 0.2794 0.1778)
						)
						(arc
							(start 0.2794 -0.1778)
							(mid 0.249642 -0.249642)
							(end 0.1778 -0.2794)
						)
					)
					(width 0)
					(fill yes)
				)
			)
		)
		(pad "2" smd custom
			(at 0 0.4445 270)
			(size 0.1397 0.1397)
			(layers "F.Cu" "F.Mask" "F.Paste")
			(net "GND")
			(options
				(clearance outline)
				(anchor circle)
			)
			(primitives
				(gr_poly
					(pts
						(arc
							(start -0.1778 -0.2794)
							(mid -0.249642 -0.249642)
							(end -0.2794 -0.1778)
						)
						(arc
							(start -0.2794 0.1778)
							(mid -0.249642 0.249642)
							(end -0.1778 0.2794)
						)
						(arc
							(start 0.1778 0.2794)
							(mid 0.249642 0.249642)
							(end 0.2794 0.1778)
						)
						(arc
							(start 0.2794 -0.1778)
							(mid 0.249642 -0.249642)
							(end 0.1778 -0.2794)
						)
					)
					(width 0)
					(fill yes)
				)
			)
		)
	)
	(footprint ""
		(layer "F.Cu")
		(at 252.220476 -256.88036)
		(property "Reference" "C18"
			(at 0 0 0)
			(layer "F.SilkS")
			(hide yes)
			(effects
				(font
					(size 1.27 1.27)
				)
			)
		)
		(property "Value" "SCD1U16V2KX-3GP"
			(at 1.1811 -2.7051 0)
			(unlocked yes)
			(layer "F.Fab")
			(hide yes)
			(effects
				(font
					(size 1.016 1.016)
					(thickness 0.1524)
				)
			)
		)
		(property "Device Type" "C402H22"
			(at 1.1811 -4.2291 0)
			(unlocked yes)
			(layer "F.Fab")
			(hide yes)
			(effects
				(font
					(size 1.016 1.016)
					(thickness 0.1524)
				)
			)
		)
		(duplicate_pad_numbers_are_jumpers no)
		(fp_rect
			(start -0.4318 0.9525)
			(end 0.4318 -0.9525)
			(stroke
				(width 0)
				(type default)
			)
			(fill no)
			(layer "F.CrtYd")
		)
		(fp_rect
			(start -0.4318 0.9525)
			(end 0.4318 -0.9525)
			(stroke
				(width 0)
				(type default)
			)
			(fill no)
			(layer "F.Fab")
		)
		(pad "1" smd custom
			(at 0 -0.4445)
			(size 0.1524 0.1524)
			(layers "F.Cu" "F.Mask" "F.Paste")
			(net "P3V3_STBY_A")
			(options
				(clearance outline)
				(anchor circle)
			)
			(primitives
				(gr_poly
					(pts
						(arc
							(start 0.3048 -0.2032)
							(mid 0.275042 -0.275042)
							(end 0.2032 -0.3048)
						)
						(arc
							(start -0.2032 -0.3048)
							(mid -0.275042 -0.275042)
							(end -0.3048 -0.2032)
						)
						(arc
							(start -0.3048 0.2032)
							(mid -0.275042 0.275042)
							(end -0.2032 0.3048)
						)
						(arc
							(start 0.2032 0.3048)
							(mid 0.275042 0.275042)
							(end 0.3048 0.2032)
						)
					)
					(width 0)
					(fill yes)
				)
			)
		)
		(pad "2" smd custom
			(at 0 0.4445)
			(size 0.1524 0.1524)
			(layers "F.Cu" "F.Mask" "F.Paste")
			(net "GND")
			(options
				(clearance outline)
				(anchor circle)
			)
			(primitives
				(gr_poly
					(pts
						(arc
							(start 0.3048 -0.2032)
							(mid 0.275042 -0.275042)
							(end 0.2032 -0.3048)
						)
						(arc
							(start -0.2032 -0.3048)
							(mid -0.275042 -0.275042)
							(end -0.3048 -0.2032)
						)
						(arc
							(start -0.3048 0.2032)
							(mid -0.275042 0.275042)
							(end -0.2032 0.3048)
						)
						(arc
							(start 0.2032 0.3048)
							(mid 0.275042 0.275042)
							(end 0.3048 0.2032)
						)
					)
					(width 0)
					(fill yes)
				)
			)
		)
	)
	(footprint ""
		(layer "F.Cu")
		(at 109.467396 -160.608518 90)
		(property "Reference" "R489"
			(at 0 0 90)
			(layer "F.SilkS")
			(hide yes)
			(effects
				(font
					(size 1.27 1.27)
				)
			)
		)
		(property "Value" "4K7R2J-2-GP"
			(at 0.064008 -3.993896 90)
			(unlocked yes)
			(layer "F.Fab")
			(hide yes)
			(effects
				(font
					(size 1.016 1.016)
					(thickness 0.1524)
				)
			)
		)
		(property "Device Type" "R402H16"
			(at 0.064008 -5.517896 90)
			(unlocked yes)
			(layer "F.Fab")
			(hide yes)
			(effects
				(font
					(size 1.016 1.016)
					(thickness 0.1524)
				)
			)
		)
		(duplicate_pad_numbers_are_jumpers no)
		(fp_line
			(start 0.508 -0.9398)
			(end -0.508 -0.9398)
			(stroke
				(width 0.1524)
				(type default)
			)
			(layer "F.SilkS")
		)
		(fp_line
			(start -0.508 -0.9398)
			(end -0.508 0.9398)
			(stroke
				(width 0.1524)
				(type default)
			)
			(layer "F.SilkS")
		)
		(fp_rect
			(start -0.508 0.9398)
			(end 0.508 -0.9398)
			(stroke
				(width 0)
				(type default)
			)
			(fill no)
			(layer "F.CrtYd")
		)
		(fp_rect
			(start -0.508 0.9398)
			(end 0.508 -0.9398)
			(stroke
				(width 0)
				(type default)
			)
			(fill no)
			(layer "F.Fab")
		)
		(pad "1" smd custom
			(at 0 -0.4445 90)
			(size 0.1397 0.1397)
			(layers "F.Cu" "F.Mask" "F.Paste")
			(net "P12V_A")
			(options
				(clearance outline)
				(anchor circle)
			)
			(primitives
				(gr_poly
					(pts
						(arc
							(start -0.1778 -0.2794)
							(mid -0.249642 -0.249642)
							(end -0.2794 -0.1778)
						)
						(arc
							(start -0.2794 0.1778)
							(mid -0.249642 0.249642)
							(end -0.1778 0.2794)
						)
						(arc
							(start 0.1778 0.2794)
							(mid 0.249642 0.249642)
							(end 0.2794 0.1778)
						)
						(arc
							(start 0.2794 -0.1778)
							(mid 0.249642 -0.249642)
							(end 0.1778 -0.2794)
						)
					)
					(width 0)
					(fill yes)
				)
			)
		)
		(pad "2" smd custom
			(at 0 0.4445 90)
			(size 0.1397 0.1397)
			(layers "F.Cu" "F.Mask" "F.Paste")
			(net "SW_HDD_R15")
			(options
				(clearance outline)
				(anchor circle)
			)
			(primitives
				(gr_poly
					(pts
						(arc
							(start -0.1778 -0.2794)
							(mid -0.249642 -0.249642)
							(end -0.2794 -0.1778)
						)
						(arc
							(start -0.2794 0.1778)
							(mid -0.249642 0.249642)
							(end -0.1778 0.2794)
						)
						(arc
							(start 0.1778 0.2794)
							(mid 0.249642 0.249642)
							(end 0.2794 0.1778)
						)
						(arc
							(start 0.2794 -0.1778)
							(mid 0.249642 -0.249642)
							(end 0.1778 -0.2794)
						)
					)
					(width 0)
					(fill yes)
				)
			)
		)
	)
	(footprint ""
		(layer "F.Cu")
		(at 98.897948 -291.127942 90)
		(property "Reference" "C70"
			(at 0 0 90)
			(layer "F.SilkS")
			(hide yes)
			(effects
				(font
					(size 1.27 1.27)
				)
			)
		)
		(property "Value" "SCD01U50V2KX-1GP"
			(at 1.1811 -2.7051 90)
			(unlocked yes)
			(layer "F.Fab")
			(hide yes)
			(effects
				(font
					(size 1.016 1.016)
					(thickness 0.1524)
				)
			)
		)
		(property "Device Type" "C402H22"
			(at 1.1811 -4.2291 90)
			(unlocked yes)
			(layer "F.Fab")
			(hide yes)
			(effects
				(font
					(size 1.016 1.016)
					(thickness 0.1524)
				)
			)
		)
		(duplicate_pad_numbers_are_jumpers no)
		(fp_rect
			(start -0.4318 0.9525)
			(end 0.4318 -0.9525)
			(stroke
				(width 0)
				(type default)
			)
			(fill no)
			(layer "F.CrtYd")
		)
		(fp_rect
			(start -0.4318 0.9525)
			(end 0.4318 -0.9525)
			(stroke
				(width 0)
				(type default)
			)
			(fill no)
			(layer "F.Fab")
		)
		(pad "1" smd custom
			(at 0 -0.4445 90)
			(size 0.1524 0.1524)
			(layers "F.Cu" "F.Mask" "F.Paste")
			(net "HDD_PRSNT_2")
			(options
				(clearance outline)
				(anchor circle)
			)
			(primitives
				(gr_poly
					(pts
						(arc
							(start 0.3048 -0.2032)
							(mid 0.275042 -0.275042)
							(end 0.2032 -0.3048)
						)
						(arc
							(start -0.2032 -0.3048)
							(mid -0.275042 -0.275042)
							(end -0.3048 -0.2032)
						)
						(arc
							(start -0.3048 0.2032)
							(mid -0.275042 0.275042)
							(end -0.2032 0.3048)
						)
						(arc
							(start 0.2032 0.3048)
							(mid 0.275042 0.275042)
							(end 0.3048 0.2032)
						)
					)
					(width 0)
					(fill yes)
				)
			)
		)
		(pad "2" smd custom
			(at 0 0.4445 90)
			(size 0.1524 0.1524)
			(layers "F.Cu" "F.Mask" "F.Paste")
			(net "GND")
			(options
				(clearance outline)
				(anchor circle)
			)
			(primitives
				(gr_poly
					(pts
						(arc
							(start 0.3048 -0.2032)
							(mid 0.275042 -0.275042)
							(end 0.2032 -0.3048)
						)
						(arc
							(start -0.2032 -0.3048)
							(mid -0.275042 -0.275042)
							(end -0.3048 -0.2032)
						)
						(arc
							(start -0.3048 0.2032)
							(mid -0.275042 0.275042)
							(end -0.2032 0.3048)
						)
						(arc
							(start 0.2032 0.3048)
							(mid 0.275042 0.275042)
							(end 0.3048 0.2032)
						)
					)
					(width 0)
					(fill yes)
				)
			)
		)
	)
	(footprint ""
		(layer "F.Cu")
		(at 130.175 -298.704)
		(property "Reference" "TP17"
			(at 0 0 0)
			(layer "F.SilkS")
			(hide yes)
			(effects
				(font
					(size 1.27 1.27)
				)
			)
		)
		(property "Value" "TPAD32-GP"
			(at -0.0508 -1.6764 0)
			(unlocked yes)
			(layer "F.Fab")
			(hide yes)
			(effects
				(font
					(size 1.016 1.016)
					(thickness 0.1524)
				)
			)
		)
		(property "Device Type" "TPAD32"
			(at -0.0508 -3.2004 0)
			(unlocked yes)
			(layer "F.Fab")
			(hide yes)
			(effects
				(font
					(size 1.016 1.016)
					(thickness 0.1524)
				)
			)
		)
		(duplicate_pad_numbers_are_jumpers no)
		(fp_poly
			(pts
				(arc
					(start 0.4064 0)
					(mid -0.4064 0)
					(end 0.4064 0)
				)
			)
			(stroke
				(width 0)
				(type default)
			)
			(fill no)
			(layer "F.CrtYd")
		)
		(fp_poly
			(pts
				(arc
					(start 0.7112 0)
					(mid -0.7112 0)
					(end 0.7112 0)
				)
			)
			(stroke
				(width 0)
				(type default)
			)
			(fill no)
			(layer "F.Fab")
		)
		(pad "1" smd circle
			(at 0 0)
			(size 0.8128 0.8128)
			(layers "F.Cu" "F.Mask" "F.Paste")
			(net "ACT_HDD_3")
		)
	)
	(footprint ""
		(layer "F.Cu")
		(at 257.1496 -13.7668 90)
		(property "Reference" "R1007"
			(at 0 0 90)
			(layer "F.SilkS")
			(hide yes)
			(effects
				(font
					(size 1.27 1.27)
				)
			)
		)
		(property "Value" "100KR2F-L1-GP"
			(at 0.064008 -3.993896 90)
			(unlocked yes)
			(layer "F.Fab")
			(hide yes)
			(effects
				(font
					(size 1.016 1.016)
					(thickness 0.1524)
				)
			)
		)
		(property "Device Type" "R402H16"
			(at 0.064008 -5.517896 90)
			(unlocked yes)
			(layer "F.Fab")
			(hide yes)
			(effects
				(font
					(size 1.016 1.016)
					(thickness 0.1524)
				)
			)
		)
		(duplicate_pad_numbers_are_jumpers no)
		(fp_line
			(start 0.508 -0.9398)
			(end -0.508 -0.9398)
			(stroke
				(width 0.1524)
				(type default)
			)
			(layer "F.SilkS")
		)
		(fp_line
			(start -0.508 -0.9398)
			(end -0.508 0.9398)
			(stroke
				(width 0.1524)
				(type default)
			)
			(layer "F.SilkS")
		)
		(fp_rect
			(start -0.508 0.9398)
			(end 0.508 -0.9398)
			(stroke
				(width 0)
				(type default)
			)
			(fill no)
			(layer "F.CrtYd")
		)
		(fp_rect
			(start -0.508 0.9398)
			(end 0.508 -0.9398)
			(stroke
				(width 0)
				(type default)
			)
			(fill no)
			(layer "F.Fab")
		)
		(pad "1" smd custom
			(at 0 -0.4445 90)
			(size 0.1397 0.1397)
			(layers "F.Cu" "F.Mask" "F.Paste")
			(net "PCIE_COMP_A_TO_IOM_A_RST_3")
			(options
				(clearance outline)
				(anchor circle)
			)
			(primitives
				(gr_poly
					(pts
						(arc
							(start -0.1778 -0.2794)
							(mid -0.249642 -0.249642)
							(end -0.2794 -0.1778)
						)
						(arc
							(start -0.2794 0.1778)
							(mid -0.249642 0.249642)
							(end -0.1778 0.2794)
						)
						(arc
							(start 0.1778 0.2794)
							(mid 0.249642 0.249642)
							(end 0.2794 0.1778)
						)
						(arc
							(start 0.2794 -0.1778)
							(mid 0.249642 -0.249642)
							(end 0.1778 -0.2794)
						)
					)
					(width 0)
					(fill yes)
				)
			)
		)
		(pad "2" smd custom
			(at 0 0.4445 90)
			(size 0.1397 0.1397)
			(layers "F.Cu" "F.Mask" "F.Paste")
			(net "GND")
			(options
				(clearance outline)
				(anchor circle)
			)
			(primitives
				(gr_poly
					(pts
						(arc
							(start -0.1778 -0.2794)
							(mid -0.249642 -0.249642)
							(end -0.2794 -0.1778)
						)
						(arc
							(start -0.2794 0.1778)
							(mid -0.249642 0.249642)
							(end -0.1778 0.2794)
						)
						(arc
							(start 0.1778 0.2794)
							(mid 0.249642 0.249642)
							(end 0.2794 0.1778)
						)
						(arc
							(start 0.2794 -0.1778)
							(mid 0.249642 -0.249642)
							(end 0.1778 -0.2794)
						)
					)
					(width 0)
					(fill yes)
				)
			)
		)
	)
	(footprint ""
		(layer "F.Cu")
		(at 175.6664 -161.649918 180)
		(property "Reference" "D17"
			(at 0 0 180)
			(layer "F.SilkS")
			(hide yes)
			(effects
				(font
					(size 1.27 1.27)
				)
			)
		)
		(property "Value" "RB551V30-GP"
			(at 0 -6.7818 180)
			(unlocked yes)
			(layer "F.Fab")
			(hide yes)
			(effects
				(font
					(size 1.016 1.016)
					(thickness 0.1524)
				)
			)
		)
		(property "Device Type" "SOD323AKH38"
			(at 0 -8.6868 180)
			(unlocked yes)
			(layer "F.Fab")
			(hide yes)
			(effects
				(font
					(size 1.016 1.016)
					(thickness 0.1524)
				)
			)
		)
		(duplicate_pad_numbers_are_jumpers no)
		(fp_line
			(start 0.889 2.159)
			(end -0.889 2.159)
			(stroke
				(width 0.1524)
				(type default)
			)
			(layer "F.SilkS")
		)
		(fp_line
			(start 0.889 -1.9304)
			(end 0.889 2.159)
			(stroke
				(width 0.1524)
				(type default)
			)
			(layer "F.SilkS")
		)
		(fp_line
			(start 0.762 2.0574)
			(end -0.762 2.0574)
			(stroke
				(width 0.508)
				(type default)
			)
			(layer "F.SilkS")
		)
		(fp_line
			(start -0.889 2.159)
			(end -0.889 -1.9304)
			(stroke
				(width 0.1524)
				(type default)
			)
			(layer "F.SilkS")
		)
		(fp_line
			(start -0.889 -1.9304)
			(end 0.889 -1.9304)
			(stroke
				(width 0.1524)
				(type default)
			)
			(layer "F.SilkS")
		)
		(fp_rect
			(start -1.016 2.3114)
			(end 1.016 -2.0066)
			(stroke
				(width 0)
				(type default)
			)
			(fill no)
			(layer "F.CrtYd")
		)
		(fp_poly
			(pts
				(xy -1.016 -2.0066) (xy 1.016 -2.0066) (xy 1.016 2.3114) (xy -1.016 2.3114)
			)
			(stroke
				(width 0)
				(type default)
			)
			(fill no)
			(layer "F.Fab")
		)
		(pad "A" smd rect
			(at 0 -1.143 180)
			(size 0.5588 1.016)
			(layers "F.Cu" "F.Mask" "F.Paste")
			(net "SW_HDD_R17")
		)
		(pad "K" smd rect
			(at 0 1.143 180)
			(size 0.5588 1.016)
			(layers "F.Cu" "F.Mask" "F.Paste")
			(net "SW_HDD_N17")
		)
	)
	(footprint ""
		(layer "F.Cu")
		(at 237.128812 -252.93828 90)
		(property "Reference" "C10"
			(at 0 0 90)
			(layer "F.SilkS")
			(hide yes)
			(effects
				(font
					(size 1.27 1.27)
				)
			)
		)
		(property "Value" "SCD1U16V2KX-3GP"
			(at 1.1811 -2.7051 90)
			(unlocked yes)
			(layer "F.Fab")
			(hide yes)
			(effects
				(font
					(size 1.016 1.016)
					(thickness 0.1524)
				)
			)
		)
		(property "Device Type" "C402H22"
			(at 1.1811 -4.2291 90)
			(unlocked yes)
			(layer "F.Fab")
			(hide yes)
			(effects
				(font
					(size 1.016 1.016)
					(thickness 0.1524)
				)
			)
		)
		(duplicate_pad_numbers_are_jumpers no)
		(fp_rect
			(start -0.4318 0.9525)
			(end 0.4318 -0.9525)
			(stroke
				(width 0)
				(type default)
			)
			(fill no)
			(layer "F.CrtYd")
		)
		(fp_rect
			(start -0.4318 0.9525)
			(end 0.4318 -0.9525)
			(stroke
				(width 0)
				(type default)
			)
			(fill no)
			(layer "F.Fab")
		)
		(pad "1" smd custom
			(at 0 -0.4445 90)
			(size 0.1524 0.1524)
			(layers "F.Cu" "F.Mask" "F.Paste")
			(net "P3V3_STBY_A")
			(options
				(clearance outline)
				(anchor circle)
			)
			(primitives
				(gr_poly
					(pts
						(arc
							(start 0.3048 -0.2032)
							(mid 0.275042 -0.275042)
							(end 0.2032 -0.3048)
						)
						(arc
							(start -0.2032 -0.3048)
							(mid -0.275042 -0.275042)
							(end -0.3048 -0.2032)
						)
						(arc
							(start -0.3048 0.2032)
							(mid -0.275042 0.275042)
							(end -0.2032 0.3048)
						)
						(arc
							(start 0.2032 0.3048)
							(mid 0.275042 0.275042)
							(end 0.3048 0.2032)
						)
					)
					(width 0)
					(fill yes)
				)
			)
		)
		(pad "2" smd custom
			(at 0 0.4445 90)
			(size 0.1524 0.1524)
			(layers "F.Cu" "F.Mask" "F.Paste")
			(net "GND")
			(options
				(clearance outline)
				(anchor circle)
			)
			(primitives
				(gr_poly
					(pts
						(arc
							(start 0.3048 -0.2032)
							(mid 0.275042 -0.275042)
							(end 0.2032 -0.3048)
						)
						(arc
							(start -0.2032 -0.3048)
							(mid -0.275042 -0.275042)
							(end -0.3048 -0.2032)
						)
						(arc
							(start -0.3048 0.2032)
							(mid -0.275042 0.275042)
							(end -0.2032 0.3048)
						)
						(arc
							(start 0.2032 0.3048)
							(mid 0.275042 0.275042)
							(end 0.3048 0.2032)
						)
					)
					(width 0)
					(fill yes)
				)
			)
		)
	)
	(footprint ""
		(layer "F.Cu")
		(at 276.2758 -284.7086 180)
		(property "Reference" "R110"
			(at 0 0 180)
			(layer "F.SilkS")
			(hide yes)
			(effects
				(font
					(size 1.27 1.27)
				)
			)
		)
		(property "Value" "4K7R2F-GP"
			(at 0.064008 -3.993896 180)
			(unlocked yes)
			(layer "F.Fab")
			(hide yes)
			(effects
				(font
					(size 1.016 1.016)
					(thickness 0.1524)
				)
			)
		)
		(property "Device Type" "R402H16"
			(at 0.064008 -5.517896 180)
			(unlocked yes)
			(layer "F.Fab")
			(hide yes)
			(effects
				(font
					(size 1.016 1.016)
					(thickness 0.1524)
				)
			)
		)
		(duplicate_pad_numbers_are_jumpers no)
		(fp_line
			(start 0.508 -0.9398)
			(end -0.508 -0.9398)
			(stroke
				(width 0.1524)
				(type default)
			)
			(layer "F.SilkS")
		)
		(fp_line
			(start -0.508 -0.9398)
			(end -0.508 0.9398)
			(stroke
				(width 0.1524)
				(type default)
			)
			(layer "F.SilkS")
		)
		(fp_rect
			(start -0.508 0.9398)
			(end 0.508 -0.9398)
			(stroke
				(width 0)
				(type default)
			)
			(fill no)
			(layer "F.CrtYd")
		)
		(fp_rect
			(start -0.508 0.9398)
			(end 0.508 -0.9398)
			(stroke
				(width 0)
				(type default)
			)
			(fill no)
			(layer "F.Fab")
		)
		(pad "1" smd custom
			(at 0 -0.4445 180)
			(size 0.1397 0.1397)
			(layers "F.Cu" "F.Mask" "F.Paste")
			(net "IO_EXP1_HDD_FAULT_A0")
			(options
				(clearance outline)
				(anchor circle)
			)
			(primitives
				(gr_poly
					(pts
						(arc
							(start -0.1778 -0.2794)
							(mid -0.249642 -0.249642)
							(end -0.2794 -0.1778)
						)
						(arc
							(start -0.2794 0.1778)
							(mid -0.249642 0.249642)
							(end -0.1778 0.2794)
						)
						(arc
							(start 0.1778 0.2794)
							(mid 0.249642 0.249642)
							(end 0.2794 0.1778)
						)
						(arc
							(start 0.2794 -0.1778)
							(mid 0.249642 -0.249642)
							(end 0.1778 -0.2794)
						)
					)
					(width 0)
					(fill yes)
				)
			)
		)
		(pad "2" smd custom
			(at 0 0.4445 180)
			(size 0.1397 0.1397)
			(layers "F.Cu" "F.Mask" "F.Paste")
			(net "GND")
			(options
				(clearance outline)
				(anchor circle)
			)
			(primitives
				(gr_poly
					(pts
						(arc
							(start -0.1778 -0.2794)
							(mid -0.249642 -0.249642)
							(end -0.2794 -0.1778)
						)
						(arc
							(start -0.2794 0.1778)
							(mid -0.249642 0.249642)
							(end -0.1778 0.2794)
						)
						(arc
							(start 0.1778 0.2794)
							(mid 0.249642 0.249642)
							(end 0.2794 0.1778)
						)
						(arc
							(start 0.2794 -0.1778)
							(mid 0.249642 -0.249642)
							(end 0.1778 -0.2794)
						)
					)
					(width 0)
					(fill yes)
				)
			)
		)
	)
	(footprint ""
		(layer "F.Cu")
		(at 452.277988 -256.3495 -90)
		(property "Reference" "R1248"
			(at 0 0 270)
			(layer "F.SilkS")
			(hide yes)
			(effects
				(font
					(size 1.27 1.27)
				)
			)
		)
		(property "Value" "10KR2F-2-GP"
			(at 0.064008 -3.993896 270)
			(unlocked yes)
			(layer "F.Fab")
			(hide yes)
			(effects
				(font
					(size 1.016 1.016)
					(thickness 0.1524)
				)
			)
		)
		(property "Device Type" "R402H16"
			(at 0.064008 -5.517896 270)
			(unlocked yes)
			(layer "F.Fab")
			(hide yes)
			(effects
				(font
					(size 1.016 1.016)
					(thickness 0.1524)
				)
			)
		)
		(duplicate_pad_numbers_are_jumpers no)
		(fp_line
			(start -0.508 -0.9398)
			(end -0.508 0.9398)
			(stroke
				(width 0.1524)
				(type default)
			)
			(layer "F.SilkS")
		)
		(fp_line
			(start 0.508 -0.9398)
			(end -0.508 -0.9398)
			(stroke
				(width 0.1524)
				(type default)
			)
			(layer "F.SilkS")
		)
		(fp_rect
			(start -0.508 0.9398)
			(end 0.508 -0.9398)
			(stroke
				(width 0)
				(type default)
			)
			(fill no)
			(layer "F.CrtYd")
		)
		(fp_rect
			(start -0.508 0.9398)
			(end 0.508 -0.9398)
			(stroke
				(width 0)
				(type default)
			)
			(fill no)
			(layer "F.Fab")
		)
		(pad "1" smd custom
			(at 0 -0.4445 270)
			(size 0.1397 0.1397)
			(layers "F.Cu" "F.Mask" "F.Paste")
			(net "P5V_A_3")
			(options
				(clearance outline)
				(anchor circle)
			)
			(primitives
				(gr_poly
					(pts
						(arc
							(start -0.1778 -0.2794)
							(mid -0.249642 -0.249642)
							(end -0.2794 -0.1778)
						)
						(arc
							(start -0.2794 0.1778)
							(mid -0.249642 0.249642)
							(end -0.1778 0.2794)
						)
						(arc
							(start 0.1778 0.2794)
							(mid 0.249642 0.249642)
							(end 0.2794 0.1778)
						)
						(arc
							(start 0.2794 -0.1778)
							(mid 0.249642 -0.249642)
							(end 0.1778 -0.2794)
						)
					)
					(width 0)
					(fill yes)
				)
			)
		)
		(pad "2" smd custom
			(at 0 0.4445 270)
			(size 0.1397 0.1397)
			(layers "F.Cu" "F.Mask" "F.Paste")
			(net "P5V_A_3_PGOOD")
			(options
				(clearance outline)
				(anchor circle)
			)
			(primitives
				(gr_poly
					(pts
						(arc
							(start -0.1778 -0.2794)
							(mid -0.249642 -0.249642)
							(end -0.2794 -0.1778)
						)
						(arc
							(start -0.2794 0.1778)
							(mid -0.249642 0.249642)
							(end -0.1778 0.2794)
						)
						(arc
							(start 0.1778 0.2794)
							(mid 0.249642 0.249642)
							(end 0.2794 0.1778)
						)
						(arc
							(start 0.2794 -0.1778)
							(mid 0.249642 -0.249642)
							(end 0.1778 -0.2794)
						)
					)
					(width 0)
					(fill yes)
				)
			)
		)
	)
	(footprint ""
		(layer "F.Cu")
		(at 381.36195 -177.169318 90)
		(property "Reference" "R590"
			(at 0 0 90)
			(layer "F.SilkS")
			(hide yes)
			(effects
				(font
					(size 1.27 1.27)
				)
			)
		)
		(property "Value" "10KR2F-2-GP"
			(at 0.064008 -3.993896 90)
			(unlocked yes)
			(layer "F.Fab")
			(hide yes)
			(effects
				(font
					(size 1.016 1.016)
					(thickness 0.1524)
				)
			)
		)
		(property "Device Type" "R402H16"
			(at 0.064008 -5.517896 90)
			(unlocked yes)
			(layer "F.Fab")
			(hide yes)
			(effects
				(font
					(size 1.016 1.016)
					(thickness 0.1524)
				)
			)
		)
		(duplicate_pad_numbers_are_jumpers no)
		(fp_line
			(start 0.508 -0.9398)
			(end -0.508 -0.9398)
			(stroke
				(width 0.1524)
				(type default)
			)
			(layer "F.SilkS")
		)
		(fp_line
			(start -0.508 -0.9398)
			(end -0.508 0.9398)
			(stroke
				(width 0.1524)
				(type default)
			)
			(layer "F.SilkS")
		)
		(fp_rect
			(start -0.508 0.9398)
			(end 0.508 -0.9398)
			(stroke
				(width 0)
				(type default)
			)
			(fill no)
			(layer "F.CrtYd")
		)
		(fp_rect
			(start -0.508 0.9398)
			(end 0.508 -0.9398)
			(stroke
				(width 0)
				(type default)
			)
			(fill no)
			(layer "F.Fab")
		)
		(pad "1" smd custom
			(at 0 -0.4445 90)
			(size 0.1397 0.1397)
			(layers "F.Cu" "F.Mask" "F.Paste")
			(net "P3V3_STBY_A")
			(options
				(clearance outline)
				(anchor circle)
			)
			(primitives
				(gr_poly
					(pts
						(arc
							(start -0.1778 -0.2794)
							(mid -0.249642 -0.249642)
							(end -0.2794 -0.1778)
						)
						(arc
							(start -0.2794 0.1778)
							(mid -0.249642 0.249642)
							(end -0.1778 0.2794)
						)
						(arc
							(start 0.1778 0.2794)
							(mid 0.249642 0.249642)
							(end 0.2794 0.1778)
						)
						(arc
							(start 0.2794 -0.1778)
							(mid 0.249642 -0.249642)
							(end 0.1778 -0.2794)
						)
					)
					(width 0)
					(fill yes)
				)
			)
		)
		(pad "2" smd custom
			(at 0 0.4445 90)
			(size 0.1397 0.1397)
			(layers "F.Cu" "F.Mask" "F.Paste")
			(net "HDD_PRSNT_20")
			(options
				(clearance outline)
				(anchor circle)
			)
			(primitives
				(gr_poly
					(pts
						(arc
							(start -0.1778 -0.2794)
							(mid -0.249642 -0.249642)
							(end -0.2794 -0.1778)
						)
						(arc
							(start -0.2794 0.1778)
							(mid -0.249642 0.249642)
							(end -0.1778 0.2794)
						)
						(arc
							(start 0.1778 0.2794)
							(mid 0.249642 0.249642)
							(end 0.2794 0.1778)
						)
						(arc
							(start 0.2794 -0.1778)
							(mid 0.249642 -0.249642)
							(end 0.1778 -0.2794)
						)
					)
					(width 0)
					(fill yes)
				)
			)
		)
	)
	(footprint ""
		(layer "F.Cu")
		(at 140.532866 -131.656074 180)
		(property "Reference" "R1051"
			(at 0 0 180)
			(layer "F.SilkS")
			(hide yes)
			(effects
				(font
					(size 1.27 1.27)
				)
			)
		)
		(property "Value" "10KR2F-2-GP"
			(at 0.064008 -3.993896 180)
			(unlocked yes)
			(layer "F.Fab")
			(hide yes)
			(effects
				(font
					(size 1.016 1.016)
					(thickness 0.1524)
				)
			)
		)
		(property "Device Type" "R402H16"
			(at 0.064008 -5.517896 180)
			(unlocked yes)
			(layer "F.Fab")
			(hide yes)
			(effects
				(font
					(size 1.016 1.016)
					(thickness 0.1524)
				)
			)
		)
		(duplicate_pad_numbers_are_jumpers no)
		(fp_line
			(start 0.508 -0.9398)
			(end -0.508 -0.9398)
			(stroke
				(width 0.1524)
				(type default)
			)
			(layer "F.SilkS")
		)
		(fp_line
			(start -0.508 -0.9398)
			(end -0.508 0.9398)
			(stroke
				(width 0.1524)
				(type default)
			)
			(layer "F.SilkS")
		)
		(fp_rect
			(start -0.508 0.9398)
			(end 0.508 -0.9398)
			(stroke
				(width 0)
				(type default)
			)
			(fill no)
			(layer "F.CrtYd")
		)
		(fp_rect
			(start -0.508 0.9398)
			(end 0.508 -0.9398)
			(stroke
				(width 0)
				(type default)
			)
			(fill no)
			(layer "F.Fab")
		)
		(pad "1" smd custom
			(at 0 -0.4445 180)
			(size 0.1397 0.1397)
			(layers "F.Cu" "F.Mask" "F.Paste")
			(net "P12V_A_COMP")
			(options
				(clearance outline)
				(anchor circle)
			)
			(primitives
				(gr_poly
					(pts
						(arc
							(start -0.1778 -0.2794)
							(mid -0.249642 -0.249642)
							(end -0.2794 -0.1778)
						)
						(arc
							(start -0.2794 0.1778)
							(mid -0.249642 0.249642)
							(end -0.1778 0.2794)
						)
						(arc
							(start 0.1778 0.2794)
							(mid 0.249642 0.249642)
							(end 0.2794 0.1778)
						)
						(arc
							(start 0.2794 -0.1778)
							(mid 0.249642 -0.249642)
							(end 0.1778 -0.2794)
						)
					)
					(width 0)
					(fill yes)
				)
			)
		)
		(pad "2" smd custom
			(at 0 0.4445 180)
			(size 0.1397 0.1397)
			(layers "F.Cu" "F.Mask" "F.Paste")
			(net "COMP_A_PGOOD")
			(options
				(clearance outline)
				(anchor circle)
			)
			(primitives
				(gr_poly
					(pts
						(arc
							(start -0.1778 -0.2794)
							(mid -0.249642 -0.249642)
							(end -0.2794 -0.1778)
						)
						(arc
							(start -0.2794 0.1778)
							(mid -0.249642 0.249642)
							(end -0.1778 0.2794)
						)
						(arc
							(start 0.1778 0.2794)
							(mid 0.249642 0.249642)
							(end 0.2794 0.1778)
						)
						(arc
							(start 0.2794 -0.1778)
							(mid 0.249642 -0.249642)
							(end 0.1778 -0.2794)
						)
					)
					(width 0)
					(fill yes)
				)
			)
		)
	)
	(footprint ""
		(layer "F.Cu")
		(at 86.096348 -163.580318 90)
		(property "Reference" "R464"
			(at 0 0 90)
			(layer "F.SilkS")
			(hide yes)
			(effects
				(font
					(size 1.27 1.27)
				)
			)
		)
		(property "Value" "4K7R2J-2-GP"
			(at 0.064008 -3.993896 90)
			(unlocked yes)
			(layer "F.Fab")
			(hide yes)
			(effects
				(font
					(size 1.016 1.016)
					(thickness 0.1524)
				)
			)
		)
		(property "Device Type" "R402H16"
			(at 0.064008 -5.517896 90)
			(unlocked yes)
			(layer "F.Fab")
			(hide yes)
			(effects
				(font
					(size 1.016 1.016)
					(thickness 0.1524)
				)
			)
		)
		(duplicate_pad_numbers_are_jumpers no)
		(fp_line
			(start 0.508 -0.9398)
			(end -0.508 -0.9398)
			(stroke
				(width 0.1524)
				(type default)
			)
			(layer "F.SilkS")
		)
		(fp_line
			(start -0.508 -0.9398)
			(end -0.508 0.9398)
			(stroke
				(width 0.1524)
				(type default)
			)
			(layer "F.SilkS")
		)
		(fp_rect
			(start -0.508 0.9398)
			(end 0.508 -0.9398)
			(stroke
				(width 0)
				(type default)
			)
			(fill no)
			(layer "F.CrtYd")
		)
		(fp_rect
			(start -0.508 0.9398)
			(end 0.508 -0.9398)
			(stroke
				(width 0)
				(type default)
			)
			(fill no)
			(layer "F.Fab")
		)
		(pad "1" smd custom
			(at 0 -0.4445 90)
			(size 0.1397 0.1397)
			(layers "F.Cu" "F.Mask" "F.Paste")
			(net "SW_PWR_R_HDD14")
			(options
				(clearance outline)
				(anchor circle)
			)
			(primitives
				(gr_poly
					(pts
						(arc
							(start -0.1778 -0.2794)
							(mid -0.249642 -0.249642)
							(end -0.2794 -0.1778)
						)
						(arc
							(start -0.2794 0.1778)
							(mid -0.249642 0.249642)
							(end -0.1778 0.2794)
						)
						(arc
							(start 0.1778 0.2794)
							(mid 0.249642 0.249642)
							(end 0.2794 0.1778)
						)
						(arc
							(start 0.2794 -0.1778)
							(mid 0.249642 -0.249642)
							(end 0.1778 -0.2794)
						)
					)
					(width 0)
					(fill yes)
				)
			)
		)
		(pad "2" smd custom
			(at 0 0.4445 90)
			(size 0.1397 0.1397)
			(layers "F.Cu" "F.Mask" "F.Paste")
			(net "GND")
			(options
				(clearance outline)
				(anchor circle)
			)
			(primitives
				(gr_poly
					(pts
						(arc
							(start -0.1778 -0.2794)
							(mid -0.249642 -0.249642)
							(end -0.2794 -0.1778)
						)
						(arc
							(start -0.2794 0.1778)
							(mid -0.249642 0.249642)
							(end -0.1778 0.2794)
						)
						(arc
							(start 0.1778 0.2794)
							(mid 0.249642 0.249642)
							(end 0.2794 0.1778)
						)
						(arc
							(start 0.2794 -0.1778)
							(mid 0.249642 -0.249642)
							(end 0.1778 -0.2794)
						)
					)
					(width 0)
					(fill yes)
				)
			)
		)
	)
	(footprint ""
		(layer "F.Cu")
		(at 264.541 -272.288 180)
		(property "Reference" "R109"
			(at 0 0 180)
			(layer "F.SilkS")
			(hide yes)
			(effects
				(font
					(size 1.27 1.27)
				)
			)
		)
		(property "Value" "4K7R2F-GP"
			(at 0.064008 -3.993896 180)
			(unlocked yes)
			(layer "F.Fab")
			(hide yes)
			(effects
				(font
					(size 1.016 1.016)
					(thickness 0.1524)
				)
			)
		)
		(property "Device Type" "R402H16"
			(at 0.064008 -5.517896 180)
			(unlocked yes)
			(layer "F.Fab")
			(hide yes)
			(effects
				(font
					(size 1.016 1.016)
					(thickness 0.1524)
				)
			)
		)
		(duplicate_pad_numbers_are_jumpers no)
		(fp_line
			(start 0.508 -0.9398)
			(end -0.508 -0.9398)
			(stroke
				(width 0.1524)
				(type default)
			)
			(layer "F.SilkS")
		)
		(fp_line
			(start -0.508 -0.9398)
			(end -0.508 0.9398)
			(stroke
				(width 0.1524)
				(type default)
			)
			(layer "F.SilkS")
		)
		(fp_rect
			(start -0.508 0.9398)
			(end 0.508 -0.9398)
			(stroke
				(width 0)
				(type default)
			)
			(fill no)
			(layer "F.CrtYd")
		)
		(fp_rect
			(start -0.508 0.9398)
			(end 0.508 -0.9398)
			(stroke
				(width 0)
				(type default)
			)
			(fill no)
			(layer "F.Fab")
		)
		(pad "1" smd custom
			(at 0 -0.4445 180)
			(size 0.1397 0.1397)
			(layers "F.Cu" "F.Mask" "F.Paste")
			(net "P3V3_STBY_A")
			(options
				(clearance outline)
				(anchor circle)
			)
			(primitives
				(gr_poly
					(pts
						(arc
							(start -0.1778 -0.2794)
							(mid -0.249642 -0.249642)
							(end -0.2794 -0.1778)
						)
						(arc
							(start -0.2794 0.1778)
							(mid -0.249642 0.249642)
							(end -0.1778 0.2794)
						)
						(arc
							(start 0.1778 0.2794)
							(mid 0.249642 0.249642)
							(end 0.2794 0.1778)
						)
						(arc
							(start 0.2794 -0.1778)
							(mid 0.249642 -0.249642)
							(end 0.1778 -0.2794)
						)
					)
					(width 0)
					(fill yes)
				)
			)
		)
		(pad "2" smd custom
			(at 0 0.4445 180)
			(size 0.1397 0.1397)
			(layers "F.Cu" "F.Mask" "F.Paste")
			(net "IO_EXP0_HDD_FAULT_A2")
			(options
				(clearance outline)
				(anchor circle)
			)
			(primitives
				(gr_poly
					(pts
						(arc
							(start -0.1778 -0.2794)
							(mid -0.249642 -0.249642)
							(end -0.2794 -0.1778)
						)
						(arc
							(start -0.2794 0.1778)
							(mid -0.249642 0.249642)
							(end -0.1778 0.2794)
						)
						(arc
							(start 0.1778 0.2794)
							(mid 0.249642 0.249642)
							(end 0.2794 0.1778)
						)
						(arc
							(start 0.2794 -0.1778)
							(mid 0.249642 -0.249642)
							(end 0.1778 -0.2794)
						)
					)
					(width 0)
					(fill yes)
				)
			)
		)
	)
	(footprint ""
		(layer "F.Cu")
		(at 231.913684 -388.72287 90)
		(property "Reference" "C102"
			(at 0 0 90)
			(layer "F.SilkS")
			(hide yes)
			(effects
				(font
					(size 1.27 1.27)
				)
			)
		)
		(property "Value" "SCD1U16V2KX-3GP"
			(at 1.1811 -2.7051 90)
			(unlocked yes)
			(layer "F.Fab")
			(hide yes)
			(effects
				(font
					(size 1.016 1.016)
					(thickness 0.1524)
				)
			)
		)
		(property "Device Type" "C402H22"
			(at 1.1811 -4.2291 90)
			(unlocked yes)
			(layer "F.Fab")
			(hide yes)
			(effects
				(font
					(size 1.016 1.016)
					(thickness 0.1524)
				)
			)
		)
		(duplicate_pad_numbers_are_jumpers no)
		(fp_rect
			(start -0.4318 0.9525)
			(end 0.4318 -0.9525)
			(stroke
				(width 0)
				(type default)
			)
			(fill no)
			(layer "F.CrtYd")
		)
		(fp_rect
			(start -0.4318 0.9525)
			(end 0.4318 -0.9525)
			(stroke
				(width 0)
				(type default)
			)
			(fill no)
			(layer "F.Fab")
		)
		(pad "1" smd custom
			(at 0 -0.4445 90)
			(size 0.1524 0.1524)
			(layers "F.Cu" "F.Mask" "F.Paste")
			(net "P3V3_IN_BIAS")
			(options
				(clearance outline)
				(anchor circle)
			)
			(primitives
				(gr_poly
					(pts
						(arc
							(start 0.3048 -0.2032)
							(mid 0.275042 -0.275042)
							(end 0.2032 -0.3048)
						)
						(arc
							(start -0.2032 -0.3048)
							(mid -0.275042 -0.275042)
							(end -0.3048 -0.2032)
						)
						(arc
							(start -0.3048 0.2032)
							(mid -0.275042 0.275042)
							(end -0.2032 0.3048)
						)
						(arc
							(start 0.2032 0.3048)
							(mid 0.275042 0.275042)
							(end 0.3048 0.2032)
						)
					)
					(width 0)
					(fill yes)
				)
			)
		)
		(pad "2" smd custom
			(at 0 0.4445 90)
			(size 0.1524 0.1524)
			(layers "F.Cu" "F.Mask" "F.Paste")
			(net "GND")
			(options
				(clearance outline)
				(anchor circle)
			)
			(primitives
				(gr_poly
					(pts
						(arc
							(start 0.3048 -0.2032)
							(mid 0.275042 -0.275042)
							(end 0.2032 -0.3048)
						)
						(arc
							(start -0.2032 -0.3048)
							(mid -0.275042 -0.275042)
							(end -0.3048 -0.2032)
						)
						(arc
							(start -0.3048 0.2032)
							(mid -0.275042 0.275042)
							(end -0.2032 0.3048)
						)
						(arc
							(start 0.2032 0.3048)
							(mid 0.275042 0.275042)
							(end 0.3048 0.2032)
						)
					)
					(width 0)
					(fill yes)
				)
			)
		)
	)
	(footprint ""
		(layer "F.Cu")
		(at 374.00992 -127.703072 180)
		(property "Reference" "Q247"
			(at 0 0 180)
			(layer "F.SilkS")
			(hide yes)
			(effects
				(font
					(size 1.27 1.27)
				)
			)
		)
		(property "Value" "2N7002K-2-GP"
			(at 0.127 -8.9662 180)
			(unlocked yes)
			(layer "F.Fab")
			(hide yes)
			(effects
				(font
					(size 1.016 1.016)
					(thickness 0.1524)
				)
			)
		)
		(property "Device Type" "SOT23DGS2D4H44"
			(at 0.127 -10.4902 180)
			(unlocked yes)
			(layer "F.Fab")
			(hide yes)
			(effects
				(font
					(size 1.016 1.016)
					(thickness 0.1524)
				)
			)
		)
		(duplicate_pad_numbers_are_jumpers no)
		(fp_line
			(start 1.651 1.778)
			(end 1.651 -1.778)
			(stroke
				(width 0.1524)
				(type default)
			)
			(layer "F.SilkS")
		)
		(fp_line
			(start 1.651 -1.778)
			(end -1.651 -1.778)
			(stroke
				(width 0.1524)
				(type default)
			)
			(layer "F.SilkS")
		)
		(fp_line
			(start -1.651 1.778)
			(end 1.651 1.778)
			(stroke
				(width 0.1524)
				(type default)
			)
			(layer "F.SilkS")
		)
		(fp_line
			(start -1.651 -1.778)
			(end -1.651 1.778)
			(stroke
				(width 0.1524)
				(type default)
			)
			(layer "F.SilkS")
		)
		(fp_poly
			(pts
				(xy -1.778 1.8796) (xy -1.778 -1.8796) (xy 1.778 -1.8796) (xy 1.778 1.8796)
			)
			(stroke
				(width 0)
				(type default)
			)
			(fill no)
			(layer "F.CrtYd")
		)
		(fp_poly
			(pts
				(xy -1.778 1.8796) (xy -1.778 -1.8796) (xy 1.778 -1.8796) (xy 1.778 1.8796)
			)
			(stroke
				(width 0)
				(type default)
			)
			(fill no)
			(layer "F.Fab")
		)
		(pad "D" smd custom
			(at 0 -0.9525 180)
			(size 0.1905 0.1905)
			(layers "F.Cu" "F.Mask" "F.Paste")
			(net "FLT_HDD20_N")
			(options
				(clearance outline)
				(anchor circle)
			)
			(primitives
				(gr_poly
					(pts
						(arc
							(start -0.1778 0.5715)
							(mid -0.321484 0.511984)
							(end -0.381 0.3683)
						)
						(arc
							(start -0.381 -0.3683)
							(mid -0.321484 -0.511984)
							(end -0.1778 -0.5715)
						)
						(arc
							(start 0.1778 -0.5715)
							(mid 0.321484 -0.511984)
							(end 0.381 -0.3683)
						)
						(arc
							(start 0.381 0.3683)
							(mid 0.321484 0.511984)
							(end 0.1778 0.5715)
						)
					)
					(width 0)
					(fill yes)
				)
			)
		)
		(pad "G" smd custom
			(at -0.98425 0.9525 180)
			(size 0.1905 0.1905)
			(layers "F.Cu" "F.Mask" "F.Paste")
			(net "DRIVE_A_20_FLT_LED")
			(options
				(clearance outline)
				(anchor circle)
			)
			(primitives
				(gr_poly
					(pts
						(arc
							(start -0.1778 0.5715)
							(mid -0.321484 0.511984)
							(end -0.381 0.3683)
						)
						(arc
							(start -0.381 -0.3683)
							(mid -0.321484 -0.511984)
							(end -0.1778 -0.5715)
						)
						(arc
							(start 0.1778 -0.5715)
							(mid 0.321484 -0.511984)
							(end 0.381 -0.3683)
						)
						(arc
							(start 0.381 0.3683)
							(mid 0.321484 0.511984)
							(end 0.1778 0.5715)
						)
					)
					(width 0)
					(fill yes)
				)
			)
		)
		(pad "S" smd custom
			(at 0.98425 0.9525 180)
			(size 0.1905 0.1905)
			(layers "F.Cu" "F.Mask" "F.Paste")
			(net "GND")
			(options
				(clearance outline)
				(anchor circle)
			)
			(primitives
				(gr_poly
					(pts
						(arc
							(start -0.1778 0.5715)
							(mid -0.321484 0.511984)
							(end -0.381 0.3683)
						)
						(arc
							(start -0.381 -0.3683)
							(mid -0.321484 -0.511984)
							(end -0.1778 -0.5715)
						)
						(arc
							(start 0.1778 -0.5715)
							(mid 0.321484 -0.511984)
							(end 0.381 -0.3683)
						)
						(arc
							(start 0.381 0.3683)
							(mid 0.321484 0.511984)
							(end 0.1778 0.5715)
						)
					)
					(width 0)
					(fill yes)
				)
			)
		)
	)
	(footprint ""
		(layer "F.Cu")
		(at 368.8588 -145.8214 180)
		(property "Reference" "R1088"
			(at 0 0 180)
			(layer "F.SilkS")
			(hide yes)
			(effects
				(font
					(size 1.27 1.27)
				)
			)
		)
		(property "Value" "11KR2F-L-GP"
			(at 0.064008 -3.993896 180)
			(unlocked yes)
			(layer "F.Fab")
			(hide yes)
			(effects
				(font
					(size 1.016 1.016)
					(thickness 0.1524)
				)
			)
		)
		(property "Device Type" "R402H16"
			(at 0.064008 -5.517896 180)
			(unlocked yes)
			(layer "F.Fab")
			(hide yes)
			(effects
				(font
					(size 1.016 1.016)
					(thickness 0.1524)
				)
			)
		)
		(duplicate_pad_numbers_are_jumpers no)
		(fp_line
			(start 0.508 -0.9398)
			(end -0.508 -0.9398)
			(stroke
				(width 0.1524)
				(type default)
			)
			(layer "F.SilkS")
		)
		(fp_line
			(start -0.508 -0.9398)
			(end -0.508 0.9398)
			(stroke
				(width 0.1524)
				(type default)
			)
			(layer "F.SilkS")
		)
		(fp_rect
			(start -0.508 0.9398)
			(end 0.508 -0.9398)
			(stroke
				(width 0)
				(type default)
			)
			(fill no)
			(layer "F.CrtYd")
		)
		(fp_rect
			(start -0.508 0.9398)
			(end 0.508 -0.9398)
			(stroke
				(width 0)
				(type default)
			)
			(fill no)
			(layer "F.Fab")
		)
		(pad "1" smd custom
			(at 0 -0.4445 180)
			(size 0.1397 0.1397)
			(layers "F.Cu" "F.Mask" "F.Paste")
			(net "MB1_P12V_PWGIN_R")
			(options
				(clearance outline)
				(anchor circle)
			)
			(primitives
				(gr_poly
					(pts
						(arc
							(start -0.1778 -0.2794)
							(mid -0.249642 -0.249642)
							(end -0.2794 -0.1778)
						)
						(arc
							(start -0.2794 0.1778)
							(mid -0.249642 0.249642)
							(end -0.1778 0.2794)
						)
						(arc
							(start 0.1778 0.2794)
							(mid 0.249642 0.249642)
							(end 0.2794 0.1778)
						)
						(arc
							(start 0.2794 -0.1778)
							(mid 0.249642 -0.249642)
							(end 0.1778 -0.2794)
						)
					)
					(width 0)
					(fill yes)
				)
			)
		)
		(pad "2" smd custom
			(at 0 0.4445 180)
			(size 0.1397 0.1397)
			(layers "F.Cu" "F.Mask" "F.Paste")
			(net "AGND_CURRENT_MONOB")
			(options
				(clearance outline)
				(anchor circle)
			)
			(primitives
				(gr_poly
					(pts
						(arc
							(start -0.1778 -0.2794)
							(mid -0.249642 -0.249642)
							(end -0.2794 -0.1778)
						)
						(arc
							(start -0.2794 0.1778)
							(mid -0.249642 0.249642)
							(end -0.1778 0.2794)
						)
						(arc
							(start 0.1778 0.2794)
							(mid 0.249642 0.249642)
							(end 0.2794 0.1778)
						)
						(arc
							(start 0.2794 -0.1778)
							(mid 0.249642 -0.249642)
							(end 0.1778 -0.2794)
						)
					)
					(width 0)
					(fill yes)
				)
			)
		)
	)
	(footprint ""
		(layer "F.Cu")
		(at 55.790846 -74.462894 180)
		(property "Reference" "C372"
			(at 0 0 180)
			(layer "F.SilkS")
			(hide yes)
			(effects
				(font
					(size 1.27 1.27)
				)
			)
		)
		(property "Value" "SC1U25V3KX-GP"
			(at 0 -2.8194 180)
			(unlocked yes)
			(layer "F.Fab")
			(hide yes)
			(effects
				(font
					(size 1.016 1.016)
					(thickness 0.1524)
				)
			)
		)
		(property "Device Type" "C603H36"
			(at 0 -4.3434 180)
			(unlocked yes)
			(layer "F.Fab")
			(hide yes)
			(effects
				(font
					(size 1.016 1.016)
					(thickness 0.1524)
				)
			)
		)
		(duplicate_pad_numbers_are_jumpers no)
		(fp_line
			(start 0.508 0)
			(end -0.508 0)
			(stroke
				(width 0.2032)
				(type default)
			)
			(layer "F.SilkS")
		)
		(fp_rect
			(start -0.5842 1.3335)
			(end 0.5842 -1.3335)
			(stroke
				(width 0)
				(type default)
			)
			(fill no)
			(layer "F.CrtYd")
		)
		(fp_rect
			(start -0.5842 1.3335)
			(end 0.5842 -1.3335)
			(stroke
				(width 0)
				(type default)
			)
			(fill no)
			(layer "F.Fab")
		)
		(pad "1" smd custom
			(at 0 -0.762 180)
			(size 0.2159 0.2159)
			(layers "F.Cu" "F.Mask" "F.Paste")
			(net "P12V_HDD25")
			(options
				(clearance outline)
				(anchor circle)
			)
			(primitives
				(gr_poly
					(pts
						(arc
							(start -0.3302 -0.4318)
							(mid -0.402042 -0.402042)
							(end -0.4318 -0.3302)
						)
						(arc
							(start -0.4318 0.3302)
							(mid -0.402042 0.402042)
							(end -0.3302 0.4318)
						)
						(arc
							(start 0.3302 0.4318)
							(mid 0.402042 0.402042)
							(end 0.4318 0.3302)
						)
						(arc
							(start 0.4318 -0.3302)
							(mid 0.402042 -0.402042)
							(end 0.3302 -0.4318)
						)
					)
					(width 0)
					(fill yes)
				)
			)
		)
		(pad "2" smd custom
			(at 0 0.762 180)
			(size 0.2159 0.2159)
			(layers "F.Cu" "F.Mask" "F.Paste")
			(net "GND")
			(options
				(clearance outline)
				(anchor circle)
			)
			(primitives
				(gr_poly
					(pts
						(arc
							(start -0.3302 -0.4318)
							(mid -0.402042 -0.402042)
							(end -0.4318 -0.3302)
						)
						(arc
							(start -0.4318 0.3302)
							(mid -0.402042 0.402042)
							(end -0.3302 0.4318)
						)
						(arc
							(start 0.3302 0.4318)
							(mid 0.402042 0.402042)
							(end 0.4318 0.3302)
						)
						(arc
							(start 0.4318 -0.3302)
							(mid 0.402042 -0.402042)
							(end 0.3302 -0.4318)
						)
					)
					(width 0)
					(fill yes)
				)
			)
		)
	)
	(footprint ""
		(layer "F.Cu")
		(at 240.538 -394.3858 -90)
		(property "Reference" "R1162"
			(at 0 0 270)
			(layer "F.SilkS")
			(hide yes)
			(effects
				(font
					(size 1.27 1.27)
				)
			)
		)
		(property "Value" "100KR2F-L1-GP"
			(at 0.064008 -3.993896 270)
			(unlocked yes)
			(layer "F.Fab")
			(hide yes)
			(effects
				(font
					(size 1.016 1.016)
					(thickness 0.1524)
				)
			)
		)
		(property "Device Type" "R402H16"
			(at 0.064008 -5.517896 270)
			(unlocked yes)
			(layer "F.Fab")
			(hide yes)
			(effects
				(font
					(size 1.016 1.016)
					(thickness 0.1524)
				)
			)
		)
		(duplicate_pad_numbers_are_jumpers no)
		(fp_line
			(start -0.508 -0.9398)
			(end -0.508 0.9398)
			(stroke
				(width 0.1524)
				(type default)
			)
			(layer "F.SilkS")
		)
		(fp_line
			(start 0.508 -0.9398)
			(end -0.508 -0.9398)
			(stroke
				(width 0.1524)
				(type default)
			)
			(layer "F.SilkS")
		)
		(fp_rect
			(start -0.508 0.9398)
			(end 0.508 -0.9398)
			(stroke
				(width 0)
				(type default)
			)
			(fill no)
			(layer "F.CrtYd")
		)
		(fp_rect
			(start -0.508 0.9398)
			(end 0.508 -0.9398)
			(stroke
				(width 0)
				(type default)
			)
			(fill no)
			(layer "F.Fab")
		)
		(pad "1" smd custom
			(at 0 -0.4445 270)
			(size 0.1397 0.1397)
			(layers "F.Cu" "F.Mask" "F.Paste")
			(net "MB3_VCAP_R")
			(options
				(clearance outline)
				(anchor circle)
			)
			(primitives
				(gr_poly
					(pts
						(arc
							(start -0.1778 -0.2794)
							(mid -0.249642 -0.249642)
							(end -0.2794 -0.1778)
						)
						(arc
							(start -0.2794 0.1778)
							(mid -0.249642 0.249642)
							(end -0.1778 0.2794)
						)
						(arc
							(start 0.1778 0.2794)
							(mid 0.249642 0.249642)
							(end 0.2794 0.1778)
						)
						(arc
							(start 0.2794 -0.1778)
							(mid 0.249642 -0.249642)
							(end 0.1778 -0.2794)
						)
					)
					(width 0)
					(fill yes)
				)
			)
		)
		(pad "2" smd custom
			(at 0 0.4445 270)
			(size 0.1397 0.1397)
			(layers "F.Cu" "F.Mask" "F.Paste")
			(net "MB3_ISET_R")
			(options
				(clearance outline)
				(anchor circle)
			)
			(primitives
				(gr_poly
					(pts
						(arc
							(start -0.1778 -0.2794)
							(mid -0.249642 -0.249642)
							(end -0.2794 -0.1778)
						)
						(arc
							(start -0.2794 0.1778)
							(mid -0.249642 0.249642)
							(end -0.1778 0.2794)
						)
						(arc
							(start 0.1778 0.2794)
							(mid 0.249642 0.249642)
							(end 0.2794 0.1778)
						)
						(arc
							(start 0.2794 -0.1778)
							(mid 0.249642 -0.249642)
							(end 0.1778 -0.2794)
						)
					)
					(width 0)
					(fill yes)
				)
			)
		)
	)
	(footprint ""
		(layer "F.Cu")
		(at 311.898538 -290.91255 90)
		(property "Reference" "R587"
			(at 0 0 90)
			(layer "F.SilkS")
			(hide yes)
			(effects
				(font
					(size 1.27 1.27)
				)
			)
		)
		(property "Value" "4K7R2J-2-GP"
			(at 0.064008 -3.993896 90)
			(unlocked yes)
			(layer "F.Fab")
			(hide yes)
			(effects
				(font
					(size 1.016 1.016)
					(thickness 0.1524)
				)
			)
		)
		(property "Device Type" "R402H16"
			(at 0.064008 -5.517896 90)
			(unlocked yes)
			(layer "F.Fab")
			(hide yes)
			(effects
				(font
					(size 1.016 1.016)
					(thickness 0.1524)
				)
			)
		)
		(duplicate_pad_numbers_are_jumpers no)
		(fp_line
			(start 0.508 -0.9398)
			(end -0.508 -0.9398)
			(stroke
				(width 0.1524)
				(type default)
			)
			(layer "F.SilkS")
		)
		(fp_line
			(start -0.508 -0.9398)
			(end -0.508 0.9398)
			(stroke
				(width 0.1524)
				(type default)
			)
			(layer "F.SilkS")
		)
		(fp_rect
			(start -0.508 0.9398)
			(end 0.508 -0.9398)
			(stroke
				(width 0)
				(type default)
			)
			(fill no)
			(layer "F.CrtYd")
		)
		(fp_rect
			(start -0.508 0.9398)
			(end 0.508 -0.9398)
			(stroke
				(width 0)
				(type default)
			)
			(fill no)
			(layer "F.Fab")
		)
		(pad "1" smd custom
			(at 0 -0.4445 90)
			(size 0.1397 0.1397)
			(layers "F.Cu" "F.Mask" "F.Paste")
			(net "DRIVE_B_30_FLT_LED")
			(options
				(clearance outline)
				(anchor circle)
			)
			(primitives
				(gr_poly
					(pts
						(arc
							(start -0.1778 -0.2794)
							(mid -0.249642 -0.249642)
							(end -0.2794 -0.1778)
						)
						(arc
							(start -0.2794 0.1778)
							(mid -0.249642 0.249642)
							(end -0.1778 0.2794)
						)
						(arc
							(start 0.1778 0.2794)
							(mid 0.249642 0.249642)
							(end 0.2794 0.1778)
						)
						(arc
							(start 0.2794 -0.1778)
							(mid 0.249642 -0.249642)
							(end 0.1778 -0.2794)
						)
					)
					(width 0)
					(fill yes)
				)
			)
		)
		(pad "2" smd custom
			(at 0 0.4445 90)
			(size 0.1397 0.1397)
			(layers "F.Cu" "F.Mask" "F.Paste")
			(net "GND")
			(options
				(clearance outline)
				(anchor circle)
			)
			(primitives
				(gr_poly
					(pts
						(arc
							(start -0.1778 -0.2794)
							(mid -0.249642 -0.249642)
							(end -0.2794 -0.1778)
						)
						(arc
							(start -0.2794 0.1778)
							(mid -0.249642 0.249642)
							(end -0.1778 0.2794)
						)
						(arc
							(start 0.1778 0.2794)
							(mid 0.249642 0.249642)
							(end 0.2794 0.1778)
						)
						(arc
							(start 0.2794 -0.1778)
							(mid 0.249642 -0.249642)
							(end 0.1778 -0.2794)
						)
					)
					(width 0)
					(fill yes)
				)
			)
		)
	)
	(footprint ""
		(layer "F.Cu")
		(at 458.5335 -272.535142 180)
		(property "Reference" "R368"
			(at 0 0 180)
			(layer "F.SilkS")
			(hide yes)
			(effects
				(font
					(size 1.27 1.27)
				)
			)
		)
		(property "Value" "1KR2F-3-GP"
			(at 0.064008 -3.993896 180)
			(unlocked yes)
			(layer "F.Fab")
			(hide yes)
			(effects
				(font
					(size 1.016 1.016)
					(thickness 0.1524)
				)
			)
		)
		(property "Device Type" "R402H16"
			(at 0.064008 -5.517896 180)
			(unlocked yes)
			(layer "F.Fab")
			(hide yes)
			(effects
				(font
					(size 1.016 1.016)
					(thickness 0.1524)
				)
			)
		)
		(duplicate_pad_numbers_are_jumpers no)
		(fp_line
			(start 0.508 -0.9398)
			(end -0.508 -0.9398)
			(stroke
				(width 0.1524)
				(type default)
			)
			(layer "F.SilkS")
		)
		(fp_line
			(start -0.508 -0.9398)
			(end -0.508 0.9398)
			(stroke
				(width 0.1524)
				(type default)
			)
			(layer "F.SilkS")
		)
		(fp_rect
			(start -0.508 0.9398)
			(end 0.508 -0.9398)
			(stroke
				(width 0)
				(type default)
			)
			(fill no)
			(layer "F.CrtYd")
		)
		(fp_rect
			(start -0.508 0.9398)
			(end 0.508 -0.9398)
			(stroke
				(width 0)
				(type default)
			)
			(fill no)
			(layer "F.Fab")
		)
		(pad "1" smd custom
			(at 0 -0.4445 180)
			(size 0.1397 0.1397)
			(layers "F.Cu" "F.Mask" "F.Paste")
			(net "P3V3_STBY_A")
			(options
				(clearance outline)
				(anchor circle)
			)
			(primitives
				(gr_poly
					(pts
						(arc
							(start -0.1778 -0.2794)
							(mid -0.249642 -0.249642)
							(end -0.2794 -0.1778)
						)
						(arc
							(start -0.2794 0.1778)
							(mid -0.249642 0.249642)
							(end -0.1778 0.2794)
						)
						(arc
							(start 0.1778 0.2794)
							(mid 0.249642 0.249642)
							(end 0.2794 0.1778)
						)
						(arc
							(start 0.2794 -0.1778)
							(mid 0.249642 -0.249642)
							(end 0.1778 -0.2794)
						)
					)
					(width 0)
					(fill yes)
				)
			)
		)
		(pad "2" smd custom
			(at 0 0.4445 180)
			(size 0.1397 0.1397)
			(layers "F.Cu" "F.Mask" "F.Paste")
			(net "SW_PWR_R_HDD10")
			(options
				(clearance outline)
				(anchor circle)
			)
			(primitives
				(gr_poly
					(pts
						(arc
							(start -0.1778 -0.2794)
							(mid -0.249642 -0.249642)
							(end -0.2794 -0.1778)
						)
						(arc
							(start -0.2794 0.1778)
							(mid -0.249642 0.249642)
							(end -0.1778 0.2794)
						)
						(arc
							(start 0.1778 0.2794)
							(mid 0.249642 0.249642)
							(end 0.2794 0.1778)
						)
						(arc
							(start 0.2794 -0.1778)
							(mid 0.249642 -0.249642)
							(end 0.1778 -0.2794)
						)
					)
					(width 0)
					(fill yes)
				)
			)
		)
	)
	(footprint ""
		(layer "F.Cu")
		(at 95.563436 -44.219368 90)
		(property "Reference" "C376"
			(at 0 0 90)
			(layer "F.SilkS")
			(hide yes)
			(effects
				(font
					(size 1.27 1.27)
				)
			)
		)
		(property "Value" "SCD01U16V1KX-GP"
			(at -2.8321 -1.7399 90)
			(unlocked yes)
			(layer "F.Fab")
			(hide yes)
			(effects
				(font
					(size 1.016 1.016)
					(thickness 0.1524)
				)
			)
		)
		(property "Device Type" "C0201H13"
			(at -2.8321 -3.2639 90)
			(unlocked yes)
			(layer "F.Fab")
			(hide yes)
			(effects
				(font
					(size 1.016 1.016)
					(thickness 0.1524)
				)
			)
		)
		(duplicate_pad_numbers_are_jumpers no)
		(fp_rect
			(start -0.2794 0.6477)
			(end 0.2794 -0.6477)
			(stroke
				(width 0)
				(type default)
			)
			(fill no)
			(layer "F.CrtYd")
		)
		(fp_rect
			(start -0.2794 0.6477)
			(end 0.2794 -0.6477)
			(stroke
				(width 0)
				(type default)
			)
			(fill no)
			(layer "F.Fab")
		)
		(pad "1" smd custom
			(at 0 -0.2794 90)
			(size 0.0762 0.0762)
			(layers "F.Cu" "F.Mask" "F.Paste")
			(net "SAS_HDD_RX_N26")
			(options
				(clearance outline)
				(anchor circle)
			)
			(primitives
				(gr_poly
					(pts
						(arc
							(start 0.1524 -0.127)
							(mid 0.137521 -0.162921)
							(end 0.1016 -0.1778)
						)
						(arc
							(start -0.1016 -0.1778)
							(mid -0.137521 -0.162921)
							(end -0.1524 -0.127)
						)
						(arc
							(start -0.1524 0.127)
							(mid -0.137521 0.162921)
							(end -0.1016 0.1778)
						)
						(arc
							(start 0.1016 0.1778)
							(mid 0.137521 0.162921)
							(end 0.1524 0.127)
						)
					)
					(width 0)
					(fill yes)
				)
			)
		)
		(pad "2" smd custom
			(at 0 0.2794 90)
			(size 0.0762 0.0762)
			(layers "F.Cu" "F.Mask" "F.Paste")
			(net "PHY_SCC_A_TO_DRV_A_26_DN")
			(options
				(clearance outline)
				(anchor circle)
			)
			(primitives
				(gr_poly
					(pts
						(arc
							(start 0.1524 -0.127)
							(mid 0.137521 -0.162921)
							(end 0.1016 -0.1778)
						)
						(arc
							(start -0.1016 -0.1778)
							(mid -0.137521 -0.162921)
							(end -0.1524 -0.127)
						)
						(arc
							(start -0.1524 0.127)
							(mid -0.137521 0.162921)
							(end -0.1016 0.1778)
						)
						(arc
							(start 0.1016 0.1778)
							(mid 0.137521 0.162921)
							(end 0.1524 0.127)
						)
					)
					(width 0)
					(fill yes)
				)
			)
		)
	)
	(footprint ""
		(layer "F.Cu")
		(at 258.367276 -261.35076)
		(property "Reference" "R60"
			(at 0 0 0)
			(layer "F.SilkS")
			(hide yes)
			(effects
				(font
					(size 1.27 1.27)
				)
			)
		)
		(property "Value" "4K7R2F-GP"
			(at 0.064008 -3.993896 0)
			(unlocked yes)
			(layer "F.Fab")
			(hide yes)
			(effects
				(font
					(size 1.016 1.016)
					(thickness 0.1524)
				)
			)
		)
		(property "Device Type" "R402H16"
			(at 0.064008 -5.517896 0)
			(unlocked yes)
			(layer "F.Fab")
			(hide yes)
			(effects
				(font
					(size 1.016 1.016)
					(thickness 0.1524)
				)
			)
		)
		(duplicate_pad_numbers_are_jumpers no)
		(fp_line
			(start -0.508 -0.9398)
			(end -0.508 0.9398)
			(stroke
				(width 0.1524)
				(type default)
			)
			(layer "F.SilkS")
		)
		(fp_line
			(start 0.508 -0.9398)
			(end -0.508 -0.9398)
			(stroke
				(width 0.1524)
				(type default)
			)
			(layer "F.SilkS")
		)
		(fp_rect
			(start -0.508 0.9398)
			(end 0.508 -0.9398)
			(stroke
				(width 0)
				(type default)
			)
			(fill no)
			(layer "F.CrtYd")
		)
		(fp_rect
			(start -0.508 0.9398)
			(end 0.508 -0.9398)
			(stroke
				(width 0)
				(type default)
			)
			(fill no)
			(layer "F.Fab")
		)
		(pad "1" smd custom
			(at 0 -0.4445)
			(size 0.1397 0.1397)
			(layers "F.Cu" "F.Mask" "F.Paste")
			(net "P3V3_STBY_A")
			(options
				(clearance outline)
				(anchor circle)
			)
			(primitives
				(gr_poly
					(pts
						(arc
							(start -0.1778 -0.2794)
							(mid -0.249642 -0.249642)
							(end -0.2794 -0.1778)
						)
						(arc
							(start -0.2794 0.1778)
							(mid -0.249642 0.249642)
							(end -0.1778 0.2794)
						)
						(arc
							(start 0.1778 0.2794)
							(mid 0.249642 0.249642)
							(end 0.2794 0.1778)
						)
						(arc
							(start 0.2794 -0.1778)
							(mid 0.249642 -0.249642)
							(end 0.1778 -0.2794)
						)
					)
					(width 0)
					(fill yes)
				)
			)
		)
		(pad "2" smd custom
			(at 0 0.4445)
			(size 0.1397 0.1397)
			(layers "F.Cu" "F.Mask" "F.Paste")
			(net "IO_EXP6_A0")
			(options
				(clearance outline)
				(anchor circle)
			)
			(primitives
				(gr_poly
					(pts
						(arc
							(start -0.1778 -0.2794)
							(mid -0.249642 -0.249642)
							(end -0.2794 -0.1778)
						)
						(arc
							(start -0.2794 0.1778)
							(mid -0.249642 0.249642)
							(end -0.1778 0.2794)
						)
						(arc
							(start 0.1778 0.2794)
							(mid 0.249642 0.249642)
							(end 0.2794 0.1778)
						)
						(arc
							(start 0.2794 -0.1778)
							(mid 0.249642 -0.249642)
							(end 0.1778 -0.2794)
						)
					)
					(width 0)
					(fill yes)
				)
			)
		)
	)
	(footprint ""
		(layer "F.Cu")
		(at 18.415 -242.25377)
		(property "Reference" "R196"
			(at 0 0 0)
			(layer "F.SilkS")
			(hide yes)
			(effects
				(font
					(size 1.27 1.27)
				)
			)
		)
		(property "Value" "91R3F-1-GP"
			(at -0.0254 -2.5146 0)
			(unlocked yes)
			(layer "F.Fab")
			(hide yes)
			(effects
				(font
					(size 1.016 1.016)
					(thickness 0.1524)
				)
			)
		)
		(property "Device Type" "R603H22"
			(at -0.0254 -4.0386 0)
			(unlocked yes)
			(layer "F.Fab")
			(hide yes)
			(effects
				(font
					(size 1.016 1.016)
					(thickness 0.1524)
				)
			)
		)
		(duplicate_pad_numbers_are_jumpers no)
		(fp_line
			(start -0.4826 0)
			(end -0.2032 0)
			(stroke
				(width 0.2032)
				(type default)
			)
			(layer "F.SilkS")
		)
		(fp_line
			(start 0.2032 0)
			(end 0.4826 0)
			(stroke
				(width 0.2032)
				(type default)
			)
			(layer "F.SilkS")
		)
		(fp_rect
			(start -0.5842 1.3335)
			(end 0.5842 -1.3335)
			(stroke
				(width 0)
				(type default)
			)
			(fill no)
			(layer "F.CrtYd")
		)
		(fp_rect
			(start -0.5842 1.3335)
			(end 0.5842 -1.3335)
			(stroke
				(width 0)
				(type default)
			)
			(fill no)
			(layer "F.Fab")
		)
		(pad "1" smd custom
			(at 0 -0.762)
			(size 0.2159 0.2159)
			(layers "F.Cu" "F.Mask" "F.Paste")
			(net "P5V_A_1")
			(options
				(clearance outline)
				(anchor circle)
			)
			(primitives
				(gr_poly
					(pts
						(arc
							(start -0.3302 -0.4318)
							(mid -0.402042 -0.402042)
							(end -0.4318 -0.3302)
						)
						(arc
							(start -0.4318 0.3302)
							(mid -0.402042 0.402042)
							(end -0.3302 0.4318)
						)
						(arc
							(start 0.3302 0.4318)
							(mid 0.402042 0.402042)
							(end 0.4318 0.3302)
						)
						(arc
							(start 0.4318 -0.3302)
							(mid 0.402042 -0.402042)
							(end 0.3302 -0.4318)
						)
					)
					(width 0)
					(fill yes)
				)
			)
		)
		(pad "2" smd custom
			(at 0 0.762)
			(size 0.2159 0.2159)
			(layers "F.Cu" "F.Mask" "F.Paste")
			(net "DRV_ACT_0")
			(options
				(clearance outline)
				(anchor circle)
			)
			(primitives
				(gr_poly
					(pts
						(arc
							(start -0.3302 -0.4318)
							(mid -0.402042 -0.402042)
							(end -0.4318 -0.3302)
						)
						(arc
							(start -0.4318 0.3302)
							(mid -0.402042 0.402042)
							(end -0.3302 0.4318)
						)
						(arc
							(start 0.3302 0.4318)
							(mid 0.402042 0.402042)
							(end 0.4318 0.3302)
						)
						(arc
							(start 0.4318 -0.3302)
							(mid 0.402042 -0.402042)
							(end 0.3302 -0.4318)
						)
					)
					(width 0)
					(fill yes)
				)
			)
		)
	)
	(footprint ""
		(layer "F.Cu")
		(at 373.622062 -294.392858 180)
		(property "Reference" "R301"
			(at 0 0 180)
			(layer "F.SilkS")
			(hide yes)
			(effects
				(font
					(size 1.27 1.27)
				)
			)
		)
		(property "Value" "91R3F-1-GP"
			(at -0.0254 -2.5146 180)
			(unlocked yes)
			(layer "F.Fab")
			(hide yes)
			(effects
				(font
					(size 1.016 1.016)
					(thickness 0.1524)
				)
			)
		)
		(property "Device Type" "R603H22"
			(at -0.0254 -4.0386 180)
			(unlocked yes)
			(layer "F.Fab")
			(hide yes)
			(effects
				(font
					(size 1.016 1.016)
					(thickness 0.1524)
				)
			)
		)
		(duplicate_pad_numbers_are_jumpers no)
		(fp_line
			(start 0.2032 0)
			(end 0.4826 0)
			(stroke
				(width 0.2032)
				(type default)
			)
			(layer "F.SilkS")
		)
		(fp_line
			(start -0.4826 0)
			(end -0.2032 0)
			(stroke
				(width 0.2032)
				(type default)
			)
			(layer "F.SilkS")
		)
		(fp_rect
			(start -0.5842 1.3335)
			(end 0.5842 -1.3335)
			(stroke
				(width 0)
				(type default)
			)
			(fill no)
			(layer "F.CrtYd")
		)
		(fp_rect
			(start -0.5842 1.3335)
			(end 0.5842 -1.3335)
			(stroke
				(width 0)
				(type default)
			)
			(fill no)
			(layer "F.Fab")
		)
		(pad "1" smd custom
			(at 0 -0.762 180)
			(size 0.2159 0.2159)
			(layers "F.Cu" "F.Mask" "F.Paste")
			(net "P5V_B")
			(options
				(clearance outline)
				(anchor circle)
			)
			(primitives
				(gr_poly
					(pts
						(arc
							(start -0.3302 -0.4318)
							(mid -0.402042 -0.402042)
							(end -0.4318 -0.3302)
						)
						(arc
							(start -0.4318 0.3302)
							(mid -0.402042 0.402042)
							(end -0.3302 0.4318)
						)
						(arc
							(start 0.3302 0.4318)
							(mid 0.402042 0.402042)
							(end 0.4318 0.3302)
						)
						(arc
							(start 0.4318 -0.3302)
							(mid 0.402042 -0.402042)
							(end 0.3302 -0.4318)
						)
					)
					(width 0)
					(fill yes)
				)
			)
		)
		(pad "2" smd custom
			(at 0 0.762 180)
			(size 0.2159 0.2159)
			(layers "F.Cu" "F.Mask" "F.Paste")
			(net "DRV_ACT_32")
			(options
				(clearance outline)
				(anchor circle)
			)
			(primitives
				(gr_poly
					(pts
						(arc
							(start -0.3302 -0.4318)
							(mid -0.402042 -0.402042)
							(end -0.4318 -0.3302)
						)
						(arc
							(start -0.4318 0.3302)
							(mid -0.402042 0.402042)
							(end -0.3302 0.4318)
						)
						(arc
							(start 0.3302 0.4318)
							(mid 0.402042 0.402042)
							(end 0.4318 0.3302)
						)
						(arc
							(start 0.4318 -0.3302)
							(mid 0.402042 -0.402042)
							(end 0.3302 -0.4318)
						)
					)
					(width 0)
					(fill yes)
				)
			)
		)
	)
	(footprint ""
		(layer "F.Cu")
		(at 80.624934 -18.50517 -90)
		(property "Reference" "R34"
			(at 0 0 270)
			(layer "F.SilkS")
			(hide yes)
			(effects
				(font
					(size 1.27 1.27)
				)
			)
		)
		(property "Value" "4K7R2F-GP"
			(at 0.064008 -3.993896 270)
			(unlocked yes)
			(layer "F.Fab")
			(hide yes)
			(effects
				(font
					(size 1.016 1.016)
					(thickness 0.1524)
				)
			)
		)
		(property "Device Type" "R402H16"
			(at 0.064008 -5.517896 270)
			(unlocked yes)
			(layer "F.Fab")
			(hide yes)
			(effects
				(font
					(size 1.016 1.016)
					(thickness 0.1524)
				)
			)
		)
		(duplicate_pad_numbers_are_jumpers no)
		(fp_line
			(start -0.508 -0.9398)
			(end -0.508 0.9398)
			(stroke
				(width 0.1524)
				(type default)
			)
			(layer "F.SilkS")
		)
		(fp_line
			(start 0.508 -0.9398)
			(end -0.508 -0.9398)
			(stroke
				(width 0.1524)
				(type default)
			)
			(layer "F.SilkS")
		)
		(fp_rect
			(start -0.508 0.9398)
			(end 0.508 -0.9398)
			(stroke
				(width 0)
				(type default)
			)
			(fill no)
			(layer "F.CrtYd")
		)
		(fp_rect
			(start -0.508 0.9398)
			(end 0.508 -0.9398)
			(stroke
				(width 0)
				(type default)
			)
			(fill no)
			(layer "F.Fab")
		)
		(pad "1" smd custom
			(at 0 -0.4445 270)
			(size 0.1397 0.1397)
			(layers "F.Cu" "F.Mask" "F.Paste")
			(net "IO_EXP10_A1")
			(options
				(clearance outline)
				(anchor circle)
			)
			(primitives
				(gr_poly
					(pts
						(arc
							(start -0.1778 -0.2794)
							(mid -0.249642 -0.249642)
							(end -0.2794 -0.1778)
						)
						(arc
							(start -0.2794 0.1778)
							(mid -0.249642 0.249642)
							(end -0.1778 0.2794)
						)
						(arc
							(start 0.1778 0.2794)
							(mid 0.249642 0.249642)
							(end 0.2794 0.1778)
						)
						(arc
							(start 0.2794 -0.1778)
							(mid 0.249642 -0.249642)
							(end 0.1778 -0.2794)
						)
					)
					(width 0)
					(fill yes)
				)
			)
		)
		(pad "2" smd custom
			(at 0 0.4445 270)
			(size 0.1397 0.1397)
			(layers "F.Cu" "F.Mask" "F.Paste")
			(net "GND")
			(options
				(clearance outline)
				(anchor circle)
			)
			(primitives
				(gr_poly
					(pts
						(arc
							(start -0.1778 -0.2794)
							(mid -0.249642 -0.249642)
							(end -0.2794 -0.1778)
						)
						(arc
							(start -0.2794 0.1778)
							(mid -0.249642 0.249642)
							(end -0.1778 0.2794)
						)
						(arc
							(start 0.1778 0.2794)
							(mid 0.249642 0.249642)
							(end 0.2794 0.1778)
						)
						(arc
							(start 0.2794 -0.1778)
							(mid 0.249642 -0.249642)
							(end 0.1778 -0.2794)
						)
					)
					(width 0)
					(fill yes)
				)
			)
		)
	)
	(footprint ""
		(layer "F.Cu")
		(at 368.354102 -292.016942)
		(property "Reference" "Q44"
			(at 0 0 0)
			(layer "F.SilkS")
			(hide yes)
			(effects
				(font
					(size 1.27 1.27)
				)
			)
		)
		(property "Value" "AO4407AL-GP"
			(at -3.707384 -1.5367 0)
			(unlocked yes)
			(layer "F.Fab")
			(hide yes)
			(effects
				(font
					(size 1.016 1.016)
					(thickness 0.1524)
				)
			)
		)
		(property "Device Type" "SOIC8H69"
			(at -3.707384 -3.0607 0)
			(unlocked yes)
			(layer "F.Fab")
			(hide yes)
			(effects
				(font
					(size 1.016 1.016)
					(thickness 0.1524)
				)
			)
		)
		(duplicate_pad_numbers_are_jumpers no)
		(fp_line
			(start -2.7432 -1.4224)
			(end -2.7432 1.4224)
			(stroke
				(width 0.1524)
				(type default)
			)
			(layer "F.SilkS")
		)
		(fp_line
			(start -2.7432 1.4224)
			(end -2.6416 1.4224)
			(stroke
				(width 0.1524)
				(type default)
			)
			(layer "F.SilkS")
		)
		(fp_line
			(start -2.7432 1.4224)
			(end 2.1336 1.4224)
			(stroke
				(width 0.1524)
				(type default)
			)
			(layer "F.SilkS")
		)
		(fp_line
			(start -2.7178 -0.508)
			(end -2.1844 -0.0508)
			(stroke
				(width 0.1524)
				(type default)
			)
			(layer "F.SilkS")
		)
		(fp_line
			(start -2.6289 3.4417)
			(end -2.6289 1.4732)
			(stroke
				(width 0.381)
				(type default)
			)
			(layer "F.SilkS")
		)
		(fp_line
			(start -2.1844 -0.0508)
			(end -2.7178 0.508)
			(stroke
				(width 0.1524)
				(type default)
			)
			(layer "F.SilkS")
		)
		(fp_line
			(start 2.1336 -1.4224)
			(end -2.7432 -1.4224)
			(stroke
				(width 0.1524)
				(type default)
			)
			(layer "F.SilkS")
		)
		(fp_line
			(start 2.1336 1.4224)
			(end 2.1336 -1.4224)
			(stroke
				(width 0.1524)
				(type default)
			)
			(layer "F.SilkS")
		)
		(fp_poly
			(pts
				(xy -2.2098 -1.4224) (xy -2.2098 1.4224) (xy 2.2098 1.4224) (xy 2.2098 -1.4224)
			)
			(stroke
				(width 0)
				(type default)
			)
			(fill yes)
			(layer "F.SilkS")
		)
		(fp_rect
			(start -2.450084 2.999994)
			(end 2.450084 -2.999994)
			(stroke
				(width 0)
				(type default)
			)
			(fill no)
			(layer "F.CrtYd")
		)
		(fp_poly
			(pts
				(xy -2.8194 3.6322) (xy -2.8194 -3.6322) (xy 2.8194 -3.6322) (xy 2.8194 1.18364) (xy 2.450084 1.18364)
				(xy 2.450084 -2.999994) (xy -2.450084 -2.999994) (xy -2.450084 2.999994) (xy 2.450084 2.999994)
				(xy 2.450084 1.18618) (xy 2.8194 1.18618) (xy 2.8194 3.6322)
			)
			(stroke
				(width 0)
				(type default)
			)
			(fill no)
			(layer "F.CrtYd")
		)
		(fp_rect
			(start -2.8194 3.6322)
			(end 2.8194 -3.6322)
			(stroke
				(width 0)
				(type default)
			)
			(fill no)
			(layer "F.Fab")
		)
		(pad "1" smd rect
			(at -1.905 2.54)
			(size 0.635 1.651)
			(layers "F.Cu" "F.Mask" "F.Paste")
			(net "P12V_A")
		)
		(pad "2" smd rect
			(at -0.635 2.54)
			(size 0.635 1.651)
			(layers "F.Cu" "F.Mask" "F.Paste")
			(net "P12V_A")
		)
		(pad "3" smd rect
			(at 0.635 2.54)
			(size 0.635 1.651)
			(layers "F.Cu" "F.Mask" "F.Paste")
			(net "P12V_A")
		)
		(pad "4" smd rect
			(at 1.905 2.54)
			(size 0.635 1.651)
			(layers "F.Cu" "F.Mask" "F.Paste")
			(net "SW_HDD_N7")
		)
		(pad "5" smd rect
			(at 1.905 -2.54)
			(size 0.635 1.651)
			(layers "F.Cu" "F.Mask" "F.Paste")
			(net "P12V_HDD7")
		)
		(pad "6" smd rect
			(at 0.635 -2.54)
			(size 0.635 1.651)
			(layers "F.Cu" "F.Mask" "F.Paste")
			(net "P12V_HDD7")
		)
		(pad "7" smd rect
			(at -0.635 -2.54)
			(size 0.635 1.651)
			(layers "F.Cu" "F.Mask" "F.Paste")
			(net "P12V_HDD7")
		)
		(pad "8" smd rect
			(at -1.905 -2.54)
			(size 0.635 1.651)
			(layers "F.Cu" "F.Mask" "F.Paste")
			(net "P12V_HDD7")
		)
	)
	(footprint ""
		(layer "F.Cu")
		(at 162.118802 -127.703072 180)
		(property "Reference" "Q244"
			(at 0 0 180)
			(layer "F.SilkS")
			(hide yes)
			(effects
				(font
					(size 1.27 1.27)
				)
			)
		)
		(property "Value" "2N7002K-2-GP"
			(at 0.127 -8.9662 180)
			(unlocked yes)
			(layer "F.Fab")
			(hide yes)
			(effects
				(font
					(size 1.016 1.016)
					(thickness 0.1524)
				)
			)
		)
		(property "Device Type" "SOT23DGS2D4H44"
			(at 0.127 -10.4902 180)
			(unlocked yes)
			(layer "F.Fab")
			(hide yes)
			(effects
				(font
					(size 1.016 1.016)
					(thickness 0.1524)
				)
			)
		)
		(duplicate_pad_numbers_are_jumpers no)
		(fp_line
			(start 1.651 1.778)
			(end 1.651 -1.778)
			(stroke
				(width 0.1524)
				(type default)
			)
			(layer "F.SilkS")
		)
		(fp_line
			(start 1.651 -1.778)
			(end -1.651 -1.778)
			(stroke
				(width 0.1524)
				(type default)
			)
			(layer "F.SilkS")
		)
		(fp_line
			(start -1.651 1.778)
			(end 1.651 1.778)
			(stroke
				(width 0.1524)
				(type default)
			)
			(layer "F.SilkS")
		)
		(fp_line
			(start -1.651 -1.778)
			(end -1.651 1.778)
			(stroke
				(width 0.1524)
				(type default)
			)
			(layer "F.SilkS")
		)
		(fp_poly
			(pts
				(xy -1.778 1.8796) (xy -1.778 -1.8796) (xy 1.778 -1.8796) (xy 1.778 1.8796)
			)
			(stroke
				(width 0)
				(type default)
			)
			(fill no)
			(layer "F.CrtYd")
		)
		(fp_poly
			(pts
				(xy -1.778 1.8796) (xy -1.778 -1.8796) (xy 1.778 -1.8796) (xy 1.778 1.8796)
			)
			(stroke
				(width 0)
				(type default)
			)
			(fill no)
			(layer "F.Fab")
		)
		(pad "D" smd custom
			(at 0 -0.9525 180)
			(size 0.1905 0.1905)
			(layers "F.Cu" "F.Mask" "F.Paste")
			(net "FLT_HDD17_N")
			(options
				(clearance outline)
				(anchor circle)
			)
			(primitives
				(gr_poly
					(pts
						(arc
							(start -0.1778 0.5715)
							(mid -0.321484 0.511984)
							(end -0.381 0.3683)
						)
						(arc
							(start -0.381 -0.3683)
							(mid -0.321484 -0.511984)
							(end -0.1778 -0.5715)
						)
						(arc
							(start 0.1778 -0.5715)
							(mid 0.321484 -0.511984)
							(end 0.381 -0.3683)
						)
						(arc
							(start 0.381 0.3683)
							(mid 0.321484 0.511984)
							(end 0.1778 0.5715)
						)
					)
					(width 0)
					(fill yes)
				)
			)
		)
		(pad "G" smd custom
			(at -0.98425 0.9525 180)
			(size 0.1905 0.1905)
			(layers "F.Cu" "F.Mask" "F.Paste")
			(net "DRIVE_A_17_FLT_LED")
			(options
				(clearance outline)
				(anchor circle)
			)
			(primitives
				(gr_poly
					(pts
						(arc
							(start -0.1778 0.5715)
							(mid -0.321484 0.511984)
							(end -0.381 0.3683)
						)
						(arc
							(start -0.381 -0.3683)
							(mid -0.321484 -0.511984)
							(end -0.1778 -0.5715)
						)
						(arc
							(start 0.1778 -0.5715)
							(mid 0.321484 -0.511984)
							(end 0.381 -0.3683)
						)
						(arc
							(start 0.381 0.3683)
							(mid 0.321484 0.511984)
							(end 0.1778 0.5715)
						)
					)
					(width 0)
					(fill yes)
				)
			)
		)
		(pad "S" smd custom
			(at 0.98425 0.9525 180)
			(size 0.1905 0.1905)
			(layers "F.Cu" "F.Mask" "F.Paste")
			(net "GND")
			(options
				(clearance outline)
				(anchor circle)
			)
			(primitives
				(gr_poly
					(pts
						(arc
							(start -0.1778 0.5715)
							(mid -0.321484 0.511984)
							(end -0.381 0.3683)
						)
						(arc
							(start -0.381 -0.3683)
							(mid -0.321484 -0.511984)
							(end -0.1778 -0.5715)
						)
						(arc
							(start 0.1778 -0.5715)
							(mid 0.321484 -0.511984)
							(end 0.381 -0.3683)
						)
						(arc
							(start 0.381 0.3683)
							(mid 0.321484 0.511984)
							(end 0.1778 0.5715)
						)
					)
					(width 0)
					(fill yes)
				)
			)
		)
	)
	(footprint ""
		(layer "F.Cu")
		(at 477.739202 -273.940016 90)
		(property "Reference" "VIA6"
			(at 0 0 90)
			(layer "F.SilkS")
			(hide yes)
			(effects
				(font
					(size 1.27 1.27)
				)
			)
		)
		(property "Value" "100OHM-8L-1D6MM-L18L16-GP"
			(at -3.7211 -4.5085 90)
			(unlocked yes)
			(layer "F.Fab")
			(hide yes)
			(effects
				(font
					(size 1.016 1.016)
					(thickness 0.1524)
				)
			)
		)
		(property "Device Type" "VIA-PCIE-4P-394076"
			(at -3.7211 -6.0325 90)
			(unlocked yes)
			(layer "F.Fab")
			(hide yes)
			(effects
				(font
					(size 1.016 1.016)
					(thickness 0.1524)
				)
			)
		)
		(duplicate_pad_numbers_are_jumpers no)
		(fp_rect
			(start -1.9685 0.381)
			(end 1.9685 -0.381)
			(stroke
				(width 0)
				(type default)
			)
			(fill no)
			(layer "F.CrtYd")
		)
		(fp_rect
			(start -1.9685 0.381)
			(end 1.9685 -0.381)
			(stroke
				(width 0)
				(type default)
			)
			(fill no)
			(layer "F.Fab")
		)
		(pad "1" thru_hole circle
			(at -1.5875 0 90)
			(size 0.508 0.508)
			(drill 0.254)
			(layers "*.Cu" "*.Mask")
			(remove_unused_layers no)
			(net "GND")
			(clearance 0.127)
			(thermal_gap 0.127)
		)
		(pad "2" thru_hole circle
			(at -0.5715 0 90)
			(size 0.508 0.508)
			(drill 0.254)
			(layers "*.Cu" "*.Mask")
			(remove_unused_layers no)
			(net "PHY_SCC_A_TO_DRV_A_11_DP")
			(clearance 0.127)
			(thermal_gap 0.127)
		)
		(pad "3" thru_hole circle
			(at 0.5715 0 90)
			(size 0.508 0.508)
			(drill 0.254)
			(layers "*.Cu" "*.Mask")
			(remove_unused_layers no)
			(net "PHY_SCC_A_TO_DRV_A_11_DN")
			(clearance 0.127)
			(thermal_gap 0.127)
		)
		(pad "4" thru_hole circle
			(at 1.5875 0 90)
			(size 0.508 0.508)
			(drill 0.254)
			(layers "*.Cu" "*.Mask")
			(remove_unused_layers no)
			(net "GND")
			(clearance 0.127)
			(thermal_gap 0.127)
		)
	)
	(footprint ""
		(layer "F.Cu")
		(at 22.996398 -274.871942 -90)
		(property "Reference" "R968"
			(at 0 0 270)
			(layer "F.SilkS")
			(hide yes)
			(effects
				(font
					(size 1.27 1.27)
				)
			)
		)
		(property "Value" "0R2J-2-GP"
			(at 0.064008 -3.993896 270)
			(unlocked yes)
			(layer "F.Fab")
			(hide yes)
			(effects
				(font
					(size 1.016 1.016)
					(thickness 0.1524)
				)
			)
		)
		(property "Device Type" "R402H16"
			(at 0.064008 -5.517896 270)
			(unlocked yes)
			(layer "F.Fab")
			(hide yes)
			(effects
				(font
					(size 1.016 1.016)
					(thickness 0.1524)
				)
			)
		)
		(duplicate_pad_numbers_are_jumpers no)
		(fp_line
			(start -0.508 -0.9398)
			(end -0.508 0.9398)
			(stroke
				(width 0.1524)
				(type default)
			)
			(layer "F.SilkS")
		)
		(fp_line
			(start 0.508 -0.9398)
			(end -0.508 -0.9398)
			(stroke
				(width 0.1524)
				(type default)
			)
			(layer "F.SilkS")
		)
		(fp_rect
			(start -0.508 0.9398)
			(end 0.508 -0.9398)
			(stroke
				(width 0)
				(type default)
			)
			(fill no)
			(layer "F.CrtYd")
		)
		(fp_rect
			(start -0.508 0.9398)
			(end 0.508 -0.9398)
			(stroke
				(width 0)
				(type default)
			)
			(fill no)
			(layer "F.Fab")
		)
		(pad "1" smd custom
			(at 0 -0.4445 270)
			(size 0.1397 0.1397)
			(layers "F.Cu" "F.Mask" "F.Paste")
			(net "DRIVE_A_0_PWR")
			(options
				(clearance outline)
				(anchor circle)
			)
			(primitives
				(gr_poly
					(pts
						(arc
							(start -0.1778 -0.2794)
							(mid -0.249642 -0.249642)
							(end -0.2794 -0.1778)
						)
						(arc
							(start -0.2794 0.1778)
							(mid -0.249642 0.249642)
							(end -0.1778 0.2794)
						)
						(arc
							(start 0.1778 0.2794)
							(mid 0.249642 0.249642)
							(end 0.2794 0.1778)
						)
						(arc
							(start 0.2794 -0.1778)
							(mid 0.249642 -0.249642)
							(end 0.1778 -0.2794)
						)
					)
					(width 0)
					(fill yes)
				)
			)
		)
		(pad "2" smd custom
			(at 0 0.4445 270)
			(size 0.1397 0.1397)
			(layers "F.Cu" "F.Mask" "F.Paste")
			(net "SW_PWR_R_HDD0")
			(options
				(clearance outline)
				(anchor circle)
			)
			(primitives
				(gr_poly
					(pts
						(arc
							(start -0.1778 -0.2794)
							(mid -0.249642 -0.249642)
							(end -0.2794 -0.1778)
						)
						(arc
							(start -0.2794 0.1778)
							(mid -0.249642 0.249642)
							(end -0.1778 0.2794)
						)
						(arc
							(start 0.1778 0.2794)
							(mid 0.249642 0.249642)
							(end 0.2794 0.1778)
						)
						(arc
							(start 0.2794 -0.1778)
							(mid 0.249642 -0.249642)
							(end 0.1778 -0.2794)
						)
					)
					(width 0)
					(fill yes)
				)
			)
		)
	)
	(footprint ""
		(layer "F.Cu")
		(at 109.365796 -179.683918 -90)
		(property "Reference" "C240"
			(at 0 0 270)
			(layer "F.SilkS")
			(hide yes)
			(effects
				(font
					(size 1.27 1.27)
				)
			)
		)
		(property "Value" "SC4D7U25V5KX-1-GP"
			(at -0.0762 -6.1214 270)
			(unlocked yes)
			(layer "F.Fab")
			(hide yes)
			(effects
				(font
					(size 1.016 1.016)
					(thickness 0.1524)
				)
			)
		)
		(property "Device Type" "C805H58"
			(at -0.0762 -8.1534 270)
			(unlocked yes)
			(layer "F.Fab")
			(hide yes)
			(effects
				(font
					(size 1.016 1.016)
					(thickness 0.1524)
				)
			)
		)
		(duplicate_pad_numbers_are_jumpers no)
		(fp_line
			(start 0.635 0)
			(end -0.635 0)
			(stroke
				(width 0.508)
				(type default)
			)
			(layer "F.SilkS")
		)
		(fp_rect
			(start -0.9652 1.778)
			(end 0.9652 -1.778)
			(stroke
				(width 0)
				(type default)
			)
			(fill no)
			(layer "F.CrtYd")
		)
		(fp_poly
			(pts
				(xy -0.9652 -1.778) (xy 0.9652 -1.778) (xy 0.9652 1.778) (xy -0.9652 1.778)
			)
			(stroke
				(width 0)
				(type default)
			)
			(fill no)
			(layer "F.Fab")
		)
		(pad "1" smd rect
			(at 0 -0.9652 270)
			(size 1.397 1.143)
			(layers "F.Cu" "F.Mask" "F.Paste")
			(net "P12V_HDD15")
		)
		(pad "2" smd rect
			(at 0 0.9652 270)
			(size 1.397 1.143)
			(layers "F.Cu" "F.Mask" "F.Paste")
			(net "GND")
		)
	)
	(footprint ""
		(layer "F.Cu")
		(at 86.832948 -62.270894)
		(property "Reference" "R727"
			(at 0 0 0)
			(layer "F.SilkS")
			(hide yes)
			(effects
				(font
					(size 1.27 1.27)
				)
			)
		)
		(property "Value" "2R6F-GP"
			(at -0.0508 -4.8514 0)
			(unlocked yes)
			(layer "F.Fab")
			(hide yes)
			(effects
				(font
					(size 1.016 1.016)
					(thickness 0.1524)
				)
			)
		)
		(property "Device Type" "R1206H26"
			(at 0 -6.3754 0)
			(unlocked yes)
			(layer "F.Fab")
			(hide yes)
			(effects
				(font
					(size 1.016 1.016)
					(thickness 0.1524)
				)
			)
		)
		(duplicate_pad_numbers_are_jumpers no)
		(fp_line
			(start -1.016 -2.2352)
			(end 1.016 -2.2352)
			(stroke
				(width 0.1524)
				(type default)
			)
			(layer "F.SilkS")
		)
		(fp_line
			(start -1.016 2.2352)
			(end -1.016 -2.2352)
			(stroke
				(width 0.1524)
				(type default)
			)
			(layer "F.SilkS")
		)
		(fp_line
			(start 1.016 -2.2352)
			(end 1.016 2.2352)
			(stroke
				(width 0.1524)
				(type default)
			)
			(layer "F.SilkS")
		)
		(fp_line
			(start 1.016 2.2352)
			(end -1.016 2.2352)
			(stroke
				(width 0.1524)
				(type default)
			)
			(layer "F.SilkS")
		)
		(fp_rect
			(start -1.0922 2.3114)
			(end 1.0922 -2.3114)
			(stroke
				(width 0)
				(type default)
			)
			(fill no)
			(layer "F.CrtYd")
		)
		(fp_poly
			(pts
				(xy -1.0922 -2.3114) (xy 1.0922 -2.3114) (xy 1.0922 2.3114) (xy -1.0922 2.3114)
			)
			(stroke
				(width 0)
				(type default)
			)
			(fill no)
			(layer "F.Fab")
		)
		(pad "1" smd rect
			(at 0 -1.397)
			(size 1.651 1.27)
			(layers "F.Cu" "F.Mask" "F.Paste")
			(net "P5V_HDD26")
		)
		(pad "2" smd rect
			(at 0 1.397)
			(size 1.651 1.27)
			(layers "F.Cu" "F.Mask" "F.Paste")
			(net "5V_PRE_26")
		)
	)
	(footprint ""
		(layer "F.Cu")
		(at 256.921 -236.347 -90)
		(property "Reference" "R129"
			(at 0 0 270)
			(layer "F.SilkS")
			(hide yes)
			(effects
				(font
					(size 1.27 1.27)
				)
			)
		)
		(property "Value" "100KR2F-L1-GP"
			(at 0.064008 -3.993896 270)
			(unlocked yes)
			(layer "F.Fab")
			(hide yes)
			(effects
				(font
					(size 1.016 1.016)
					(thickness 0.1524)
				)
			)
		)
		(property "Device Type" "R402H16"
			(at 0.064008 -5.517896 270)
			(unlocked yes)
			(layer "F.Fab")
			(hide yes)
			(effects
				(font
					(size 1.016 1.016)
					(thickness 0.1524)
				)
			)
		)
		(duplicate_pad_numbers_are_jumpers no)
		(fp_line
			(start -0.508 -0.9398)
			(end -0.508 0.9398)
			(stroke
				(width 0.1524)
				(type default)
			)
			(layer "F.SilkS")
		)
		(fp_line
			(start 0.508 -0.9398)
			(end -0.508 -0.9398)
			(stroke
				(width 0.1524)
				(type default)
			)
			(layer "F.SilkS")
		)
		(fp_rect
			(start -0.508 0.9398)
			(end 0.508 -0.9398)
			(stroke
				(width 0)
				(type default)
			)
			(fill no)
			(layer "F.CrtYd")
		)
		(fp_rect
			(start -0.508 0.9398)
			(end 0.508 -0.9398)
			(stroke
				(width 0)
				(type default)
			)
			(fill no)
			(layer "F.Fab")
		)
		(pad "1" smd custom
			(at 0 -0.4445 270)
			(size 0.1397 0.1397)
			(layers "F.Cu" "F.Mask" "F.Paste")
			(net "GPIO_VCC_U9")
			(options
				(clearance outline)
				(anchor circle)
			)
			(primitives
				(gr_poly
					(pts
						(arc
							(start -0.1778 -0.2794)
							(mid -0.249642 -0.249642)
							(end -0.2794 -0.1778)
						)
						(arc
							(start -0.2794 0.1778)
							(mid -0.249642 0.249642)
							(end -0.1778 0.2794)
						)
						(arc
							(start 0.1778 0.2794)
							(mid 0.249642 0.249642)
							(end 0.2794 0.1778)
						)
						(arc
							(start 0.2794 -0.1778)
							(mid 0.249642 -0.249642)
							(end 0.1778 -0.2794)
						)
					)
					(width 0)
					(fill yes)
				)
			)
		)
		(pad "2" smd custom
			(at 0 0.4445 270)
			(size 0.1397 0.1397)
			(layers "F.Cu" "F.Mask" "F.Paste")
			(net "GND")
			(options
				(clearance outline)
				(anchor circle)
			)
			(primitives
				(gr_poly
					(pts
						(arc
							(start -0.1778 -0.2794)
							(mid -0.249642 -0.249642)
							(end -0.2794 -0.1778)
						)
						(arc
							(start -0.2794 0.1778)
							(mid -0.249642 0.249642)
							(end -0.1778 0.2794)
						)
						(arc
							(start 0.1778 0.2794)
							(mid 0.249642 0.249642)
							(end 0.2794 0.1778)
						)
						(arc
							(start 0.2794 -0.1778)
							(mid 0.249642 -0.249642)
							(end 0.1778 -0.2794)
						)
					)
					(width 0)
					(fill yes)
				)
			)
		)
	)
	(footprint ""
		(layer "F.Cu")
		(at 475.784926 -170.285918 180)
		(property "Reference" "Q137"
			(at 0 0 180)
			(layer "F.SilkS")
			(hide yes)
			(effects
				(font
					(size 1.27 1.27)
				)
			)
		)
		(property "Value" "AO4406AL-GP"
			(at -3.707384 -1.5367 180)
			(unlocked yes)
			(layer "F.Fab")
			(hide yes)
			(effects
				(font
					(size 1.016 1.016)
					(thickness 0.1524)
				)
			)
		)
		(property "Device Type" "SOIC8H69"
			(at -3.707384 -3.0607 180)
			(unlocked yes)
			(layer "F.Fab")
			(hide yes)
			(effects
				(font
					(size 1.016 1.016)
					(thickness 0.1524)
				)
			)
		)
		(duplicate_pad_numbers_are_jumpers no)
		(fp_line
			(start 2.1336 1.4224)
			(end 2.1336 -1.4224)
			(stroke
				(width 0.1524)
				(type default)
			)
			(layer "F.SilkS")
		)
		(fp_line
			(start 2.1336 -1.4224)
			(end -2.7432 -1.4224)
			(stroke
				(width 0.1524)
				(type default)
			)
			(layer "F.SilkS")
		)
		(fp_line
			(start -2.1844 -0.0508)
			(end -2.7178 0.508)
			(stroke
				(width 0.1524)
				(type default)
			)
			(layer "F.SilkS")
		)
		(fp_line
			(start -2.6289 3.4417)
			(end -2.6289 1.4732)
			(stroke
				(width 0.381)
				(type default)
			)
			(layer "F.SilkS")
		)
		(fp_line
			(start -2.7178 -0.508)
			(end -2.1844 -0.0508)
			(stroke
				(width 0.1524)
				(type default)
			)
			(layer "F.SilkS")
		)
		(fp_line
			(start -2.7432 1.4224)
			(end 2.1336 1.4224)
			(stroke
				(width 0.1524)
				(type default)
			)
			(layer "F.SilkS")
		)
		(fp_line
			(start -2.7432 1.4224)
			(end -2.6416 1.4224)
			(stroke
				(width 0.1524)
				(type default)
			)
			(layer "F.SilkS")
		)
		(fp_line
			(start -2.7432 -1.4224)
			(end -2.7432 1.4224)
			(stroke
				(width 0.1524)
				(type default)
			)
			(layer "F.SilkS")
		)
		(fp_poly
			(pts
				(xy -2.2098 -1.4224) (xy -2.2098 1.4224) (xy 2.2098 1.4224) (xy 2.2098 -1.4224)
			)
			(stroke
				(width 0)
				(type default)
			)
			(fill yes)
			(layer "F.SilkS")
		)
		(fp_rect
			(start -2.450084 2.999994)
			(end 2.450084 -2.999994)
			(stroke
				(width 0)
				(type default)
			)
			(fill no)
			(layer "F.CrtYd")
		)
		(fp_poly
			(pts
				(xy -2.8194 3.6322) (xy -2.8194 -3.6322) (xy 2.8194 -3.6322) (xy 2.8194 1.18364) (xy 2.450084 1.18364)
				(xy 2.450084 -2.999994) (xy -2.450084 -2.999994) (xy -2.450084 2.999994) (xy 2.450084 2.999994)
				(xy 2.450084 1.18618) (xy 2.8194 1.18618) (xy 2.8194 3.6322)
			)
			(stroke
				(width 0)
				(type default)
			)
			(fill no)
			(layer "F.CrtYd")
		)
		(fp_rect
			(start -2.8194 3.6322)
			(end 2.8194 -3.6322)
			(stroke
				(width 0)
				(type default)
			)
			(fill no)
			(layer "F.Fab")
		)
		(pad "1" smd rect
			(at -1.905 2.54 180)
			(size 0.635 1.651)
			(layers "F.Cu" "F.Mask" "F.Paste")
			(net "P5V_HDD23")
		)
		(pad "2" smd rect
			(at -0.635 2.54 180)
			(size 0.635 1.651)
			(layers "F.Cu" "F.Mask" "F.Paste")
			(net "P5V_HDD23")
		)
		(pad "3" smd rect
			(at 0.635 2.54 180)
			(size 0.635 1.651)
			(layers "F.Cu" "F.Mask" "F.Paste")
			(net "P5V_HDD23")
		)
		(pad "4" smd rect
			(at 1.905 2.54 180)
			(size 0.635 1.651)
			(layers "F.Cu" "F.Mask" "F.Paste")
			(net "SW_HDD_P23")
		)
		(pad "5" smd rect
			(at 1.905 -2.54 180)
			(size 0.635 1.651)
			(layers "F.Cu" "F.Mask" "F.Paste")
			(net "P5V_A_4")
		)
		(pad "6" smd rect
			(at 0.635 -2.54 180)
			(size 0.635 1.651)
			(layers "F.Cu" "F.Mask" "F.Paste")
			(net "P5V_A_4")
		)
		(pad "7" smd rect
			(at -0.635 -2.54 180)
			(size 0.635 1.651)
			(layers "F.Cu" "F.Mask" "F.Paste")
			(net "P5V_A_4")
		)
		(pad "8" smd rect
			(at -1.905 -2.54 180)
			(size 0.635 1.651)
			(layers "F.Cu" "F.Mask" "F.Paste")
			(net "P5V_A_4")
		)
	)
	(footprint ""
		(layer "F.Cu")
		(at 253.9238 -290.195)
		(property "Reference" "R6"
			(at 0 0 0)
			(layer "F.SilkS")
			(hide yes)
			(effects
				(font
					(size 1.27 1.27)
				)
			)
		)
		(property "Value" "4K7R2F-GP"
			(at 0.064008 -3.993896 0)
			(unlocked yes)
			(layer "F.Fab")
			(hide yes)
			(effects
				(font
					(size 1.016 1.016)
					(thickness 0.1524)
				)
			)
		)
		(property "Device Type" "R402H16"
			(at 0.064008 -5.517896 0)
			(unlocked yes)
			(layer "F.Fab")
			(hide yes)
			(effects
				(font
					(size 1.016 1.016)
					(thickness 0.1524)
				)
			)
		)
		(duplicate_pad_numbers_are_jumpers no)
		(fp_line
			(start -0.508 -0.9398)
			(end -0.508 0.9398)
			(stroke
				(width 0.1524)
				(type default)
			)
			(layer "F.SilkS")
		)
		(fp_line
			(start 0.508 -0.9398)
			(end -0.508 -0.9398)
			(stroke
				(width 0.1524)
				(type default)
			)
			(layer "F.SilkS")
		)
		(fp_rect
			(start -0.508 0.9398)
			(end 0.508 -0.9398)
			(stroke
				(width 0)
				(type default)
			)
			(fill no)
			(layer "F.CrtYd")
		)
		(fp_rect
			(start -0.508 0.9398)
			(end 0.508 -0.9398)
			(stroke
				(width 0)
				(type default)
			)
			(fill no)
			(layer "F.Fab")
		)
		(pad "1" smd custom
			(at 0 -0.4445)
			(size 0.1397 0.1397)
			(layers "F.Cu" "F.Mask" "F.Paste")
			(net "EEPROM_A0")
			(options
				(clearance outline)
				(anchor circle)
			)
			(primitives
				(gr_poly
					(pts
						(arc
							(start -0.1778 -0.2794)
							(mid -0.249642 -0.249642)
							(end -0.2794 -0.1778)
						)
						(arc
							(start -0.2794 0.1778)
							(mid -0.249642 0.249642)
							(end -0.1778 0.2794)
						)
						(arc
							(start 0.1778 0.2794)
							(mid 0.249642 0.249642)
							(end 0.2794 0.1778)
						)
						(arc
							(start 0.2794 -0.1778)
							(mid 0.249642 -0.249642)
							(end 0.1778 -0.2794)
						)
					)
					(width 0)
					(fill yes)
				)
			)
		)
		(pad "2" smd custom
			(at 0 0.4445)
			(size 0.1397 0.1397)
			(layers "F.Cu" "F.Mask" "F.Paste")
			(net "GND")
			(options
				(clearance outline)
				(anchor circle)
			)
			(primitives
				(gr_poly
					(pts
						(arc
							(start -0.1778 -0.2794)
							(mid -0.249642 -0.249642)
							(end -0.2794 -0.1778)
						)
						(arc
							(start -0.2794 0.1778)
							(mid -0.249642 0.249642)
							(end -0.1778 0.2794)
						)
						(arc
							(start 0.1778 0.2794)
							(mid 0.249642 0.249642)
							(end 0.2794 0.1778)
						)
						(arc
							(start 0.2794 -0.1778)
							(mid 0.249642 -0.249642)
							(end 0.1778 -0.2794)
						)
					)
					(width 0)
					(fill yes)
				)
			)
		)
	)
	(footprint ""
		(layer "F.Cu")
		(at 481.249736 -120.499886)
		(property "Reference" ""
			(at 0 0 0)
			(layer "F.SilkS")
			(hide yes)
			(effects
				(font
					(size 1.27 1.27)
				)
			)
		)
		(property "Value" "*"
			(at -4.9911 1.5494 0)
			(unlocked yes)
			(layer "F.Fab")
			(hide yes)
			(effects
				(font
					(size 1.016 1.016)
					(thickness 0.1524)
				)
			)
		)
		(duplicate_pad_numbers_are_jumpers no)
		(fp_poly
			(pts
				(arc
					(start 4.064 0)
					(mid -4.064 0)
					(end 4.064 0)
				)
			)
			(stroke
				(width 0)
				(type default)
			)
			(fill no)
			(layer "B.CrtYd")
		)
		(fp_poly
			(pts
				(arc
					(start 4.064 0)
					(mid -4.064 0)
					(end 4.064 0)
				)
			)
			(stroke
				(width 0)
				(type default)
			)
			(fill no)
			(layer "F.CrtYd")
		)
		(fp_poly
			(pts
				(arc
					(start 4.064 0)
					(mid -4.064 0)
					(end 4.064 0)
				)
			)
			(stroke
				(width 0)
				(type default)
			)
			(fill no)
			(layer "B.Fab")
		)
		(fp_poly
			(pts
				(arc
					(start 4.064 0)
					(mid -4.064 0)
					(end 4.064 0)
				)
			)
			(stroke
				(width 0)
				(type default)
			)
			(fill no)
			(layer "F.Fab")
		)
		(pad "1" thru_hole circle
			(at 0 0)
			(size 7.5184 7.5184)
			(drill oval 6.223 4.2164)
			(layers "*.Cu" "*.Mask")
			(remove_unused_layers no)
			(net "Net_59")
			(clearance -1.143)
			(thermal_gap 0.1524)
			(padstack
				(mode front_inner_back)
				(layer "Inner"
					(shape oval)
					(size 4.9276 6.9342)
					(clearance 0.1524)
				)
				(layer "B.Cu"
					(shape circle)
					(size 7.5184 7.5184)
					(clearance -1.143)
				)
			)
		)
		(zone
			(layers "F.Cu" "B.Cu" "In1.Cu" "In2.Cu" "In3.Cu" "In4.Cu" "In5.Cu" "In6.Cu"
				"In7.Cu" "In8.Cu" "In9.Cu" "In10.Cu"
			)
			(hatch none 0.5)
			(connect_pads
				(clearance 0)
			)
			(min_thickness 0.25)
			(keepout
				(tracks not_allowed)
				(vias allowed)
				(pads allowed)
				(copperpour not_allowed)
				(footprints allowed)
			)
			(placement
				(enabled no)
				(sheetname "")
			)
			(fill
				(thermal_gap 0.5)
				(thermal_bridge_width 0.5)
				(island_removal_mode 0)
			)
			(polygon
				(pts
					(arc
						(start 485.008936 -120.499886)
						(mid 477.490536 -120.499886)
						(end 485.008936 -120.499886)
					)
				)
			)
		)
	)
	(footprint ""
		(layer "F.Cu")
		(at 471.924126 -167.085518 90)
		(property "Reference" "R666"
			(at 0 0 90)
			(layer "F.SilkS")
			(hide yes)
			(effects
				(font
					(size 1.27 1.27)
				)
			)
		)
		(property "Value" "4K7R2J-2-GP"
			(at 0.064008 -3.993896 90)
			(unlocked yes)
			(layer "F.Fab")
			(hide yes)
			(effects
				(font
					(size 1.016 1.016)
					(thickness 0.1524)
				)
			)
		)
		(property "Device Type" "R402H16"
			(at 0.064008 -5.517896 90)
			(unlocked yes)
			(layer "F.Fab")
			(hide yes)
			(effects
				(font
					(size 1.016 1.016)
					(thickness 0.1524)
				)
			)
		)
		(duplicate_pad_numbers_are_jumpers no)
		(fp_line
			(start 0.508 -0.9398)
			(end -0.508 -0.9398)
			(stroke
				(width 0.1524)
				(type default)
			)
			(layer "F.SilkS")
		)
		(fp_line
			(start -0.508 -0.9398)
			(end -0.508 0.9398)
			(stroke
				(width 0.1524)
				(type default)
			)
			(layer "F.SilkS")
		)
		(fp_rect
			(start -0.508 0.9398)
			(end 0.508 -0.9398)
			(stroke
				(width 0)
				(type default)
			)
			(fill no)
			(layer "F.CrtYd")
		)
		(fp_rect
			(start -0.508 0.9398)
			(end 0.508 -0.9398)
			(stroke
				(width 0)
				(type default)
			)
			(fill no)
			(layer "F.Fab")
		)
		(pad "1" smd custom
			(at 0 -0.4445 90)
			(size 0.1397 0.1397)
			(layers "F.Cu" "F.Mask" "F.Paste")
			(net "P12V_A")
			(options
				(clearance outline)
				(anchor circle)
			)
			(primitives
				(gr_poly
					(pts
						(arc
							(start -0.1778 -0.2794)
							(mid -0.249642 -0.249642)
							(end -0.2794 -0.1778)
						)
						(arc
							(start -0.2794 0.1778)
							(mid -0.249642 0.249642)
							(end -0.1778 0.2794)
						)
						(arc
							(start 0.1778 0.2794)
							(mid 0.249642 0.249642)
							(end 0.2794 0.1778)
						)
						(arc
							(start 0.2794 -0.1778)
							(mid 0.249642 -0.249642)
							(end 0.1778 -0.2794)
						)
					)
					(width 0)
					(fill yes)
				)
			)
		)
		(pad "2" smd custom
			(at 0 0.4445 90)
			(size 0.1397 0.1397)
			(layers "F.Cu" "F.Mask" "F.Paste")
			(net "SW_HDD_P23")
			(options
				(clearance outline)
				(anchor circle)
			)
			(primitives
				(gr_poly
					(pts
						(arc
							(start -0.1778 -0.2794)
							(mid -0.249642 -0.249642)
							(end -0.2794 -0.1778)
						)
						(arc
							(start -0.2794 0.1778)
							(mid -0.249642 0.249642)
							(end -0.1778 0.2794)
						)
						(arc
							(start 0.1778 0.2794)
							(mid 0.249642 0.249642)
							(end 0.2794 0.1778)
						)
						(arc
							(start 0.2794 -0.1778)
							(mid 0.249642 -0.249642)
							(end 0.1778 -0.2794)
						)
					)
					(width 0)
					(fill yes)
				)
			)
		)
	)
	(footprint ""
		(layer "F.Cu")
		(at 256.9718 -237.49 -90)
		(property "Reference" "C29"
			(at 0 0 270)
			(layer "F.SilkS")
			(hide yes)
			(effects
				(font
					(size 1.27 1.27)
				)
			)
		)
		(property "Value" "SC1U16V3KX-5GP"
			(at 0 -2.8194 270)
			(unlocked yes)
			(layer "F.Fab")
			(hide yes)
			(effects
				(font
					(size 1.016 1.016)
					(thickness 0.1524)
				)
			)
		)
		(property "Device Type" "C603H36"
			(at 0 -4.3434 270)
			(unlocked yes)
			(layer "F.Fab")
			(hide yes)
			(effects
				(font
					(size 1.016 1.016)
					(thickness 0.1524)
				)
			)
		)
		(duplicate_pad_numbers_are_jumpers no)
		(fp_line
			(start 0.508 0)
			(end -0.508 0)
			(stroke
				(width 0.2032)
				(type default)
			)
			(layer "F.SilkS")
		)
		(fp_rect
			(start -0.5842 1.3335)
			(end 0.5842 -1.3335)
			(stroke
				(width 0)
				(type default)
			)
			(fill no)
			(layer "F.CrtYd")
		)
		(fp_rect
			(start -0.5842 1.3335)
			(end 0.5842 -1.3335)
			(stroke
				(width 0)
				(type default)
			)
			(fill no)
			(layer "F.Fab")
		)
		(pad "1" smd custom
			(at 0 -0.762 270)
			(size 0.2159 0.2159)
			(layers "F.Cu" "F.Mask" "F.Paste")
			(net "GPIO_VCC_U9")
			(options
				(clearance outline)
				(anchor circle)
			)
			(primitives
				(gr_poly
					(pts
						(arc
							(start -0.3302 -0.4318)
							(mid -0.402042 -0.402042)
							(end -0.4318 -0.3302)
						)
						(arc
							(start -0.4318 0.3302)
							(mid -0.402042 0.402042)
							(end -0.3302 0.4318)
						)
						(arc
							(start 0.3302 0.4318)
							(mid 0.402042 0.402042)
							(end 0.4318 0.3302)
						)
						(arc
							(start 0.4318 -0.3302)
							(mid 0.402042 -0.402042)
							(end 0.3302 -0.4318)
						)
					)
					(width 0)
					(fill yes)
				)
			)
		)
		(pad "2" smd custom
			(at 0 0.762 270)
			(size 0.2159 0.2159)
			(layers "F.Cu" "F.Mask" "F.Paste")
			(net "GND")
			(options
				(clearance outline)
				(anchor circle)
			)
			(primitives
				(gr_poly
					(pts
						(arc
							(start -0.3302 -0.4318)
							(mid -0.402042 -0.402042)
							(end -0.4318 -0.3302)
						)
						(arc
							(start -0.4318 0.3302)
							(mid -0.402042 0.402042)
							(end -0.3302 0.4318)
						)
						(arc
							(start 0.3302 0.4318)
							(mid 0.402042 0.402042)
							(end 0.4318 0.3302)
						)
						(arc
							(start 0.4318 -0.3302)
							(mid 0.402042 -0.402042)
							(end 0.3302 -0.4318)
						)
					)
					(width 0)
					(fill yes)
				)
			)
		)
	)
	(footprint ""
		(layer "F.Cu")
		(at 409.144978 -127.254)
		(property "Reference" "R335"
			(at 0 0 0)
			(layer "F.SilkS")
			(hide yes)
			(effects
				(font
					(size 1.27 1.27)
				)
			)
		)
		(property "Value" "130R3F-GP"
			(at -0.0254 -2.5146 0)
			(unlocked yes)
			(layer "F.Fab")
			(hide yes)
			(effects
				(font
					(size 1.016 1.016)
					(thickness 0.1524)
				)
			)
		)
		(property "Device Type" "R603H22"
			(at -0.0254 -4.0386 0)
			(unlocked yes)
			(layer "F.Fab")
			(hide yes)
			(effects
				(font
					(size 1.016 1.016)
					(thickness 0.1524)
				)
			)
		)
		(duplicate_pad_numbers_are_jumpers no)
		(fp_line
			(start -0.4826 0)
			(end -0.2032 0)
			(stroke
				(width 0.2032)
				(type default)
			)
			(layer "F.SilkS")
		)
		(fp_line
			(start 0.2032 0)
			(end 0.4826 0)
			(stroke
				(width 0.2032)
				(type default)
			)
			(layer "F.SilkS")
		)
		(fp_rect
			(start -0.5842 1.3335)
			(end 0.5842 -1.3335)
			(stroke
				(width 0)
				(type default)
			)
			(fill no)
			(layer "F.CrtYd")
		)
		(fp_rect
			(start -0.5842 1.3335)
			(end 0.5842 -1.3335)
			(stroke
				(width 0)
				(type default)
			)
			(fill no)
			(layer "F.Fab")
		)
		(pad "1" smd custom
			(at 0 -0.762)
			(size 0.2159 0.2159)
			(layers "F.Cu" "F.Mask" "F.Paste")
			(net "P5V_A_4")
			(options
				(clearance outline)
				(anchor circle)
			)
			(primitives
				(gr_poly
					(pts
						(arc
							(start -0.3302 -0.4318)
							(mid -0.402042 -0.402042)
							(end -0.4318 -0.3302)
						)
						(arc
							(start -0.4318 0.3302)
							(mid -0.402042 0.402042)
							(end -0.3302 0.4318)
						)
						(arc
							(start 0.3302 0.4318)
							(mid 0.402042 0.402042)
							(end 0.4318 0.3302)
						)
						(arc
							(start 0.4318 -0.3302)
							(mid 0.402042 -0.402042)
							(end 0.3302 -0.4318)
						)
					)
					(width 0)
					(fill yes)
				)
			)
		)
		(pad "2" smd custom
			(at 0 0.762)
			(size 0.2159 0.2159)
			(layers "F.Cu" "F.Mask" "F.Paste")
			(net "FLT_HDD21")
			(options
				(clearance outline)
				(anchor circle)
			)
			(primitives
				(gr_poly
					(pts
						(arc
							(start -0.3302 -0.4318)
							(mid -0.402042 -0.402042)
							(end -0.4318 -0.3302)
						)
						(arc
							(start -0.4318 0.3302)
							(mid -0.402042 0.402042)
							(end -0.3302 0.4318)
						)
						(arc
							(start 0.3302 0.4318)
							(mid 0.402042 0.402042)
							(end 0.4318 0.3302)
						)
						(arc
							(start 0.4318 -0.3302)
							(mid 0.402042 -0.402042)
							(end 0.3302 -0.4318)
						)
					)
					(width 0)
					(fill yes)
				)
			)
		)
	)
	(footprint ""
		(layer "F.Cu")
		(at 274.955 -272.288)
		(property "Reference" "R118"
			(at 0 0 0)
			(layer "F.SilkS")
			(hide yes)
			(effects
				(font
					(size 1.27 1.27)
				)
			)
		)
		(property "Value" "4K7R2F-GP"
			(at 0.064008 -3.993896 0)
			(unlocked yes)
			(layer "F.Fab")
			(hide yes)
			(effects
				(font
					(size 1.016 1.016)
					(thickness 0.1524)
				)
			)
		)
		(property "Device Type" "R402H16"
			(at 0.064008 -5.517896 0)
			(unlocked yes)
			(layer "F.Fab")
			(hide yes)
			(effects
				(font
					(size 1.016 1.016)
					(thickness 0.1524)
				)
			)
		)
		(duplicate_pad_numbers_are_jumpers no)
		(fp_line
			(start -0.508 -0.9398)
			(end -0.508 0.9398)
			(stroke
				(width 0.1524)
				(type default)
			)
			(layer "F.SilkS")
		)
		(fp_line
			(start 0.508 -0.9398)
			(end -0.508 -0.9398)
			(stroke
				(width 0.1524)
				(type default)
			)
			(layer "F.SilkS")
		)
		(fp_rect
			(start -0.508 0.9398)
			(end 0.508 -0.9398)
			(stroke
				(width 0)
				(type default)
			)
			(fill no)
			(layer "F.CrtYd")
		)
		(fp_rect
			(start -0.508 0.9398)
			(end 0.508 -0.9398)
			(stroke
				(width 0)
				(type default)
			)
			(fill no)
			(layer "F.Fab")
		)
		(pad "1" smd custom
			(at 0 -0.4445)
			(size 0.1397 0.1397)
			(layers "F.Cu" "F.Mask" "F.Paste")
			(net "IO_EXP1_HDD_FAULT_A2")
			(options
				(clearance outline)
				(anchor circle)
			)
			(primitives
				(gr_poly
					(pts
						(arc
							(start -0.1778 -0.2794)
							(mid -0.249642 -0.249642)
							(end -0.2794 -0.1778)
						)
						(arc
							(start -0.2794 0.1778)
							(mid -0.249642 0.249642)
							(end -0.1778 0.2794)
						)
						(arc
							(start 0.1778 0.2794)
							(mid 0.249642 0.249642)
							(end 0.2794 0.1778)
						)
						(arc
							(start 0.2794 -0.1778)
							(mid 0.249642 -0.249642)
							(end 0.1778 -0.2794)
						)
					)
					(width 0)
					(fill yes)
				)
			)
		)
		(pad "2" smd custom
			(at 0 0.4445)
			(size 0.1397 0.1397)
			(layers "F.Cu" "F.Mask" "F.Paste")
			(net "GND")
			(options
				(clearance outline)
				(anchor circle)
			)
			(primitives
				(gr_poly
					(pts
						(arc
							(start -0.1778 -0.2794)
							(mid -0.249642 -0.249642)
							(end -0.2794 -0.1778)
						)
						(arc
							(start -0.2794 0.1778)
							(mid -0.249642 0.249642)
							(end -0.1778 0.2794)
						)
						(arc
							(start 0.1778 0.2794)
							(mid 0.249642 0.249642)
							(end 0.2794 0.1778)
						)
						(arc
							(start 0.2794 -0.1778)
							(mid 0.249642 -0.249642)
							(end 0.1778 -0.2794)
						)
					)
					(width 0)
					(fill yes)
				)
			)
		)
	)
	(footprint ""
		(layer "F.Cu")
		(at 471.275918 -44.08805 90)
		(property "Reference" "Q211"
			(at 0 0 90)
			(layer "F.SilkS")
			(hide yes)
			(effects
				(font
					(size 1.27 1.27)
				)
			)
		)
		(property "Value" "2N7002KDW-GP"
			(at -2.3622 -8.2042 90)
			(unlocked yes)
			(layer "F.Fab")
			(hide yes)
			(effects
				(font
					(size 1.016 1.016)
					(thickness 0.1524)
				)
			)
		)
		(property "Device Type" "SOT-363H44"
			(at -2.3622 -10.1092 90)
			(unlocked yes)
			(layer "F.Fab")
			(hide yes)
			(effects
				(font
					(size 1.016 1.016)
					(thickness 0.1524)
				)
			)
		)
		(duplicate_pad_numbers_are_jumpers no)
		(fp_line
			(start 1.4478 -1.7018)
			(end -1.4478 -1.7018)
			(stroke
				(width 0.1524)
				(type default)
			)
			(layer "F.SilkS")
		)
		(fp_line
			(start -1.4478 -1.7018)
			(end -1.4478 1.7018)
			(stroke
				(width 0.1524)
				(type default)
			)
			(layer "F.SilkS")
		)
		(fp_line
			(start -1.27 1.524)
			(end -1.27 0.6604)
			(stroke
				(width 0.4826)
				(type default)
			)
			(layer "F.SilkS")
		)
		(fp_line
			(start 1.4478 1.7018)
			(end 1.4478 -1.7018)
			(stroke
				(width 0.1524)
				(type default)
			)
			(layer "F.SilkS")
		)
		(fp_line
			(start -1.4478 1.7018)
			(end 1.4478 1.7018)
			(stroke
				(width 0.1524)
				(type default)
			)
			(layer "F.SilkS")
		)
		(fp_poly
			(pts
				(xy -1.524 -1.778) (xy 1.524 -1.778) (xy 1.524 1.778) (xy -1.524 1.778)
			)
			(stroke
				(width 0)
				(type default)
			)
			(fill no)
			(layer "F.CrtYd")
		)
		(fp_poly
			(pts
				(xy -1.524 -1.778) (xy 1.524 -1.778) (xy 1.524 1.778) (xy -1.524 1.778)
			)
			(stroke
				(width 0)
				(type default)
			)
			(fill no)
			(layer "F.Fab")
		)
		(pad "1" smd rect
			(at -0.65024 0.9398 90)
			(size 0.4064 1.016)
			(layers "F.Cu" "F.Mask" "F.Paste")
			(net "GND")
		)
		(pad "2" smd rect
			(at 0 0.9398 90)
			(size 0.4064 1.016)
			(layers "F.Cu" "F.Mask" "F.Paste")
			(net "SW_PWR_R_HDD35")
		)
		(pad "3" smd rect
			(at 0.65024 0.9398 90)
			(size 0.4064 1.016)
			(layers "F.Cu" "F.Mask" "F.Paste")
			(net "SW_HDD_P35")
		)
		(pad "4" smd rect
			(at 0.65024 -0.9398 90)
			(size 0.4064 1.016)
			(layers "F.Cu" "F.Mask" "F.Paste")
			(net "GND")
		)
		(pad "5" smd rect
			(at 0 -0.9398 90)
			(size 0.4064 1.016)
			(layers "F.Cu" "F.Mask" "F.Paste")
			(net "SW_HDD_G35")
		)
		(pad "6" smd rect
			(at -0.65024 -0.9398 90)
			(size 0.4064 1.016)
			(layers "F.Cu" "F.Mask" "F.Paste")
			(net "SW_HDD_R35")
		)
	)
	(footprint ""
		(layer "F.Cu")
		(at 221.074488 -345.066112 -90)
		(property "Reference" "R26"
			(at 0 0 270)
			(layer "F.SilkS")
			(hide yes)
			(effects
				(font
					(size 1.27 1.27)
				)
			)
		)
		(property "Value" "4K7R2F-GP"
			(at 0.064008 -3.993896 270)
			(unlocked yes)
			(layer "F.Fab")
			(hide yes)
			(effects
				(font
					(size 1.016 1.016)
					(thickness 0.1524)
				)
			)
		)
		(property "Device Type" "R402H16"
			(at 0.064008 -5.517896 270)
			(unlocked yes)
			(layer "F.Fab")
			(hide yes)
			(effects
				(font
					(size 1.016 1.016)
					(thickness 0.1524)
				)
			)
		)
		(duplicate_pad_numbers_are_jumpers no)
		(fp_line
			(start -0.508 -0.9398)
			(end -0.508 0.9398)
			(stroke
				(width 0.1524)
				(type default)
			)
			(layer "F.SilkS")
		)
		(fp_line
			(start 0.508 -0.9398)
			(end -0.508 -0.9398)
			(stroke
				(width 0.1524)
				(type default)
			)
			(layer "F.SilkS")
		)
		(fp_rect
			(start -0.508 0.9398)
			(end 0.508 -0.9398)
			(stroke
				(width 0)
				(type default)
			)
			(fill no)
			(layer "F.CrtYd")
		)
		(fp_rect
			(start -0.508 0.9398)
			(end 0.508 -0.9398)
			(stroke
				(width 0)
				(type default)
			)
			(fill no)
			(layer "F.Fab")
		)
		(pad "1" smd custom
			(at 0 -0.4445 270)
			(size 0.1397 0.1397)
			(layers "F.Cu" "F.Mask" "F.Paste")
			(net "P3V3_STBY_A")
			(options
				(clearance outline)
				(anchor circle)
			)
			(primitives
				(gr_poly
					(pts
						(arc
							(start -0.1778 -0.2794)
							(mid -0.249642 -0.249642)
							(end -0.2794 -0.1778)
						)
						(arc
							(start -0.2794 0.1778)
							(mid -0.249642 0.249642)
							(end -0.1778 0.2794)
						)
						(arc
							(start 0.1778 0.2794)
							(mid 0.249642 0.249642)
							(end 0.2794 0.1778)
						)
						(arc
							(start 0.2794 -0.1778)
							(mid 0.249642 -0.249642)
							(end 0.1778 -0.2794)
						)
					)
					(width 0)
					(fill yes)
				)
			)
		)
		(pad "2" smd custom
			(at 0 0.4445 270)
			(size 0.1397 0.1397)
			(layers "F.Cu" "F.Mask" "F.Paste")
			(net "VOL_SEN_INT_N")
			(options
				(clearance outline)
				(anchor circle)
			)
			(primitives
				(gr_poly
					(pts
						(arc
							(start -0.1778 -0.2794)
							(mid -0.249642 -0.249642)
							(end -0.2794 -0.1778)
						)
						(arc
							(start -0.2794 0.1778)
							(mid -0.249642 0.249642)
							(end -0.1778 0.2794)
						)
						(arc
							(start 0.1778 0.2794)
							(mid 0.249642 0.249642)
							(end 0.2794 0.1778)
						)
						(arc
							(start 0.2794 -0.1778)
							(mid 0.249642 -0.249642)
							(end 0.1778 -0.2794)
						)
					)
					(width 0)
					(fill yes)
				)
			)
		)
	)
	(footprint ""
		(layer "F.Cu")
		(at 317.947294 -130.419602 -90)
		(property "Reference" "R527"
			(at 0 0 270)
			(layer "F.SilkS")
			(hide yes)
			(effects
				(font
					(size 1.27 1.27)
				)
			)
		)
		(property "Value" "4K7R2J-2-GP"
			(at 0.064008 -3.993896 270)
			(unlocked yes)
			(layer "F.Fab")
			(hide yes)
			(effects
				(font
					(size 1.016 1.016)
					(thickness 0.1524)
				)
			)
		)
		(property "Device Type" "R402H16"
			(at 0.064008 -5.517896 270)
			(unlocked yes)
			(layer "F.Fab")
			(hide yes)
			(effects
				(font
					(size 1.016 1.016)
					(thickness 0.1524)
				)
			)
		)
		(duplicate_pad_numbers_are_jumpers no)
		(fp_line
			(start -0.508 -0.9398)
			(end -0.508 0.9398)
			(stroke
				(width 0.1524)
				(type default)
			)
			(layer "F.SilkS")
		)
		(fp_line
			(start 0.508 -0.9398)
			(end -0.508 -0.9398)
			(stroke
				(width 0.1524)
				(type default)
			)
			(layer "F.SilkS")
		)
		(fp_rect
			(start -0.508 0.9398)
			(end 0.508 -0.9398)
			(stroke
				(width 0)
				(type default)
			)
			(fill no)
			(layer "F.CrtYd")
		)
		(fp_rect
			(start -0.508 0.9398)
			(end 0.508 -0.9398)
			(stroke
				(width 0)
				(type default)
			)
			(fill no)
			(layer "F.Fab")
		)
		(pad "1" smd custom
			(at 0 -0.4445 270)
			(size 0.1397 0.1397)
			(layers "F.Cu" "F.Mask" "F.Paste")
			(net "DRIVE_A_18_FLT_LED")
			(options
				(clearance outline)
				(anchor circle)
			)
			(primitives
				(gr_poly
					(pts
						(arc
							(start -0.1778 -0.2794)
							(mid -0.249642 -0.249642)
							(end -0.2794 -0.1778)
						)
						(arc
							(start -0.2794 0.1778)
							(mid -0.249642 0.249642)
							(end -0.1778 0.2794)
						)
						(arc
							(start 0.1778 0.2794)
							(mid 0.249642 0.249642)
							(end 0.2794 0.1778)
						)
						(arc
							(start 0.2794 -0.1778)
							(mid 0.249642 -0.249642)
							(end 0.1778 -0.2794)
						)
					)
					(width 0)
					(fill yes)
				)
			)
		)
		(pad "2" smd custom
			(at 0 0.4445 270)
			(size 0.1397 0.1397)
			(layers "F.Cu" "F.Mask" "F.Paste")
			(net "GND")
			(options
				(clearance outline)
				(anchor circle)
			)
			(primitives
				(gr_poly
					(pts
						(arc
							(start -0.1778 -0.2794)
							(mid -0.249642 -0.249642)
							(end -0.2794 -0.1778)
						)
						(arc
							(start -0.2794 0.1778)
							(mid -0.249642 0.249642)
							(end -0.1778 0.2794)
						)
						(arc
							(start 0.1778 0.2794)
							(mid 0.249642 0.249642)
							(end 0.2794 0.1778)
						)
						(arc
							(start 0.2794 -0.1778)
							(mid 0.249642 -0.249642)
							(end 0.1778 -0.2794)
						)
					)
					(width 0)
					(fill yes)
				)
			)
		)
	)
	(footprint ""
		(layer "F.Cu")
		(at 261.957566 -341.037672 90)
		(property "Reference" "R385"
			(at 0 0 90)
			(layer "F.SilkS")
			(hide yes)
			(effects
				(font
					(size 1.27 1.27)
				)
			)
		)
		(property "Value" "10KR2F-2-GP"
			(at 0.064008 -3.993896 90)
			(unlocked yes)
			(layer "F.Fab")
			(hide yes)
			(effects
				(font
					(size 1.016 1.016)
					(thickness 0.1524)
				)
			)
		)
		(property "Device Type" "R402H16"
			(at 0.064008 -5.517896 90)
			(unlocked yes)
			(layer "F.Fab")
			(hide yes)
			(effects
				(font
					(size 1.016 1.016)
					(thickness 0.1524)
				)
			)
		)
		(duplicate_pad_numbers_are_jumpers no)
		(fp_line
			(start 0.508 -0.9398)
			(end -0.508 -0.9398)
			(stroke
				(width 0.1524)
				(type default)
			)
			(layer "F.SilkS")
		)
		(fp_line
			(start -0.508 -0.9398)
			(end -0.508 0.9398)
			(stroke
				(width 0.1524)
				(type default)
			)
			(layer "F.SilkS")
		)
		(fp_rect
			(start -0.508 0.9398)
			(end 0.508 -0.9398)
			(stroke
				(width 0)
				(type default)
			)
			(fill no)
			(layer "F.CrtYd")
		)
		(fp_rect
			(start -0.508 0.9398)
			(end 0.508 -0.9398)
			(stroke
				(width 0)
				(type default)
			)
			(fill no)
			(layer "F.Fab")
		)
		(pad "1" smd custom
			(at 0 -0.4445 90)
			(size 0.1397 0.1397)
			(layers "F.Cu" "F.Mask" "F.Paste")
			(net "P3V3_STBY_A")
			(options
				(clearance outline)
				(anchor circle)
			)
			(primitives
				(gr_poly
					(pts
						(arc
							(start -0.1778 -0.2794)
							(mid -0.249642 -0.249642)
							(end -0.2794 -0.1778)
						)
						(arc
							(start -0.2794 0.1778)
							(mid -0.249642 0.249642)
							(end -0.1778 0.2794)
						)
						(arc
							(start 0.1778 0.2794)
							(mid 0.249642 0.249642)
							(end 0.2794 0.1778)
						)
						(arc
							(start 0.2794 -0.1778)
							(mid 0.249642 -0.249642)
							(end 0.1778 -0.2794)
						)
					)
					(width 0)
					(fill yes)
				)
			)
		)
		(pad "2" smd custom
			(at 0 0.4445 90)
			(size 0.1397 0.1397)
			(layers "F.Cu" "F.Mask" "F.Paste")
			(net "SCC_A_TYPE_1")
			(options
				(clearance outline)
				(anchor circle)
			)
			(primitives
				(gr_poly
					(pts
						(arc
							(start -0.1778 -0.2794)
							(mid -0.249642 -0.249642)
							(end -0.2794 -0.1778)
						)
						(arc
							(start -0.2794 0.1778)
							(mid -0.249642 0.249642)
							(end -0.1778 0.2794)
						)
						(arc
							(start 0.1778 0.2794)
							(mid 0.249642 0.249642)
							(end 0.2794 0.1778)
						)
						(arc
							(start 0.2794 -0.1778)
							(mid 0.249642 -0.249642)
							(end 0.1778 -0.2794)
						)
					)
					(width 0)
					(fill yes)
				)
			)
		)
	)
	(footprint ""
		(layer "F.Cu")
		(at 271.81937 -284.734762 180)
		(property "Reference" "R435"
			(at 0 0 180)
			(layer "F.SilkS")
			(hide yes)
			(effects
				(font
					(size 1.27 1.27)
				)
			)
		)
		(property "Value" "1KR2F-3-GP"
			(at 0.064008 -3.993896 180)
			(unlocked yes)
			(layer "F.Fab")
			(hide yes)
			(effects
				(font
					(size 1.016 1.016)
					(thickness 0.1524)
				)
			)
		)
		(property "Device Type" "R402H16"
			(at 0.064008 -5.517896 180)
			(unlocked yes)
			(layer "F.Fab")
			(hide yes)
			(effects
				(font
					(size 1.016 1.016)
					(thickness 0.1524)
				)
			)
		)
		(duplicate_pad_numbers_are_jumpers no)
		(fp_line
			(start 0.508 -0.9398)
			(end -0.508 -0.9398)
			(stroke
				(width 0.1524)
				(type default)
			)
			(layer "F.SilkS")
		)
		(fp_line
			(start -0.508 -0.9398)
			(end -0.508 0.9398)
			(stroke
				(width 0.1524)
				(type default)
			)
			(layer "F.SilkS")
		)
		(fp_rect
			(start -0.508 0.9398)
			(end 0.508 -0.9398)
			(stroke
				(width 0)
				(type default)
			)
			(fill no)
			(layer "F.CrtYd")
		)
		(fp_rect
			(start -0.508 0.9398)
			(end 0.508 -0.9398)
			(stroke
				(width 0)
				(type default)
			)
			(fill no)
			(layer "F.Fab")
		)
		(pad "1" smd custom
			(at 0 -0.4445 180)
			(size 0.1397 0.1397)
			(layers "F.Cu" "F.Mask" "F.Paste")
			(net "P3V3_STBY_A")
			(options
				(clearance outline)
				(anchor circle)
			)
			(primitives
				(gr_poly
					(pts
						(arc
							(start -0.1778 -0.2794)
							(mid -0.249642 -0.249642)
							(end -0.2794 -0.1778)
						)
						(arc
							(start -0.2794 0.1778)
							(mid -0.249642 0.249642)
							(end -0.1778 0.2794)
						)
						(arc
							(start 0.1778 0.2794)
							(mid 0.249642 0.249642)
							(end 0.2794 0.1778)
						)
						(arc
							(start 0.2794 -0.1778)
							(mid 0.249642 -0.249642)
							(end 0.1778 -0.2794)
						)
					)
					(width 0)
					(fill yes)
				)
			)
		)
		(pad "2" smd custom
			(at 0 0.4445 180)
			(size 0.1397 0.1397)
			(layers "F.Cu" "F.Mask" "F.Paste")
			(net "I2C_DRIVE_A_FLT_LED_SDA")
			(options
				(clearance outline)
				(anchor circle)
			)
			(primitives
				(gr_poly
					(pts
						(arc
							(start -0.1778 -0.2794)
							(mid -0.249642 -0.249642)
							(end -0.2794 -0.1778)
						)
						(arc
							(start -0.2794 0.1778)
							(mid -0.249642 0.249642)
							(end -0.1778 0.2794)
						)
						(arc
							(start 0.1778 0.2794)
							(mid 0.249642 0.249642)
							(end 0.2794 0.1778)
						)
						(arc
							(start 0.2794 -0.1778)
							(mid 0.249642 -0.249642)
							(end 0.1778 -0.2794)
						)
					)
					(width 0)
					(fill yes)
				)
			)
		)
	)
	(footprint ""
		(layer "F.Cu")
		(at 48.297846 -281.018742 90)
		(property "Reference" "R160"
			(at 0 0 90)
			(layer "F.SilkS")
			(hide yes)
			(effects
				(font
					(size 1.27 1.27)
				)
			)
		)
		(property "Value" "4K7R2J-2-GP"
			(at 0.064008 -3.993896 90)
			(unlocked yes)
			(layer "F.Fab")
			(hide yes)
			(effects
				(font
					(size 1.016 1.016)
					(thickness 0.1524)
				)
			)
		)
		(property "Device Type" "R402H16"
			(at 0.064008 -5.517896 90)
			(unlocked yes)
			(layer "F.Fab")
			(hide yes)
			(effects
				(font
					(size 1.016 1.016)
					(thickness 0.1524)
				)
			)
		)
		(duplicate_pad_numbers_are_jumpers no)
		(fp_line
			(start 0.508 -0.9398)
			(end -0.508 -0.9398)
			(stroke
				(width 0.1524)
				(type default)
			)
			(layer "F.SilkS")
		)
		(fp_line
			(start -0.508 -0.9398)
			(end -0.508 0.9398)
			(stroke
				(width 0.1524)
				(type default)
			)
			(layer "F.SilkS")
		)
		(fp_rect
			(start -0.508 0.9398)
			(end 0.508 -0.9398)
			(stroke
				(width 0)
				(type default)
			)
			(fill no)
			(layer "F.CrtYd")
		)
		(fp_rect
			(start -0.508 0.9398)
			(end 0.508 -0.9398)
			(stroke
				(width 0)
				(type default)
			)
			(fill no)
			(layer "F.Fab")
		)
		(pad "1" smd custom
			(at 0 -0.4445 90)
			(size 0.1397 0.1397)
			(layers "F.Cu" "F.Mask" "F.Paste")
			(net "P12V_A")
			(options
				(clearance outline)
				(anchor circle)
			)
			(primitives
				(gr_poly
					(pts
						(arc
							(start -0.1778 -0.2794)
							(mid -0.249642 -0.249642)
							(end -0.2794 -0.1778)
						)
						(arc
							(start -0.2794 0.1778)
							(mid -0.249642 0.249642)
							(end -0.1778 0.2794)
						)
						(arc
							(start 0.1778 0.2794)
							(mid 0.249642 0.249642)
							(end 0.2794 0.1778)
						)
						(arc
							(start 0.2794 -0.1778)
							(mid 0.249642 -0.249642)
							(end 0.1778 -0.2794)
						)
					)
					(width 0)
					(fill yes)
				)
			)
		)
		(pad "2" smd custom
			(at 0 0.4445 90)
			(size 0.1397 0.1397)
			(layers "F.Cu" "F.Mask" "F.Paste")
			(net "SW_HDD_P1")
			(options
				(clearance outline)
				(anchor circle)
			)
			(primitives
				(gr_poly
					(pts
						(arc
							(start -0.1778 -0.2794)
							(mid -0.249642 -0.249642)
							(end -0.2794 -0.1778)
						)
						(arc
							(start -0.2794 0.1778)
							(mid -0.249642 0.249642)
							(end -0.1778 0.2794)
						)
						(arc
							(start 0.1778 0.2794)
							(mid 0.249642 0.249642)
							(end 0.2794 0.1778)
						)
						(arc
							(start 0.2794 -0.1778)
							(mid 0.249642 -0.249642)
							(end 0.1778 -0.2794)
						)
					)
					(width 0)
					(fill yes)
				)
			)
		)
	)
	(footprint ""
		(layer "F.Cu")
		(at 101.163374 -298.52493)
		(property "Reference" "Q290"
			(at 0 0 0)
			(layer "F.SilkS")
			(hide yes)
			(effects
				(font
					(size 1.27 1.27)
				)
			)
		)
		(property "Value" "SSM3K324R-GP"
			(at 0.127 -8.9662 0)
			(unlocked yes)
			(layer "F.Fab")
			(hide yes)
			(effects
				(font
					(size 1.016 1.016)
					(thickness 0.1524)
				)
			)
		)
		(property "Device Type" "SOT23DGS2D4H35"
			(at 0.127 -10.4902 0)
			(unlocked yes)
			(layer "F.Fab")
			(hide yes)
			(effects
				(font
					(size 1.016 1.016)
					(thickness 0.1524)
				)
			)
		)
		(duplicate_pad_numbers_are_jumpers no)
		(fp_line
			(start -1.651 -1.778)
			(end -1.651 1.778)
			(stroke
				(width 0.1524)
				(type default)
			)
			(layer "F.SilkS")
		)
		(fp_line
			(start -1.651 1.778)
			(end 1.651 1.778)
			(stroke
				(width 0.1524)
				(type default)
			)
			(layer "F.SilkS")
		)
		(fp_line
			(start 1.651 -1.778)
			(end -1.651 -1.778)
			(stroke
				(width 0.1524)
				(type default)
			)
			(layer "F.SilkS")
		)
		(fp_line
			(start 1.651 1.778)
			(end 1.651 -1.778)
			(stroke
				(width 0.1524)
				(type default)
			)
			(layer "F.SilkS")
		)
		(fp_poly
			(pts
				(xy -1.778 1.8796) (xy -1.778 -1.8796) (xy 1.778 -1.8796) (xy 1.778 1.8796)
			)
			(stroke
				(width 0)
				(type default)
			)
			(fill no)
			(layer "F.CrtYd")
		)
		(fp_poly
			(pts
				(xy -1.778 1.8796) (xy -1.778 -1.8796) (xy 1.778 -1.8796) (xy 1.778 1.8796)
			)
			(stroke
				(width 0)
				(type default)
			)
			(fill no)
			(layer "F.Fab")
		)
		(pad "D" smd custom
			(at 0 -0.9525)
			(size 0.1905 0.1905)
			(layers "F.Cu" "F.Mask" "F.Paste")
			(net "DRV_ACT_27_N")
			(options
				(clearance outline)
				(anchor circle)
			)
			(primitives
				(gr_poly
					(pts
						(arc
							(start -0.1778 0.5715)
							(mid -0.321484 0.511984)
							(end -0.381 0.3683)
						)
						(arc
							(start -0.381 -0.3683)
							(mid -0.321484 -0.511984)
							(end -0.1778 -0.5715)
						)
						(arc
							(start 0.1778 -0.5715)
							(mid 0.321484 -0.511984)
							(end 0.381 -0.3683)
						)
						(arc
							(start 0.381 0.3683)
							(mid 0.321484 0.511984)
							(end 0.1778 0.5715)
						)
					)
					(width 0)
					(fill yes)
				)
			)
		)
		(pad "G" smd custom
			(at -0.98425 0.9525)
			(size 0.1905 0.1905)
			(layers "F.Cu" "F.Mask" "F.Paste")
			(net "DRIVE_B_27_ACT")
			(options
				(clearance outline)
				(anchor circle)
			)
			(primitives
				(gr_poly
					(pts
						(arc
							(start -0.1778 0.5715)
							(mid -0.321484 0.511984)
							(end -0.381 0.3683)
						)
						(arc
							(start -0.381 -0.3683)
							(mid -0.321484 -0.511984)
							(end -0.1778 -0.5715)
						)
						(arc
							(start 0.1778 -0.5715)
							(mid 0.321484 -0.511984)
							(end 0.381 -0.3683)
						)
						(arc
							(start 0.381 0.3683)
							(mid 0.321484 0.511984)
							(end 0.1778 0.5715)
						)
					)
					(width 0)
					(fill yes)
				)
			)
		)
		(pad "S" smd custom
			(at 0.98425 0.9525)
			(size 0.1905 0.1905)
			(layers "F.Cu" "F.Mask" "F.Paste")
			(net "GND")
			(options
				(clearance outline)
				(anchor circle)
			)
			(primitives
				(gr_poly
					(pts
						(arc
							(start -0.1778 0.5715)
							(mid -0.321484 0.511984)
							(end -0.381 0.3683)
						)
						(arc
							(start -0.381 -0.3683)
							(mid -0.321484 -0.511984)
							(end -0.1778 -0.5715)
						)
						(arc
							(start 0.1778 -0.5715)
							(mid 0.321484 -0.511984)
							(end 0.381 -0.3683)
						)
						(arc
							(start 0.381 0.3683)
							(mid 0.321484 0.511984)
							(end 0.1778 0.5715)
						)
					)
					(width 0)
					(fill yes)
				)
			)
		)
	)
	(footprint ""
		(layer "F.Cu")
		(at 338.709 -171.809918 -90)
		(property "Reference" "R559"
			(at 0 0 270)
			(layer "F.SilkS")
			(hide yes)
			(effects
				(font
					(size 1.27 1.27)
				)
			)
		)
		(property "Value" "300KR2F-GP"
			(at 0.064008 -3.993896 270)
			(unlocked yes)
			(layer "F.Fab")
			(hide yes)
			(effects
				(font
					(size 1.016 1.016)
					(thickness 0.1524)
				)
			)
		)
		(property "Device Type" "R402H16"
			(at 0.064008 -5.517896 270)
			(unlocked yes)
			(layer "F.Fab")
			(hide yes)
			(effects
				(font
					(size 1.016 1.016)
					(thickness 0.1524)
				)
			)
		)
		(duplicate_pad_numbers_are_jumpers no)
		(fp_line
			(start -0.508 -0.9398)
			(end -0.508 0.9398)
			(stroke
				(width 0.1524)
				(type default)
			)
			(layer "F.SilkS")
		)
		(fp_line
			(start 0.508 -0.9398)
			(end -0.508 -0.9398)
			(stroke
				(width 0.1524)
				(type default)
			)
			(layer "F.SilkS")
		)
		(fp_rect
			(start -0.508 0.9398)
			(end 0.508 -0.9398)
			(stroke
				(width 0)
				(type default)
			)
			(fill no)
			(layer "F.CrtYd")
		)
		(fp_rect
			(start -0.508 0.9398)
			(end 0.508 -0.9398)
			(stroke
				(width 0)
				(type default)
			)
			(fill no)
			(layer "F.Fab")
		)
		(pad "1" smd custom
			(at 0 -0.4445 270)
			(size 0.1397 0.1397)
			(layers "F.Cu" "F.Mask" "F.Paste")
			(net "SW_HDD_N18")
			(options
				(clearance outline)
				(anchor circle)
			)
			(primitives
				(gr_poly
					(pts
						(arc
							(start -0.1778 -0.2794)
							(mid -0.249642 -0.249642)
							(end -0.2794 -0.1778)
						)
						(arc
							(start -0.2794 0.1778)
							(mid -0.249642 0.249642)
							(end -0.1778 0.2794)
						)
						(arc
							(start 0.1778 0.2794)
							(mid 0.249642 0.249642)
							(end 0.2794 0.1778)
						)
						(arc
							(start 0.2794 -0.1778)
							(mid 0.249642 -0.249642)
							(end 0.1778 -0.2794)
						)
					)
					(width 0)
					(fill yes)
				)
			)
		)
		(pad "2" smd custom
			(at 0 0.4445 270)
			(size 0.1397 0.1397)
			(layers "F.Cu" "F.Mask" "F.Paste")
			(net "P12V_A")
			(options
				(clearance outline)
				(anchor circle)
			)
			(primitives
				(gr_poly
					(pts
						(arc
							(start -0.1778 -0.2794)
							(mid -0.249642 -0.249642)
							(end -0.2794 -0.1778)
						)
						(arc
							(start -0.2794 0.1778)
							(mid -0.249642 0.249642)
							(end -0.1778 0.2794)
						)
						(arc
							(start 0.1778 0.2794)
							(mid 0.249642 0.249642)
							(end 0.2794 0.1778)
						)
						(arc
							(start 0.2794 -0.1778)
							(mid 0.249642 -0.249642)
							(end 0.1778 -0.2794)
						)
					)
					(width 0)
					(fill yes)
				)
			)
		)
	)
	(footprint ""
		(layer "F.Cu")
		(at 202.300078 -63.805562)
		(property "Reference" ""
			(at 0 0 0)
			(layer "F.SilkS")
			(hide yes)
			(effects
				(font
					(size 1.27 1.27)
				)
			)
		)
		(property "Value" "*"
			(at -8.398764 -8.057642 0)
			(unlocked yes)
			(layer "F.Fab")
			(hide yes)
			(effects
				(font
					(size 1.016 1.016)
					(thickness 0.1524)
				)
			)
		)
		(duplicate_pad_numbers_are_jumpers no)
		(fp_poly
			(pts
				(arc
					(start 7.3152 0)
					(mid 0 7.3152)
					(end -7.3152 0)
				)
				(arc
					(start -7.3152 -5.9944)
					(mid 0 -13.3096)
					(end 7.3152 -5.9944)
				)
			)
			(stroke
				(width 0)
				(type default)
			)
			(fill no)
			(layer "B.CrtYd")
		)
		(fp_poly
			(pts
				(arc
					(start 7.3152 0)
					(mid 0 7.3152)
					(end -7.3152 0)
				)
				(arc
					(start -7.3152 -5.9944)
					(mid 0 -13.3096)
					(end 7.3152 -5.9944)
				)
			)
			(stroke
				(width 0)
				(type default)
			)
			(fill no)
			(layer "F.CrtYd")
		)
		(fp_poly
			(pts
				(arc
					(start 7.3152 0)
					(mid 0 7.3152)
					(end -7.3152 0)
				)
				(arc
					(start -7.3152 -5.9944)
					(mid 0 -13.3096)
					(end 7.3152 -5.9944)
				)
			)
			(stroke
				(width 0)
				(type default)
			)
			(fill no)
			(layer "B.Fab")
		)
		(fp_poly
			(pts
				(arc
					(start 7.3152 0)
					(mid 0 7.3152)
					(end -7.3152 0)
				)
				(arc
					(start -7.3152 -5.9944)
					(mid 0 -13.3096)
					(end 7.3152 -5.9944)
				)
			)
			(stroke
				(width 0)
				(type default)
			)
			(fill no)
			(layer "F.Fab")
		)
		(pad "1" thru_hole oval
			(at 0 0)
			(size 14.0208 20.0152)
			(drill 0.0254
				(offset 0 -2.9972)
			)
			(layers "*.Cu" "*.Mask")
			(remove_unused_layers no)
			(net "Net_35")
			(clearance -1.002284)
			(thermal_gap 0.1524)
			(padstack
				(mode front_inner_back)
				(layer "Inner"
					(shape custom)
					(size 2.928012 2.928012)
					(options
						(anchor circle)
					)
					(primitives
						(gr_poly
							(pts
								(arc
									(start 4.571746 -2.084324)
									(mid 0.000333 7.430372)
									(end -4.571492 -2.084324)
								)
								(arc
									(start -4.571492 -2.084324)
									(mid -3.570296 -3.611977)
									(end -2.875026 -5.30098)
								)
								(arc
									(start -2.875026 -5.30098)
									(mid 0.000217 -7.43089)
									(end 2.87528 -5.30098)
								)
								(arc
									(start 2.87528 -5.30098)
									(mid 3.570511 -3.611956)
									(end 4.571746 -2.084324)
								)
							)
							(width 0)
							(fill yes)
						)
					)
					(clearance 0.1524)
				)
				(layer "B.Cu"
					(shape oval)
					(size 14.0208 20.0152)
					(offset 0 -2.9972)
					(clearance -1.002284)
				)
			)
		)
		(zone
			(layers "F.Cu" "B.Cu" "In1.Cu" "In2.Cu" "In3.Cu" "In4.Cu" "In5.Cu" "In6.Cu"
				"In7.Cu" "In8.Cu" "In9.Cu" "In10.Cu"
			)
			(hatch none 0.5)
			(connect_pads
				(clearance 0)
			)
			(min_thickness 0.25)
			(keepout
				(tracks not_allowed)
				(vias allowed)
				(pads allowed)
				(copperpour not_allowed)
				(footprints allowed)
			)
			(placement
				(enabled no)
				(sheetname "")
			)
			(fill
				(thermal_gap 0.5)
				(thermal_bridge_width 0.5)
				(island_removal_mode 0)
			)
			(polygon
				(pts
					(arc
						(start 195.289678 -69.799962)
						(mid 202.300078 -76.810362)
						(end 209.310478 -69.799962)
					)
					(arc
						(start 209.310478 -63.805562)
						(mid 202.300078 -56.795162)
						(end 195.289678 -63.805562)
					)
				)
			)
		)
	)
	(footprint ""
		(layer "F.Cu")
		(at 14.817598 -45.608494 90)
		(property "Reference" "R696"
			(at 0 0 90)
			(layer "F.SilkS")
			(hide yes)
			(effects
				(font
					(size 1.27 1.27)
				)
			)
		)
		(property "Value" "4K7R2J-2-GP"
			(at 0.064008 -3.993896 90)
			(unlocked yes)
			(layer "F.Fab")
			(hide yes)
			(effects
				(font
					(size 1.016 1.016)
					(thickness 0.1524)
				)
			)
		)
		(property "Device Type" "R402H16"
			(at 0.064008 -5.517896 90)
			(unlocked yes)
			(layer "F.Fab")
			(hide yes)
			(effects
				(font
					(size 1.016 1.016)
					(thickness 0.1524)
				)
			)
		)
		(duplicate_pad_numbers_are_jumpers no)
		(fp_line
			(start 0.508 -0.9398)
			(end -0.508 -0.9398)
			(stroke
				(width 0.1524)
				(type default)
			)
			(layer "F.SilkS")
		)
		(fp_line
			(start -0.508 -0.9398)
			(end -0.508 0.9398)
			(stroke
				(width 0.1524)
				(type default)
			)
			(layer "F.SilkS")
		)
		(fp_rect
			(start -0.508 0.9398)
			(end 0.508 -0.9398)
			(stroke
				(width 0)
				(type default)
			)
			(fill no)
			(layer "F.CrtYd")
		)
		(fp_rect
			(start -0.508 0.9398)
			(end 0.508 -0.9398)
			(stroke
				(width 0)
				(type default)
			)
			(fill no)
			(layer "F.Fab")
		)
		(pad "1" smd custom
			(at 0 -0.4445 90)
			(size 0.1397 0.1397)
			(layers "F.Cu" "F.Mask" "F.Paste")
			(net "P12V_A")
			(options
				(clearance outline)
				(anchor circle)
			)
			(primitives
				(gr_poly
					(pts
						(arc
							(start -0.1778 -0.2794)
							(mid -0.249642 -0.249642)
							(end -0.2794 -0.1778)
						)
						(arc
							(start -0.2794 0.1778)
							(mid -0.249642 0.249642)
							(end -0.1778 0.2794)
						)
						(arc
							(start 0.1778 0.2794)
							(mid 0.249642 0.249642)
							(end 0.2794 0.1778)
						)
						(arc
							(start 0.2794 -0.1778)
							(mid 0.249642 -0.249642)
							(end 0.1778 -0.2794)
						)
					)
					(width 0)
					(fill yes)
				)
			)
		)
		(pad "2" smd custom
			(at 0 0.4445 90)
			(size 0.1397 0.1397)
			(layers "F.Cu" "F.Mask" "F.Paste")
			(net "SW_HDD_R24")
			(options
				(clearance outline)
				(anchor circle)
			)
			(primitives
				(gr_poly
					(pts
						(arc
							(start -0.1778 -0.2794)
							(mid -0.249642 -0.249642)
							(end -0.2794 -0.1778)
						)
						(arc
							(start -0.2794 0.1778)
							(mid -0.249642 0.249642)
							(end -0.1778 0.2794)
						)
						(arc
							(start 0.1778 0.2794)
							(mid 0.249642 0.249642)
							(end 0.2794 0.1778)
						)
						(arc
							(start 0.2794 -0.1778)
							(mid 0.249642 -0.249642)
							(end 0.1778 -0.2794)
						)
					)
					(width 0)
					(fill yes)
				)
			)
		)
	)
	(footprint ""
		(layer "F.Cu")
		(at 413.166052 -183.620918)
		(property "Reference" "TP107"
			(at 0 0 0)
			(layer "F.SilkS")
			(hide yes)
			(effects
				(font
					(size 1.27 1.27)
				)
			)
		)
		(property "Value" "TPAD32-GP"
			(at -0.0508 -1.6764 0)
			(unlocked yes)
			(layer "F.Fab")
			(hide yes)
			(effects
				(font
					(size 1.016 1.016)
					(thickness 0.1524)
				)
			)
		)
		(property "Device Type" "TPAD32"
			(at -0.0508 -3.2004 0)
			(unlocked yes)
			(layer "F.Fab")
			(hide yes)
			(effects
				(font
					(size 1.016 1.016)
					(thickness 0.1524)
				)
			)
		)
		(duplicate_pad_numbers_are_jumpers no)
		(fp_poly
			(pts
				(arc
					(start 0.4064 0)
					(mid -0.4064 0)
					(end 0.4064 0)
				)
			)
			(stroke
				(width 0)
				(type default)
			)
			(fill no)
			(layer "F.CrtYd")
		)
		(fp_poly
			(pts
				(arc
					(start 0.7112 0)
					(mid -0.7112 0)
					(end 0.7112 0)
				)
			)
			(stroke
				(width 0)
				(type default)
			)
			(fill no)
			(layer "F.Fab")
		)
		(pad "1" smd circle
			(at 0 0)
			(size 0.8128 0.8128)
			(layers "F.Cu" "F.Mask" "F.Paste")
			(net "ACT_HDD_21")
		)
	)
	(footprint ""
		(layer "F.Cu")
		(at 377.308872 -293.892732)
		(property "Reference" "Q259"
			(at 0 0 0)
			(layer "F.SilkS")
			(hide yes)
			(effects
				(font
					(size 1.27 1.27)
				)
			)
		)
		(property "Value" "2N7002K-2-GP"
			(at 0.127 -8.9662 0)
			(unlocked yes)
			(layer "F.Fab")
			(hide yes)
			(effects
				(font
					(size 1.016 1.016)
					(thickness 0.1524)
				)
			)
		)
		(property "Device Type" "SOT23DGS2D4H44"
			(at 0.127 -10.4902 0)
			(unlocked yes)
			(layer "F.Fab")
			(hide yes)
			(effects
				(font
					(size 1.016 1.016)
					(thickness 0.1524)
				)
			)
		)
		(duplicate_pad_numbers_are_jumpers no)
		(fp_line
			(start -1.651 -1.778)
			(end -1.651 1.778)
			(stroke
				(width 0.1524)
				(type default)
			)
			(layer "F.SilkS")
		)
		(fp_line
			(start -1.651 1.778)
			(end 1.651 1.778)
			(stroke
				(width 0.1524)
				(type default)
			)
			(layer "F.SilkS")
		)
		(fp_line
			(start 1.651 -1.778)
			(end -1.651 -1.778)
			(stroke
				(width 0.1524)
				(type default)
			)
			(layer "F.SilkS")
		)
		(fp_line
			(start 1.651 1.778)
			(end 1.651 -1.778)
			(stroke
				(width 0.1524)
				(type default)
			)
			(layer "F.SilkS")
		)
		(fp_poly
			(pts
				(xy -1.778 1.8796) (xy -1.778 -1.8796) (xy 1.778 -1.8796) (xy 1.778 1.8796)
			)
			(stroke
				(width 0)
				(type default)
			)
			(fill no)
			(layer "F.CrtYd")
		)
		(fp_poly
			(pts
				(xy -1.778 1.8796) (xy -1.778 -1.8796) (xy 1.778 -1.8796) (xy 1.778 1.8796)
			)
			(stroke
				(width 0)
				(type default)
			)
			(fill no)
			(layer "F.Fab")
		)
		(pad "D" smd custom
			(at 0 -0.9525)
			(size 0.1905 0.1905)
			(layers "F.Cu" "F.Mask" "F.Paste")
			(net "FLT_HDD32_N")
			(options
				(clearance outline)
				(anchor circle)
			)
			(primitives
				(gr_poly
					(pts
						(arc
							(start -0.1778 0.5715)
							(mid -0.321484 0.511984)
							(end -0.381 0.3683)
						)
						(arc
							(start -0.381 -0.3683)
							(mid -0.321484 -0.511984)
							(end -0.1778 -0.5715)
						)
						(arc
							(start 0.1778 -0.5715)
							(mid 0.321484 -0.511984)
							(end 0.381 -0.3683)
						)
						(arc
							(start 0.381 0.3683)
							(mid 0.321484 0.511984)
							(end 0.1778 0.5715)
						)
					)
					(width 0)
					(fill yes)
				)
			)
		)
		(pad "G" smd custom
			(at -0.98425 0.9525)
			(size 0.1905 0.1905)
			(layers "F.Cu" "F.Mask" "F.Paste")
			(net "DRIVE_B_32_FLT_LED")
			(options
				(clearance outline)
				(anchor circle)
			)
			(primitives
				(gr_poly
					(pts
						(arc
							(start -0.1778 0.5715)
							(mid -0.321484 0.511984)
							(end -0.381 0.3683)
						)
						(arc
							(start -0.381 -0.3683)
							(mid -0.321484 -0.511984)
							(end -0.1778 -0.5715)
						)
						(arc
							(start 0.1778 -0.5715)
							(mid 0.321484 -0.511984)
							(end 0.381 -0.3683)
						)
						(arc
							(start 0.381 0.3683)
							(mid 0.321484 0.511984)
							(end 0.1778 0.5715)
						)
					)
					(width 0)
					(fill yes)
				)
			)
		)
		(pad "S" smd custom
			(at 0.98425 0.9525)
			(size 0.1905 0.1905)
			(layers "F.Cu" "F.Mask" "F.Paste")
			(net "GND")
			(options
				(clearance outline)
				(anchor circle)
			)
			(primitives
				(gr_poly
					(pts
						(arc
							(start -0.1778 0.5715)
							(mid -0.321484 0.511984)
							(end -0.381 0.3683)
						)
						(arc
							(start -0.381 -0.3683)
							(mid -0.321484 -0.511984)
							(end -0.1778 -0.5715)
						)
						(arc
							(start 0.1778 -0.5715)
							(mid 0.321484 -0.511984)
							(end 0.381 -0.3683)
						)
						(arc
							(start 0.381 0.3683)
							(mid 0.321484 0.511984)
							(end 0.1778 0.5715)
						)
					)
					(width 0)
					(fill yes)
				)
			)
		)
	)
	(footprint ""
		(layer "F.Cu")
		(at 314.94603 -293.906956)
		(property "Reference" "Q293"
			(at 0 0 0)
			(layer "F.SilkS")
			(hide yes)
			(effects
				(font
					(size 1.27 1.27)
				)
			)
		)
		(property "Value" "SSM3K324R-GP"
			(at 0.127 -8.9662 0)
			(unlocked yes)
			(layer "F.Fab")
			(hide yes)
			(effects
				(font
					(size 1.016 1.016)
					(thickness 0.1524)
				)
			)
		)
		(property "Device Type" "SOT23DGS2D4H35"
			(at 0.127 -10.4902 0)
			(unlocked yes)
			(layer "F.Fab")
			(hide yes)
			(effects
				(font
					(size 1.016 1.016)
					(thickness 0.1524)
				)
			)
		)
		(duplicate_pad_numbers_are_jumpers no)
		(fp_line
			(start -1.651 -1.778)
			(end -1.651 1.778)
			(stroke
				(width 0.1524)
				(type default)
			)
			(layer "F.SilkS")
		)
		(fp_line
			(start -1.651 1.778)
			(end 1.651 1.778)
			(stroke
				(width 0.1524)
				(type default)
			)
			(layer "F.SilkS")
		)
		(fp_line
			(start 1.651 -1.778)
			(end -1.651 -1.778)
			(stroke
				(width 0.1524)
				(type default)
			)
			(layer "F.SilkS")
		)
		(fp_line
			(start 1.651 1.778)
			(end 1.651 -1.778)
			(stroke
				(width 0.1524)
				(type default)
			)
			(layer "F.SilkS")
		)
		(fp_poly
			(pts
				(xy -1.778 1.8796) (xy -1.778 -1.8796) (xy 1.778 -1.8796) (xy 1.778 1.8796)
			)
			(stroke
				(width 0)
				(type default)
			)
			(fill no)
			(layer "F.CrtYd")
		)
		(fp_poly
			(pts
				(xy -1.778 1.8796) (xy -1.778 -1.8796) (xy 1.778 -1.8796) (xy 1.778 1.8796)
			)
			(stroke
				(width 0)
				(type default)
			)
			(fill no)
			(layer "F.Fab")
		)
		(pad "D" smd custom
			(at 0 -0.9525)
			(size 0.1905 0.1905)
			(layers "F.Cu" "F.Mask" "F.Paste")
			(net "DRV_ACT_30_N")
			(options
				(clearance outline)
				(anchor circle)
			)
			(primitives
				(gr_poly
					(pts
						(arc
							(start -0.1778 0.5715)
							(mid -0.321484 0.511984)
							(end -0.381 0.3683)
						)
						(arc
							(start -0.381 -0.3683)
							(mid -0.321484 -0.511984)
							(end -0.1778 -0.5715)
						)
						(arc
							(start 0.1778 -0.5715)
							(mid 0.321484 -0.511984)
							(end 0.381 -0.3683)
						)
						(arc
							(start 0.381 0.3683)
							(mid 0.321484 0.511984)
							(end 0.1778 0.5715)
						)
					)
					(width 0)
					(fill yes)
				)
			)
		)
		(pad "G" smd custom
			(at -0.98425 0.9525)
			(size 0.1905 0.1905)
			(layers "F.Cu" "F.Mask" "F.Paste")
			(net "DRIVE_B_30_ACT")
			(options
				(clearance outline)
				(anchor circle)
			)
			(primitives
				(gr_poly
					(pts
						(arc
							(start -0.1778 0.5715)
							(mid -0.321484 0.511984)
							(end -0.381 0.3683)
						)
						(arc
							(start -0.381 -0.3683)
							(mid -0.321484 -0.511984)
							(end -0.1778 -0.5715)
						)
						(arc
							(start 0.1778 -0.5715)
							(mid 0.321484 -0.511984)
							(end 0.381 -0.3683)
						)
						(arc
							(start 0.381 0.3683)
							(mid 0.321484 0.511984)
							(end 0.1778 0.5715)
						)
					)
					(width 0)
					(fill yes)
				)
			)
		)
		(pad "S" smd custom
			(at 0.98425 0.9525)
			(size 0.1905 0.1905)
			(layers "F.Cu" "F.Mask" "F.Paste")
			(net "GND")
			(options
				(clearance outline)
				(anchor circle)
			)
			(primitives
				(gr_poly
					(pts
						(arc
							(start -0.1778 0.5715)
							(mid -0.321484 0.511984)
							(end -0.381 0.3683)
						)
						(arc
							(start -0.381 -0.3683)
							(mid -0.321484 -0.511984)
							(end -0.1778 -0.5715)
						)
						(arc
							(start 0.1778 -0.5715)
							(mid 0.321484 -0.511984)
							(end 0.381 -0.3683)
						)
						(arc
							(start 0.381 0.3683)
							(mid 0.321484 0.511984)
							(end 0.1778 0.5715)
						)
					)
					(width 0)
					(fill yes)
				)
			)
		)
	)
	(footprint ""
		(layer "F.Cu")
		(at 256.2098 -290.195 180)
		(property "Reference" "R7"
			(at 0 0 180)
			(layer "F.SilkS")
			(hide yes)
			(effects
				(font
					(size 1.27 1.27)
				)
			)
		)
		(property "Value" "4K7R2F-GP"
			(at 0.064008 -3.993896 180)
			(unlocked yes)
			(layer "F.Fab")
			(hide yes)
			(effects
				(font
					(size 1.016 1.016)
					(thickness 0.1524)
				)
			)
		)
		(property "Device Type" "R402H16"
			(at 0.064008 -5.517896 180)
			(unlocked yes)
			(layer "F.Fab")
			(hide yes)
			(effects
				(font
					(size 1.016 1.016)
					(thickness 0.1524)
				)
			)
		)
		(duplicate_pad_numbers_are_jumpers no)
		(fp_line
			(start 0.508 -0.9398)
			(end -0.508 -0.9398)
			(stroke
				(width 0.1524)
				(type default)
			)
			(layer "F.SilkS")
		)
		(fp_line
			(start -0.508 -0.9398)
			(end -0.508 0.9398)
			(stroke
				(width 0.1524)
				(type default)
			)
			(layer "F.SilkS")
		)
		(fp_rect
			(start -0.508 0.9398)
			(end 0.508 -0.9398)
			(stroke
				(width 0)
				(type default)
			)
			(fill no)
			(layer "F.CrtYd")
		)
		(fp_rect
			(start -0.508 0.9398)
			(end 0.508 -0.9398)
			(stroke
				(width 0)
				(type default)
			)
			(fill no)
			(layer "F.Fab")
		)
		(pad "1" smd custom
			(at 0 -0.4445 180)
			(size 0.1397 0.1397)
			(layers "F.Cu" "F.Mask" "F.Paste")
			(net "P3V3_STBY_A")
			(options
				(clearance outline)
				(anchor circle)
			)
			(primitives
				(gr_poly
					(pts
						(arc
							(start -0.1778 -0.2794)
							(mid -0.249642 -0.249642)
							(end -0.2794 -0.1778)
						)
						(arc
							(start -0.2794 0.1778)
							(mid -0.249642 0.249642)
							(end -0.1778 0.2794)
						)
						(arc
							(start 0.1778 0.2794)
							(mid 0.249642 0.249642)
							(end 0.2794 0.1778)
						)
						(arc
							(start 0.2794 -0.1778)
							(mid 0.249642 -0.249642)
							(end 0.1778 -0.2794)
						)
					)
					(width 0)
					(fill yes)
				)
			)
		)
		(pad "2" smd custom
			(at 0 0.4445 180)
			(size 0.1397 0.1397)
			(layers "F.Cu" "F.Mask" "F.Paste")
			(net "EEPROM_A1")
			(options
				(clearance outline)
				(anchor circle)
			)
			(primitives
				(gr_poly
					(pts
						(arc
							(start -0.1778 -0.2794)
							(mid -0.249642 -0.249642)
							(end -0.2794 -0.1778)
						)
						(arc
							(start -0.2794 0.1778)
							(mid -0.249642 0.249642)
							(end -0.1778 0.2794)
						)
						(arc
							(start 0.1778 0.2794)
							(mid 0.249642 0.249642)
							(end 0.2794 0.1778)
						)
						(arc
							(start 0.2794 -0.1778)
							(mid 0.249642 -0.249642)
							(end 0.1778 -0.2794)
						)
					)
					(width 0)
					(fill yes)
				)
			)
		)
	)
	(footprint ""
		(layer "F.Cu")
		(at 427.009052 -65.826894 180)
		(property "Reference" "C470"
			(at 0 0 180)
			(layer "F.SilkS")
			(hide yes)
			(effects
				(font
					(size 1.27 1.27)
				)
			)
		)
		(property "Value" "SC10U16V6KX-2GP"
			(at -0.0762 -5.1308 180)
			(unlocked yes)
			(layer "F.Fab")
			(hide yes)
			(effects
				(font
					(size 1.016 1.016)
					(thickness 0.1524)
				)
			)
		)
		(property "Device Type" "C1206H71"
			(at -0.127 -6.6548 180)
			(unlocked yes)
			(layer "F.Fab")
			(hide yes)
			(effects
				(font
					(size 1.016 1.016)
					(thickness 0.1524)
				)
			)
		)
		(duplicate_pad_numbers_are_jumpers no)
		(fp_line
			(start 1.016 2.2352)
			(end -1.016 2.2352)
			(stroke
				(width 0.1524)
				(type default)
			)
			(layer "F.SilkS")
		)
		(fp_line
			(start 1.016 0.8382)
			(end 1.016 2.2352)
			(stroke
				(width 0.1524)
				(type default)
			)
			(layer "F.SilkS")
		)
		(fp_line
			(start 1.016 -2.2352)
			(end 1.016 -0.8382)
			(stroke
				(width 0.1524)
				(type default)
			)
			(layer "F.SilkS")
		)
		(fp_line
			(start -1.016 2.2352)
			(end -1.016 0.8382)
			(stroke
				(width 0.1524)
				(type default)
			)
			(layer "F.SilkS")
		)
		(fp_line
			(start -1.016 -0.8382)
			(end -1.016 -2.2352)
			(stroke
				(width 0.1524)
				(type default)
			)
			(layer "F.SilkS")
		)
		(fp_line
			(start -1.016 -2.2352)
			(end 1.016 -2.2352)
			(stroke
				(width 0.1524)
				(type default)
			)
			(layer "F.SilkS")
		)
		(fp_rect
			(start -1.0922 2.3114)
			(end 1.0922 -2.3114)
			(stroke
				(width 0)
				(type default)
			)
			(fill no)
			(layer "F.CrtYd")
		)
		(fp_poly
			(pts
				(xy 1.0922 -2.3114) (xy 1.0922 2.3114) (xy -1.0922 2.3114) (xy -1.0922 -2.3114)
			)
			(stroke
				(width 0)
				(type default)
			)
			(fill no)
			(layer "F.Fab")
		)
		(pad "1" smd rect
			(at 0 -1.397 180)
			(size 1.651 1.27)
			(layers "F.Cu" "F.Mask" "F.Paste")
			(net "P5V_HDD33")
		)
		(pad "2" smd rect
			(at 0 1.397 180)
			(size 1.651 1.27)
			(layers "F.Cu" "F.Mask" "F.Paste")
			(net "GND")
		)
	)
	(footprint ""
		(layer "F.Cu")
		(at 475.784926 -55.285894 180)
		(property "Reference" "Q209"
			(at 0 0 180)
			(layer "F.SilkS")
			(hide yes)
			(effects
				(font
					(size 1.27 1.27)
				)
			)
		)
		(property "Value" "AO4406AL-GP"
			(at -3.707384 -1.5367 180)
			(unlocked yes)
			(layer "F.Fab")
			(hide yes)
			(effects
				(font
					(size 1.016 1.016)
					(thickness 0.1524)
				)
			)
		)
		(property "Device Type" "SOIC8H69"
			(at -3.707384 -3.0607 180)
			(unlocked yes)
			(layer "F.Fab")
			(hide yes)
			(effects
				(font
					(size 1.016 1.016)
					(thickness 0.1524)
				)
			)
		)
		(duplicate_pad_numbers_are_jumpers no)
		(fp_line
			(start 2.1336 1.4224)
			(end 2.1336 -1.4224)
			(stroke
				(width 0.1524)
				(type default)
			)
			(layer "F.SilkS")
		)
		(fp_line
			(start 2.1336 -1.4224)
			(end -2.7432 -1.4224)
			(stroke
				(width 0.1524)
				(type default)
			)
			(layer "F.SilkS")
		)
		(fp_line
			(start -2.1844 -0.0508)
			(end -2.7178 0.508)
			(stroke
				(width 0.1524)
				(type default)
			)
			(layer "F.SilkS")
		)
		(fp_line
			(start -2.6289 3.4417)
			(end -2.6289 1.4732)
			(stroke
				(width 0.381)
				(type default)
			)
			(layer "F.SilkS")
		)
		(fp_line
			(start -2.7178 -0.508)
			(end -2.1844 -0.0508)
			(stroke
				(width 0.1524)
				(type default)
			)
			(layer "F.SilkS")
		)
		(fp_line
			(start -2.7432 1.4224)
			(end 2.1336 1.4224)
			(stroke
				(width 0.1524)
				(type default)
			)
			(layer "F.SilkS")
		)
		(fp_line
			(start -2.7432 1.4224)
			(end -2.6416 1.4224)
			(stroke
				(width 0.1524)
				(type default)
			)
			(layer "F.SilkS")
		)
		(fp_line
			(start -2.7432 -1.4224)
			(end -2.7432 1.4224)
			(stroke
				(width 0.1524)
				(type default)
			)
			(layer "F.SilkS")
		)
		(fp_poly
			(pts
				(xy -2.2098 -1.4224) (xy -2.2098 1.4224) (xy 2.2098 1.4224) (xy 2.2098 -1.4224)
			)
			(stroke
				(width 0)
				(type default)
			)
			(fill yes)
			(layer "F.SilkS")
		)
		(fp_rect
			(start -2.450084 2.999994)
			(end 2.450084 -2.999994)
			(stroke
				(width 0)
				(type default)
			)
			(fill no)
			(layer "F.CrtYd")
		)
		(fp_poly
			(pts
				(xy -2.8194 3.6322) (xy -2.8194 -3.6322) (xy 2.8194 -3.6322) (xy 2.8194 1.18364) (xy 2.450084 1.18364)
				(xy 2.450084 -2.999994) (xy -2.450084 -2.999994) (xy -2.450084 2.999994) (xy 2.450084 2.999994)
				(xy 2.450084 1.18618) (xy 2.8194 1.18618) (xy 2.8194 3.6322)
			)
			(stroke
				(width 0)
				(type default)
			)
			(fill no)
			(layer "F.CrtYd")
		)
		(fp_rect
			(start -2.8194 3.6322)
			(end 2.8194 -3.6322)
			(stroke
				(width 0)
				(type default)
			)
			(fill no)
			(layer "F.Fab")
		)
		(pad "1" smd rect
			(at -1.905 2.54 180)
			(size 0.635 1.651)
			(layers "F.Cu" "F.Mask" "F.Paste")
			(net "P5V_HDD35")
		)
		(pad "2" smd rect
			(at -0.635 2.54 180)
			(size 0.635 1.651)
			(layers "F.Cu" "F.Mask" "F.Paste")
			(net "P5V_HDD35")
		)
		(pad "3" smd rect
			(at 0.635 2.54 180)
			(size 0.635 1.651)
			(layers "F.Cu" "F.Mask" "F.Paste")
			(net "P5V_HDD35")
		)
		(pad "4" smd rect
			(at 1.905 2.54 180)
			(size 0.635 1.651)
			(layers "F.Cu" "F.Mask" "F.Paste")
			(net "SW_HDD_P35")
		)
		(pad "5" smd rect
			(at 1.905 -2.54 180)
			(size 0.635 1.651)
			(layers "F.Cu" "F.Mask" "F.Paste")
			(net "P5V_A_4")
		)
		(pad "6" smd rect
			(at 0.635 -2.54 180)
			(size 0.635 1.651)
			(layers "F.Cu" "F.Mask" "F.Paste")
			(net "P5V_A_4")
		)
		(pad "7" smd rect
			(at -0.635 -2.54 180)
			(size 0.635 1.651)
			(layers "F.Cu" "F.Mask" "F.Paste")
			(net "P5V_A_4")
		)
		(pad "8" smd rect
			(at -1.905 -2.54 180)
			(size 0.635 1.651)
			(layers "F.Cu" "F.Mask" "F.Paste")
			(net "P5V_A_4")
		)
	)
	(footprint ""
		(layer "F.Cu")
		(at 368.3508 -133.6294 90)
		(property "Reference" "R1092"
			(at 0 0 90)
			(layer "F.SilkS")
			(hide yes)
			(effects
				(font
					(size 1.27 1.27)
				)
			)
		)
		(property "Value" "100KR2F-L1-GP"
			(at 0.064008 -3.993896 90)
			(unlocked yes)
			(layer "F.Fab")
			(hide yes)
			(effects
				(font
					(size 1.016 1.016)
					(thickness 0.1524)
				)
			)
		)
		(property "Device Type" "R402H16"
			(at 0.064008 -5.517896 90)
			(unlocked yes)
			(layer "F.Fab")
			(hide yes)
			(effects
				(font
					(size 1.016 1.016)
					(thickness 0.1524)
				)
			)
		)
		(duplicate_pad_numbers_are_jumpers no)
		(fp_line
			(start 0.508 -0.9398)
			(end -0.508 -0.9398)
			(stroke
				(width 0.1524)
				(type default)
			)
			(layer "F.SilkS")
		)
		(fp_line
			(start -0.508 -0.9398)
			(end -0.508 0.9398)
			(stroke
				(width 0.1524)
				(type default)
			)
			(layer "F.SilkS")
		)
		(fp_rect
			(start -0.508 0.9398)
			(end 0.508 -0.9398)
			(stroke
				(width 0)
				(type default)
			)
			(fill no)
			(layer "F.CrtYd")
		)
		(fp_rect
			(start -0.508 0.9398)
			(end 0.508 -0.9398)
			(stroke
				(width 0)
				(type default)
			)
			(fill no)
			(layer "F.Fab")
		)
		(pad "1" smd custom
			(at 0 -0.4445 90)
			(size 0.1397 0.1397)
			(layers "F.Cu" "F.Mask" "F.Paste")
			(net "MB1_VCAP_R")
			(options
				(clearance outline)
				(anchor circle)
			)
			(primitives
				(gr_poly
					(pts
						(arc
							(start -0.1778 -0.2794)
							(mid -0.249642 -0.249642)
							(end -0.2794 -0.1778)
						)
						(arc
							(start -0.2794 0.1778)
							(mid -0.249642 0.249642)
							(end -0.1778 0.2794)
						)
						(arc
							(start 0.1778 0.2794)
							(mid 0.249642 0.249642)
							(end 0.2794 0.1778)
						)
						(arc
							(start 0.2794 -0.1778)
							(mid 0.249642 -0.249642)
							(end 0.1778 -0.2794)
						)
					)
					(width 0)
					(fill yes)
				)
			)
		)
		(pad "2" smd custom
			(at 0 0.4445 90)
			(size 0.1397 0.1397)
			(layers "F.Cu" "F.Mask" "F.Paste")
			(net "MB1_ISET_R")
			(options
				(clearance outline)
				(anchor circle)
			)
			(primitives
				(gr_poly
					(pts
						(arc
							(start -0.1778 -0.2794)
							(mid -0.249642 -0.249642)
							(end -0.2794 -0.1778)
						)
						(arc
							(start -0.2794 0.1778)
							(mid -0.249642 0.249642)
							(end -0.1778 0.2794)
						)
						(arc
							(start 0.1778 0.2794)
							(mid 0.249642 0.249642)
							(end 0.2794 0.1778)
						)
						(arc
							(start 0.2794 -0.1778)
							(mid 0.249642 -0.249642)
							(end 0.1778 -0.2794)
						)
					)
					(width 0)
					(fill yes)
				)
			)
		)
	)
	(footprint ""
		(layer "F.Cu")
		(at 222.631 -119.6594 -90)
		(property "Reference" "R618"
			(at 0 0 270)
			(layer "F.SilkS")
			(hide yes)
			(effects
				(font
					(size 1.27 1.27)
				)
			)
		)
		(property "Value" "4K7R2F-GP"
			(at 0.064008 -3.993896 270)
			(unlocked yes)
			(layer "F.Fab")
			(hide yes)
			(effects
				(font
					(size 1.016 1.016)
					(thickness 0.1524)
				)
			)
		)
		(property "Device Type" "R402H16"
			(at 0.064008 -5.517896 270)
			(unlocked yes)
			(layer "F.Fab")
			(hide yes)
			(effects
				(font
					(size 1.016 1.016)
					(thickness 0.1524)
				)
			)
		)
		(duplicate_pad_numbers_are_jumpers no)
		(fp_line
			(start -0.508 -0.9398)
			(end -0.508 0.9398)
			(stroke
				(width 0.1524)
				(type default)
			)
			(layer "F.SilkS")
		)
		(fp_line
			(start 0.508 -0.9398)
			(end -0.508 -0.9398)
			(stroke
				(width 0.1524)
				(type default)
			)
			(layer "F.SilkS")
		)
		(fp_rect
			(start -0.508 0.9398)
			(end 0.508 -0.9398)
			(stroke
				(width 0)
				(type default)
			)
			(fill no)
			(layer "F.CrtYd")
		)
		(fp_rect
			(start -0.508 0.9398)
			(end 0.508 -0.9398)
			(stroke
				(width 0)
				(type default)
			)
			(fill no)
			(layer "F.Fab")
		)
		(pad "1" smd custom
			(at 0 -0.4445 270)
			(size 0.1397 0.1397)
			(layers "F.Cu" "F.Mask" "F.Paste")
			(net "COMP_A_BMC_A_ALERT_N")
			(options
				(clearance outline)
				(anchor circle)
			)
			(primitives
				(gr_poly
					(pts
						(arc
							(start -0.1778 -0.2794)
							(mid -0.249642 -0.249642)
							(end -0.2794 -0.1778)
						)
						(arc
							(start -0.2794 0.1778)
							(mid -0.249642 0.249642)
							(end -0.1778 0.2794)
						)
						(arc
							(start 0.1778 0.2794)
							(mid 0.249642 0.249642)
							(end 0.2794 0.1778)
						)
						(arc
							(start 0.2794 -0.1778)
							(mid 0.249642 -0.249642)
							(end 0.1778 -0.2794)
						)
					)
					(width 0)
					(fill yes)
				)
			)
		)
		(pad "2" smd custom
			(at 0 0.4445 270)
			(size 0.1397 0.1397)
			(layers "F.Cu" "F.Mask" "F.Paste")
			(net "P3V3_STBY_A")
			(options
				(clearance outline)
				(anchor circle)
			)
			(primitives
				(gr_poly
					(pts
						(arc
							(start -0.1778 -0.2794)
							(mid -0.249642 -0.249642)
							(end -0.2794 -0.1778)
						)
						(arc
							(start -0.2794 0.1778)
							(mid -0.249642 0.249642)
							(end -0.1778 0.2794)
						)
						(arc
							(start 0.1778 0.2794)
							(mid 0.249642 0.249642)
							(end 0.2794 0.1778)
						)
						(arc
							(start 0.2794 -0.1778)
							(mid 0.249642 -0.249642)
							(end 0.1778 -0.2794)
						)
					)
					(width 0)
					(fill yes)
				)
			)
		)
	)
	(footprint ""
		(layer "F.Cu")
		(at 77.942948 -54.523894 90)
		(property "Reference" "C387"
			(at 0 0 90)
			(layer "F.SilkS")
			(hide yes)
			(effects
				(font
					(size 1.27 1.27)
				)
			)
		)
		(property "Value" "SCD033U25V2KX-GP"
			(at 1.1811 -2.7051 90)
			(unlocked yes)
			(layer "F.Fab")
			(hide yes)
			(effects
				(font
					(size 1.016 1.016)
					(thickness 0.1524)
				)
			)
		)
		(property "Device Type" "C402H22"
			(at 1.1811 -4.2291 90)
			(unlocked yes)
			(layer "F.Fab")
			(hide yes)
			(effects
				(font
					(size 1.016 1.016)
					(thickness 0.1524)
				)
			)
		)
		(duplicate_pad_numbers_are_jumpers no)
		(fp_rect
			(start -0.4318 0.9525)
			(end 0.4318 -0.9525)
			(stroke
				(width 0)
				(type default)
			)
			(fill no)
			(layer "F.CrtYd")
		)
		(fp_rect
			(start -0.4318 0.9525)
			(end 0.4318 -0.9525)
			(stroke
				(width 0)
				(type default)
			)
			(fill no)
			(layer "F.Fab")
		)
		(pad "1" smd custom
			(at 0 -0.4445 90)
			(size 0.1524 0.1524)
			(layers "F.Cu" "F.Mask" "F.Paste")
			(net "P12V_A")
			(options
				(clearance outline)
				(anchor circle)
			)
			(primitives
				(gr_poly
					(pts
						(arc
							(start 0.3048 -0.2032)
							(mid 0.275042 -0.275042)
							(end 0.2032 -0.3048)
						)
						(arc
							(start -0.2032 -0.3048)
							(mid -0.275042 -0.275042)
							(end -0.3048 -0.2032)
						)
						(arc
							(start -0.3048 0.2032)
							(mid -0.275042 0.275042)
							(end -0.2032 0.3048)
						)
						(arc
							(start 0.2032 0.3048)
							(mid 0.275042 0.275042)
							(end 0.3048 0.2032)
						)
					)
					(width 0)
					(fill yes)
				)
			)
		)
		(pad "2" smd custom
			(at 0 0.4445 90)
			(size 0.1524 0.1524)
			(layers "F.Cu" "F.Mask" "F.Paste")
			(net "SW_HDD_N26")
			(options
				(clearance outline)
				(anchor circle)
			)
			(primitives
				(gr_poly
					(pts
						(arc
							(start 0.3048 -0.2032)
							(mid 0.275042 -0.275042)
							(end 0.2032 -0.3048)
						)
						(arc
							(start -0.2032 -0.3048)
							(mid -0.275042 -0.275042)
							(end -0.3048 -0.2032)
						)
						(arc
							(start -0.3048 0.2032)
							(mid -0.275042 0.275042)
							(end -0.2032 0.3048)
						)
						(arc
							(start 0.2032 0.3048)
							(mid 0.275042 0.275042)
							(end 0.3048 0.2032)
						)
					)
					(width 0)
					(fill yes)
				)
			)
		)
	)
	(footprint ""
		(layer "F.Cu")
		(at 35.797998 -62.169294 -90)
		(property "Reference" "R682"
			(at 0 0 270)
			(layer "F.SilkS")
			(hide yes)
			(effects
				(font
					(size 1.27 1.27)
				)
			)
		)
		(property "Value" "10KR2F-2-GP"
			(at 0.064008 -3.993896 270)
			(unlocked yes)
			(layer "F.Fab")
			(hide yes)
			(effects
				(font
					(size 1.016 1.016)
					(thickness 0.1524)
				)
			)
		)
		(property "Device Type" "R402H16"
			(at 0.064008 -5.517896 270)
			(unlocked yes)
			(layer "F.Fab")
			(hide yes)
			(effects
				(font
					(size 1.016 1.016)
					(thickness 0.1524)
				)
			)
		)
		(duplicate_pad_numbers_are_jumpers no)
		(fp_line
			(start -0.508 -0.9398)
			(end -0.508 0.9398)
			(stroke
				(width 0.1524)
				(type default)
			)
			(layer "F.SilkS")
		)
		(fp_line
			(start 0.508 -0.9398)
			(end -0.508 -0.9398)
			(stroke
				(width 0.1524)
				(type default)
			)
			(layer "F.SilkS")
		)
		(fp_rect
			(start -0.508 0.9398)
			(end 0.508 -0.9398)
			(stroke
				(width 0)
				(type default)
			)
			(fill no)
			(layer "F.CrtYd")
		)
		(fp_rect
			(start -0.508 0.9398)
			(end 0.508 -0.9398)
			(stroke
				(width 0)
				(type default)
			)
			(fill no)
			(layer "F.Fab")
		)
		(pad "1" smd custom
			(at 0 -0.4445 270)
			(size 0.1397 0.1397)
			(layers "F.Cu" "F.Mask" "F.Paste")
			(net "P3V3_STBY_A")
			(options
				(clearance outline)
				(anchor circle)
			)
			(primitives
				(gr_poly
					(pts
						(arc
							(start -0.1778 -0.2794)
							(mid -0.249642 -0.249642)
							(end -0.2794 -0.1778)
						)
						(arc
							(start -0.2794 0.1778)
							(mid -0.249642 0.249642)
							(end -0.1778 0.2794)
						)
						(arc
							(start 0.1778 0.2794)
							(mid 0.249642 0.249642)
							(end 0.2794 0.1778)
						)
						(arc
							(start 0.2794 -0.1778)
							(mid 0.249642 -0.249642)
							(end 0.1778 -0.2794)
						)
					)
					(width 0)
					(fill yes)
				)
			)
		)
		(pad "2" smd custom
			(at 0 0.4445 270)
			(size 0.1397 0.1397)
			(layers "F.Cu" "F.Mask" "F.Paste")
			(net "HDD_PRSNT_24")
			(options
				(clearance outline)
				(anchor circle)
			)
			(primitives
				(gr_poly
					(pts
						(arc
							(start -0.1778 -0.2794)
							(mid -0.249642 -0.249642)
							(end -0.2794 -0.1778)
						)
						(arc
							(start -0.2794 0.1778)
							(mid -0.249642 0.249642)
							(end -0.1778 0.2794)
						)
						(arc
							(start 0.1778 0.2794)
							(mid 0.249642 0.249642)
							(end 0.2794 0.1778)
						)
						(arc
							(start 0.2794 -0.1778)
							(mid 0.249642 -0.249642)
							(end 0.1778 -0.2794)
						)
					)
					(width 0)
					(fill yes)
				)
			)
		)
	)
	(footprint ""
		(layer "F.Cu")
		(at 146.630898 -177.778918 -90)
		(property "Reference" "C248"
			(at 0 0 270)
			(layer "F.SilkS")
			(hide yes)
			(effects
				(font
					(size 1.27 1.27)
				)
			)
		)
		(property "Value" "SC1U16V3KX-5GP"
			(at 0 -2.8194 270)
			(unlocked yes)
			(layer "F.Fab")
			(hide yes)
			(effects
				(font
					(size 1.016 1.016)
					(thickness 0.1524)
				)
			)
		)
		(property "Device Type" "C603H36"
			(at 0 -4.3434 270)
			(unlocked yes)
			(layer "F.Fab")
			(hide yes)
			(effects
				(font
					(size 1.016 1.016)
					(thickness 0.1524)
				)
			)
		)
		(duplicate_pad_numbers_are_jumpers no)
		(fp_line
			(start 0.508 0)
			(end -0.508 0)
			(stroke
				(width 0.2032)
				(type default)
			)
			(layer "F.SilkS")
		)
		(fp_rect
			(start -0.5842 1.3335)
			(end 0.5842 -1.3335)
			(stroke
				(width 0)
				(type default)
			)
			(fill no)
			(layer "F.CrtYd")
		)
		(fp_rect
			(start -0.5842 1.3335)
			(end 0.5842 -1.3335)
			(stroke
				(width 0)
				(type default)
			)
			(fill no)
			(layer "F.Fab")
		)
		(pad "1" smd custom
			(at 0 -0.762 270)
			(size 0.2159 0.2159)
			(layers "F.Cu" "F.Mask" "F.Paste")
			(net "P5V_HDD16")
			(options
				(clearance outline)
				(anchor circle)
			)
			(primitives
				(gr_poly
					(pts
						(arc
							(start -0.3302 -0.4318)
							(mid -0.402042 -0.402042)
							(end -0.4318 -0.3302)
						)
						(arc
							(start -0.4318 0.3302)
							(mid -0.402042 0.402042)
							(end -0.3302 0.4318)
						)
						(arc
							(start 0.3302 0.4318)
							(mid 0.402042 0.402042)
							(end 0.4318 0.3302)
						)
						(arc
							(start 0.4318 -0.3302)
							(mid 0.402042 -0.402042)
							(end 0.3302 -0.4318)
						)
					)
					(width 0)
					(fill yes)
				)
			)
		)
		(pad "2" smd custom
			(at 0 0.762 270)
			(size 0.2159 0.2159)
			(layers "F.Cu" "F.Mask" "F.Paste")
			(net "GND")
			(options
				(clearance outline)
				(anchor circle)
			)
			(primitives
				(gr_poly
					(pts
						(arc
							(start -0.3302 -0.4318)
							(mid -0.402042 -0.402042)
							(end -0.4318 -0.3302)
						)
						(arc
							(start -0.4318 0.3302)
							(mid -0.402042 0.402042)
							(end -0.3302 0.4318)
						)
						(arc
							(start 0.3302 0.4318)
							(mid 0.402042 0.402042)
							(end 0.4318 0.3302)
						)
						(arc
							(start 0.4318 -0.3302)
							(mid 0.402042 -0.402042)
							(end 0.3302 -0.4318)
						)
					)
					(width 0)
					(fill yes)
				)
			)
		)
	)
	(footprint ""
		(layer "F.Cu")
		(at 101.1555 -185.042302)
		(property "Reference" "Q266"
			(at 0 0 0)
			(layer "F.SilkS")
			(hide yes)
			(effects
				(font
					(size 1.27 1.27)
				)
			)
		)
		(property "Value" "SSM3K324R-GP"
			(at 0.127 -8.9662 0)
			(unlocked yes)
			(layer "F.Fab")
			(hide yes)
			(effects
				(font
					(size 1.016 1.016)
					(thickness 0.1524)
				)
			)
		)
		(property "Device Type" "SOT23DGS2D4H35"
			(at 0.127 -10.4902 0)
			(unlocked yes)
			(layer "F.Fab")
			(hide yes)
			(effects
				(font
					(size 1.016 1.016)
					(thickness 0.1524)
				)
			)
		)
		(duplicate_pad_numbers_are_jumpers no)
		(fp_line
			(start -1.651 -1.778)
			(end -1.651 1.778)
			(stroke
				(width 0.1524)
				(type default)
			)
			(layer "F.SilkS")
		)
		(fp_line
			(start -1.651 1.778)
			(end 1.651 1.778)
			(stroke
				(width 0.1524)
				(type default)
			)
			(layer "F.SilkS")
		)
		(fp_line
			(start 1.651 -1.778)
			(end -1.651 -1.778)
			(stroke
				(width 0.1524)
				(type default)
			)
			(layer "F.SilkS")
		)
		(fp_line
			(start 1.651 1.778)
			(end 1.651 -1.778)
			(stroke
				(width 0.1524)
				(type default)
			)
			(layer "F.SilkS")
		)
		(fp_poly
			(pts
				(xy -1.778 1.8796) (xy -1.778 -1.8796) (xy 1.778 -1.8796) (xy 1.778 1.8796)
			)
			(stroke
				(width 0)
				(type default)
			)
			(fill no)
			(layer "F.CrtYd")
		)
		(fp_poly
			(pts
				(xy -1.778 1.8796) (xy -1.778 -1.8796) (xy 1.778 -1.8796) (xy 1.778 1.8796)
			)
			(stroke
				(width 0)
				(type default)
			)
			(fill no)
			(layer "F.Fab")
		)
		(pad "D" smd custom
			(at 0 -0.9525)
			(size 0.1905 0.1905)
			(layers "F.Cu" "F.Mask" "F.Paste")
			(net "DRV_ACT_3_N")
			(options
				(clearance outline)
				(anchor circle)
			)
			(primitives
				(gr_poly
					(pts
						(arc
							(start -0.1778 0.5715)
							(mid -0.321484 0.511984)
							(end -0.381 0.3683)
						)
						(arc
							(start -0.381 -0.3683)
							(mid -0.321484 -0.511984)
							(end -0.1778 -0.5715)
						)
						(arc
							(start 0.1778 -0.5715)
							(mid 0.321484 -0.511984)
							(end 0.381 -0.3683)
						)
						(arc
							(start 0.381 0.3683)
							(mid 0.321484 0.511984)
							(end 0.1778 0.5715)
						)
					)
					(width 0)
					(fill yes)
				)
			)
		)
		(pad "G" smd custom
			(at -0.98425 0.9525)
			(size 0.1905 0.1905)
			(layers "F.Cu" "F.Mask" "F.Paste")
			(net "DRIVE_A_3_ACT")
			(options
				(clearance outline)
				(anchor circle)
			)
			(primitives
				(gr_poly
					(pts
						(arc
							(start -0.1778 0.5715)
							(mid -0.321484 0.511984)
							(end -0.381 0.3683)
						)
						(arc
							(start -0.381 -0.3683)
							(mid -0.321484 -0.511984)
							(end -0.1778 -0.5715)
						)
						(arc
							(start 0.1778 -0.5715)
							(mid 0.321484 -0.511984)
							(end 0.381 -0.3683)
						)
						(arc
							(start 0.381 0.3683)
							(mid 0.321484 0.511984)
							(end 0.1778 0.5715)
						)
					)
					(width 0)
					(fill yes)
				)
			)
		)
		(pad "S" smd custom
			(at 0.98425 0.9525)
			(size 0.1905 0.1905)
			(layers "F.Cu" "F.Mask" "F.Paste")
			(net "GND")
			(options
				(clearance outline)
				(anchor circle)
			)
			(primitives
				(gr_poly
					(pts
						(arc
							(start -0.1778 0.5715)
							(mid -0.321484 0.511984)
							(end -0.381 0.3683)
						)
						(arc
							(start -0.381 -0.3683)
							(mid -0.321484 -0.511984)
							(end -0.1778 -0.5715)
						)
						(arc
							(start 0.1778 -0.5715)
							(mid 0.321484 -0.511984)
							(end 0.381 -0.3683)
						)
						(arc
							(start 0.381 0.3683)
							(mid 0.321484 0.511984)
							(end 0.1778 0.5715)
						)
					)
					(width 0)
					(fill yes)
				)
			)
		)
	)
	(footprint ""
		(layer "F.Cu")
		(at 381.61595 -183.620918)
		(property "Reference" "TP102"
			(at 0 0 0)
			(layer "F.SilkS")
			(hide yes)
			(effects
				(font
					(size 1.27 1.27)
				)
			)
		)
		(property "Value" "TPAD32-GP"
			(at -0.0508 -1.6764 0)
			(unlocked yes)
			(layer "F.Fab")
			(hide yes)
			(effects
				(font
					(size 1.016 1.016)
					(thickness 0.1524)
				)
			)
		)
		(property "Device Type" "TPAD32"
			(at -0.0508 -3.2004 0)
			(unlocked yes)
			(layer "F.Fab")
			(hide yes)
			(effects
				(font
					(size 1.016 1.016)
					(thickness 0.1524)
				)
			)
		)
		(duplicate_pad_numbers_are_jumpers no)
		(fp_poly
			(pts
				(arc
					(start 0.4064 0)
					(mid -0.4064 0)
					(end 0.4064 0)
				)
			)
			(stroke
				(width 0)
				(type default)
			)
			(fill no)
			(layer "F.CrtYd")
		)
		(fp_poly
			(pts
				(arc
					(start 0.7112 0)
					(mid -0.7112 0)
					(end 0.7112 0)
				)
			)
			(stroke
				(width 0)
				(type default)
			)
			(fill no)
			(layer "F.Fab")
		)
		(pad "1" smd circle
			(at 0 0)
			(size 0.8128 0.8128)
			(layers "F.Cu" "F.Mask" "F.Paste")
			(net "ACT_HDD_20")
		)
	)
	(footprint ""
		(layer "F.Cu")
		(at 154.29484 -140.531596)
		(property "Reference" "C553"
			(at 0 0 0)
			(layer "F.SilkS")
			(hide yes)
			(effects
				(font
					(size 1.27 1.27)
				)
			)
		)
		(property "Value" "SC1U16V3KX-5GP"
			(at 0 -2.8194 0)
			(unlocked yes)
			(layer "F.Fab")
			(hide yes)
			(effects
				(font
					(size 1.016 1.016)
					(thickness 0.1524)
				)
			)
		)
		(property "Device Type" "C603H36"
			(at 0 -4.3434 0)
			(unlocked yes)
			(layer "F.Fab")
			(hide yes)
			(effects
				(font
					(size 1.016 1.016)
					(thickness 0.1524)
				)
			)
		)
		(duplicate_pad_numbers_are_jumpers no)
		(fp_line
			(start 0.508 0)
			(end -0.508 0)
			(stroke
				(width 0.2032)
				(type default)
			)
			(layer "F.SilkS")
		)
		(fp_rect
			(start -0.5842 1.3335)
			(end 0.5842 -1.3335)
			(stroke
				(width 0)
				(type default)
			)
			(fill no)
			(layer "F.CrtYd")
		)
		(fp_rect
			(start -0.5842 1.3335)
			(end 0.5842 -1.3335)
			(stroke
				(width 0)
				(type default)
			)
			(fill no)
			(layer "F.Fab")
		)
		(pad "1" smd custom
			(at 0 -0.762)
			(size 0.2159 0.2159)
			(layers "F.Cu" "F.Mask" "F.Paste")
			(net "MB0_CM_UV_R")
			(options
				(clearance outline)
				(anchor circle)
			)
			(primitives
				(gr_poly
					(pts
						(arc
							(start -0.3302 -0.4318)
							(mid -0.402042 -0.402042)
							(end -0.4318 -0.3302)
						)
						(arc
							(start -0.4318 0.3302)
							(mid -0.402042 0.402042)
							(end -0.3302 0.4318)
						)
						(arc
							(start 0.3302 0.4318)
							(mid 0.402042 0.402042)
							(end 0.4318 0.3302)
						)
						(arc
							(start 0.4318 -0.3302)
							(mid 0.402042 -0.402042)
							(end 0.3302 -0.4318)
						)
					)
					(width 0)
					(fill yes)
				)
			)
		)
		(pad "2" smd custom
			(at 0 0.762)
			(size 0.2159 0.2159)
			(layers "F.Cu" "F.Mask" "F.Paste")
			(net "AGND_CURRENT_MONOA")
			(options
				(clearance outline)
				(anchor circle)
			)
			(primitives
				(gr_poly
					(pts
						(arc
							(start -0.3302 -0.4318)
							(mid -0.402042 -0.402042)
							(end -0.4318 -0.3302)
						)
						(arc
							(start -0.4318 0.3302)
							(mid -0.402042 0.402042)
							(end -0.3302 0.4318)
						)
						(arc
							(start 0.3302 0.4318)
							(mid 0.402042 0.402042)
							(end 0.4318 0.3302)
						)
						(arc
							(start 0.4318 -0.3302)
							(mid 0.402042 -0.402042)
							(end 0.3302 -0.4318)
						)
					)
					(width 0)
					(fill yes)
				)
			)
		)
	)
	(footprint ""
		(layer "F.Cu")
		(at 266.24661 -141.491462 -90)
		(property "Reference" "R993"
			(at 0 0 270)
			(layer "F.SilkS")
			(hide yes)
			(effects
				(font
					(size 1.27 1.27)
				)
			)
		)
		(property "Value" "100KR2F-L1-GP"
			(at 0.064008 -3.993896 270)
			(unlocked yes)
			(layer "F.Fab")
			(hide yes)
			(effects
				(font
					(size 1.016 1.016)
					(thickness 0.1524)
				)
			)
		)
		(property "Device Type" "R402H16"
			(at 0.064008 -5.517896 270)
			(unlocked yes)
			(layer "F.Fab")
			(hide yes)
			(effects
				(font
					(size 1.016 1.016)
					(thickness 0.1524)
				)
			)
		)
		(duplicate_pad_numbers_are_jumpers no)
		(fp_line
			(start -0.508 -0.9398)
			(end -0.508 0.9398)
			(stroke
				(width 0.1524)
				(type default)
			)
			(layer "F.SilkS")
		)
		(fp_line
			(start 0.508 -0.9398)
			(end -0.508 -0.9398)
			(stroke
				(width 0.1524)
				(type default)
			)
			(layer "F.SilkS")
		)
		(fp_rect
			(start -0.508 0.9398)
			(end 0.508 -0.9398)
			(stroke
				(width 0)
				(type default)
			)
			(fill no)
			(layer "F.CrtYd")
		)
		(fp_rect
			(start -0.508 0.9398)
			(end 0.508 -0.9398)
			(stroke
				(width 0)
				(type default)
			)
			(fill no)
			(layer "F.Fab")
		)
		(pad "1" smd custom
			(at 0 -0.4445 270)
			(size 0.1397 0.1397)
			(layers "F.Cu" "F.Mask" "F.Paste")
			(net "PCIE_COMP_B_PCIE_RST_1")
			(options
				(clearance outline)
				(anchor circle)
			)
			(primitives
				(gr_poly
					(pts
						(arc
							(start -0.1778 -0.2794)
							(mid -0.249642 -0.249642)
							(end -0.2794 -0.1778)
						)
						(arc
							(start -0.2794 0.1778)
							(mid -0.249642 0.249642)
							(end -0.1778 0.2794)
						)
						(arc
							(start 0.1778 0.2794)
							(mid 0.249642 0.249642)
							(end 0.2794 0.1778)
						)
						(arc
							(start 0.2794 -0.1778)
							(mid 0.249642 -0.249642)
							(end 0.1778 -0.2794)
						)
					)
					(width 0)
					(fill yes)
				)
			)
		)
		(pad "2" smd custom
			(at 0 0.4445 270)
			(size 0.1397 0.1397)
			(layers "F.Cu" "F.Mask" "F.Paste")
			(net "GND")
			(options
				(clearance outline)
				(anchor circle)
			)
			(primitives
				(gr_poly
					(pts
						(arc
							(start -0.1778 -0.2794)
							(mid -0.249642 -0.249642)
							(end -0.2794 -0.1778)
						)
						(arc
							(start -0.2794 0.1778)
							(mid -0.249642 0.249642)
							(end -0.1778 0.2794)
						)
						(arc
							(start 0.1778 0.2794)
							(mid 0.249642 0.249642)
							(end 0.2794 0.1778)
						)
						(arc
							(start 0.2794 -0.1778)
							(mid 0.249642 -0.249642)
							(end 0.1778 -0.2794)
						)
					)
					(width 0)
					(fill yes)
				)
			)
		)
	)
	(footprint ""
		(layer "F.Cu")
		(at 432.724052 -164.443918 90)
		(property "Reference" "R629"
			(at 0 0 90)
			(layer "F.SilkS")
			(hide yes)
			(effects
				(font
					(size 1.27 1.27)
				)
			)
		)
		(property "Value" "200KR2F-L-GP"
			(at 0.064008 -3.993896 90)
			(unlocked yes)
			(layer "F.Fab")
			(hide yes)
			(effects
				(font
					(size 1.016 1.016)
					(thickness 0.1524)
				)
			)
		)
		(property "Device Type" "R402H16"
			(at 0.064008 -5.517896 90)
			(unlocked yes)
			(layer "F.Fab")
			(hide yes)
			(effects
				(font
					(size 1.016 1.016)
					(thickness 0.1524)
				)
			)
		)
		(duplicate_pad_numbers_are_jumpers no)
		(fp_line
			(start 0.508 -0.9398)
			(end -0.508 -0.9398)
			(stroke
				(width 0.1524)
				(type default)
			)
			(layer "F.SilkS")
		)
		(fp_line
			(start -0.508 -0.9398)
			(end -0.508 0.9398)
			(stroke
				(width 0.1524)
				(type default)
			)
			(layer "F.SilkS")
		)
		(fp_rect
			(start -0.508 0.9398)
			(end 0.508 -0.9398)
			(stroke
				(width 0)
				(type default)
			)
			(fill no)
			(layer "F.CrtYd")
		)
		(fp_rect
			(start -0.508 0.9398)
			(end 0.508 -0.9398)
			(stroke
				(width 0)
				(type default)
			)
			(fill no)
			(layer "F.Fab")
		)
		(pad "1" smd custom
			(at 0 -0.4445 90)
			(size 0.1397 0.1397)
			(layers "F.Cu" "F.Mask" "F.Paste")
			(net "SW_HDD_R21")
			(options
				(clearance outline)
				(anchor circle)
			)
			(primitives
				(gr_poly
					(pts
						(arc
							(start -0.1778 -0.2794)
							(mid -0.249642 -0.249642)
							(end -0.2794 -0.1778)
						)
						(arc
							(start -0.2794 0.1778)
							(mid -0.249642 0.249642)
							(end -0.1778 0.2794)
						)
						(arc
							(start 0.1778 0.2794)
							(mid 0.249642 0.249642)
							(end 0.2794 0.1778)
						)
						(arc
							(start 0.2794 -0.1778)
							(mid 0.249642 -0.249642)
							(end 0.1778 -0.2794)
						)
					)
					(width 0)
					(fill yes)
				)
			)
		)
		(pad "2" smd custom
			(at 0 0.4445 90)
			(size 0.1397 0.1397)
			(layers "F.Cu" "F.Mask" "F.Paste")
			(net "SW_HDD_N21")
			(options
				(clearance outline)
				(anchor circle)
			)
			(primitives
				(gr_poly
					(pts
						(arc
							(start -0.1778 -0.2794)
							(mid -0.249642 -0.249642)
							(end -0.2794 -0.1778)
						)
						(arc
							(start -0.2794 0.1778)
							(mid -0.249642 0.249642)
							(end -0.1778 0.2794)
						)
						(arc
							(start 0.1778 0.2794)
							(mid 0.249642 0.249642)
							(end 0.2794 0.1778)
						)
						(arc
							(start 0.2794 -0.1778)
							(mid 0.249642 -0.249642)
							(end 0.1778 -0.2794)
						)
					)
					(width 0)
					(fill yes)
				)
			)
		)
	)
	(footprint ""
		(layer "F.Cu")
		(at 215.799416 -390.80186 90)
		(property "Reference" "C688"
			(at 0 0 90)
			(layer "F.SilkS")
			(hide yes)
			(effects
				(font
					(size 1.27 1.27)
				)
			)
		)
		(property "Value" "SCD1U16V2KX-3GP"
			(at 1.1811 -2.7051 90)
			(unlocked yes)
			(layer "F.Fab")
			(hide yes)
			(effects
				(font
					(size 1.016 1.016)
					(thickness 0.1524)
				)
			)
		)
		(property "Device Type" "C402H22"
			(at 1.1811 -4.2291 90)
			(unlocked yes)
			(layer "F.Fab")
			(hide yes)
			(effects
				(font
					(size 1.016 1.016)
					(thickness 0.1524)
				)
			)
		)
		(duplicate_pad_numbers_are_jumpers no)
		(fp_rect
			(start -0.4318 0.9525)
			(end 0.4318 -0.9525)
			(stroke
				(width 0)
				(type default)
			)
			(fill no)
			(layer "F.CrtYd")
		)
		(fp_rect
			(start -0.4318 0.9525)
			(end 0.4318 -0.9525)
			(stroke
				(width 0)
				(type default)
			)
			(fill no)
			(layer "F.Fab")
		)
		(pad "1" smd custom
			(at 0 -0.4445 90)
			(size 0.1524 0.1524)
			(layers "F.Cu" "F.Mask" "F.Paste")
			(net "P3V3_STBY_B")
			(options
				(clearance outline)
				(anchor circle)
			)
			(primitives
				(gr_poly
					(pts
						(arc
							(start 0.3048 -0.2032)
							(mid 0.275042 -0.275042)
							(end 0.2032 -0.3048)
						)
						(arc
							(start -0.2032 -0.3048)
							(mid -0.275042 -0.275042)
							(end -0.3048 -0.2032)
						)
						(arc
							(start -0.3048 0.2032)
							(mid -0.275042 0.275042)
							(end -0.2032 0.3048)
						)
						(arc
							(start 0.2032 0.3048)
							(mid 0.275042 0.275042)
							(end 0.3048 0.2032)
						)
					)
					(width 0)
					(fill yes)
				)
			)
		)
		(pad "2" smd custom
			(at 0 0.4445 90)
			(size 0.1524 0.1524)
			(layers "F.Cu" "F.Mask" "F.Paste")
			(net "GND")
			(options
				(clearance outline)
				(anchor circle)
			)
			(primitives
				(gr_poly
					(pts
						(arc
							(start 0.3048 -0.2032)
							(mid 0.275042 -0.275042)
							(end 0.2032 -0.3048)
						)
						(arc
							(start -0.2032 -0.3048)
							(mid -0.275042 -0.275042)
							(end -0.3048 -0.2032)
						)
						(arc
							(start -0.3048 0.2032)
							(mid -0.275042 0.275042)
							(end -0.2032 0.3048)
						)
						(arc
							(start 0.2032 0.3048)
							(mid 0.275042 0.275042)
							(end 0.3048 0.2032)
						)
					)
					(width 0)
					(fill yes)
				)
			)
		)
	)
	(footprint ""
		(layer "F.Cu")
		(at 429.549052 -167.872918 -90)
		(property "Reference" "Q125"
			(at 0 0 270)
			(layer "F.SilkS")
			(hide yes)
			(effects
				(font
					(size 1.27 1.27)
				)
			)
		)
		(property "Value" "AO4406AL-GP"
			(at -3.707384 -1.5367 270)
			(unlocked yes)
			(layer "F.Fab")
			(hide yes)
			(effects
				(font
					(size 1.016 1.016)
					(thickness 0.1524)
				)
			)
		)
		(property "Device Type" "SOIC8H69"
			(at -3.707384 -3.0607 270)
			(unlocked yes)
			(layer "F.Fab")
			(hide yes)
			(effects
				(font
					(size 1.016 1.016)
					(thickness 0.1524)
				)
			)
		)
		(duplicate_pad_numbers_are_jumpers no)
		(fp_line
			(start -2.6289 3.4417)
			(end -2.6289 1.4732)
			(stroke
				(width 0.381)
				(type default)
			)
			(layer "F.SilkS")
		)
		(fp_line
			(start -2.7432 1.4224)
			(end -2.6416 1.4224)
			(stroke
				(width 0.1524)
				(type default)
			)
			(layer "F.SilkS")
		)
		(fp_line
			(start -2.7432 1.4224)
			(end 2.1336 1.4224)
			(stroke
				(width 0.1524)
				(type default)
			)
			(layer "F.SilkS")
		)
		(fp_line
			(start 2.1336 1.4224)
			(end 2.1336 -1.4224)
			(stroke
				(width 0.1524)
				(type default)
			)
			(layer "F.SilkS")
		)
		(fp_line
			(start -2.1844 -0.0508)
			(end -2.7178 0.508)
			(stroke
				(width 0.1524)
				(type default)
			)
			(layer "F.SilkS")
		)
		(fp_line
			(start -2.7178 -0.508)
			(end -2.1844 -0.0508)
			(stroke
				(width 0.1524)
				(type default)
			)
			(layer "F.SilkS")
		)
		(fp_line
			(start -2.7432 -1.4224)
			(end -2.7432 1.4224)
			(stroke
				(width 0.1524)
				(type default)
			)
			(layer "F.SilkS")
		)
		(fp_line
			(start 2.1336 -1.4224)
			(end -2.7432 -1.4224)
			(stroke
				(width 0.1524)
				(type default)
			)
			(layer "F.SilkS")
		)
		(fp_poly
			(pts
				(xy -2.2098 -1.4224) (xy -2.2098 1.4224) (xy 2.2098 1.4224) (xy 2.2098 -1.4224)
			)
			(stroke
				(width 0)
				(type default)
			)
			(fill yes)
			(layer "F.SilkS")
		)
		(fp_rect
			(start -2.450084 2.999994)
			(end 2.450084 -2.999994)
			(stroke
				(width 0)
				(type default)
			)
			(fill no)
			(layer "F.CrtYd")
		)
		(fp_poly
			(pts
				(xy -2.8194 3.6322) (xy -2.8194 -3.6322) (xy 2.8194 -3.6322) (xy 2.8194 1.18364) (xy 2.450084 1.18364)
				(xy 2.450084 -2.999994) (xy -2.450084 -2.999994) (xy -2.450084 2.999994) (xy 2.450084 2.999994)
				(xy 2.450084 1.18618) (xy 2.8194 1.18618) (xy 2.8194 3.6322)
			)
			(stroke
				(width 0)
				(type default)
			)
			(fill no)
			(layer "F.CrtYd")
		)
		(fp_rect
			(start -2.8194 3.6322)
			(end 2.8194 -3.6322)
			(stroke
				(width 0)
				(type default)
			)
			(fill no)
			(layer "F.Fab")
		)
		(pad "1" smd rect
			(at -1.905 2.54 270)
			(size 0.635 1.651)
			(layers "F.Cu" "F.Mask" "F.Paste")
			(net "P5V_HDD21")
		)
		(pad "2" smd rect
			(at -0.635 2.54 270)
			(size 0.635 1.651)
			(layers "F.Cu" "F.Mask" "F.Paste")
			(net "P5V_HDD21")
		)
		(pad "3" smd rect
			(at 0.635 2.54 270)
			(size 0.635 1.651)
			(layers "F.Cu" "F.Mask" "F.Paste")
			(net "P5V_HDD21")
		)
		(pad "4" smd rect
			(at 1.905 2.54 270)
			(size 0.635 1.651)
			(layers "F.Cu" "F.Mask" "F.Paste")
			(net "SW_HDD_P21")
		)
		(pad "5" smd rect
			(at 1.905 -2.54 270)
			(size 0.635 1.651)
			(layers "F.Cu" "F.Mask" "F.Paste")
			(net "P5V_A_4")
		)
		(pad "6" smd rect
			(at 0.635 -2.54 270)
			(size 0.635 1.651)
			(layers "F.Cu" "F.Mask" "F.Paste")
			(net "P5V_A_4")
		)
		(pad "7" smd rect
			(at -0.635 -2.54 270)
			(size 0.635 1.651)
			(layers "F.Cu" "F.Mask" "F.Paste")
			(net "P5V_A_4")
		)
		(pad "8" smd rect
			(at -1.905 -2.54 270)
			(size 0.635 1.651)
			(layers "F.Cu" "F.Mask" "F.Paste")
			(net "P5V_A_4")
		)
	)
	(footprint ""
		(layer "F.Cu")
		(at 459.4479 -157.585918 180)
		(property "Reference" "R644"
			(at 0 0 180)
			(layer "F.SilkS")
			(hide yes)
			(effects
				(font
					(size 1.27 1.27)
				)
			)
		)
		(property "Value" "1KR2F-3-GP"
			(at 0.064008 -3.993896 180)
			(unlocked yes)
			(layer "F.Fab")
			(hide yes)
			(effects
				(font
					(size 1.016 1.016)
					(thickness 0.1524)
				)
			)
		)
		(property "Device Type" "R402H16"
			(at 0.064008 -5.517896 180)
			(unlocked yes)
			(layer "F.Fab")
			(hide yes)
			(effects
				(font
					(size 1.016 1.016)
					(thickness 0.1524)
				)
			)
		)
		(duplicate_pad_numbers_are_jumpers no)
		(fp_line
			(start 0.508 -0.9398)
			(end -0.508 -0.9398)
			(stroke
				(width 0.1524)
				(type default)
			)
			(layer "F.SilkS")
		)
		(fp_line
			(start -0.508 -0.9398)
			(end -0.508 0.9398)
			(stroke
				(width 0.1524)
				(type default)
			)
			(layer "F.SilkS")
		)
		(fp_rect
			(start -0.508 0.9398)
			(end 0.508 -0.9398)
			(stroke
				(width 0)
				(type default)
			)
			(fill no)
			(layer "F.CrtYd")
		)
		(fp_rect
			(start -0.508 0.9398)
			(end 0.508 -0.9398)
			(stroke
				(width 0)
				(type default)
			)
			(fill no)
			(layer "F.Fab")
		)
		(pad "1" smd custom
			(at 0 -0.4445 180)
			(size 0.1397 0.1397)
			(layers "F.Cu" "F.Mask" "F.Paste")
			(net "P3V3_STBY_A")
			(options
				(clearance outline)
				(anchor circle)
			)
			(primitives
				(gr_poly
					(pts
						(arc
							(start -0.1778 -0.2794)
							(mid -0.249642 -0.249642)
							(end -0.2794 -0.1778)
						)
						(arc
							(start -0.2794 0.1778)
							(mid -0.249642 0.249642)
							(end -0.1778 0.2794)
						)
						(arc
							(start 0.1778 0.2794)
							(mid 0.249642 0.249642)
							(end 0.2794 0.1778)
						)
						(arc
							(start 0.2794 -0.1778)
							(mid 0.249642 -0.249642)
							(end 0.1778 -0.2794)
						)
					)
					(width 0)
					(fill yes)
				)
			)
		)
		(pad "2" smd custom
			(at 0 0.4445 180)
			(size 0.1397 0.1397)
			(layers "F.Cu" "F.Mask" "F.Paste")
			(net "SW_PWR_R_HDD22")
			(options
				(clearance outline)
				(anchor circle)
			)
			(primitives
				(gr_poly
					(pts
						(arc
							(start -0.1778 -0.2794)
							(mid -0.249642 -0.249642)
							(end -0.2794 -0.1778)
						)
						(arc
							(start -0.2794 0.1778)
							(mid -0.249642 0.249642)
							(end -0.1778 0.2794)
						)
						(arc
							(start 0.1778 0.2794)
							(mid 0.249642 0.249642)
							(end 0.2794 0.1778)
						)
						(arc
							(start 0.2794 -0.1778)
							(mid 0.249642 -0.249642)
							(end 0.1778 -0.2794)
						)
					)
					(width 0)
					(fill yes)
				)
			)
		)
	)
	(footprint ""
		(layer "F.Cu")
		(at 438.293764 -127.724408 180)
		(property "Reference" "Q249"
			(at 0 0 180)
			(layer "F.SilkS")
			(hide yes)
			(effects
				(font
					(size 1.27 1.27)
				)
			)
		)
		(property "Value" "2N7002K-2-GP"
			(at 0.127 -8.9662 180)
			(unlocked yes)
			(layer "F.Fab")
			(hide yes)
			(effects
				(font
					(size 1.016 1.016)
					(thickness 0.1524)
				)
			)
		)
		(property "Device Type" "SOT23DGS2D4H44"
			(at 0.127 -10.4902 180)
			(unlocked yes)
			(layer "F.Fab")
			(hide yes)
			(effects
				(font
					(size 1.016 1.016)
					(thickness 0.1524)
				)
			)
		)
		(duplicate_pad_numbers_are_jumpers no)
		(fp_line
			(start 1.651 1.778)
			(end 1.651 -1.778)
			(stroke
				(width 0.1524)
				(type default)
			)
			(layer "F.SilkS")
		)
		(fp_line
			(start 1.651 -1.778)
			(end -1.651 -1.778)
			(stroke
				(width 0.1524)
				(type default)
			)
			(layer "F.SilkS")
		)
		(fp_line
			(start -1.651 1.778)
			(end 1.651 1.778)
			(stroke
				(width 0.1524)
				(type default)
			)
			(layer "F.SilkS")
		)
		(fp_line
			(start -1.651 -1.778)
			(end -1.651 1.778)
			(stroke
				(width 0.1524)
				(type default)
			)
			(layer "F.SilkS")
		)
		(fp_poly
			(pts
				(xy -1.778 1.8796) (xy -1.778 -1.8796) (xy 1.778 -1.8796) (xy 1.778 1.8796)
			)
			(stroke
				(width 0)
				(type default)
			)
			(fill no)
			(layer "F.CrtYd")
		)
		(fp_poly
			(pts
				(xy -1.778 1.8796) (xy -1.778 -1.8796) (xy 1.778 -1.8796) (xy 1.778 1.8796)
			)
			(stroke
				(width 0)
				(type default)
			)
			(fill no)
			(layer "F.Fab")
		)
		(pad "D" smd custom
			(at 0 -0.9525 180)
			(size 0.1905 0.1905)
			(layers "F.Cu" "F.Mask" "F.Paste")
			(net "FLT_HDD22_N")
			(options
				(clearance outline)
				(anchor circle)
			)
			(primitives
				(gr_poly
					(pts
						(arc
							(start -0.1778 0.5715)
							(mid -0.321484 0.511984)
							(end -0.381 0.3683)
						)
						(arc
							(start -0.381 -0.3683)
							(mid -0.321484 -0.511984)
							(end -0.1778 -0.5715)
						)
						(arc
							(start 0.1778 -0.5715)
							(mid 0.321484 -0.511984)
							(end 0.381 -0.3683)
						)
						(arc
							(start 0.381 0.3683)
							(mid 0.321484 0.511984)
							(end 0.1778 0.5715)
						)
					)
					(width 0)
					(fill yes)
				)
			)
		)
		(pad "G" smd custom
			(at -0.98425 0.9525 180)
			(size 0.1905 0.1905)
			(layers "F.Cu" "F.Mask" "F.Paste")
			(net "DRIVE_A_22_FLT_LED")
			(options
				(clearance outline)
				(anchor circle)
			)
			(primitives
				(gr_poly
					(pts
						(arc
							(start -0.1778 0.5715)
							(mid -0.321484 0.511984)
							(end -0.381 0.3683)
						)
						(arc
							(start -0.381 -0.3683)
							(mid -0.321484 -0.511984)
							(end -0.1778 -0.5715)
						)
						(arc
							(start 0.1778 -0.5715)
							(mid 0.321484 -0.511984)
							(end 0.381 -0.3683)
						)
						(arc
							(start 0.381 0.3683)
							(mid 0.321484 0.511984)
							(end 0.1778 0.5715)
						)
					)
					(width 0)
					(fill yes)
				)
			)
		)
		(pad "S" smd custom
			(at 0.98425 0.9525 180)
			(size 0.1905 0.1905)
			(layers "F.Cu" "F.Mask" "F.Paste")
			(net "GND")
			(options
				(clearance outline)
				(anchor circle)
			)
			(primitives
				(gr_poly
					(pts
						(arc
							(start -0.1778 0.5715)
							(mid -0.321484 0.511984)
							(end -0.381 0.3683)
						)
						(arc
							(start -0.381 -0.3683)
							(mid -0.321484 -0.511984)
							(end -0.1778 -0.5715)
						)
						(arc
							(start 0.1778 -0.5715)
							(mid 0.321484 -0.511984)
							(end 0.381 -0.3683)
						)
						(arc
							(start 0.381 0.3683)
							(mid 0.321484 0.511984)
							(end 0.1778 0.5715)
						)
					)
					(width 0)
					(fill yes)
				)
			)
		)
	)
	(footprint ""
		(layer "F.Cu")
		(at 256.843276 -248.87936)
		(property "Reference" "R55"
			(at 0 0 0)
			(layer "F.SilkS")
			(hide yes)
			(effects
				(font
					(size 1.27 1.27)
				)
			)
		)
		(property "Value" "4K7R2F-GP"
			(at 0.064008 -3.993896 0)
			(unlocked yes)
			(layer "F.Fab")
			(hide yes)
			(effects
				(font
					(size 1.016 1.016)
					(thickness 0.1524)
				)
			)
		)
		(property "Device Type" "R402H16"
			(at 0.064008 -5.517896 0)
			(unlocked yes)
			(layer "F.Fab")
			(hide yes)
			(effects
				(font
					(size 1.016 1.016)
					(thickness 0.1524)
				)
			)
		)
		(duplicate_pad_numbers_are_jumpers no)
		(fp_line
			(start -0.508 -0.9398)
			(end -0.508 0.9398)
			(stroke
				(width 0.1524)
				(type default)
			)
			(layer "F.SilkS")
		)
		(fp_line
			(start 0.508 -0.9398)
			(end -0.508 -0.9398)
			(stroke
				(width 0.1524)
				(type default)
			)
			(layer "F.SilkS")
		)
		(fp_rect
			(start -0.508 0.9398)
			(end 0.508 -0.9398)
			(stroke
				(width 0)
				(type default)
			)
			(fill no)
			(layer "F.CrtYd")
		)
		(fp_rect
			(start -0.508 0.9398)
			(end 0.508 -0.9398)
			(stroke
				(width 0)
				(type default)
			)
			(fill no)
			(layer "F.Fab")
		)
		(pad "1" smd custom
			(at 0 -0.4445)
			(size 0.1397 0.1397)
			(layers "F.Cu" "F.Mask" "F.Paste")
			(net "IO_EXP6_A2")
			(options
				(clearance outline)
				(anchor circle)
			)
			(primitives
				(gr_poly
					(pts
						(arc
							(start -0.1778 -0.2794)
							(mid -0.249642 -0.249642)
							(end -0.2794 -0.1778)
						)
						(arc
							(start -0.2794 0.1778)
							(mid -0.249642 0.249642)
							(end -0.1778 0.2794)
						)
						(arc
							(start 0.1778 0.2794)
							(mid 0.249642 0.249642)
							(end 0.2794 0.1778)
						)
						(arc
							(start 0.2794 -0.1778)
							(mid 0.249642 -0.249642)
							(end 0.1778 -0.2794)
						)
					)
					(width 0)
					(fill yes)
				)
			)
		)
		(pad "2" smd custom
			(at 0 0.4445)
			(size 0.1397 0.1397)
			(layers "F.Cu" "F.Mask" "F.Paste")
			(net "GND")
			(options
				(clearance outline)
				(anchor circle)
			)
			(primitives
				(gr_poly
					(pts
						(arc
							(start -0.1778 -0.2794)
							(mid -0.249642 -0.249642)
							(end -0.2794 -0.1778)
						)
						(arc
							(start -0.2794 0.1778)
							(mid -0.249642 0.249642)
							(end -0.1778 0.2794)
						)
						(arc
							(start 0.1778 0.2794)
							(mid 0.249642 0.249642)
							(end 0.2794 0.1778)
						)
						(arc
							(start 0.2794 -0.1778)
							(mid 0.249642 -0.249642)
							(end 0.1778 -0.2794)
						)
					)
					(width 0)
					(fill yes)
				)
			)
		)
	)
	(footprint ""
		(layer "F.Cu")
		(at 282.351734 20.532852 90)
		(property "Reference" "R1137"
			(at 0 0 90)
			(layer "F.SilkS")
			(hide yes)
			(effects
				(font
					(size 1.27 1.27)
				)
			)
		)
		(property "Value" "3K83R2F-GP"
			(at 0.064008 -3.993896 90)
			(unlocked yes)
			(layer "F.Fab")
			(hide yes)
			(effects
				(font
					(size 1.016 1.016)
					(thickness 0.1524)
				)
			)
		)
		(property "Device Type" "R402H16"
			(at 0.064008 -5.517896 90)
			(unlocked yes)
			(layer "F.Fab")
			(hide yes)
			(effects
				(font
					(size 1.016 1.016)
					(thickness 0.1524)
				)
			)
		)
		(duplicate_pad_numbers_are_jumpers no)
		(fp_line
			(start 0.508 -0.9398)
			(end -0.508 -0.9398)
			(stroke
				(width 0.1524)
				(type default)
			)
			(layer "F.SilkS")
		)
		(fp_line
			(start -0.508 -0.9398)
			(end -0.508 0.9398)
			(stroke
				(width 0.1524)
				(type default)
			)
			(layer "F.SilkS")
		)
		(fp_rect
			(start -0.508 0.9398)
			(end 0.508 -0.9398)
			(stroke
				(width 0)
				(type default)
			)
			(fill no)
			(layer "F.CrtYd")
		)
		(fp_rect
			(start -0.508 0.9398)
			(end 0.508 -0.9398)
			(stroke
				(width 0)
				(type default)
			)
			(fill no)
			(layer "F.Fab")
		)
		(pad "1" smd custom
			(at 0 -0.4445 90)
			(size 0.1397 0.1397)
			(layers "F.Cu" "F.Mask" "F.Paste")
			(net "DPB_PWR_BTN_B")
			(options
				(clearance outline)
				(anchor circle)
			)
			(primitives
				(gr_poly
					(pts
						(arc
							(start -0.1778 -0.2794)
							(mid -0.249642 -0.249642)
							(end -0.2794 -0.1778)
						)
						(arc
							(start -0.2794 0.1778)
							(mid -0.249642 0.249642)
							(end -0.1778 0.2794)
						)
						(arc
							(start 0.1778 0.2794)
							(mid 0.249642 0.249642)
							(end 0.2794 0.1778)
						)
						(arc
							(start 0.2794 -0.1778)
							(mid 0.249642 -0.249642)
							(end 0.1778 -0.2794)
						)
					)
					(width 0)
					(fill yes)
				)
			)
		)
		(pad "2" smd custom
			(at 0 0.4445 90)
			(size 0.1397 0.1397)
			(layers "F.Cu" "F.Mask" "F.Paste")
			(net "GND")
			(options
				(clearance outline)
				(anchor circle)
			)
			(primitives
				(gr_poly
					(pts
						(arc
							(start -0.1778 -0.2794)
							(mid -0.249642 -0.249642)
							(end -0.2794 -0.1778)
						)
						(arc
							(start -0.2794 0.1778)
							(mid -0.249642 0.249642)
							(end -0.1778 0.2794)
						)
						(arc
							(start 0.1778 0.2794)
							(mid 0.249642 0.249642)
							(end 0.2794 0.1778)
						)
						(arc
							(start 0.2794 -0.1778)
							(mid 0.249642 -0.249642)
							(end 0.1778 -0.2794)
						)
					)
					(width 0)
					(fill yes)
				)
			)
		)
	)
	(footprint ""
		(layer "F.Cu")
		(at 426.755052 -272.585942)
		(property "Reference" "R350"
			(at 0 0 0)
			(layer "F.SilkS")
			(hide yes)
			(effects
				(font
					(size 1.27 1.27)
				)
			)
		)
		(property "Value" "4K7R2J-2-GP"
			(at 0.064008 -3.993896 0)
			(unlocked yes)
			(layer "F.Fab")
			(hide yes)
			(effects
				(font
					(size 1.016 1.016)
					(thickness 0.1524)
				)
			)
		)
		(property "Device Type" "R402H16"
			(at 0.064008 -5.517896 0)
			(unlocked yes)
			(layer "F.Fab")
			(hide yes)
			(effects
				(font
					(size 1.016 1.016)
					(thickness 0.1524)
				)
			)
		)
		(duplicate_pad_numbers_are_jumpers no)
		(fp_line
			(start -0.508 -0.9398)
			(end -0.508 0.9398)
			(stroke
				(width 0.1524)
				(type default)
			)
			(layer "F.SilkS")
		)
		(fp_line
			(start 0.508 -0.9398)
			(end -0.508 -0.9398)
			(stroke
				(width 0.1524)
				(type default)
			)
			(layer "F.SilkS")
		)
		(fp_rect
			(start -0.508 0.9398)
			(end 0.508 -0.9398)
			(stroke
				(width 0)
				(type default)
			)
			(fill no)
			(layer "F.CrtYd")
		)
		(fp_rect
			(start -0.508 0.9398)
			(end 0.508 -0.9398)
			(stroke
				(width 0)
				(type default)
			)
			(fill no)
			(layer "F.Fab")
		)
		(pad "1" smd custom
			(at 0 -0.4445)
			(size 0.1397 0.1397)
			(layers "F.Cu" "F.Mask" "F.Paste")
			(net "SW_PWR_R_HDD9")
			(options
				(clearance outline)
				(anchor circle)
			)
			(primitives
				(gr_poly
					(pts
						(arc
							(start -0.1778 -0.2794)
							(mid -0.249642 -0.249642)
							(end -0.2794 -0.1778)
						)
						(arc
							(start -0.2794 0.1778)
							(mid -0.249642 0.249642)
							(end -0.1778 0.2794)
						)
						(arc
							(start 0.1778 0.2794)
							(mid 0.249642 0.249642)
							(end 0.2794 0.1778)
						)
						(arc
							(start 0.2794 -0.1778)
							(mid 0.249642 -0.249642)
							(end 0.1778 -0.2794)
						)
					)
					(width 0)
					(fill yes)
				)
			)
		)
		(pad "2" smd custom
			(at 0 0.4445)
			(size 0.1397 0.1397)
			(layers "F.Cu" "F.Mask" "F.Paste")
			(net "GND")
			(options
				(clearance outline)
				(anchor circle)
			)
			(primitives
				(gr_poly
					(pts
						(arc
							(start -0.1778 -0.2794)
							(mid -0.249642 -0.249642)
							(end -0.2794 -0.1778)
						)
						(arc
							(start -0.2794 0.1778)
							(mid -0.249642 0.249642)
							(end -0.1778 0.2794)
						)
						(arc
							(start 0.1778 0.2794)
							(mid 0.249642 0.249642)
							(end 0.2794 0.1778)
						)
						(arc
							(start 0.2794 -0.1778)
							(mid 0.249642 -0.249642)
							(end 0.1778 -0.2794)
						)
					)
					(width 0)
					(fill yes)
				)
			)
		)
	)
	(footprint ""
		(layer "F.Cu")
		(at 272.91157 -371.731794)
		(property "Reference" "R1172"
			(at 0 0 0)
			(layer "F.SilkS")
			(hide yes)
			(effects
				(font
					(size 1.27 1.27)
				)
			)
		)
		(property "Value" "10R5F-1-GP"
			(at 0 -8.9535 0)
			(unlocked yes)
			(layer "F.Fab")
			(hide yes)
			(effects
				(font
					(size 1.27 1.016)
					(thickness 0.1524)
				)
			)
		)
		(property "Device Type" "R805H24"
			(at 0 -10.6299 0)
			(unlocked yes)
			(layer "F.Fab")
			(hide yes)
			(effects
				(font
					(size 1.27 1.016)
					(thickness 0.1524)
				)
			)
		)
		(duplicate_pad_numbers_are_jumpers no)
		(fp_line
			(start -0.889 -1.7018)
			(end -0.889 0.2794)
			(stroke
				(width 0.1524)
				(type default)
			)
			(layer "F.SilkS")
		)
		(fp_line
			(start -0.889 0.0762)
			(end -0.889 1.7018)
			(stroke
				(width 0.1524)
				(type default)
			)
			(layer "F.SilkS")
		)
		(fp_line
			(start -0.889 1.7018)
			(end 0.889 1.7018)
			(stroke
				(width 0.1524)
				(type default)
			)
			(layer "F.SilkS")
		)
		(fp_line
			(start 0.889 -1.7018)
			(end -0.889 -1.7018)
			(stroke
				(width 0.1524)
				(type default)
			)
			(layer "F.SilkS")
		)
		(fp_line
			(start 0.889 -1.7018)
			(end 0.889 -0.381)
			(stroke
				(width 0.1524)
				(type default)
			)
			(layer "F.SilkS")
		)
		(fp_line
			(start 0.889 1.7018)
			(end 0.889 -0.508)
			(stroke
				(width 0.1524)
				(type default)
			)
			(layer "F.SilkS")
		)
		(fp_poly
			(pts
				(xy 0.9652 -1.778) (xy 0.9652 1.778) (xy -0.9652 1.778) (xy -0.9652 -1.778)
			)
			(stroke
				(width 0)
				(type default)
			)
			(fill no)
			(layer "F.CrtYd")
		)
		(fp_rect
			(start -0.9652 1.778)
			(end 0.9652 -1.778)
			(stroke
				(width 0)
				(type default)
			)
			(fill no)
			(layer "F.Fab")
		)
		(pad "1" smd rect
			(at 0 -0.9652)
			(size 1.397 1.143)
			(layers "F.Cu" "F.Mask" "F.Paste")
			(net "MB3_12V_CTRL_GATE1")
		)
		(pad "2" smd rect
			(at 0 0.9652)
			(size 1.397 1.143)
			(layers "F.Cu" "F.Mask" "F.Paste")
			(net "MB3_CM_GATE_R")
		)
	)
	(footprint ""
		(layer "F.Cu")
		(at 264.999978 -418.669978 180)
		(property "Reference" "DPB2"
			(at 0 0 180)
			(layer "F.SilkS")
			(hide yes)
			(effects
				(font
					(size 1.27 1.27)
				)
			)
		)
		(property "Value" "AMP-CONN54-6R-GP"
			(at 31.175452 18.813018 180)
			(unlocked yes)
			(layer "F.Fab")
			(hide yes)
			(effects
				(font
					(size 1.016 1.016)
					(thickness 0.1524)
				)
			)
		)
		(property "Device Type" "PREFIT-54P-216315H542"
			(at 31.175452 17.289018 180)
			(unlocked yes)
			(layer "F.Fab")
			(hide yes)
			(effects
				(font
					(size 1.016 1.016)
					(thickness 0.1524)
				)
			)
		)
		(duplicate_pad_numbers_are_jumpers no)
		(fp_line
			(start 19.812 2.530094)
			(end -2.2606 2.530094)
			(stroke
				(width 0.1524)
				(type default)
			)
			(layer "F.SilkS")
		)
		(fp_line
			(start 19.812 -17.018)
			(end 19.812 2.530094)
			(stroke
				(width 0.1524)
				(type default)
			)
			(layer "F.SilkS")
		)
		(fp_line
			(start -2.2606 2.530094)
			(end -2.2606 -17.018)
			(stroke
				(width 0.1524)
				(type default)
			)
			(layer "F.SilkS")
		)
		(fp_line
			(start -2.2606 -17.018)
			(end 19.812 -17.018)
			(stroke
				(width 0.1524)
				(type default)
			)
			(layer "F.SilkS")
		)
		(fp_poly
			(pts
				(xy -2.2606 2.530094) (xy -2.2606 -17.018) (xy 19.812 -17.018) (xy 19.812 2.530094) (xy 18.450814 2.530094)
				(xy 18.450814 -15.350998) (xy 13.6906 -15.350998) (xy 13.6906 -16.764) (xy 3.3274 -16.764) (xy 3.3274 -15.350998)
				(xy -0.8509 -15.350998) (xy -0.8509 2.530094)
			)
			(stroke
				(width 0)
				(type default)
			)
			(fill yes)
			(layer "F.SilkS")
		)
		(fp_poly
			(pts
				(arc
					(start 18.00479 2.00152)
					(mid 17.62379 2.38252)
					(end 17.24279 2.00152)
				)
				(arc
					(start 17.24279 1.36652)
					(mid 17.62379 0.98552)
					(end 18.00479 1.36652)
				)
			)
			(stroke
				(width 0)
				(type default)
			)
			(fill yes)
			(layer "F.SilkS")
		)
		(fp_poly
			(pts
				(arc
					(start 14.804898 2.00152)
					(mid 14.423898 2.38252)
					(end 14.042898 2.00152)
				)
				(arc
					(start 14.042898 1.36652)
					(mid 14.423898 0.98552)
					(end 14.804898 1.36652)
				)
			)
			(stroke
				(width 0)
				(type default)
			)
			(fill yes)
			(layer "F.SilkS")
		)
		(fp_poly
			(pts
				(arc
					(start 10.804906 2.00152)
					(mid 10.423906 2.38252)
					(end 10.042906 2.00152)
				)
				(arc
					(start 10.042906 1.36652)
					(mid 10.423906 0.98552)
					(end 10.804906 1.36652)
				)
			)
			(stroke
				(width 0)
				(type default)
			)
			(fill yes)
			(layer "F.SilkS")
		)
		(fp_poly
			(pts
				(arc
					(start 7.605014 2.00152)
					(mid 7.224014 2.38252)
					(end 6.843014 2.00152)
				)
				(arc
					(start 6.843014 1.36652)
					(mid 7.224014 0.98552)
					(end 7.605014 1.36652)
				)
			)
			(stroke
				(width 0)
				(type default)
			)
			(fill yes)
			(layer "F.SilkS")
		)
		(fp_poly
			(pts
				(arc
					(start 3.605022 2.00152)
					(mid 3.224022 2.38252)
					(end 2.843022 2.00152)
				)
				(arc
					(start 2.843022 1.36652)
					(mid 3.224022 0.98552)
					(end 3.605022 1.36652)
				)
			)
			(stroke
				(width 0)
				(type default)
			)
			(fill yes)
			(layer "F.SilkS")
		)
		(fp_poly
			(pts
				(arc
					(start 0.40513 2.00152)
					(mid 0.02413 2.38252)
					(end -0.35687 2.00152)
				)
				(arc
					(start -0.35687 1.36652)
					(mid 0.02413 0.98552)
					(end 0.40513 1.36652)
				)
			)
			(stroke
				(width 0)
				(type default)
			)
			(fill yes)
			(layer "F.SilkS")
		)
		(fp_rect
			(start -5.6134 5.6134)
			(end 23.2156 -20.1168)
			(stroke
				(width 0)
				(type default)
			)
			(fill no)
			(layer "B.CrtYd")
		)
		(fp_rect
			(start -2.0066 14.732)
			(end 19.558 -16.764)
			(stroke
				(width 0)
				(type default)
			)
			(fill no)
			(layer "F.CrtYd")
		)
		(fp_poly
			(pts
				(xy -2.5146 15.24) (xy -2.5146 -17.272) (xy 20.066 -17.272) (xy 20.066 0) (xy 19.558 0) (xy 19.558 -16.764)
				(xy -2.0066 -16.764) (xy -2.0066 14.732) (xy 19.558 14.732) (xy 19.558 0.0127) (xy 20.066 0.0127)
				(xy 20.066 15.24)
			)
			(stroke
				(width 0)
				(type default)
			)
			(fill no)
			(layer "F.CrtYd")
		)
		(fp_poly
			(pts
				(xy -7.0104 19.7358) (xy -7.0104 -21.7678) (xy 24.5618 -21.7678) (xy 24.5618 0) (xy 20.066 0) (xy 20.066 -17.272)
				(xy -2.5146 -17.272) (xy -2.5146 15.24) (xy 20.066 15.24) (xy 20.066 0.0127) (xy 24.5618 0.0127)
				(xy 24.5618 19.7358)
			)
			(stroke
				(width 0)
				(type default)
			)
			(fill no)
			(layer "F.CrtYd")
		)
		(fp_rect
			(start -5.6134 5.6134)
			(end 23.2156 -20.1168)
			(stroke
				(width 0)
				(type default)
			)
			(fill no)
			(layer "B.Fab")
		)
		(fp_rect
			(start -10.6172 10.6172)
			(end 28.2194 -25.1206)
			(stroke
				(width 0)
				(type default)
			)
			(fill no)
			(layer "B.Fab")
		)
		(fp_rect
			(start -2.5146 15.24)
			(end 20.066 -17.272)
			(stroke
				(width 0)
				(type default)
			)
			(fill no)
			(layer "F.Fab")
		)
		(fp_rect
			(start -7.0104 19.7358)
			(end 24.5618 -21.7678)
			(stroke
				(width 0)
				(type default)
			)
			(fill no)
			(layer "F.Fab")
		)
		(fp_rect
			(start -12.0142 24.7396)
			(end 29.5656 -26.7716)
			(stroke
				(width 0)
				(type default)
			)
			(fill no)
			(layer "F.Fab")
		)
		(fp_text user "Press Fit"
			(at 3.4671 -16.0147 180)
			(unlocked yes)
			(layer "F.SilkS")
			(effects
				(font
					(size 1.016 1.016)
					(thickness 0.1524)
				)
				(justify left)
			)
		)
		(fp_text user "Can not place BGA,CSP,Wave Solder Component"
			(at -18.3388 8.001 180)
			(unlocked yes)
			(layer "B.Fab")
			(effects
				(font
					(size 1.016 1.016)
					(thickness 0.1524)
				)
				(justify left)
			)
		)
		(fp_text user "High Limit 2mm"
			(at -1.0541 17.6403 180)
			(unlocked yes)
			(layer "F.Fab")
			(effects
				(font
					(size 1.016 1.016)
					(thickness 0.1524)
				)
				(justify left)
			)
		)
		(fp_text user "Can not place BGA,CSP,Wave Solder Component"
			(at -16.0655 22.6441 180)
			(unlocked yes)
			(layer "F.Fab")
			(effects
				(font
					(size 1.016 1.016)
					(thickness 0.1524)
				)
				(justify left)
			)
		)
		(pad "A1" thru_hole circle
			(at 0 0 180)
			(size 1.2192 1.2192)
			(drill 0.739902)
			(layers "*.Cu" "*.Mask")
			(remove_unused_layers no)
			(net "P12V_IN")
			(clearance 0.127)
			(thermal_gap 0.127)
		)
		(pad "A2" thru_hole circle
			(at 3.199892 0 180)
			(size 1.2192 1.2192)
			(drill 0.739902)
			(layers "*.Cu" "*.Mask")
			(remove_unused_layers no)
			(net "P12V_IN")
			(clearance 0.127)
			(thermal_gap 0.127)
		)
		(pad "A3" thru_hole circle
			(at 7.199884 0 180)
			(size 1.2192 1.2192)
			(drill 0.739902)
			(layers "*.Cu" "*.Mask")
			(remove_unused_layers no)
			(net "P12V_IN")
			(clearance 0.127)
			(thermal_gap 0.127)
		)
		(pad "A4" thru_hole circle
			(at 10.40003 0 180)
			(size 1.2192 1.2192)
			(drill 0.739902)
			(layers "*.Cu" "*.Mask")
			(remove_unused_layers no)
			(net "P12V_IN")
			(clearance 0.127)
			(thermal_gap 0.127)
		)
		(pad "A5" thru_hole circle
			(at 14.400022 0 180)
			(size 1.2192 1.2192)
			(drill 0.739902)
			(layers "*.Cu" "*.Mask")
			(remove_unused_layers no)
			(net "P12V_B")
			(clearance 0.127)
			(thermal_gap 0.127)
		)
		(pad "A6" thru_hole circle
			(at 17.599914 0 180)
			(size 1.2192 1.2192)
			(drill 0.739902)
			(layers "*.Cu" "*.Mask")
			(remove_unused_layers no)
			(net "P12V_B")
			(clearance 0.127)
			(thermal_gap 0.127)
		)
		(pad "B1" thru_hole oval
			(at 0 -1.500124 180)
			(size 1.2192 4.2164)
			(drill 0.739902)
			(layers "*.Cu" "*.Mask")
			(remove_unused_layers no)
			(net "P12V_IN")
			(clearance 0.127)
			(thermal_gap 0.127)
			(padstack
				(mode front_inner_back)
				(layer "Inner"
					(shape circle)
					(size 1.2192 1.2192)
					(clearance 0.127)
				)
				(layer "B.Cu"
					(shape circle)
					(size 1.2192 1.2192)
					(clearance 0.127)
				)
			)
		)
		(pad "B2" thru_hole oval
			(at 3.199892 -1.500124 180)
			(size 1.2192 4.2164)
			(drill 0.739902)
			(layers "*.Cu" "*.Mask")
			(remove_unused_layers no)
			(net "P12V_IN")
			(clearance 0.127)
			(thermal_gap 0.127)
			(padstack
				(mode front_inner_back)
				(layer "Inner"
					(shape circle)
					(size 1.2192 1.2192)
					(clearance 0.127)
				)
				(layer "B.Cu"
					(shape circle)
					(size 1.2192 1.2192)
					(clearance 0.127)
				)
			)
		)
		(pad "B3" thru_hole oval
			(at 7.199884 -1.500124 180)
			(size 1.2192 4.2164)
			(drill 0.739902)
			(layers "*.Cu" "*.Mask")
			(remove_unused_layers no)
			(net "P12V_IN")
			(clearance 0.127)
			(thermal_gap 0.127)
			(padstack
				(mode front_inner_back)
				(layer "Inner"
					(shape circle)
					(size 1.2192 1.2192)
					(clearance 0.127)
				)
				(layer "B.Cu"
					(shape circle)
					(size 1.2192 1.2192)
					(clearance 0.127)
				)
			)
		)
		(pad "B4" thru_hole oval
			(at 10.40003 -1.500124 180)
			(size 1.2192 4.2164)
			(drill 0.739902)
			(layers "*.Cu" "*.Mask")
			(remove_unused_layers no)
			(net "P12V_IN")
			(clearance 0.127)
			(thermal_gap 0.127)
			(padstack
				(mode front_inner_back)
				(layer "Inner"
					(shape circle)
					(size 1.2192 1.2192)
					(clearance 0.127)
				)
				(layer "B.Cu"
					(shape circle)
					(size 1.2192 1.2192)
					(clearance 0.127)
				)
			)
		)
		(pad "B5" thru_hole oval
			(at 14.400022 -1.500124 180)
			(size 1.2192 4.2164)
			(drill 0.739902)
			(layers "*.Cu" "*.Mask")
			(remove_unused_layers no)
			(net "P12V_B")
			(clearance 0.127)
			(thermal_gap 0.127)
			(padstack
				(mode front_inner_back)
				(layer "Inner"
					(shape circle)
					(size 1.2192 1.2192)
					(clearance 0.127)
				)
				(layer "B.Cu"
					(shape circle)
					(size 1.2192 1.2192)
					(clearance 0.127)
				)
			)
		)
		(pad "B6" thru_hole oval
			(at 17.599914 -1.500124 180)
			(size 1.2192 4.2164)
			(drill 0.739902)
			(layers "*.Cu" "*.Mask")
			(remove_unused_layers no)
			(net "P12V_B")
			(clearance 0.127)
			(thermal_gap 0.127)
			(padstack
				(mode front_inner_back)
				(layer "Inner"
					(shape circle)
					(size 1.2192 1.2192)
					(clearance 0.127)
				)
				(layer "B.Cu"
					(shape circle)
					(size 1.2192 1.2192)
					(clearance 0.127)
				)
			)
		)
		(pad "C1" thru_hole circle
			(at 0 -2.999994 180)
			(size 1.2192 1.2192)
			(drill 0.739902)
			(layers "*.Cu" "*.Mask")
			(remove_unused_layers no)
			(net "P12V_IN")
			(clearance 0.127)
			(thermal_gap 0.127)
		)
		(pad "C2" thru_hole circle
			(at 3.199892 -2.999994 180)
			(size 1.2192 1.2192)
			(drill 0.739902)
			(layers "*.Cu" "*.Mask")
			(remove_unused_layers no)
			(net "P12V_IN")
			(clearance 0.127)
			(thermal_gap 0.127)
		)
		(pad "C3" thru_hole circle
			(at 7.199884 -2.999994 180)
			(size 1.2192 1.2192)
			(drill 0.739902)
			(layers "*.Cu" "*.Mask")
			(remove_unused_layers no)
			(net "P12V_IN")
			(clearance 0.127)
			(thermal_gap 0.127)
		)
		(pad "C4" thru_hole circle
			(at 10.40003 -2.999994 180)
			(size 1.2192 1.2192)
			(drill 0.739902)
			(layers "*.Cu" "*.Mask")
			(remove_unused_layers no)
			(net "P12V_IN")
			(clearance 0.127)
			(thermal_gap 0.127)
		)
		(pad "C5" thru_hole circle
			(at 14.400022 -2.999994 180)
			(size 1.2192 1.2192)
			(drill 0.739902)
			(layers "*.Cu" "*.Mask")
			(remove_unused_layers no)
			(net "P12V_B")
			(clearance 0.127)
			(thermal_gap 0.127)
		)
		(pad "C6" thru_hole circle
			(at 17.599914 -2.999994 180)
			(size 1.2192 1.2192)
			(drill 0.739902)
			(layers "*.Cu" "*.Mask")
			(remove_unused_layers no)
			(net "P12V_B")
			(clearance 0.127)
			(thermal_gap 0.127)
		)
		(pad "D1" thru_hole circle
			(at 0 -5.750052 180)
			(size 1.2192 1.2192)
			(drill 0.739902)
			(layers "*.Cu" "*.Mask")
			(remove_unused_layers no)
			(net "P12V_IN")
			(clearance 0.127)
			(thermal_gap 0.127)
		)
		(pad "D2" thru_hole circle
			(at 3.199892 -5.750052 180)
			(size 1.2192 1.2192)
			(drill 0.739902)
			(layers "*.Cu" "*.Mask")
			(remove_unused_layers no)
			(net "P12V_IN")
			(clearance 0.127)
			(thermal_gap 0.127)
		)
		(pad "D3" thru_hole circle
			(at 7.199884 -5.750052 180)
			(size 1.2192 1.2192)
			(drill 0.739902)
			(layers "*.Cu" "*.Mask")
			(remove_unused_layers no)
			(net "P12V_IN")
			(clearance 0.127)
			(thermal_gap 0.127)
		)
		(pad "D4" thru_hole circle
			(at 10.40003 -5.750052 180)
			(size 1.2192 1.2192)
			(drill 0.739902)
			(layers "*.Cu" "*.Mask")
			(remove_unused_layers no)
			(net "P12V_IN")
			(clearance 0.127)
			(thermal_gap 0.127)
		)
		(pad "D5" thru_hole circle
			(at 14.400022 -5.750052 180)
			(size 1.2192 1.2192)
			(drill 0.739902)
			(layers "*.Cu" "*.Mask")
			(remove_unused_layers no)
			(net "GND")
			(clearance 0.127)
			(thermal_gap 0.127)
		)
		(pad "D6" thru_hole circle
			(at 17.599914 -5.750052 180)
			(size 1.2192 1.2192)
			(drill 0.739902)
			(layers "*.Cu" "*.Mask")
			(remove_unused_layers no)
			(net "GND")
			(clearance 0.127)
			(thermal_gap 0.127)
		)
		(pad "E1" thru_hole oval
			(at 0 -7.249922 180)
			(size 1.2192 4.2164)
			(drill 0.739902)
			(layers "*.Cu" "*.Mask")
			(remove_unused_layers no)
			(net "P12V_IN")
			(clearance 0.127)
			(thermal_gap 0.127)
			(padstack
				(mode front_inner_back)
				(layer "Inner"
					(shape circle)
					(size 1.2192 1.2192)
					(clearance 0.127)
				)
				(layer "B.Cu"
					(shape circle)
					(size 1.2192 1.2192)
					(clearance 0.127)
				)
			)
		)
		(pad "E2" thru_hole oval
			(at 3.199892 -7.249922 180)
			(size 1.2192 4.2164)
			(drill 0.739902)
			(layers "*.Cu" "*.Mask")
			(remove_unused_layers no)
			(net "P12V_IN")
			(clearance 0.127)
			(thermal_gap 0.127)
			(padstack
				(mode front_inner_back)
				(layer "Inner"
					(shape circle)
					(size 1.2192 1.2192)
					(clearance 0.127)
				)
				(layer "B.Cu"
					(shape circle)
					(size 1.2192 1.2192)
					(clearance 0.127)
				)
			)
		)
		(pad "E3" thru_hole oval
			(at 7.199884 -7.249922 180)
			(size 1.2192 4.2164)
			(drill 0.739902)
			(layers "*.Cu" "*.Mask")
			(remove_unused_layers no)
			(net "P12V_IN")
			(clearance 0.127)
			(thermal_gap 0.127)
			(padstack
				(mode front_inner_back)
				(layer "Inner"
					(shape circle)
					(size 1.2192 1.2192)
					(clearance 0.127)
				)
				(layer "B.Cu"
					(shape circle)
					(size 1.2192 1.2192)
					(clearance 0.127)
				)
			)
		)
		(pad "E4" thru_hole oval
			(at 10.40003 -7.249922 180)
			(size 1.2192 4.2164)
			(drill 0.739902)
			(layers "*.Cu" "*.Mask")
			(remove_unused_layers no)
			(net "P12V_IN")
			(clearance 0.127)
			(thermal_gap 0.127)
			(padstack
				(mode front_inner_back)
				(layer "Inner"
					(shape circle)
					(size 1.2192 1.2192)
					(clearance 0.127)
				)
				(layer "B.Cu"
					(shape circle)
					(size 1.2192 1.2192)
					(clearance 0.127)
				)
			)
		)
		(pad "E5" thru_hole oval
			(at 14.400022 -7.249922 180)
			(size 1.2192 4.2164)
			(drill 0.739902)
			(layers "*.Cu" "*.Mask")
			(remove_unused_layers no)
			(net "GND")
			(clearance 0.127)
			(thermal_gap 0.127)
			(padstack
				(mode front_inner_back)
				(layer "Inner"
					(shape circle)
					(size 1.2192 1.2192)
					(clearance 0.127)
				)
				(layer "B.Cu"
					(shape circle)
					(size 1.2192 1.2192)
					(clearance 0.127)
				)
			)
		)
		(pad "E6" thru_hole oval
			(at 17.599914 -7.249922 180)
			(size 1.2192 4.2164)
			(drill 0.739902)
			(layers "*.Cu" "*.Mask")
			(remove_unused_layers no)
			(net "GND")
			(clearance 0.127)
			(thermal_gap 0.127)
			(padstack
				(mode front_inner_back)
				(layer "Inner"
					(shape circle)
					(size 1.2192 1.2192)
					(clearance 0.127)
				)
				(layer "B.Cu"
					(shape circle)
					(size 1.2192 1.2192)
					(clearance 0.127)
				)
			)
		)
		(pad "F1" thru_hole circle
			(at 0 -8.750046 180)
			(size 1.2192 1.2192)
			(drill 0.739902)
			(layers "*.Cu" "*.Mask")
			(remove_unused_layers no)
			(net "P12V_IN")
			(clearance 0.127)
			(thermal_gap 0.127)
		)
		(pad "F2" thru_hole circle
			(at 3.199892 -8.750046 180)
			(size 1.2192 1.2192)
			(drill 0.739902)
			(layers "*.Cu" "*.Mask")
			(remove_unused_layers no)
			(net "P12V_IN")
			(clearance 0.127)
			(thermal_gap 0.127)
		)
		(pad "F3" thru_hole circle
			(at 7.199884 -8.750046 180)
			(size 1.2192 1.2192)
			(drill 0.739902)
			(layers "*.Cu" "*.Mask")
			(remove_unused_layers no)
			(net "P12V_IN")
			(clearance 0.127)
			(thermal_gap 0.127)
		)
		(pad "F4" thru_hole circle
			(at 10.40003 -8.750046 180)
			(size 1.2192 1.2192)
			(drill 0.739902)
			(layers "*.Cu" "*.Mask")
			(remove_unused_layers no)
			(net "P12V_IN")
			(clearance 0.127)
			(thermal_gap 0.127)
		)
		(pad "F5" thru_hole circle
			(at 14.400022 -8.750046 180)
			(size 1.2192 1.2192)
			(drill 0.739902)
			(layers "*.Cu" "*.Mask")
			(remove_unused_layers no)
			(net "GND")
			(clearance 0.127)
			(thermal_gap 0.127)
		)
		(pad "F6" thru_hole circle
			(at 17.599914 -8.750046 180)
			(size 1.2192 1.2192)
			(drill 0.739902)
			(layers "*.Cu" "*.Mask")
			(remove_unused_layers no)
			(net "GND")
			(clearance 0.127)
			(thermal_gap 0.127)
		)
		(pad "G1" thru_hole circle
			(at 0 -11.500104 180)
			(size 1.2192 1.2192)
			(drill 0.739902)
			(layers "*.Cu" "*.Mask")
			(remove_unused_layers no)
			(net "GND")
			(clearance 0.127)
			(thermal_gap 0.127)
		)
		(pad "G2" thru_hole circle
			(at 3.199892 -11.500104 180)
			(size 1.2192 1.2192)
			(drill 0.739902)
			(layers "*.Cu" "*.Mask")
			(remove_unused_layers no)
			(net "GND")
			(clearance 0.127)
			(thermal_gap 0.127)
		)
		(pad "G3" thru_hole circle
			(at 7.199884 -11.500104 180)
			(size 1.2192 1.2192)
			(drill 0.739902)
			(layers "*.Cu" "*.Mask")
			(remove_unused_layers no)
			(net "GND")
			(clearance 0.127)
			(thermal_gap 0.127)
		)
		(pad "G4" thru_hole circle
			(at 10.40003 -11.500104 180)
			(size 1.2192 1.2192)
			(drill 0.739902)
			(layers "*.Cu" "*.Mask")
			(remove_unused_layers no)
			(net "GND")
			(clearance 0.127)
			(thermal_gap 0.127)
		)
		(pad "G5" thru_hole circle
			(at 14.400022 -11.500104 180)
			(size 1.2192 1.2192)
			(drill 0.739902)
			(layers "*.Cu" "*.Mask")
			(remove_unused_layers no)
			(net "GND")
			(clearance 0.127)
			(thermal_gap 0.127)
		)
		(pad "G6" thru_hole circle
			(at 17.599914 -11.500104 180)
			(size 1.2192 1.2192)
			(drill 0.739902)
			(layers "*.Cu" "*.Mask")
			(remove_unused_layers no)
			(net "GND")
			(clearance 0.127)
			(thermal_gap 0.127)
		)
		(pad "H1" thru_hole oval
			(at 0 -12.999974 180)
			(size 1.2192 4.2164)
			(drill 0.739902)
			(layers "*.Cu" "*.Mask")
			(remove_unused_layers no)
			(net "GND")
			(clearance 0.127)
			(thermal_gap 0.127)
			(padstack
				(mode front_inner_back)
				(layer "Inner"
					(shape circle)
					(size 1.2192 1.2192)
					(clearance 0.127)
				)
				(layer "B.Cu"
					(shape circle)
					(size 1.2192 1.2192)
					(clearance 0.127)
				)
			)
		)
		(pad "H2" thru_hole oval
			(at 3.199892 -12.999974 180)
			(size 1.2192 4.2164)
			(drill 0.739902)
			(layers "*.Cu" "*.Mask")
			(remove_unused_layers no)
			(net "GND")
			(clearance 0.127)
			(thermal_gap 0.127)
			(padstack
				(mode front_inner_back)
				(layer "Inner"
					(shape circle)
					(size 1.2192 1.2192)
					(clearance 0.127)
				)
				(layer "B.Cu"
					(shape circle)
					(size 1.2192 1.2192)
					(clearance 0.127)
				)
			)
		)
		(pad "H3" thru_hole oval
			(at 7.199884 -12.999974 180)
			(size 1.2192 4.2164)
			(drill 0.739902)
			(layers "*.Cu" "*.Mask")
			(remove_unused_layers no)
			(net "GND")
			(clearance 0.127)
			(thermal_gap 0.127)
			(padstack
				(mode front_inner_back)
				(layer "Inner"
					(shape circle)
					(size 1.2192 1.2192)
					(clearance 0.127)
				)
				(layer "B.Cu"
					(shape circle)
					(size 1.2192 1.2192)
					(clearance 0.127)
				)
			)
		)
		(pad "H4" thru_hole oval
			(at 10.40003 -12.999974 180)
			(size 1.2192 4.2164)
			(drill 0.739902)
			(layers "*.Cu" "*.Mask")
			(remove_unused_layers no)
			(net "GND")
			(clearance 0.127)
			(thermal_gap 0.127)
			(padstack
				(mode front_inner_back)
				(layer "Inner"
					(shape circle)
					(size 1.2192 1.2192)
					(clearance 0.127)
				)
				(layer "B.Cu"
					(shape circle)
					(size 1.2192 1.2192)
					(clearance 0.127)
				)
			)
		)
		(pad "H5" thru_hole oval
			(at 14.400022 -12.999974 180)
			(size 1.2192 4.2164)
			(drill 0.739902)
			(layers "*.Cu" "*.Mask")
			(remove_unused_layers no)
			(net "GND")
			(clearance 0.127)
			(thermal_gap 0.127)
			(padstack
				(mode front_inner_back)
				(layer "Inner"
					(shape circle)
					(size 1.2192 1.2192)
					(clearance 0.127)
				)
				(layer "B.Cu"
					(shape circle)
					(size 1.2192 1.2192)
					(clearance 0.127)
				)
			)
		)
		(pad "H6" thru_hole oval
			(at 17.599914 -12.999974 180)
			(size 1.2192 4.2164)
			(drill 0.739902)
			(layers "*.Cu" "*.Mask")
			(remove_unused_layers no)
			(net "GND")
			(clearance 0.127)
			(thermal_gap 0.127)
			(padstack
				(mode front_inner_back)
				(layer "Inner"
					(shape circle)
					(size 1.2192 1.2192)
					(clearance 0.127)
				)
				(layer "B.Cu"
					(shape circle)
					(size 1.2192 1.2192)
					(clearance 0.127)
				)
			)
		)
		(pad "J1" thru_hole circle
			(at 0 -14.500098 180)
			(size 1.2192 1.2192)
			(drill 0.739902)
			(layers "*.Cu" "*.Mask")
			(remove_unused_layers no)
			(net "GND")
			(clearance 0.127)
			(thermal_gap 0.127)
		)
		(pad "J2" thru_hole circle
			(at 3.199892 -14.500098 180)
			(size 1.2192 1.2192)
			(drill 0.739902)
			(layers "*.Cu" "*.Mask")
			(remove_unused_layers no)
			(net "GND")
			(clearance 0.127)
			(thermal_gap 0.127)
		)
		(pad "J3" thru_hole circle
			(at 7.199884 -14.500098 180)
			(size 1.2192 1.2192)
			(drill 0.739902)
			(layers "*.Cu" "*.Mask")
			(remove_unused_layers no)
			(net "GND")
			(clearance 0.127)
			(thermal_gap 0.127)
		)
		(pad "J4" thru_hole circle
			(at 10.40003 -14.500098 180)
			(size 1.2192 1.2192)
			(drill 0.739902)
			(layers "*.Cu" "*.Mask")
			(remove_unused_layers no)
			(net "GND")
			(clearance 0.127)
			(thermal_gap 0.127)
		)
		(pad "J5" thru_hole circle
			(at 14.400022 -14.500098 180)
			(size 1.2192 1.2192)
			(drill 0.739902)
			(layers "*.Cu" "*.Mask")
			(remove_unused_layers no)
			(net "GND")
			(clearance 0.127)
			(thermal_gap 0.127)
		)
		(pad "J6" thru_hole circle
			(at 17.599914 -14.500098 180)
			(size 1.2192 1.2192)
			(drill 0.739902)
			(layers "*.Cu" "*.Mask")
			(remove_unused_layers no)
			(net "GND")
			(clearance 0.127)
			(thermal_gap 0.127)
		)
		(zone
			(layer "F.Cu")
			(hatch none 0.5)
			(connect_pads
				(clearance 0)
			)
			(min_thickness 0.25)
			(keepout
				(tracks allowed)
				(vias not_allowed)
				(pads allowed)
				(copperpour not_allowed)
				(footprints allowed)
			)
			(placement
				(enabled no)
				(sheetname "")
			)
			(fill
				(thermal_gap 0.5)
				(thermal_bridge_width 0.5)
				(island_removal_mode 0)
			)
			(polygon
				(pts
					(xy 251.44984 -419.519862) (xy 251.44984 -403.319996) (xy 250.606306 -403.319996)
					(arc
						(start 250.606306 -403.560026)
						(mid 251.033272 -403.740695)
						(end 251.20981 -404.169372)
					)
					(arc
						(start 251.20981 -407.170128)
						(mid 251.033427 -407.599109)
						(end 250.606306 -407.779982)
					)
					(arc
						(start 250.606306 -409.310078)
						(mid 251.033451 -409.490928)
						(end 251.20981 -409.919932)
					)
					(arc
						(start 251.20981 -412.919926)
						(mid 251.033427 -413.348907)
						(end 250.606306 -413.52978)
					)
					(arc
						(start 250.606306 -415.06013)
						(mid 251.033451 -415.24098)
						(end 251.20981 -415.669984)
					)
					(arc
						(start 251.20981 -418.669978)
						(mid 250.599956 -419.279832)
						(end 249.990102 -418.669978)
					)
					(arc
						(start 249.990102 -415.669984)
						(mid 250.166485 -415.241003)
						(end 250.593606 -415.06013)
					)
					(arc
						(start 250.593606 -413.52978)
						(mid 250.166461 -413.34893)
						(end 249.990102 -412.919926)
					)
					(arc
						(start 249.990102 -409.919932)
						(mid 250.166485 -409.490951)
						(end 250.593606 -409.310078)
					)
					(arc
						(start 250.593606 -407.779982)
						(mid 250.166461 -407.599132)
						(end 249.990102 -407.170128)
					)
					(arc
						(start 249.990102 -404.169372)
						(mid 250.166664 -403.740718)
						(end 250.593606 -403.560026)
					)
					(xy 250.593606 -403.319996) (xy 247.406414 -403.319996)
					(arc
						(start 247.406414 -403.560026)
						(mid 247.833559 -403.740876)
						(end 248.009918 -404.16988)
					)
					(arc
						(start 248.009918 -407.169874)
						(mid 247.833535 -407.598855)
						(end 247.406414 -407.779728)
					)
					(arc
						(start 247.406414 -409.310078)
						(mid 247.833559 -409.490928)
						(end 248.009918 -409.919932)
					)
					(arc
						(start 248.009918 -412.919926)
						(mid 247.833535 -413.348907)
						(end 247.406414 -413.52978)
					)
					(arc
						(start 247.406414 -415.06013)
						(mid 247.83338 -415.240799)
						(end 248.009918 -415.669476)
					)
					(arc
						(start 248.009918 -418.669978)
						(mid 247.400064 -419.279832)
						(end 246.79021 -418.669978)
					)
					(arc
						(start 246.79021 -415.669476)
						(mid 246.966772 -415.240822)
						(end 247.393714 -415.06013)
					)
					(arc
						(start 247.393714 -413.52978)
						(mid 246.966569 -413.34893)
						(end 246.79021 -412.919926)
					)
					(arc
						(start 246.79021 -409.919932)
						(mid 246.966593 -409.490951)
						(end 247.393714 -409.310078)
					)
					(arc
						(start 247.393714 -407.779728)
						(mid 246.966569 -407.598878)
						(end 246.79021 -407.169874)
					)
					(arc
						(start 246.79021 -404.16988)
						(mid 246.966593 -403.740899)
						(end 247.393714 -403.560026)
					)
					(xy 247.393714 -403.319996) (xy 246.549926 -403.319996) (xy 246.549926 -419.519862)
				)
			)
		)
		(zone
			(layer "F.Cu")
			(hatch none 0.5)
			(connect_pads
				(clearance 0)
			)
			(min_thickness 0.25)
			(keepout
				(tracks not_allowed)
				(vias allowed)
				(pads allowed)
				(copperpour not_allowed)
				(footprints allowed)
			)
			(placement
				(enabled no)
				(sheetname "")
			)
			(fill
				(thermal_gap 0.5)
				(thermal_bridge_width 0.5)
				(island_removal_mode 0)
			)
			(polygon
				(pts
					(xy 251.44984 -419.519862) (xy 251.44984 -403.319996) (xy 250.606306 -403.319996)
					(arc
						(start 250.606306 -403.560026)
						(mid 251.033272 -403.740695)
						(end 251.20981 -404.169372)
					)
					(arc
						(start 251.20981 -407.170128)
						(mid 251.033427 -407.599109)
						(end 250.606306 -407.779982)
					)
					(arc
						(start 250.606306 -409.310078)
						(mid 251.033451 -409.490928)
						(end 251.20981 -409.919932)
					)
					(arc
						(start 251.20981 -412.919926)
						(mid 251.033427 -413.348907)
						(end 250.606306 -413.52978)
					)
					(arc
						(start 250.606306 -415.06013)
						(mid 251.033451 -415.24098)
						(end 251.20981 -415.669984)
					)
					(arc
						(start 251.20981 -418.669978)
						(mid 250.599956 -419.279832)
						(end 249.990102 -418.669978)
					)
					(arc
						(start 249.990102 -415.669984)
						(mid 250.166485 -415.241003)
						(end 250.593606 -415.06013)
					)
					(arc
						(start 250.593606 -413.52978)
						(mid 250.166461 -413.34893)
						(end 249.990102 -412.919926)
					)
					(arc
						(start 249.990102 -409.919932)
						(mid 250.166485 -409.490951)
						(end 250.593606 -409.310078)
					)
					(arc
						(start 250.593606 -407.779982)
						(mid 250.166461 -407.599132)
						(end 249.990102 -407.170128)
					)
					(arc
						(start 249.990102 -404.169372)
						(mid 250.166664 -403.740718)
						(end 250.593606 -403.560026)
					)
					(xy 250.593606 -403.319996) (xy 247.406414 -403.319996)
					(arc
						(start 247.406414 -403.560026)
						(mid 247.833559 -403.740876)
						(end 248.009918 -404.16988)
					)
					(arc
						(start 248.009918 -407.169874)
						(mid 247.833535 -407.598855)
						(end 247.406414 -407.779728)
					)
					(arc
						(start 247.406414 -409.310078)
						(mid 247.833559 -409.490928)
						(end 248.009918 -409.919932)
					)
					(arc
						(start 248.009918 -412.919926)
						(mid 247.833535 -413.348907)
						(end 247.406414 -413.52978)
					)
					(arc
						(start 247.406414 -415.06013)
						(mid 247.83338 -415.240799)
						(end 248.009918 -415.669476)
					)
					(arc
						(start 248.009918 -418.669978)
						(mid 247.400064 -419.279832)
						(end 246.79021 -418.669978)
					)
					(arc
						(start 246.79021 -415.669476)
						(mid 246.966772 -415.240822)
						(end 247.393714 -415.06013)
					)
					(arc
						(start 247.393714 -413.52978)
						(mid 246.966569 -413.34893)
						(end 246.79021 -412.919926)
					)
					(arc
						(start 246.79021 -409.919932)
						(mid 246.966593 -409.490951)
						(end 247.393714 -409.310078)
					)
					(arc
						(start 247.393714 -407.779728)
						(mid 246.966569 -407.598878)
						(end 246.79021 -407.169874)
					)
					(arc
						(start 246.79021 -404.16988)
						(mid 246.966593 -403.740899)
						(end 247.393714 -403.560026)
					)
					(xy 247.393714 -403.319996) (xy 246.549926 -403.319996) (xy 246.549926 -419.519862)
				)
			)
		)
		(zone
			(layer "F.Cu")
			(hatch none 0.5)
			(connect_pads
				(clearance 0)
			)
			(min_thickness 0.25)
			(keepout
				(tracks not_allowed)
				(vias allowed)
				(pads allowed)
				(copperpour not_allowed)
				(footprints allowed)
			)
			(placement
				(enabled no)
				(sheetname "")
			)
			(fill
				(thermal_gap 0.5)
				(thermal_bridge_width 0.5)
				(island_removal_mode 0)
			)
			(polygon
				(pts
					(xy 258.649978 -419.519862) (xy 258.649978 -403.319996) (xy 257.806444 -403.319996)
					(arc
						(start 257.806444 -403.560026)
						(mid 258.23341 -403.740695)
						(end 258.409948 -404.169372)
					)
					(arc
						(start 258.409948 -407.170128)
						(mid 258.233565 -407.599109)
						(end 257.806444 -407.779982)
					)
					(arc
						(start 257.806444 -409.310078)
						(mid 258.233589 -409.490928)
						(end 258.409948 -409.919932)
					)
					(arc
						(start 258.409948 -412.919926)
						(mid 258.233565 -413.348907)
						(end 257.806444 -413.52978)
					)
					(arc
						(start 257.806444 -415.06013)
						(mid 258.233589 -415.24098)
						(end 258.409948 -415.669984)
					)
					(arc
						(start 258.409948 -418.669978)
						(mid 257.800094 -419.279832)
						(end 257.19024 -418.669978)
					)
					(arc
						(start 257.19024 -415.669984)
						(mid 257.366623 -415.241003)
						(end 257.793744 -415.06013)
					)
					(arc
						(start 257.793744 -413.52978)
						(mid 257.366599 -413.34893)
						(end 257.19024 -412.919926)
					)
					(arc
						(start 257.19024 -409.919932)
						(mid 257.366623 -409.490951)
						(end 257.793744 -409.310078)
					)
					(arc
						(start 257.793744 -407.779982)
						(mid 257.366599 -407.599132)
						(end 257.19024 -407.170128)
					)
					(arc
						(start 257.19024 -404.169372)
						(mid 257.366802 -403.740718)
						(end 257.793744 -403.560026)
					)
					(xy 257.793744 -403.319996) (xy 254.606552 -403.319996)
					(arc
						(start 254.606552 -403.560026)
						(mid 255.033697 -403.740876)
						(end 255.210056 -404.16988)
					)
					(arc
						(start 255.210056 -407.169874)
						(mid 255.033673 -407.598855)
						(end 254.606552 -407.779728)
					)
					(arc
						(start 254.606552 -409.310078)
						(mid 255.033697 -409.490928)
						(end 255.210056 -409.919932)
					)
					(arc
						(start 255.210056 -412.919926)
						(mid 255.033673 -413.348907)
						(end 254.606552 -413.52978)
					)
					(arc
						(start 254.606552 -415.06013)
						(mid 255.033518 -415.240799)
						(end 255.210056 -415.669476)
					)
					(arc
						(start 255.210056 -418.669978)
						(mid 254.600202 -419.279832)
						(end 253.990348 -418.669978)
					)
					(arc
						(start 253.990348 -415.669476)
						(mid 254.16691 -415.240822)
						(end 254.593852 -415.06013)
					)
					(arc
						(start 254.593852 -413.52978)
						(mid 254.166707 -413.34893)
						(end 253.990348 -412.919926)
					)
					(arc
						(start 253.990348 -409.919932)
						(mid 254.166731 -409.490951)
						(end 254.593852 -409.310078)
					)
					(arc
						(start 254.593852 -407.779728)
						(mid 254.166707 -407.598878)
						(end 253.990348 -407.169874)
					)
					(arc
						(start 253.990348 -404.16988)
						(mid 254.166731 -403.740899)
						(end 254.593852 -403.560026)
					)
					(xy 254.593852 -403.319996) (xy 253.750064 -403.319996) (xy 253.750064 -419.519862)
				)
			)
		)
		(zone
			(layer "F.Cu")
			(hatch none 0.5)
			(connect_pads
				(clearance 0)
			)
			(min_thickness 0.25)
			(keepout
				(tracks allowed)
				(vias not_allowed)
				(pads allowed)
				(copperpour not_allowed)
				(footprints allowed)
			)
			(placement
				(enabled no)
				(sheetname "")
			)
			(fill
				(thermal_gap 0.5)
				(thermal_bridge_width 0.5)
				(island_removal_mode 0)
			)
			(polygon
				(pts
					(xy 258.649978 -419.519862) (xy 258.649978 -403.319996) (xy 257.806444 -403.319996)
					(arc
						(start 257.806444 -403.560026)
						(mid 258.23341 -403.740695)
						(end 258.409948 -404.169372)
					)
					(arc
						(start 258.409948 -407.170128)
						(mid 258.233565 -407.599109)
						(end 257.806444 -407.779982)
					)
					(arc
						(start 257.806444 -409.310078)
						(mid 258.233589 -409.490928)
						(end 258.409948 -409.919932)
					)
					(arc
						(start 258.409948 -412.919926)
						(mid 258.233565 -413.348907)
						(end 257.806444 -413.52978)
					)
					(arc
						(start 257.806444 -415.06013)
						(mid 258.233589 -415.24098)
						(end 258.409948 -415.669984)
					)
					(arc
						(start 258.409948 -418.669978)
						(mid 257.800094 -419.279832)
						(end 257.19024 -418.669978)
					)
					(arc
						(start 257.19024 -415.669984)
						(mid 257.366623 -415.241003)
						(end 257.793744 -415.06013)
					)
					(arc
						(start 257.793744 -413.52978)
						(mid 257.366599 -413.34893)
						(end 257.19024 -412.919926)
					)
					(arc
						(start 257.19024 -409.919932)
						(mid 257.366623 -409.490951)
						(end 257.793744 -409.310078)
					)
					(arc
						(start 257.793744 -407.779982)
						(mid 257.366599 -407.599132)
						(end 257.19024 -407.170128)
					)
					(arc
						(start 257.19024 -404.169372)
						(mid 257.366802 -403.740718)
						(end 257.793744 -403.560026)
					)
					(xy 257.793744 -403.319996) (xy 254.606552 -403.319996)
					(arc
						(start 254.606552 -403.560026)
						(mid 255.033697 -403.740876)
						(end 255.210056 -404.16988)
					)
					(arc
						(start 255.210056 -407.169874)
						(mid 255.033673 -407.598855)
						(end 254.606552 -407.779728)
					)
					(arc
						(start 254.606552 -409.310078)
						(mid 255.033697 -409.490928)
						(end 255.210056 -409.919932)
					)
					(arc
						(start 255.210056 -412.919926)
						(mid 255.033673 -413.348907)
						(end 254.606552 -413.52978)
					)
					(arc
						(start 254.606552 -415.06013)
						(mid 255.033518 -415.240799)
						(end 255.210056 -415.669476)
					)
					(arc
						(start 255.210056 -418.669978)
						(mid 254.600202 -419.279832)
						(end 253.990348 -418.669978)
					)
					(arc
						(start 253.990348 -415.669476)
						(mid 254.16691 -415.240822)
						(end 254.593852 -415.06013)
					)
					(arc
						(start 254.593852 -413.52978)
						(mid 254.166707 -413.34893)
						(end 253.990348 -412.919926)
					)
					(arc
						(start 253.990348 -409.919932)
						(mid 254.166731 -409.490951)
						(end 254.593852 -409.310078)
					)
					(arc
						(start 254.593852 -407.779728)
						(mid 254.166707 -407.598878)
						(end 253.990348 -407.169874)
					)
					(arc
						(start 253.990348 -404.16988)
						(mid 254.166731 -403.740899)
						(end 254.593852 -403.560026)
					)
					(xy 254.593852 -403.319996) (xy 253.750064 -403.319996) (xy 253.750064 -419.519862)
				)
			)
		)
		(zone
			(layer "F.Cu")
			(hatch none 0.5)
			(connect_pads
				(clearance 0)
			)
			(min_thickness 0.25)
			(keepout
				(tracks not_allowed)
				(vias allowed)
				(pads allowed)
				(copperpour not_allowed)
				(footprints allowed)
			)
			(placement
				(enabled no)
				(sheetname "")
			)
			(fill
				(thermal_gap 0.5)
				(thermal_bridge_width 0.5)
				(island_removal_mode 0)
			)
			(polygon
				(pts
					(xy 265.849862 -419.519862) (xy 265.849862 -403.319996) (xy 265.006328 -403.319996)
					(arc
						(start 265.006328 -403.560026)
						(mid 265.433294 -403.740695)
						(end 265.609832 -404.169372)
					)
					(arc
						(start 265.609832 -407.170128)
						(mid 265.433449 -407.599109)
						(end 265.006328 -407.779982)
					)
					(arc
						(start 265.006328 -409.310078)
						(mid 265.433473 -409.490928)
						(end 265.609832 -409.919932)
					)
					(arc
						(start 265.609832 -412.919926)
						(mid 265.433449 -413.348907)
						(end 265.006328 -413.52978)
					)
					(arc
						(start 265.006328 -415.06013)
						(mid 265.433473 -415.24098)
						(end 265.609832 -415.669984)
					)
					(arc
						(start 265.609832 -418.669978)
						(mid 264.999978 -419.279832)
						(end 264.390124 -418.669978)
					)
					(arc
						(start 264.390124 -415.669984)
						(mid 264.566507 -415.241003)
						(end 264.993628 -415.06013)
					)
					(arc
						(start 264.993628 -413.52978)
						(mid 264.566483 -413.34893)
						(end 264.390124 -412.919926)
					)
					(arc
						(start 264.390124 -409.919932)
						(mid 264.566507 -409.490951)
						(end 264.993628 -409.310078)
					)
					(arc
						(start 264.993628 -407.779982)
						(mid 264.566483 -407.599132)
						(end 264.390124 -407.170128)
					)
					(arc
						(start 264.390124 -404.169372)
						(mid 264.566686 -403.740718)
						(end 264.993628 -403.560026)
					)
					(xy 264.993628 -403.319996) (xy 261.806436 -403.319996)
					(arc
						(start 261.806436 -403.560026)
						(mid 262.233581 -403.740876)
						(end 262.40994 -404.16988)
					)
					(arc
						(start 262.40994 -407.169874)
						(mid 262.233557 -407.598855)
						(end 261.806436 -407.779728)
					)
					(arc
						(start 261.806436 -409.310078)
						(mid 262.233581 -409.490928)
						(end 262.40994 -409.919932)
					)
					(arc
						(start 262.40994 -412.919926)
						(mid 262.233557 -413.348907)
						(end 261.806436 -413.52978)
					)
					(arc
						(start 261.806436 -415.06013)
						(mid 262.233402 -415.240799)
						(end 262.40994 -415.669476)
					)
					(arc
						(start 262.40994 -418.669978)
						(mid 261.800086 -419.279832)
						(end 261.190232 -418.669978)
					)
					(arc
						(start 261.190232 -415.669476)
						(mid 261.366794 -415.240822)
						(end 261.793736 -415.06013)
					)
					(arc
						(start 261.793736 -413.52978)
						(mid 261.366591 -413.34893)
						(end 261.190232 -412.919926)
					)
					(arc
						(start 261.190232 -409.919932)
						(mid 261.366615 -409.490951)
						(end 261.793736 -409.310078)
					)
					(arc
						(start 261.793736 -407.779728)
						(mid 261.366591 -407.598878)
						(end 261.190232 -407.169874)
					)
					(arc
						(start 261.190232 -404.16988)
						(mid 261.366615 -403.740899)
						(end 261.793736 -403.560026)
					)
					(xy 261.793736 -403.319996) (xy 260.949948 -403.319996) (xy 260.949948 -419.519862)
				)
			)
		)
		(zone
			(layer "F.Cu")
			(hatch none 0.5)
			(connect_pads
				(clearance 0)
			)
			(min_thickness 0.25)
			(keepout
				(tracks allowed)
				(vias not_allowed)
				(pads allowed)
				(copperpour not_allowed)
				(footprints allowed)
			)
			(placement
				(enabled no)
				(sheetname "")
			)
			(fill
				(thermal_gap 0.5)
				(thermal_bridge_width 0.5)
				(island_removal_mode 0)
			)
			(polygon
				(pts
					(xy 265.849862 -419.519862) (xy 265.849862 -403.319996) (xy 265.006328 -403.319996)
					(arc
						(start 265.006328 -403.560026)
						(mid 265.433294 -403.740695)
						(end 265.609832 -404.169372)
					)
					(arc
						(start 265.609832 -407.170128)
						(mid 265.433449 -407.599109)
						(end 265.006328 -407.779982)
					)
					(arc
						(start 265.006328 -409.310078)
						(mid 265.433473 -409.490928)
						(end 265.609832 -409.919932)
					)
					(arc
						(start 265.609832 -412.919926)
						(mid 265.433449 -413.348907)
						(end 265.006328 -413.52978)
					)
					(arc
						(start 265.006328 -415.06013)
						(mid 265.433473 -415.24098)
						(end 265.609832 -415.669984)
					)
					(arc
						(start 265.609832 -418.669978)
						(mid 264.999978 -419.279832)
						(end 264.390124 -418.669978)
					)
					(arc
						(start 264.390124 -415.669984)
						(mid 264.566507 -415.241003)
						(end 264.993628 -415.06013)
					)
					(arc
						(start 264.993628 -413.52978)
						(mid 264.566483 -413.34893)
						(end 264.390124 -412.919926)
					)
					(arc
						(start 264.390124 -409.919932)
						(mid 264.566507 -409.490951)
						(end 264.993628 -409.310078)
					)
					(arc
						(start 264.993628 -407.779982)
						(mid 264.566483 -407.599132)
						(end 264.390124 -407.170128)
					)
					(arc
						(start 264.390124 -404.169372)
						(mid 264.566686 -403.740718)
						(end 264.993628 -403.560026)
					)
					(xy 264.993628 -403.319996) (xy 261.806436 -403.319996)
					(arc
						(start 261.806436 -403.560026)
						(mid 262.233581 -403.740876)
						(end 262.40994 -404.16988)
					)
					(arc
						(start 262.40994 -407.169874)
						(mid 262.233557 -407.598855)
						(end 261.806436 -407.779728)
					)
					(arc
						(start 261.806436 -409.310078)
						(mid 262.233581 -409.490928)
						(end 262.40994 -409.919932)
					)
					(arc
						(start 262.40994 -412.919926)
						(mid 262.233557 -413.348907)
						(end 261.806436 -413.52978)
					)
					(arc
						(start 261.806436 -415.06013)
						(mid 262.233402 -415.240799)
						(end 262.40994 -415.669476)
					)
					(arc
						(start 262.40994 -418.669978)
						(mid 261.800086 -419.279832)
						(end 261.190232 -418.669978)
					)
					(arc
						(start 261.190232 -415.669476)
						(mid 261.366794 -415.240822)
						(end 261.793736 -415.06013)
					)
					(arc
						(start 261.793736 -413.52978)
						(mid 261.366591 -413.34893)
						(end 261.190232 -412.919926)
					)
					(arc
						(start 261.190232 -409.919932)
						(mid 261.366615 -409.490951)
						(end 261.793736 -409.310078)
					)
					(arc
						(start 261.793736 -407.779728)
						(mid 261.366591 -407.598878)
						(end 261.190232 -407.169874)
					)
					(arc
						(start 261.190232 -404.16988)
						(mid 261.366615 -403.740899)
						(end 261.793736 -403.560026)
					)
					(xy 261.793736 -403.319996) (xy 260.949948 -403.319996) (xy 260.949948 -419.519862)
				)
			)
		)
	)
	(footprint ""
		(layer "F.Cu")
		(at 17.800066 -209.399886)
		(property "Reference" "FLED1"
			(at 0 0 0)
			(layer "F.SilkS")
			(hide yes)
			(effects
				(font
					(size 1.27 1.27)
				)
			)
		)
		(property "Value" "LED-BY-19-GP"
			(at -2.132076 1.414018 0)
			(unlocked yes)
			(layer "F.Fab")
			(hide yes)
			(effects
				(font
					(size 1.016 1.016)
					(thickness 0.1524)
				)
			)
		)
		(property "Device Type" "LED-1615-4PH26"
			(at -2.132076 -0.109982 0)
			(unlocked yes)
			(layer "F.Fab")
			(hide yes)
			(effects
				(font
					(size 1.016 1.016)
					(thickness 0.1524)
				)
			)
		)
		(duplicate_pad_numbers_are_jumpers no)
		(fp_line
			(start -1.2954 0.254)
			(end -1.2954 1.6002)
			(stroke
				(width 0.508)
				(type default)
			)
			(layer "F.SilkS")
		)
		(fp_line
			(start -1.2954 1.6002)
			(end 1.2954 1.6002)
			(stroke
				(width 0.508)
				(type default)
			)
			(layer "F.SilkS")
		)
		(fp_line
			(start -1.1176 -1.4224)
			(end 1.1176 -1.4224)
			(stroke
				(width 0.1524)
				(type default)
			)
			(layer "F.SilkS")
		)
		(fp_line
			(start -1.1176 1.4224)
			(end -1.1176 -1.4224)
			(stroke
				(width 0.1524)
				(type default)
			)
			(layer "F.SilkS")
		)
		(fp_line
			(start 1.1176 -1.4224)
			(end 1.1176 1.4224)
			(stroke
				(width 0.1524)
				(type default)
			)
			(layer "F.SilkS")
		)
		(fp_line
			(start 1.1176 1.4224)
			(end -1.1176 1.4224)
			(stroke
				(width 0.1524)
				(type default)
			)
			(layer "F.SilkS")
		)
		(fp_line
			(start 1.2954 1.6002)
			(end 1.2954 0.254)
			(stroke
				(width 0.508)
				(type default)
			)
			(layer "F.SilkS")
		)
		(fp_rect
			(start -0.7493 0.8001)
			(end 0.7493 -0.8001)
			(stroke
				(width 0)
				(type default)
			)
			(fill no)
			(layer "F.CrtYd")
		)
		(fp_poly
			(pts
				(xy -1.3716 1.6764) (xy -1.3716 -1.6764) (xy 1.3716 -1.6764) (xy 1.3716 0.0635) (xy 0.7493 0.0635)
				(xy 0.7493 -0.8001) (xy -0.7493 -0.8001) (xy -0.7493 0.8001) (xy 0.7493 0.8001) (xy 0.7493 0.0762)
				(xy 1.3716 0.0762) (xy 1.3716 1.6764)
			)
			(stroke
				(width 0)
				(type default)
			)
			(fill no)
			(layer "F.CrtYd")
		)
		(fp_rect
			(start -1.3716 1.6764)
			(end 1.3716 -1.6764)
			(stroke
				(width 0)
				(type default)
			)
			(fill no)
			(layer "F.Fab")
		)
		(pad "1" smd rect
			(at 0.50038 -0.73025)
			(size 0.7112 0.8636)
			(layers "F.Cu" "F.Mask" "F.Paste")
			(net "DRV_ACT_0")
		)
		(pad "2" smd rect
			(at -0.50038 -0.73025)
			(size 0.7112 0.8636)
			(layers "F.Cu" "F.Mask" "F.Paste")
			(net "FLT_HDD0")
		)
		(pad "3" smd rect
			(at 0.50038 0.73025)
			(size 0.7112 0.8636)
			(layers "F.Cu" "F.Mask" "F.Paste")
			(net "DRV_ACT_0_N")
		)
		(pad "4" smd rect
			(at -0.50038 0.73025)
			(size 0.7112 0.8636)
			(layers "F.Cu" "F.Mask" "F.Paste")
			(net "FLT_HDD0_N")
		)
	)
	(footprint ""
		(layer "F.Cu")
		(at 141.042898 -174.857918)
		(property "Reference" "Q98"
			(at 0 0 0)
			(layer "F.SilkS")
			(hide yes)
			(effects
				(font
					(size 1.27 1.27)
				)
			)
		)
		(property "Value" "AO4407AL-GP"
			(at -3.707384 -1.5367 0)
			(unlocked yes)
			(layer "F.Fab")
			(hide yes)
			(effects
				(font
					(size 1.016 1.016)
					(thickness 0.1524)
				)
			)
		)
		(property "Device Type" "SOIC8H69"
			(at -3.707384 -3.0607 0)
			(unlocked yes)
			(layer "F.Fab")
			(hide yes)
			(effects
				(font
					(size 1.016 1.016)
					(thickness 0.1524)
				)
			)
		)
		(duplicate_pad_numbers_are_jumpers no)
		(fp_line
			(start -2.7432 -1.4224)
			(end -2.7432 1.4224)
			(stroke
				(width 0.1524)
				(type default)
			)
			(layer "F.SilkS")
		)
		(fp_line
			(start -2.7432 1.4224)
			(end -2.6416 1.4224)
			(stroke
				(width 0.1524)
				(type default)
			)
			(layer "F.SilkS")
		)
		(fp_line
			(start -2.7432 1.4224)
			(end 2.1336 1.4224)
			(stroke
				(width 0.1524)
				(type default)
			)
			(layer "F.SilkS")
		)
		(fp_line
			(start -2.7178 -0.508)
			(end -2.1844 -0.0508)
			(stroke
				(width 0.1524)
				(type default)
			)
			(layer "F.SilkS")
		)
		(fp_line
			(start -2.6289 3.4417)
			(end -2.6289 1.4732)
			(stroke
				(width 0.381)
				(type default)
			)
			(layer "F.SilkS")
		)
		(fp_line
			(start -2.1844 -0.0508)
			(end -2.7178 0.508)
			(stroke
				(width 0.1524)
				(type default)
			)
			(layer "F.SilkS")
		)
		(fp_line
			(start 2.1336 -1.4224)
			(end -2.7432 -1.4224)
			(stroke
				(width 0.1524)
				(type default)
			)
			(layer "F.SilkS")
		)
		(fp_line
			(start 2.1336 1.4224)
			(end 2.1336 -1.4224)
			(stroke
				(width 0.1524)
				(type default)
			)
			(layer "F.SilkS")
		)
		(fp_poly
			(pts
				(xy -2.2098 -1.4224) (xy -2.2098 1.4224) (xy 2.2098 1.4224) (xy 2.2098 -1.4224)
			)
			(stroke
				(width 0)
				(type default)
			)
			(fill yes)
			(layer "F.SilkS")
		)
		(fp_rect
			(start -2.450084 2.999994)
			(end 2.450084 -2.999994)
			(stroke
				(width 0)
				(type default)
			)
			(fill no)
			(layer "F.CrtYd")
		)
		(fp_poly
			(pts
				(xy -2.8194 3.6322) (xy -2.8194 -3.6322) (xy 2.8194 -3.6322) (xy 2.8194 1.18364) (xy 2.450084 1.18364)
				(xy 2.450084 -2.999994) (xy -2.450084 -2.999994) (xy -2.450084 2.999994) (xy 2.450084 2.999994)
				(xy 2.450084 1.18618) (xy 2.8194 1.18618) (xy 2.8194 3.6322)
			)
			(stroke
				(width 0)
				(type default)
			)
			(fill no)
			(layer "F.CrtYd")
		)
		(fp_rect
			(start -2.8194 3.6322)
			(end 2.8194 -3.6322)
			(stroke
				(width 0)
				(type default)
			)
			(fill no)
			(layer "F.Fab")
		)
		(pad "1" smd rect
			(at -1.905 2.54)
			(size 0.635 1.651)
			(layers "F.Cu" "F.Mask" "F.Paste")
			(net "P12V_A")
		)
		(pad "2" smd rect
			(at -0.635 2.54)
			(size 0.635 1.651)
			(layers "F.Cu" "F.Mask" "F.Paste")
			(net "P12V_A")
		)
		(pad "3" smd rect
			(at 0.635 2.54)
			(size 0.635 1.651)
			(layers "F.Cu" "F.Mask" "F.Paste")
			(net "P12V_A")
		)
		(pad "4" smd rect
			(at 1.905 2.54)
			(size 0.635 1.651)
			(layers "F.Cu" "F.Mask" "F.Paste")
			(net "SW_HDD_N16")
		)
		(pad "5" smd rect
			(at 1.905 -2.54)
			(size 0.635 1.651)
			(layers "F.Cu" "F.Mask" "F.Paste")
			(net "P12V_HDD16")
		)
		(pad "6" smd rect
			(at 0.635 -2.54)
			(size 0.635 1.651)
			(layers "F.Cu" "F.Mask" "F.Paste")
			(net "P12V_HDD16")
		)
		(pad "7" smd rect
			(at -0.635 -2.54)
			(size 0.635 1.651)
			(layers "F.Cu" "F.Mask" "F.Paste")
			(net "P12V_HDD16")
		)
		(pad "8" smd rect
			(at -1.905 -2.54)
			(size 0.635 1.651)
			(layers "F.Cu" "F.Mask" "F.Paste")
			(net "P12V_HDD16")
		)
	)
	(footprint ""
		(layer "F.Cu")
		(at 428.152052 -303.954942 180)
		(property "Reference" "C162"
			(at 0 0 180)
			(layer "F.SilkS")
			(hide yes)
			(effects
				(font
					(size 1.27 1.27)
				)
			)
		)
		(property "Value" "SC4D7U25V5KX-1-GP"
			(at -0.0762 -6.1214 180)
			(unlocked yes)
			(layer "F.Fab")
			(hide yes)
			(effects
				(font
					(size 1.016 1.016)
					(thickness 0.1524)
				)
			)
		)
		(property "Device Type" "C805H58"
			(at -0.0762 -8.1534 180)
			(unlocked yes)
			(layer "F.Fab")
			(hide yes)
			(effects
				(font
					(size 1.016 1.016)
					(thickness 0.1524)
				)
			)
		)
		(duplicate_pad_numbers_are_jumpers no)
		(fp_line
			(start 0.635 0)
			(end -0.635 0)
			(stroke
				(width 0.508)
				(type default)
			)
			(layer "F.SilkS")
		)
		(fp_rect
			(start -0.9652 1.778)
			(end 0.9652 -1.778)
			(stroke
				(width 0)
				(type default)
			)
			(fill no)
			(layer "F.CrtYd")
		)
		(fp_poly
			(pts
				(xy -0.9652 -1.778) (xy 0.9652 -1.778) (xy 0.9652 1.778) (xy -0.9652 1.778)
			)
			(stroke
				(width 0)
				(type default)
			)
			(fill no)
			(layer "F.Fab")
		)
		(pad "1" smd rect
			(at 0 -0.9652 180)
			(size 1.397 1.143)
			(layers "F.Cu" "F.Mask" "F.Paste")
			(net "P12V_HDD9")
		)
		(pad "2" smd rect
			(at 0 0.9652 180)
			(size 1.397 1.143)
			(layers "F.Cu" "F.Mask" "F.Paste")
			(net "GND")
		)
	)
	(footprint ""
		(layer "F.Cu")
		(at 460.355442 -184.345072 -90)
		(property "Reference" "R637"
			(at 0 0 270)
			(layer "F.SilkS")
			(hide yes)
			(effects
				(font
					(size 1.27 1.27)
				)
			)
		)
		(property "Value" "2R6F-GP"
			(at -0.0508 -4.8514 270)
			(unlocked yes)
			(layer "F.Fab")
			(hide yes)
			(effects
				(font
					(size 1.016 1.016)
					(thickness 0.1524)
				)
			)
		)
		(property "Device Type" "R1206H26"
			(at 0 -6.3754 270)
			(unlocked yes)
			(layer "F.Fab")
			(hide yes)
			(effects
				(font
					(size 1.016 1.016)
					(thickness 0.1524)
				)
			)
		)
		(duplicate_pad_numbers_are_jumpers no)
		(fp_line
			(start -1.016 2.2352)
			(end -1.016 -2.2352)
			(stroke
				(width 0.1524)
				(type default)
			)
			(layer "F.SilkS")
		)
		(fp_line
			(start 1.016 2.2352)
			(end -1.016 2.2352)
			(stroke
				(width 0.1524)
				(type default)
			)
			(layer "F.SilkS")
		)
		(fp_line
			(start -1.016 -2.2352)
			(end 1.016 -2.2352)
			(stroke
				(width 0.1524)
				(type default)
			)
			(layer "F.SilkS")
		)
		(fp_line
			(start 1.016 -2.2352)
			(end 1.016 2.2352)
			(stroke
				(width 0.1524)
				(type default)
			)
			(layer "F.SilkS")
		)
		(fp_rect
			(start -1.0922 2.3114)
			(end 1.0922 -2.3114)
			(stroke
				(width 0)
				(type default)
			)
			(fill no)
			(layer "F.CrtYd")
		)
		(fp_poly
			(pts
				(xy -1.0922 -2.3114) (xy 1.0922 -2.3114) (xy 1.0922 2.3114) (xy -1.0922 2.3114)
			)
			(stroke
				(width 0)
				(type default)
			)
			(fill no)
			(layer "F.Fab")
		)
		(pad "1" smd rect
			(at 0 -1.397 270)
			(size 1.651 1.27)
			(layers "F.Cu" "F.Mask" "F.Paste")
			(net "P12V_HDD22")
		)
		(pad "2" smd rect
			(at 0 1.397 270)
			(size 1.651 1.27)
			(layers "F.Cu" "F.Mask" "F.Paste")
			(net "12V_PRE_22")
		)
	)
	(footprint ""
		(layer "F.Cu")
		(at 38.654228 -301.29988 90)
		(property "Reference" "R564"
			(at 0 0 90)
			(layer "F.SilkS")
			(hide yes)
			(effects
				(font
					(size 1.27 1.27)
				)
			)
		)
		(property "Value" "4K7R2J-2-GP"
			(at 0.064008 -3.993896 90)
			(unlocked yes)
			(layer "F.Fab")
			(hide yes)
			(effects
				(font
					(size 1.016 1.016)
					(thickness 0.1524)
				)
			)
		)
		(property "Device Type" "R402H16"
			(at 0.064008 -5.517896 90)
			(unlocked yes)
			(layer "F.Fab")
			(hide yes)
			(effects
				(font
					(size 1.016 1.016)
					(thickness 0.1524)
				)
			)
		)
		(duplicate_pad_numbers_are_jumpers no)
		(fp_line
			(start 0.508 -0.9398)
			(end -0.508 -0.9398)
			(stroke
				(width 0.1524)
				(type default)
			)
			(layer "F.SilkS")
		)
		(fp_line
			(start -0.508 -0.9398)
			(end -0.508 0.9398)
			(stroke
				(width 0.1524)
				(type default)
			)
			(layer "F.SilkS")
		)
		(fp_rect
			(start -0.508 0.9398)
			(end 0.508 -0.9398)
			(stroke
				(width 0)
				(type default)
			)
			(fill no)
			(layer "F.CrtYd")
		)
		(fp_rect
			(start -0.508 0.9398)
			(end 0.508 -0.9398)
			(stroke
				(width 0)
				(type default)
			)
			(fill no)
			(layer "F.Fab")
		)
		(pad "1" smd custom
			(at 0 -0.4445 90)
			(size 0.1397 0.1397)
			(layers "F.Cu" "F.Mask" "F.Paste")
			(net "DRIVE_B_25_FLT_LED")
			(options
				(clearance outline)
				(anchor circle)
			)
			(primitives
				(gr_poly
					(pts
						(arc
							(start -0.1778 -0.2794)
							(mid -0.249642 -0.249642)
							(end -0.2794 -0.1778)
						)
						(arc
							(start -0.2794 0.1778)
							(mid -0.249642 0.249642)
							(end -0.1778 0.2794)
						)
						(arc
							(start 0.1778 0.2794)
							(mid 0.249642 0.249642)
							(end 0.2794 0.1778)
						)
						(arc
							(start 0.2794 -0.1778)
							(mid 0.249642 -0.249642)
							(end 0.1778 -0.2794)
						)
					)
					(width 0)
					(fill yes)
				)
			)
		)
		(pad "2" smd custom
			(at 0 0.4445 90)
			(size 0.1397 0.1397)
			(layers "F.Cu" "F.Mask" "F.Paste")
			(net "GND")
			(options
				(clearance outline)
				(anchor circle)
			)
			(primitives
				(gr_poly
					(pts
						(arc
							(start -0.1778 -0.2794)
							(mid -0.249642 -0.249642)
							(end -0.2794 -0.1778)
						)
						(arc
							(start -0.2794 0.1778)
							(mid -0.249642 0.249642)
							(end -0.1778 0.2794)
						)
						(arc
							(start 0.1778 0.2794)
							(mid 0.249642 0.249642)
							(end 0.2794 0.1778)
						)
						(arc
							(start 0.2794 -0.1778)
							(mid 0.249642 -0.249642)
							(end 0.1778 -0.2794)
						)
					)
					(width 0)
					(fill yes)
				)
			)
		)
	)
	(footprint ""
		(layer "F.Cu")
		(at 150.943818 -135.22198)
		(property "Reference" "R1037"
			(at 0 0 0)
			(layer "F.SilkS")
			(hide yes)
			(effects
				(font
					(size 1.27 1.27)
				)
			)
		)
		(property "Value" "100R2D-GP"
			(at 0.064008 -3.993896 0)
			(unlocked yes)
			(layer "F.Fab")
			(hide yes)
			(effects
				(font
					(size 1.016 1.016)
					(thickness 0.1524)
				)
			)
		)
		(property "Device Type" "R402H14"
			(at 0.064008 -5.517896 0)
			(unlocked yes)
			(layer "F.Fab")
			(hide yes)
			(effects
				(font
					(size 1.016 1.016)
					(thickness 0.1524)
				)
			)
		)
		(duplicate_pad_numbers_are_jumpers no)
		(fp_line
			(start -0.508 -0.9398)
			(end -0.508 0.9398)
			(stroke
				(width 0.1524)
				(type default)
			)
			(layer "F.SilkS")
		)
		(fp_line
			(start 0.508 -0.9398)
			(end -0.508 -0.9398)
			(stroke
				(width 0.1524)
				(type default)
			)
			(layer "F.SilkS")
		)
		(fp_rect
			(start -0.508 0.9398)
			(end 0.508 -0.9398)
			(stroke
				(width 0)
				(type default)
			)
			(fill no)
			(layer "F.CrtYd")
		)
		(fp_rect
			(start -0.508 0.9398)
			(end 0.508 -0.9398)
			(stroke
				(width 0)
				(type default)
			)
			(fill no)
			(layer "F.Fab")
		)
		(pad "1" smd custom
			(at 0 -0.4445)
			(size 0.1397 0.1397)
			(layers "F.Cu" "F.Mask" "F.Paste")
			(net "MB0_TEMP")
			(options
				(clearance outline)
				(anchor circle)
			)
			(primitives
				(gr_poly
					(pts
						(arc
							(start -0.1778 -0.2794)
							(mid -0.249642 -0.249642)
							(end -0.2794 -0.1778)
						)
						(arc
							(start -0.2794 0.1778)
							(mid -0.249642 0.249642)
							(end -0.1778 0.2794)
						)
						(arc
							(start 0.1778 0.2794)
							(mid 0.249642 0.249642)
							(end 0.2794 0.1778)
						)
						(arc
							(start 0.2794 -0.1778)
							(mid 0.249642 -0.249642)
							(end 0.1778 -0.2794)
						)
					)
					(width 0)
					(fill yes)
				)
			)
		)
		(pad "2" smd custom
			(at 0 0.4445)
			(size 0.1397 0.1397)
			(layers "F.Cu" "F.Mask" "F.Paste")
			(net "MB0_TEMP_B")
			(options
				(clearance outline)
				(anchor circle)
			)
			(primitives
				(gr_poly
					(pts
						(arc
							(start -0.1778 -0.2794)
							(mid -0.249642 -0.249642)
							(end -0.2794 -0.1778)
						)
						(arc
							(start -0.2794 0.1778)
							(mid -0.249642 0.249642)
							(end -0.1778 0.2794)
						)
						(arc
							(start 0.1778 0.2794)
							(mid 0.249642 0.249642)
							(end 0.2794 0.1778)
						)
						(arc
							(start 0.2794 -0.1778)
							(mid 0.249642 -0.249642)
							(end 0.1778 -0.2794)
						)
					)
					(width 0)
					(fill yes)
				)
			)
		)
	)
	(footprint ""
		(layer "F.Cu")
		(at 261.932166 -338.052664 90)
		(property "Reference" "R388"
			(at 0 0 90)
			(layer "F.SilkS")
			(hide yes)
			(effects
				(font
					(size 1.27 1.27)
				)
			)
		)
		(property "Value" "10KR2F-2-GP"
			(at 0.064008 -3.993896 90)
			(unlocked yes)
			(layer "F.Fab")
			(hide yes)
			(effects
				(font
					(size 1.016 1.016)
					(thickness 0.1524)
				)
			)
		)
		(property "Device Type" "R402H16"
			(at 0.064008 -5.517896 90)
			(unlocked yes)
			(layer "F.Fab")
			(hide yes)
			(effects
				(font
					(size 1.016 1.016)
					(thickness 0.1524)
				)
			)
		)
		(duplicate_pad_numbers_are_jumpers no)
		(fp_line
			(start 0.508 -0.9398)
			(end -0.508 -0.9398)
			(stroke
				(width 0.1524)
				(type default)
			)
			(layer "F.SilkS")
		)
		(fp_line
			(start -0.508 -0.9398)
			(end -0.508 0.9398)
			(stroke
				(width 0.1524)
				(type default)
			)
			(layer "F.SilkS")
		)
		(fp_rect
			(start -0.508 0.9398)
			(end 0.508 -0.9398)
			(stroke
				(width 0)
				(type default)
			)
			(fill no)
			(layer "F.CrtYd")
		)
		(fp_rect
			(start -0.508 0.9398)
			(end 0.508 -0.9398)
			(stroke
				(width 0)
				(type default)
			)
			(fill no)
			(layer "F.Fab")
		)
		(pad "1" smd custom
			(at 0 -0.4445 90)
			(size 0.1397 0.1397)
			(layers "F.Cu" "F.Mask" "F.Paste")
			(net "P3V3_STBY_A")
			(options
				(clearance outline)
				(anchor circle)
			)
			(primitives
				(gr_poly
					(pts
						(arc
							(start -0.1778 -0.2794)
							(mid -0.249642 -0.249642)
							(end -0.2794 -0.1778)
						)
						(arc
							(start -0.2794 0.1778)
							(mid -0.249642 0.249642)
							(end -0.1778 0.2794)
						)
						(arc
							(start 0.1778 0.2794)
							(mid 0.249642 0.249642)
							(end 0.2794 0.1778)
						)
						(arc
							(start 0.2794 -0.1778)
							(mid 0.249642 -0.249642)
							(end 0.1778 -0.2794)
						)
					)
					(width 0)
					(fill yes)
				)
			)
		)
		(pad "2" smd custom
			(at 0 0.4445 90)
			(size 0.1397 0.1397)
			(layers "F.Cu" "F.Mask" "F.Paste")
			(net "SCC_A_TYPE_3")
			(options
				(clearance outline)
				(anchor circle)
			)
			(primitives
				(gr_poly
					(pts
						(arc
							(start -0.1778 -0.2794)
							(mid -0.249642 -0.249642)
							(end -0.2794 -0.1778)
						)
						(arc
							(start -0.2794 0.1778)
							(mid -0.249642 0.249642)
							(end -0.1778 0.2794)
						)
						(arc
							(start 0.1778 0.2794)
							(mid 0.249642 0.249642)
							(end 0.2794 0.1778)
						)
						(arc
							(start 0.2794 -0.1778)
							(mid 0.249642 -0.249642)
							(end 0.1778 -0.2794)
						)
					)
					(width 0)
					(fill yes)
				)
			)
		)
	)
	(footprint ""
		(layer "F.Cu")
		(at 426.120052 -188.954918 180)
		(property "Reference" "C318"
			(at 0 0 180)
			(layer "F.SilkS")
			(hide yes)
			(effects
				(font
					(size 1.27 1.27)
				)
			)
		)
		(property "Value" "SC4D7U25V5KX-1-GP"
			(at -0.0762 -6.1214 180)
			(unlocked yes)
			(layer "F.Fab")
			(hide yes)
			(effects
				(font
					(size 1.016 1.016)
					(thickness 0.1524)
				)
			)
		)
		(property "Device Type" "C805H58"
			(at -0.0762 -8.1534 180)
			(unlocked yes)
			(layer "F.Fab")
			(hide yes)
			(effects
				(font
					(size 1.016 1.016)
					(thickness 0.1524)
				)
			)
		)
		(duplicate_pad_numbers_are_jumpers no)
		(fp_line
			(start 0.635 0)
			(end -0.635 0)
			(stroke
				(width 0.508)
				(type default)
			)
			(layer "F.SilkS")
		)
		(fp_rect
			(start -0.9652 1.778)
			(end 0.9652 -1.778)
			(stroke
				(width 0)
				(type default)
			)
			(fill no)
			(layer "F.CrtYd")
		)
		(fp_poly
			(pts
				(xy -0.9652 -1.778) (xy 0.9652 -1.778) (xy 0.9652 1.778) (xy -0.9652 1.778)
			)
			(stroke
				(width 0)
				(type default)
			)
			(fill no)
			(layer "F.Fab")
		)
		(pad "1" smd rect
			(at 0 -0.9652 180)
			(size 1.397 1.143)
			(layers "F.Cu" "F.Mask" "F.Paste")
			(net "P12V_HDD21")
		)
		(pad "2" smd rect
			(at 0 0.9652 180)
			(size 1.397 1.143)
			(layers "F.Cu" "F.Mask" "F.Paste")
			(net "GND")
		)
	)
	(footprint ""
		(layer "F.Cu")
		(at 252.386846 -261.326122 180)
		(property "Reference" "R427"
			(at 0 0 180)
			(layer "F.SilkS")
			(hide yes)
			(effects
				(font
					(size 1.27 1.27)
				)
			)
		)
		(property "Value" "1KR2F-3-GP"
			(at 0.064008 -3.993896 180)
			(unlocked yes)
			(layer "F.Fab")
			(hide yes)
			(effects
				(font
					(size 1.016 1.016)
					(thickness 0.1524)
				)
			)
		)
		(property "Device Type" "R402H16"
			(at 0.064008 -5.517896 180)
			(unlocked yes)
			(layer "F.Fab")
			(hide yes)
			(effects
				(font
					(size 1.016 1.016)
					(thickness 0.1524)
				)
			)
		)
		(duplicate_pad_numbers_are_jumpers no)
		(fp_line
			(start 0.508 -0.9398)
			(end -0.508 -0.9398)
			(stroke
				(width 0.1524)
				(type default)
			)
			(layer "F.SilkS")
		)
		(fp_line
			(start -0.508 -0.9398)
			(end -0.508 0.9398)
			(stroke
				(width 0.1524)
				(type default)
			)
			(layer "F.SilkS")
		)
		(fp_rect
			(start -0.508 0.9398)
			(end 0.508 -0.9398)
			(stroke
				(width 0)
				(type default)
			)
			(fill no)
			(layer "F.CrtYd")
		)
		(fp_rect
			(start -0.508 0.9398)
			(end 0.508 -0.9398)
			(stroke
				(width 0)
				(type default)
			)
			(fill no)
			(layer "F.Fab")
		)
		(pad "1" smd custom
			(at 0 -0.4445 180)
			(size 0.1397 0.1397)
			(layers "F.Cu" "F.Mask" "F.Paste")
			(net "P3V3_STBY_A")
			(options
				(clearance outline)
				(anchor circle)
			)
			(primitives
				(gr_poly
					(pts
						(arc
							(start -0.1778 -0.2794)
							(mid -0.249642 -0.249642)
							(end -0.2794 -0.1778)
						)
						(arc
							(start -0.2794 0.1778)
							(mid -0.249642 0.249642)
							(end -0.1778 0.2794)
						)
						(arc
							(start 0.1778 0.2794)
							(mid 0.249642 0.249642)
							(end 0.2794 0.1778)
						)
						(arc
							(start 0.2794 -0.1778)
							(mid 0.249642 -0.249642)
							(end 0.1778 -0.2794)
						)
					)
					(width 0)
					(fill yes)
				)
			)
		)
		(pad "2" smd custom
			(at 0 0.4445 180)
			(size 0.1397 0.1397)
			(layers "F.Cu" "F.Mask" "F.Paste")
			(net "I2C_DRIVE_A_INS_SDA")
			(options
				(clearance outline)
				(anchor circle)
			)
			(primitives
				(gr_poly
					(pts
						(arc
							(start -0.1778 -0.2794)
							(mid -0.249642 -0.249642)
							(end -0.2794 -0.1778)
						)
						(arc
							(start -0.2794 0.1778)
							(mid -0.249642 0.249642)
							(end -0.1778 0.2794)
						)
						(arc
							(start 0.1778 0.2794)
							(mid 0.249642 0.249642)
							(end 0.2794 0.1778)
						)
						(arc
							(start 0.2794 -0.1778)
							(mid 0.249642 -0.249642)
							(end 0.1778 -0.2794)
						)
					)
					(width 0)
					(fill yes)
				)
			)
		)
	)
	(footprint ""
		(layer "F.Cu")
		(at 469.370918 -162.644074 90)
		(property "Reference" "D23"
			(at 0 0 90)
			(layer "F.SilkS")
			(hide yes)
			(effects
				(font
					(size 1.27 1.27)
				)
			)
		)
		(property "Value" "RB551V30-GP"
			(at 0 -6.7818 90)
			(unlocked yes)
			(layer "F.Fab")
			(hide yes)
			(effects
				(font
					(size 1.016 1.016)
					(thickness 0.1524)
				)
			)
		)
		(property "Device Type" "SOD323AKH38"
			(at 0 -8.6868 90)
			(unlocked yes)
			(layer "F.Fab")
			(hide yes)
			(effects
				(font
					(size 1.016 1.016)
					(thickness 0.1524)
				)
			)
		)
		(duplicate_pad_numbers_are_jumpers no)
		(fp_line
			(start 0.889 -1.9304)
			(end 0.889 2.159)
			(stroke
				(width 0.1524)
				(type default)
			)
			(layer "F.SilkS")
		)
		(fp_line
			(start -0.889 -1.9304)
			(end 0.889 -1.9304)
			(stroke
				(width 0.1524)
				(type default)
			)
			(layer "F.SilkS")
		)
		(fp_line
			(start 0.762 2.0574)
			(end -0.762 2.0574)
			(stroke
				(width 0.508)
				(type default)
			)
			(layer "F.SilkS")
		)
		(fp_line
			(start 0.889 2.159)
			(end -0.889 2.159)
			(stroke
				(width 0.1524)
				(type default)
			)
			(layer "F.SilkS")
		)
		(fp_line
			(start -0.889 2.159)
			(end -0.889 -1.9304)
			(stroke
				(width 0.1524)
				(type default)
			)
			(layer "F.SilkS")
		)
		(fp_rect
			(start -1.016 2.3114)
			(end 1.016 -2.0066)
			(stroke
				(width 0)
				(type default)
			)
			(fill no)
			(layer "F.CrtYd")
		)
		(fp_poly
			(pts
				(xy -1.016 -2.0066) (xy 1.016 -2.0066) (xy 1.016 2.3114) (xy -1.016 2.3114)
			)
			(stroke
				(width 0)
				(type default)
			)
			(fill no)
			(layer "F.Fab")
		)
		(pad "A" smd rect
			(at 0 -1.143 90)
			(size 0.5588 1.016)
			(layers "F.Cu" "F.Mask" "F.Paste")
			(net "SW_HDD_R23")
		)
		(pad "K" smd rect
			(at 0 1.143 90)
			(size 0.5588 1.016)
			(layers "F.Cu" "F.Mask" "F.Paste")
			(net "SW_HDD_N23")
		)
	)
	(footprint ""
		(layer "F.Cu")
		(at 264.16 -278.13)
		(property "Reference" "U10"
			(at 0 0 0)
			(layer "F.SilkS")
			(hide yes)
			(effects
				(font
					(size 1.27 1.27)
				)
			)
		)
		(property "Value" "TCA9555PWR-GP"
			(at 0 -6.9342 0)
			(unlocked yes)
			(layer "F.Fab")
			(hide yes)
			(effects
				(font
					(size 1.016 1.016)
					(thickness 0.1524)
				)
			)
		)
		(property "Device Type" "TSOIC24H48"
			(at 0 -8.5852 0)
			(unlocked yes)
			(layer "F.Fab")
			(hide yes)
			(effects
				(font
					(size 1.016 1.016)
					(thickness 0.1524)
				)
			)
		)
		(duplicate_pad_numbers_are_jumpers no)
		(fp_line
			(start -4.2291 -1.397)
			(end 3.81 -1.397)
			(stroke
				(width 0.1524)
				(type default)
			)
			(layer "F.SilkS")
		)
		(fp_line
			(start -4.2291 -0.8001)
			(end -3.429 0)
			(stroke
				(width 0.1524)
				(type default)
			)
			(layer "F.SilkS")
		)
		(fp_line
			(start -4.2291 3.937)
			(end -4.2291 -1.397)
			(stroke
				(width 0.1524)
				(type default)
			)
			(layer "F.SilkS")
		)
		(fp_line
			(start -4.22656 3.81)
			(end -4.2291 1.397)
			(stroke
				(width 0.508)
				(type default)
			)
			(layer "F.SilkS")
		)
		(fp_line
			(start -3.429 0)
			(end -4.2291 0.8001)
			(stroke
				(width 0.1524)
				(type default)
			)
			(layer "F.SilkS")
		)
		(fp_line
			(start 3.81 -1.397)
			(end 3.81 1.397)
			(stroke
				(width 0.1524)
				(type default)
			)
			(layer "F.SilkS")
		)
		(fp_line
			(start 3.81 1.397)
			(end -4.2291 1.397)
			(stroke
				(width 0.1524)
				(type default)
			)
			(layer "F.SilkS")
		)
		(fp_poly
			(pts
				(xy -3.90652 -1.8542) (xy 3.90652 -1.8542) (xy 3.90652 1.8542) (xy -3.90652 1.8542)
			)
			(stroke
				(width 0)
				(type default)
			)
			(fill yes)
			(layer "F.SilkS")
		)
		(fp_poly
			(pts
				(xy -4.2164 3.81) (xy 4.2164 3.81) (xy 4.22656 -3.81) (xy -4.2164 -3.81)
			)
			(stroke
				(width 0)
				(type default)
			)
			(fill no)
			(layer "F.CrtYd")
		)
		(fp_poly
			(pts
				(xy -4.22656 -3.81) (xy 4.22656 -3.81) (xy 4.22656 3.81) (xy -4.22656 3.81)
			)
			(stroke
				(width 0)
				(type default)
			)
			(fill no)
			(layer "F.Fab")
		)
		(pad "1" smd rect
			(at -3.57632 2.8194)
			(size 0.3556 1.524)
			(layers "F.Cu" "F.Mask" "F.Paste")
			(net "IO_EXP0_INT_N")
		)
		(pad "2" smd rect
			(at -2.92608 2.8194)
			(size 0.3556 1.524)
			(layers "F.Cu" "F.Mask" "F.Paste")
			(net "IO_EXP0_HDD_FAULT_A1")
		)
		(pad "3" smd rect
			(at -2.27584 2.8194)
			(size 0.3556 1.524)
			(layers "F.Cu" "F.Mask" "F.Paste")
			(net "IO_EXP0_HDD_FAULT_A2")
		)
		(pad "4" smd rect
			(at -1.6256 2.8194)
			(size 0.3556 1.524)
			(layers "F.Cu" "F.Mask" "F.Paste")
			(net "DRIVE_A_0_FLT_LED")
		)
		(pad "5" smd rect
			(at -0.97536 2.8194)
			(size 0.3556 1.524)
			(layers "F.Cu" "F.Mask" "F.Paste")
			(net "DRIVE_A_1_FLT_LED")
		)
		(pad "6" smd rect
			(at -0.32512 2.8194)
			(size 0.3556 1.524)
			(layers "F.Cu" "F.Mask" "F.Paste")
			(net "DRIVE_A_2_FLT_LED")
		)
		(pad "7" smd rect
			(at 0.32512 2.8194)
			(size 0.3556 1.524)
			(layers "F.Cu" "F.Mask" "F.Paste")
			(net "DRIVE_A_3_FLT_LED")
		)
		(pad "8" smd rect
			(at 0.97536 2.8194)
			(size 0.3556 1.524)
			(layers "F.Cu" "F.Mask" "F.Paste")
			(net "DRIVE_A_4_FLT_LED")
		)
		(pad "9" smd rect
			(at 1.6256 2.8194)
			(size 0.3556 1.524)
			(layers "F.Cu" "F.Mask" "F.Paste")
			(net "DRIVE_A_5_FLT_LED")
		)
		(pad "10" smd rect
			(at 2.27584 2.8194)
			(size 0.3556 1.524)
			(layers "F.Cu" "F.Mask" "F.Paste")
			(net "DRIVE_A_6_FLT_LED")
		)
		(pad "11" smd rect
			(at 2.92608 2.8194)
			(size 0.3556 1.524)
			(layers "F.Cu" "F.Mask" "F.Paste")
			(net "DRIVE_A_7_FLT_LED")
		)
		(pad "12" smd rect
			(at 3.57632 2.8194)
			(size 0.3556 1.524)
			(layers "F.Cu" "F.Mask" "F.Paste")
			(net "GND")
		)
		(pad "13" smd rect
			(at 3.57632 -2.8194)
			(size 0.3556 1.524)
			(layers "F.Cu" "F.Mask" "F.Paste")
			(net "DRIVE_A_8_FLT_LED")
		)
		(pad "14" smd rect
			(at 2.92608 -2.8194)
			(size 0.3556 1.524)
			(layers "F.Cu" "F.Mask" "F.Paste")
			(net "DRIVE_A_9_FLT_LED")
		)
		(pad "15" smd rect
			(at 2.27584 -2.8194)
			(size 0.3556 1.524)
			(layers "F.Cu" "F.Mask" "F.Paste")
			(net "DRIVE_A_10_FLT_LED")
		)
		(pad "16" smd rect
			(at 1.6256 -2.8194)
			(size 0.3556 1.524)
			(layers "F.Cu" "F.Mask" "F.Paste")
			(net "DRIVE_A_11_FLT_LED")
		)
		(pad "17" smd rect
			(at 0.97536 -2.8194)
			(size 0.3556 1.524)
			(layers "F.Cu" "F.Mask" "F.Paste")
			(net "DRIVE_A_12_FLT_LED")
		)
		(pad "18" smd rect
			(at 0.32512 -2.8194)
			(size 0.3556 1.524)
			(layers "F.Cu" "F.Mask" "F.Paste")
			(net "DRIVE_A_13_FLT_LED")
		)
		(pad "19" smd rect
			(at -0.32512 -2.8194)
			(size 0.3556 1.524)
			(layers "F.Cu" "F.Mask" "F.Paste")
			(net "DRIVE_A_14_FLT_LED")
		)
		(pad "20" smd rect
			(at -0.97536 -2.8194)
			(size 0.3556 1.524)
			(layers "F.Cu" "F.Mask" "F.Paste")
			(net "DRIVE_A_15_FLT_LED")
		)
		(pad "21" smd rect
			(at -1.6256 -2.8194)
			(size 0.3556 1.524)
			(layers "F.Cu" "F.Mask" "F.Paste")
			(net "IO_EXP0_HDD_FAULT_A0")
		)
		(pad "22" smd rect
			(at -2.27584 -2.8194)
			(size 0.3556 1.524)
			(layers "F.Cu" "F.Mask" "F.Paste")
			(net "IO_EXP0_LED_SCL")
		)
		(pad "23" smd rect
			(at -2.92608 -2.8194)
			(size 0.3556 1.524)
			(layers "F.Cu" "F.Mask" "F.Paste")
			(net "IO_EXP0_LED_SDA")
		)
		(pad "24" smd rect
			(at -3.57632 -2.8194)
			(size 0.3556 1.524)
			(layers "F.Cu" "F.Mask" "F.Paste")
			(net "P3V3_STBY_A")
		)
	)
	(footprint ""
		(layer "F.Cu")
		(at 349.431102 -180.064918 -90)
		(property "Reference" "R571"
			(at 0 0 270)
			(layer "F.SilkS")
			(hide yes)
			(effects
				(font
					(size 1.27 1.27)
				)
			)
		)
		(property "Value" "220R3F-1-GP"
			(at -0.0254 -2.5146 270)
			(unlocked yes)
			(layer "F.Fab")
			(hide yes)
			(effects
				(font
					(size 1.016 1.016)
					(thickness 0.1524)
				)
			)
		)
		(property "Device Type" "R603H22"
			(at -0.0254 -4.0386 270)
			(unlocked yes)
			(layer "F.Fab")
			(hide yes)
			(effects
				(font
					(size 1.016 1.016)
					(thickness 0.1524)
				)
			)
		)
		(duplicate_pad_numbers_are_jumpers no)
		(fp_line
			(start -0.4826 0)
			(end -0.2032 0)
			(stroke
				(width 0.2032)
				(type default)
			)
			(layer "F.SilkS")
		)
		(fp_line
			(start 0.2032 0)
			(end 0.4826 0)
			(stroke
				(width 0.2032)
				(type default)
			)
			(layer "F.SilkS")
		)
		(fp_rect
			(start -0.5842 1.3335)
			(end 0.5842 -1.3335)
			(stroke
				(width 0)
				(type default)
			)
			(fill no)
			(layer "F.CrtYd")
		)
		(fp_rect
			(start -0.5842 1.3335)
			(end 0.5842 -1.3335)
			(stroke
				(width 0)
				(type default)
			)
			(fill no)
			(layer "F.Fab")
		)
		(pad "1" smd custom
			(at 0 -0.762 270)
			(size 0.2159 0.2159)
			(layers "F.Cu" "F.Mask" "F.Paste")
			(net "HDD_PRSNT_19")
			(options
				(clearance outline)
				(anchor circle)
			)
			(primitives
				(gr_poly
					(pts
						(arc
							(start -0.3302 -0.4318)
							(mid -0.402042 -0.402042)
							(end -0.4318 -0.3302)
						)
						(arc
							(start -0.4318 0.3302)
							(mid -0.402042 0.402042)
							(end -0.3302 0.4318)
						)
						(arc
							(start 0.3302 0.4318)
							(mid 0.402042 0.402042)
							(end 0.4318 0.3302)
						)
						(arc
							(start 0.4318 -0.3302)
							(mid 0.402042 -0.402042)
							(end 0.3302 -0.4318)
						)
					)
					(width 0)
					(fill yes)
				)
			)
		)
		(pad "2" smd custom
			(at 0 0.762 270)
			(size 0.2159 0.2159)
			(layers "F.Cu" "F.Mask" "F.Paste")
			(net "DRIVE_A_19_INS")
			(options
				(clearance outline)
				(anchor circle)
			)
			(primitives
				(gr_poly
					(pts
						(arc
							(start -0.3302 -0.4318)
							(mid -0.402042 -0.402042)
							(end -0.4318 -0.3302)
						)
						(arc
							(start -0.4318 0.3302)
							(mid -0.402042 0.402042)
							(end -0.3302 0.4318)
						)
						(arc
							(start 0.3302 0.4318)
							(mid 0.402042 0.402042)
							(end 0.4318 0.3302)
						)
						(arc
							(start 0.4318 -0.3302)
							(mid 0.402042 -0.402042)
							(end 0.3302 -0.4318)
						)
					)
					(width 0)
					(fill yes)
				)
			)
		)
	)
	(footprint ""
		(layer "F.Cu")
		(at 274.066 -284.734 180)
		(property "Reference" "R114"
			(at 0 0 180)
			(layer "F.SilkS")
			(hide yes)
			(effects
				(font
					(size 1.27 1.27)
				)
			)
		)
		(property "Value" "0R2J-2-GP"
			(at 0.064008 -3.993896 180)
			(unlocked yes)
			(layer "F.Fab")
			(hide yes)
			(effects
				(font
					(size 1.016 1.016)
					(thickness 0.1524)
				)
			)
		)
		(property "Device Type" "R402H16"
			(at 0.064008 -5.517896 180)
			(unlocked yes)
			(layer "F.Fab")
			(hide yes)
			(effects
				(font
					(size 1.016 1.016)
					(thickness 0.1524)
				)
			)
		)
		(duplicate_pad_numbers_are_jumpers no)
		(fp_line
			(start 0.508 -0.9398)
			(end -0.508 -0.9398)
			(stroke
				(width 0.1524)
				(type default)
			)
			(layer "F.SilkS")
		)
		(fp_line
			(start -0.508 -0.9398)
			(end -0.508 0.9398)
			(stroke
				(width 0.1524)
				(type default)
			)
			(layer "F.SilkS")
		)
		(fp_rect
			(start -0.508 0.9398)
			(end 0.508 -0.9398)
			(stroke
				(width 0)
				(type default)
			)
			(fill no)
			(layer "F.CrtYd")
		)
		(fp_rect
			(start -0.508 0.9398)
			(end 0.508 -0.9398)
			(stroke
				(width 0)
				(type default)
			)
			(fill no)
			(layer "F.Fab")
		)
		(pad "1" smd custom
			(at 0 -0.4445 180)
			(size 0.1397 0.1397)
			(layers "F.Cu" "F.Mask" "F.Paste")
			(net "IO_EXP1_LED_SCL")
			(options
				(clearance outline)
				(anchor circle)
			)
			(primitives
				(gr_poly
					(pts
						(arc
							(start -0.1778 -0.2794)
							(mid -0.249642 -0.249642)
							(end -0.2794 -0.1778)
						)
						(arc
							(start -0.2794 0.1778)
							(mid -0.249642 0.249642)
							(end -0.1778 0.2794)
						)
						(arc
							(start 0.1778 0.2794)
							(mid 0.249642 0.249642)
							(end 0.2794 0.1778)
						)
						(arc
							(start 0.2794 -0.1778)
							(mid 0.249642 -0.249642)
							(end 0.1778 -0.2794)
						)
					)
					(width 0)
					(fill yes)
				)
			)
		)
		(pad "2" smd custom
			(at 0 0.4445 180)
			(size 0.1397 0.1397)
			(layers "F.Cu" "F.Mask" "F.Paste")
			(net "I2C_DRIVE_A_FLT_LED_SCL")
			(options
				(clearance outline)
				(anchor circle)
			)
			(primitives
				(gr_poly
					(pts
						(arc
							(start -0.1778 -0.2794)
							(mid -0.249642 -0.249642)
							(end -0.2794 -0.1778)
						)
						(arc
							(start -0.2794 0.1778)
							(mid -0.249642 0.249642)
							(end -0.1778 0.2794)
						)
						(arc
							(start 0.1778 0.2794)
							(mid 0.249642 0.249642)
							(end 0.2794 0.1778)
						)
						(arc
							(start 0.2794 -0.1778)
							(mid 0.249642 -0.249642)
							(end 0.1778 -0.2794)
						)
					)
					(width 0)
					(fill yes)
				)
			)
		)
	)
	(footprint ""
		(layer "F.Cu")
		(at 257.683 -301.244 180)
		(property "Reference" "R5"
			(at 0 0 180)
			(layer "F.SilkS")
			(hide yes)
			(effects
				(font
					(size 1.27 1.27)
				)
			)
		)
		(property "Value" "0R2J-2-GP"
			(at 0.064008 -3.993896 180)
			(unlocked yes)
			(layer "F.Fab")
			(hide yes)
			(effects
				(font
					(size 1.016 1.016)
					(thickness 0.1524)
				)
			)
		)
		(property "Device Type" "R402H16"
			(at 0.064008 -5.517896 180)
			(unlocked yes)
			(layer "F.Fab")
			(hide yes)
			(effects
				(font
					(size 1.016 1.016)
					(thickness 0.1524)
				)
			)
		)
		(duplicate_pad_numbers_are_jumpers no)
		(fp_line
			(start 0.508 -0.9398)
			(end -0.508 -0.9398)
			(stroke
				(width 0.1524)
				(type default)
			)
			(layer "F.SilkS")
		)
		(fp_line
			(start -0.508 -0.9398)
			(end -0.508 0.9398)
			(stroke
				(width 0.1524)
				(type default)
			)
			(layer "F.SilkS")
		)
		(fp_rect
			(start -0.508 0.9398)
			(end 0.508 -0.9398)
			(stroke
				(width 0)
				(type default)
			)
			(fill no)
			(layer "F.CrtYd")
		)
		(fp_rect
			(start -0.508 0.9398)
			(end 0.508 -0.9398)
			(stroke
				(width 0)
				(type default)
			)
			(fill no)
			(layer "F.Fab")
		)
		(pad "1" smd custom
			(at 0 -0.4445 180)
			(size 0.1397 0.1397)
			(layers "F.Cu" "F.Mask" "F.Paste")
			(net "EEPROM_SDA")
			(options
				(clearance outline)
				(anchor circle)
			)
			(primitives
				(gr_poly
					(pts
						(arc
							(start -0.1778 -0.2794)
							(mid -0.249642 -0.249642)
							(end -0.2794 -0.1778)
						)
						(arc
							(start -0.2794 0.1778)
							(mid -0.249642 0.249642)
							(end -0.1778 0.2794)
						)
						(arc
							(start 0.1778 0.2794)
							(mid 0.249642 0.249642)
							(end 0.2794 0.1778)
						)
						(arc
							(start 0.2794 -0.1778)
							(mid 0.249642 -0.249642)
							(end 0.1778 -0.2794)
						)
					)
					(width 0)
					(fill yes)
				)
			)
		)
		(pad "2" smd custom
			(at 0 0.4445 180)
			(size 0.1397 0.1397)
			(layers "F.Cu" "F.Mask" "F.Paste")
			(net "I2C_DPB_A_SDA_BUF")
			(options
				(clearance outline)
				(anchor circle)
			)
			(primitives
				(gr_poly
					(pts
						(arc
							(start -0.1778 -0.2794)
							(mid -0.249642 -0.249642)
							(end -0.2794 -0.1778)
						)
						(arc
							(start -0.2794 0.1778)
							(mid -0.249642 0.249642)
							(end -0.1778 0.2794)
						)
						(arc
							(start 0.1778 0.2794)
							(mid 0.249642 0.249642)
							(end 0.2794 0.1778)
						)
						(arc
							(start 0.2794 -0.1778)
							(mid 0.249642 -0.249642)
							(end 0.1778 -0.2794)
						)
					)
					(width 0)
					(fill yes)
				)
			)
		)
	)
	(footprint ""
		(layer "F.Cu")
		(at 321.634612 -159.219392 -90)
		(property "Reference" "C272"
			(at 0 0 270)
			(layer "F.SilkS")
			(hide yes)
			(effects
				(font
					(size 1.27 1.27)
				)
			)
		)
		(property "Value" "SCD01U16V1KX-GP"
			(at -2.8321 -1.7399 270)
			(unlocked yes)
			(layer "F.Fab")
			(hide yes)
			(effects
				(font
					(size 1.016 1.016)
					(thickness 0.1524)
				)
			)
		)
		(property "Device Type" "C0201H13"
			(at -2.8321 -3.2639 270)
			(unlocked yes)
			(layer "F.Fab")
			(hide yes)
			(effects
				(font
					(size 1.016 1.016)
					(thickness 0.1524)
				)
			)
		)
		(duplicate_pad_numbers_are_jumpers no)
		(fp_rect
			(start -0.2794 0.6477)
			(end 0.2794 -0.6477)
			(stroke
				(width 0)
				(type default)
			)
			(fill no)
			(layer "F.CrtYd")
		)
		(fp_rect
			(start -0.2794 0.6477)
			(end 0.2794 -0.6477)
			(stroke
				(width 0)
				(type default)
			)
			(fill no)
			(layer "F.Fab")
		)
		(pad "1" smd custom
			(at 0 -0.2794 270)
			(size 0.0762 0.0762)
			(layers "F.Cu" "F.Mask" "F.Paste")
			(net "SAS_HDD_RX_N18")
			(options
				(clearance outline)
				(anchor circle)
			)
			(primitives
				(gr_poly
					(pts
						(arc
							(start 0.1524 -0.127)
							(mid 0.137521 -0.162921)
							(end 0.1016 -0.1778)
						)
						(arc
							(start -0.1016 -0.1778)
							(mid -0.137521 -0.162921)
							(end -0.1524 -0.127)
						)
						(arc
							(start -0.1524 0.127)
							(mid -0.137521 0.162921)
							(end -0.1016 0.1778)
						)
						(arc
							(start 0.1016 0.1778)
							(mid 0.137521 0.162921)
							(end 0.1524 0.127)
						)
					)
					(width 0)
					(fill yes)
				)
			)
		)
		(pad "2" smd custom
			(at 0 0.2794 270)
			(size 0.0762 0.0762)
			(layers "F.Cu" "F.Mask" "F.Paste")
			(net "PHY_SCC_A_TO_DRV_A_18_DN")
			(options
				(clearance outline)
				(anchor circle)
			)
			(primitives
				(gr_poly
					(pts
						(arc
							(start 0.1524 -0.127)
							(mid 0.137521 -0.162921)
							(end 0.1016 -0.1778)
						)
						(arc
							(start -0.1016 -0.1778)
							(mid -0.137521 -0.162921)
							(end -0.1524 -0.127)
						)
						(arc
							(start -0.1524 0.127)
							(mid -0.137521 0.162921)
							(end -0.1016 0.1778)
						)
						(arc
							(start 0.1016 0.1778)
							(mid 0.137521 0.162921)
							(end 0.1524 0.127)
						)
					)
					(width 0)
					(fill yes)
				)
			)
		)
	)
	(footprint ""
		(layer "F.Cu")
		(at 469.21293 -130.376168 -90)
		(property "Reference" "R549"
			(at 0 0 270)
			(layer "F.SilkS")
			(hide yes)
			(effects
				(font
					(size 1.27 1.27)
				)
			)
		)
		(property "Value" "4K7R2J-2-GP"
			(at 0.064008 -3.993896 270)
			(unlocked yes)
			(layer "F.Fab")
			(hide yes)
			(effects
				(font
					(size 1.016 1.016)
					(thickness 0.1524)
				)
			)
		)
		(property "Device Type" "R402H16"
			(at 0.064008 -5.517896 270)
			(unlocked yes)
			(layer "F.Fab")
			(hide yes)
			(effects
				(font
					(size 1.016 1.016)
					(thickness 0.1524)
				)
			)
		)
		(duplicate_pad_numbers_are_jumpers no)
		(fp_line
			(start -0.508 -0.9398)
			(end -0.508 0.9398)
			(stroke
				(width 0.1524)
				(type default)
			)
			(layer "F.SilkS")
		)
		(fp_line
			(start 0.508 -0.9398)
			(end -0.508 -0.9398)
			(stroke
				(width 0.1524)
				(type default)
			)
			(layer "F.SilkS")
		)
		(fp_rect
			(start -0.508 0.9398)
			(end 0.508 -0.9398)
			(stroke
				(width 0)
				(type default)
			)
			(fill no)
			(layer "F.CrtYd")
		)
		(fp_rect
			(start -0.508 0.9398)
			(end 0.508 -0.9398)
			(stroke
				(width 0)
				(type default)
			)
			(fill no)
			(layer "F.Fab")
		)
		(pad "1" smd custom
			(at 0 -0.4445 270)
			(size 0.1397 0.1397)
			(layers "F.Cu" "F.Mask" "F.Paste")
			(net "DRIVE_A_23_FLT_LED")
			(options
				(clearance outline)
				(anchor circle)
			)
			(primitives
				(gr_poly
					(pts
						(arc
							(start -0.1778 -0.2794)
							(mid -0.249642 -0.249642)
							(end -0.2794 -0.1778)
						)
						(arc
							(start -0.2794 0.1778)
							(mid -0.249642 0.249642)
							(end -0.1778 0.2794)
						)
						(arc
							(start 0.1778 0.2794)
							(mid 0.249642 0.249642)
							(end 0.2794 0.1778)
						)
						(arc
							(start 0.2794 -0.1778)
							(mid 0.249642 -0.249642)
							(end 0.1778 -0.2794)
						)
					)
					(width 0)
					(fill yes)
				)
			)
		)
		(pad "2" smd custom
			(at 0 0.4445 270)
			(size 0.1397 0.1397)
			(layers "F.Cu" "F.Mask" "F.Paste")
			(net "GND")
			(options
				(clearance outline)
				(anchor circle)
			)
			(primitives
				(gr_poly
					(pts
						(arc
							(start -0.1778 -0.2794)
							(mid -0.249642 -0.249642)
							(end -0.2794 -0.1778)
						)
						(arc
							(start -0.2794 0.1778)
							(mid -0.249642 0.249642)
							(end -0.1778 0.2794)
						)
						(arc
							(start 0.1778 0.2794)
							(mid 0.249642 0.249642)
							(end 0.2794 0.1778)
						)
						(arc
							(start 0.2794 -0.1778)
							(mid 0.249642 -0.249642)
							(end 0.1778 -0.2794)
						)
					)
					(width 0)
					(fill yes)
				)
			)
		)
	)
	(footprint ""
		(layer "F.Cu")
		(at 78.361286 -130.271012 -90)
		(property "Reference" "R510"
			(at 0 0 270)
			(layer "F.SilkS")
			(hide yes)
			(effects
				(font
					(size 1.27 1.27)
				)
			)
		)
		(property "Value" "4K7R2J-2-GP"
			(at 0.064008 -3.993896 270)
			(unlocked yes)
			(layer "F.Fab")
			(hide yes)
			(effects
				(font
					(size 1.016 1.016)
					(thickness 0.1524)
				)
			)
		)
		(property "Device Type" "R402H16"
			(at 0.064008 -5.517896 270)
			(unlocked yes)
			(layer "F.Fab")
			(hide yes)
			(effects
				(font
					(size 1.016 1.016)
					(thickness 0.1524)
				)
			)
		)
		(duplicate_pad_numbers_are_jumpers no)
		(fp_line
			(start -0.508 -0.9398)
			(end -0.508 0.9398)
			(stroke
				(width 0.1524)
				(type default)
			)
			(layer "F.SilkS")
		)
		(fp_line
			(start 0.508 -0.9398)
			(end -0.508 -0.9398)
			(stroke
				(width 0.1524)
				(type default)
			)
			(layer "F.SilkS")
		)
		(fp_rect
			(start -0.508 0.9398)
			(end 0.508 -0.9398)
			(stroke
				(width 0)
				(type default)
			)
			(fill no)
			(layer "F.CrtYd")
		)
		(fp_rect
			(start -0.508 0.9398)
			(end 0.508 -0.9398)
			(stroke
				(width 0)
				(type default)
			)
			(fill no)
			(layer "F.Fab")
		)
		(pad "1" smd custom
			(at 0 -0.4445 270)
			(size 0.1397 0.1397)
			(layers "F.Cu" "F.Mask" "F.Paste")
			(net "DRIVE_A_14_FLT_LED")
			(options
				(clearance outline)
				(anchor circle)
			)
			(primitives
				(gr_poly
					(pts
						(arc
							(start -0.1778 -0.2794)
							(mid -0.249642 -0.249642)
							(end -0.2794 -0.1778)
						)
						(arc
							(start -0.2794 0.1778)
							(mid -0.249642 0.249642)
							(end -0.1778 0.2794)
						)
						(arc
							(start 0.1778 0.2794)
							(mid 0.249642 0.249642)
							(end 0.2794 0.1778)
						)
						(arc
							(start 0.2794 -0.1778)
							(mid 0.249642 -0.249642)
							(end 0.1778 -0.2794)
						)
					)
					(width 0)
					(fill yes)
				)
			)
		)
		(pad "2" smd custom
			(at 0 0.4445 270)
			(size 0.1397 0.1397)
			(layers "F.Cu" "F.Mask" "F.Paste")
			(net "GND")
			(options
				(clearance outline)
				(anchor circle)
			)
			(primitives
				(gr_poly
					(pts
						(arc
							(start -0.1778 -0.2794)
							(mid -0.249642 -0.249642)
							(end -0.2794 -0.1778)
						)
						(arc
							(start -0.2794 0.1778)
							(mid -0.249642 0.249642)
							(end -0.1778 0.2794)
						)
						(arc
							(start 0.1778 0.2794)
							(mid 0.249642 0.249642)
							(end 0.2794 0.1778)
						)
						(arc
							(start 0.2794 -0.1778)
							(mid 0.249642 -0.249642)
							(end 0.1778 -0.2794)
						)
					)
					(width 0)
					(fill yes)
				)
			)
		)
	)
	(footprint ""
		(layer "F.Cu")
		(at 122.849894 -172.909992 -90)
		(property "Reference" "HDDSAS15"
			(at 0 0 270)
			(layer "F.SilkS")
			(hide yes)
			(effects
				(font
					(size 1.27 1.27)
				)
			)
		)
		(property "Value" "SKT-SAS15P-14P-45-GP"
			(at -20.7645 -8.9789 270)
			(unlocked yes)
			(layer "F.Fab")
			(hide yes)
			(effects
				(font
					(size 1.016 1.016)
					(thickness 0.1524)
				)
			)
		)
		(property "Device Type" "10120818-001C-TRLF"
			(at -20.7645 -10.5029 270)
			(unlocked yes)
			(layer "F.Fab")
			(hide yes)
			(effects
				(font
					(size 1.016 1.016)
					(thickness 0.1524)
				)
			)
		)
		(duplicate_pad_numbers_are_jumpers no)
		(fp_line
			(start 1.651 4.2926)
			(end 1.651 3.0099)
			(stroke
				(width 0.1524)
				(type default)
			)
			(layer "F.SilkS")
		)
		(fp_line
			(start 8.509 4.2926)
			(end 1.651 4.2926)
			(stroke
				(width 0.1524)
				(type default)
			)
			(layer "F.SilkS")
		)
		(fp_line
			(start -23.4188 3.0099)
			(end -23.4188 -3.2512)
			(stroke
				(width 0.1524)
				(type default)
			)
			(layer "F.SilkS")
		)
		(fp_line
			(start 1.651 3.0099)
			(end -23.4188 3.0099)
			(stroke
				(width 0.1524)
				(type default)
			)
			(layer "F.SilkS")
		)
		(fp_line
			(start 8.509 3.0099)
			(end 8.509 4.2926)
			(stroke
				(width 0.1524)
				(type default)
			)
			(layer "F.SilkS")
		)
		(fp_line
			(start 23.4188 3.0099)
			(end 8.509 3.0099)
			(stroke
				(width 0.1524)
				(type default)
			)
			(layer "F.SilkS")
		)
		(fp_line
			(start -23.4188 -3.2512)
			(end 23.4188 -3.2512)
			(stroke
				(width 0.1524)
				(type default)
			)
			(layer "F.SilkS")
		)
		(fp_line
			(start 23.4188 -3.2512)
			(end 23.4188 3.0099)
			(stroke
				(width 0.1524)
				(type default)
			)
			(layer "F.SilkS")
		)
		(fp_line
			(start 15.5067 -3.3401)
			(end 16.2687 -3.3401)
			(stroke
				(width 0.3302)
				(type default)
			)
			(layer "F.SilkS")
		)
		(fp_poly
			(pts
				(xy 15.868904 -3.230372) (xy 16.503904 -3.865372) (xy 15.233904 -3.865372)
			)
			(stroke
				(width 0)
				(type default)
			)
			(fill yes)
			(layer "F.SilkS")
		)
		(fp_poly
			(pts
				(xy -22.8727 -2.7559) (xy 22.8727 -2.7559) (xy 22.8727 2.7559) (xy 8.255 2.7559) (xy 8.255 3.5179)
				(xy 1.905 3.5179) (xy 1.905 2.7559) (xy -22.8727 2.7559)
			)
			(stroke
				(width 0)
				(type default)
			)
			(fill no)
			(layer "F.CrtYd")
		)
		(fp_poly
			(pts
				(xy 1.397 4.5466) (xy 1.397 3.2639) (xy -23.6728 3.2639) (xy -23.6728 -3.5052) (xy 23.6728 -3.5052)
				(xy 23.6728 -0.00635) (xy 22.8727 -0.00635) (xy 22.8727 -2.7559) (xy -22.8727 -2.7559) (xy -22.8727 2.7559)
				(xy 1.905 2.7559) (xy 1.905 3.5179) (xy 8.255 3.5179) (xy 8.255 2.7559) (xy 22.8727 2.7559) (xy 22.8727 0.00635)
				(xy 23.6728 0.00635) (xy 23.6728 3.2639) (xy 8.763 3.2639) (xy 8.763 4.5466)
			)
			(stroke
				(width 0)
				(type default)
			)
			(fill no)
			(layer "F.CrtYd")
		)
		(fp_poly
			(pts
				(xy 1.397 4.5466) (xy 1.397 3.2639) (xy -23.6728 3.2639) (xy -23.6728 -3.5052) (xy 23.6728 -3.5052)
				(xy 23.6728 3.2639) (xy 8.763 3.2639) (xy 8.763 4.5466)
			)
			(stroke
				(width 0)
				(type default)
			)
			(fill no)
			(layer "F.Fab")
		)
		(pad "" np_thru_hole circle
			(at -18.874994 0 270)
			(size 0.254 0.254)
			(drill 1.3462)
			(layers "*.Cu" "*.Mask")
			(clearance 0.9017)
			(thermal_gap 0.9017)
		)
		(pad "" np_thru_hole circle
			(at 18.874994 0 270)
			(size 0.254 0.254)
			(drill 0.9398)
			(layers "*.Cu" "*.Mask")
			(clearance 0.6985)
			(thermal_gap 0.6985)
		)
		(pad "G1" smd rect
			(at 21.874988 0 270)
			(size 2.5908 2.5908)
			(layers "F.Cu" "F.Mask" "F.Paste")
			(net "GND")
		)
		(pad "G2" smd rect
			(at -21.874988 0 270)
			(size 2.5908 2.5908)
			(layers "F.Cu" "F.Mask" "F.Paste")
			(net "GND")
		)
		(pad "P1" smd rect
			(at 1.905 -1.82499 270)
			(size 0.6096 2.3622)
			(layers "F.Cu" "F.Mask" "F.Paste")
			(net "Net_2141")
		)
		(pad "P2" smd rect
			(at 0.635 -1.82499 270)
			(size 0.6096 2.3622)
			(layers "F.Cu" "F.Mask" "F.Paste")
			(net "Net_2142")
		)
		(pad "P3" smd rect
			(at -0.635 -1.82499 270)
			(size 0.6096 2.3622)
			(layers "F.Cu" "F.Mask" "F.Paste")
			(net "Net_2143")
		)
		(pad "P4" smd rect
			(at -1.905 -1.82499 270)
			(size 0.6096 2.3622)
			(layers "F.Cu" "F.Mask" "F.Paste")
			(net "GND")
		)
		(pad "P5" smd rect
			(at -3.175 -1.82499 270)
			(size 0.6096 2.3622)
			(layers "F.Cu" "F.Mask" "F.Paste")
			(net "HDD_PRSNT_15")
		)
		(pad "P6" smd rect
			(at -4.445 -1.82499 270)
			(size 0.6096 2.3622)
			(layers "F.Cu" "F.Mask" "F.Paste")
			(net "GND")
		)
		(pad "P7" smd rect
			(at -5.715 -1.82499 270)
			(size 0.6096 2.3622)
			(layers "F.Cu" "F.Mask" "F.Paste")
			(net "5V_PRE_15")
		)
		(pad "P8" smd rect
			(at -6.985 -1.82499 270)
			(size 0.6096 2.3622)
			(layers "F.Cu" "F.Mask" "F.Paste")
			(net "P5V_HDD15")
		)
		(pad "P9" smd rect
			(at -8.255 -1.82499 270)
			(size 0.6096 2.3622)
			(layers "F.Cu" "F.Mask" "F.Paste")
			(net "P5V_HDD15")
		)
		(pad "P10" smd rect
			(at -9.525 -1.82499 270)
			(size 0.6096 2.3622)
			(layers "F.Cu" "F.Mask" "F.Paste")
			(net "GND")
		)
		(pad "P11" smd rect
			(at -10.795 -1.82499 270)
			(size 0.6096 2.3622)
			(layers "F.Cu" "F.Mask" "F.Paste")
			(net "ACT_HDD_15")
		)
		(pad "P12" smd rect
			(at -12.065 -1.82499 270)
			(size 0.6096 2.3622)
			(layers "F.Cu" "F.Mask" "F.Paste")
			(net "GND")
		)
		(pad "P13" smd rect
			(at -13.335 -1.82499 270)
			(size 0.6096 2.3622)
			(layers "F.Cu" "F.Mask" "F.Paste")
			(net "12V_PRE_15")
		)
		(pad "P14" smd rect
			(at -14.605 -1.82499 270)
			(size 0.6096 2.3622)
			(layers "F.Cu" "F.Mask" "F.Paste")
			(net "P12V_HDD15")
		)
		(pad "P15" smd rect
			(at -15.875 -1.82499 270)
			(size 0.6096 2.3622)
			(layers "F.Cu" "F.Mask" "F.Paste")
			(net "P12V_HDD15")
		)
		(pad "S1" smd rect
			(at 15.875 -1.82499 270)
			(size 0.6096 2.3622)
			(layers "F.Cu" "F.Mask" "F.Paste")
			(net "GND")
		)
		(pad "S2" smd rect
			(at 14.605 -1.82499 270)
			(size 0.6096 2.3622)
			(layers "F.Cu" "F.Mask" "F.Paste")
			(net "SAS_HDD_RX_P15")
		)
		(pad "S3" smd rect
			(at 13.335 -1.82499 270)
			(size 0.6096 2.3622)
			(layers "F.Cu" "F.Mask" "F.Paste")
			(net "SAS_HDD_RX_N15")
		)
		(pad "S4" smd rect
			(at 12.065 -1.82499 270)
			(size 0.6096 2.3622)
			(layers "F.Cu" "F.Mask" "F.Paste")
			(net "GND")
		)
		(pad "S5" smd rect
			(at 10.795 -1.82499 270)
			(size 0.6096 2.3622)
			(layers "F.Cu" "F.Mask" "F.Paste")
			(net "PHY_DRV_A_TO_SCC_A_15_DN")
		)
		(pad "S6" smd rect
			(at 9.525 -1.82499 270)
			(size 0.6096 2.3622)
			(layers "F.Cu" "F.Mask" "F.Paste")
			(net "PHY_DRV_A_TO_SCC_A_15_DP")
		)
		(pad "S7" smd rect
			(at 8.255 -1.82499 270)
			(size 0.6096 2.3622)
			(layers "F.Cu" "F.Mask" "F.Paste")
			(net "GND")
		)
		(pad "S8" smd rect
			(at 7.480046 2.845054 270)
			(size 0.508 2.3622)
			(layers "F.Cu" "F.Mask" "F.Paste")
			(net "GND")
		)
		(pad "S9" smd rect
			(at 6.679946 2.845054 270)
			(size 0.508 2.3622)
			(layers "F.Cu" "F.Mask" "F.Paste")
			(net "Net_452")
		)
		(pad "S10" smd rect
			(at 5.8801 2.845054 270)
			(size 0.508 2.3622)
			(layers "F.Cu" "F.Mask" "F.Paste")
			(net "Net_344")
		)
		(pad "S11" smd rect
			(at 5.08 2.845054 270)
			(size 0.508 2.3622)
			(layers "F.Cu" "F.Mask" "F.Paste")
			(net "GND")
		)
		(pad "S12" smd rect
			(at 4.2799 2.845054 270)
			(size 0.508 2.3622)
			(layers "F.Cu" "F.Mask" "F.Paste")
			(net "Net_380")
		)
		(pad "S13" smd rect
			(at 3.480054 2.845054 270)
			(size 0.508 2.3622)
			(layers "F.Cu" "F.Mask" "F.Paste")
			(net "Net_416")
		)
		(pad "S14" smd rect
			(at 2.679954 2.845054 270)
			(size 0.508 2.3622)
			(layers "F.Cu" "F.Mask" "F.Paste")
			(net "GND")
		)
		(zone
			(layer "F.Cu")
			(hatch none 0.5)
			(connect_pads
				(clearance 0)
			)
			(min_thickness 0.25)
			(keepout
				(tracks allowed)
				(vias not_allowed)
				(pads allowed)
				(copperpour not_allowed)
				(footprints allowed)
			)
			(placement
				(enabled no)
				(sheetname "")
			)
			(fill
				(thermal_gap 0.5)
				(thermal_bridge_width 0.5)
				(island_removal_mode 0)
			)
			(polygon
				(pts
					(xy 126.507494 -189.648592) (xy 119.433594 -189.648592) (xy 119.433594 -196.582792) (xy 120.538494 -196.582792)
					(xy 120.538494 -192.467992) (xy 125.161294 -192.467992) (xy 125.161294 -196.582792) (xy 126.507494 -196.582792)
				)
			)
		)
		(zone
			(layer "F.Cu")
			(hatch none 0.5)
			(connect_pads
				(clearance 0)
			)
			(min_thickness 0.25)
			(keepout
				(tracks not_allowed)
				(vias allowed)
				(pads allowed)
				(copperpour not_allowed)
				(footprints allowed)
			)
			(placement
				(enabled no)
				(sheetname "")
			)
			(fill
				(thermal_gap 0.5)
				(thermal_bridge_width 0.5)
				(island_removal_mode 0)
			)
			(polygon
				(pts
					(xy 126.507494 -189.648592) (xy 119.433594 -189.648592) (xy 119.433594 -196.582792) (xy 120.538494 -196.582792)
					(xy 120.538494 -192.467992) (xy 125.161294 -192.467992) (xy 125.161294 -196.582792) (xy 126.507494 -196.582792)
				)
			)
		)
		(zone
			(layer "F.Cu")
			(hatch none 0.5)
			(connect_pads
				(clearance 0)
			)
			(min_thickness 0.25)
			(keepout
				(tracks not_allowed)
				(vias allowed)
				(pads allowed)
				(copperpour not_allowed)
				(footprints allowed)
			)
			(placement
				(enabled no)
				(sheetname "")
			)
			(fill
				(thermal_gap 0.5)
				(thermal_bridge_width 0.5)
				(island_removal_mode 0)
			)
			(polygon
				(pts
					(xy 126.507494 -156.171392) (xy 119.433594 -156.171392) (xy 119.433594 -149.237192) (xy 120.538494 -149.237192)
					(xy 120.538494 -153.351992) (xy 125.161294 -153.351992) (xy 125.161294 -149.237192) (xy 126.507494 -149.237192)
				)
			)
		)
		(zone
			(layer "F.Cu")
			(hatch none 0.5)
			(connect_pads
				(clearance 0)
			)
			(min_thickness 0.25)
			(keepout
				(tracks allowed)
				(vias not_allowed)
				(pads allowed)
				(copperpour not_allowed)
				(footprints allowed)
			)
			(placement
				(enabled no)
				(sheetname "")
			)
			(fill
				(thermal_gap 0.5)
				(thermal_bridge_width 0.5)
				(island_removal_mode 0)
			)
			(polygon
				(pts
					(xy 126.507494 -156.171392) (xy 119.433594 -156.171392) (xy 119.433594 -149.237192) (xy 120.538494 -149.237192)
					(xy 120.538494 -153.351992) (xy 125.161294 -153.351992) (xy 125.161294 -149.237192) (xy 126.507494 -149.237192)
				)
			)
		)
		(zone
			(layers "F.Cu" "B.Cu" "In1.Cu" "In2.Cu" "In3.Cu" "In4.Cu" "In5.Cu" "In6.Cu"
				"In7.Cu" "In8.Cu" "In9.Cu" "In10.Cu"
			)
			(hatch none 0.5)
			(connect_pads
				(clearance 0)
			)
			(min_thickness 0.25)
			(keepout
				(tracks not_allowed)
				(vias allowed)
				(pads allowed)
				(copperpour not_allowed)
				(footprints allowed)
			)
			(placement
				(enabled no)
				(sheetname "")
			)
			(fill
				(thermal_gap 0.5)
				(thermal_bridge_width 0.5)
				(island_removal_mode 0)
			)
			(polygon
				(pts
					(arc
						(start 123.624594 -154.034998)
						(mid 122.075194 -154.034998)
						(end 123.624594 -154.034998)
					)
				)
			)
		)
		(zone
			(layers "F.Cu" "B.Cu" "In1.Cu" "In2.Cu" "In3.Cu" "In4.Cu" "In5.Cu" "In6.Cu"
				"In7.Cu" "In8.Cu" "In9.Cu" "In10.Cu"
			)
			(hatch none 0.5)
			(connect_pads
				(clearance 0)
			)
			(min_thickness 0.25)
			(keepout
				(tracks not_allowed)
				(vias allowed)
				(pads allowed)
				(copperpour not_allowed)
				(footprints allowed)
			)
			(placement
				(enabled no)
				(sheetname "")
			)
			(fill
				(thermal_gap 0.5)
				(thermal_bridge_width 0.5)
				(island_removal_mode 0)
			)
			(polygon
				(pts
					(arc
						(start 123.827794 -191.784986)
						(mid 121.871994 -191.784986)
						(end 123.827794 -191.784986)
					)
				)
			)
		)
	)
	(footprint ""
		(layer "F.Cu")
		(at 367.858294 -132.088636)
		(property "Reference" "R1093"
			(at 0 0 0)
			(layer "F.SilkS")
			(hide yes)
			(effects
				(font
					(size 1.27 1.27)
				)
			)
		)
		(property "Value" "62KR2F-GP"
			(at 0.064008 -3.993896 0)
			(unlocked yes)
			(layer "F.Fab")
			(hide yes)
			(effects
				(font
					(size 1.016 1.016)
					(thickness 0.1524)
				)
			)
		)
		(property "Device Type" "R402H16"
			(at 0.064008 -5.517896 0)
			(unlocked yes)
			(layer "F.Fab")
			(hide yes)
			(effects
				(font
					(size 1.016 1.016)
					(thickness 0.1524)
				)
			)
		)
		(duplicate_pad_numbers_are_jumpers no)
		(fp_line
			(start -0.508 -0.9398)
			(end -0.508 0.9398)
			(stroke
				(width 0.1524)
				(type default)
			)
			(layer "F.SilkS")
		)
		(fp_line
			(start 0.508 -0.9398)
			(end -0.508 -0.9398)
			(stroke
				(width 0.1524)
				(type default)
			)
			(layer "F.SilkS")
		)
		(fp_rect
			(start -0.508 0.9398)
			(end 0.508 -0.9398)
			(stroke
				(width 0)
				(type default)
			)
			(fill no)
			(layer "F.CrtYd")
		)
		(fp_rect
			(start -0.508 0.9398)
			(end 0.508 -0.9398)
			(stroke
				(width 0)
				(type default)
			)
			(fill no)
			(layer "F.Fab")
		)
		(pad "1" smd custom
			(at 0 -0.4445)
			(size 0.1397 0.1397)
			(layers "F.Cu" "F.Mask" "F.Paste")
			(net "MB1_ISET_R")
			(options
				(clearance outline)
				(anchor circle)
			)
			(primitives
				(gr_poly
					(pts
						(arc
							(start -0.1778 -0.2794)
							(mid -0.249642 -0.249642)
							(end -0.2794 -0.1778)
						)
						(arc
							(start -0.2794 0.1778)
							(mid -0.249642 0.249642)
							(end -0.1778 0.2794)
						)
						(arc
							(start 0.1778 0.2794)
							(mid 0.249642 0.249642)
							(end 0.2794 0.1778)
						)
						(arc
							(start 0.2794 -0.1778)
							(mid 0.249642 -0.249642)
							(end 0.1778 -0.2794)
						)
					)
					(width 0)
					(fill yes)
				)
			)
		)
		(pad "2" smd custom
			(at 0 0.4445)
			(size 0.1397 0.1397)
			(layers "F.Cu" "F.Mask" "F.Paste")
			(net "AGND_CURRENT_MONOB")
			(options
				(clearance outline)
				(anchor circle)
			)
			(primitives
				(gr_poly
					(pts
						(arc
							(start -0.1778 -0.2794)
							(mid -0.249642 -0.249642)
							(end -0.2794 -0.1778)
						)
						(arc
							(start -0.2794 0.1778)
							(mid -0.249642 0.249642)
							(end -0.1778 0.2794)
						)
						(arc
							(start 0.1778 0.2794)
							(mid 0.249642 0.249642)
							(end 0.2794 0.1778)
						)
						(arc
							(start 0.2794 -0.1778)
							(mid 0.249642 -0.249642)
							(end 0.1778 -0.2794)
						)
					)
					(width 0)
					(fill yes)
				)
			)
		)
	)
	(footprint ""
		(layer "F.Cu")
		(at 463.0039 -62.016894)
		(property "Reference" "Q206"
			(at 0 0 0)
			(layer "F.SilkS")
			(hide yes)
			(effects
				(font
					(size 1.27 1.27)
				)
			)
		)
		(property "Value" "AO4407AL-GP"
			(at -3.707384 -1.5367 0)
			(unlocked yes)
			(layer "F.Fab")
			(hide yes)
			(effects
				(font
					(size 1.016 1.016)
					(thickness 0.1524)
				)
			)
		)
		(property "Device Type" "SOIC8H69"
			(at -3.707384 -3.0607 0)
			(unlocked yes)
			(layer "F.Fab")
			(hide yes)
			(effects
				(font
					(size 1.016 1.016)
					(thickness 0.1524)
				)
			)
		)
		(duplicate_pad_numbers_are_jumpers no)
		(fp_line
			(start -2.7432 -1.4224)
			(end -2.7432 1.4224)
			(stroke
				(width 0.1524)
				(type default)
			)
			(layer "F.SilkS")
		)
		(fp_line
			(start -2.7432 1.4224)
			(end -2.6416 1.4224)
			(stroke
				(width 0.1524)
				(type default)
			)
			(layer "F.SilkS")
		)
		(fp_line
			(start -2.7432 1.4224)
			(end 2.1336 1.4224)
			(stroke
				(width 0.1524)
				(type default)
			)
			(layer "F.SilkS")
		)
		(fp_line
			(start -2.7178 -0.508)
			(end -2.1844 -0.0508)
			(stroke
				(width 0.1524)
				(type default)
			)
			(layer "F.SilkS")
		)
		(fp_line
			(start -2.6289 3.4417)
			(end -2.6289 1.4732)
			(stroke
				(width 0.381)
				(type default)
			)
			(layer "F.SilkS")
		)
		(fp_line
			(start -2.1844 -0.0508)
			(end -2.7178 0.508)
			(stroke
				(width 0.1524)
				(type default)
			)
			(layer "F.SilkS")
		)
		(fp_line
			(start 2.1336 -1.4224)
			(end -2.7432 -1.4224)
			(stroke
				(width 0.1524)
				(type default)
			)
			(layer "F.SilkS")
		)
		(fp_line
			(start 2.1336 1.4224)
			(end 2.1336 -1.4224)
			(stroke
				(width 0.1524)
				(type default)
			)
			(layer "F.SilkS")
		)
		(fp_poly
			(pts
				(xy -2.2098 -1.4224) (xy -2.2098 1.4224) (xy 2.2098 1.4224) (xy 2.2098 -1.4224)
			)
			(stroke
				(width 0)
				(type default)
			)
			(fill yes)
			(layer "F.SilkS")
		)
		(fp_rect
			(start -2.450084 2.999994)
			(end 2.450084 -2.999994)
			(stroke
				(width 0)
				(type default)
			)
			(fill no)
			(layer "F.CrtYd")
		)
		(fp_poly
			(pts
				(xy -2.8194 3.6322) (xy -2.8194 -3.6322) (xy 2.8194 -3.6322) (xy 2.8194 1.18364) (xy 2.450084 1.18364)
				(xy 2.450084 -2.999994) (xy -2.450084 -2.999994) (xy -2.450084 2.999994) (xy 2.450084 2.999994)
				(xy 2.450084 1.18618) (xy 2.8194 1.18618) (xy 2.8194 3.6322)
			)
			(stroke
				(width 0)
				(type default)
			)
			(fill no)
			(layer "F.CrtYd")
		)
		(fp_rect
			(start -2.8194 3.6322)
			(end 2.8194 -3.6322)
			(stroke
				(width 0)
				(type default)
			)
			(fill no)
			(layer "F.Fab")
		)
		(pad "1" smd rect
			(at -1.905 2.54)
			(size 0.635 1.651)
			(layers "F.Cu" "F.Mask" "F.Paste")
			(net "P12V_A")
		)
		(pad "2" smd rect
			(at -0.635 2.54)
			(size 0.635 1.651)
			(layers "F.Cu" "F.Mask" "F.Paste")
			(net "P12V_A")
		)
		(pad "3" smd rect
			(at 0.635 2.54)
			(size 0.635 1.651)
			(layers "F.Cu" "F.Mask" "F.Paste")
			(net "P12V_A")
		)
		(pad "4" smd rect
			(at 1.905 2.54)
			(size 0.635 1.651)
			(layers "F.Cu" "F.Mask" "F.Paste")
			(net "SW_HDD_N34")
		)
		(pad "5" smd rect
			(at 1.905 -2.54)
			(size 0.635 1.651)
			(layers "F.Cu" "F.Mask" "F.Paste")
			(net "P12V_HDD34")
		)
		(pad "6" smd rect
			(at 0.635 -2.54)
			(size 0.635 1.651)
			(layers "F.Cu" "F.Mask" "F.Paste")
			(net "P12V_HDD34")
		)
		(pad "7" smd rect
			(at -0.635 -2.54)
			(size 0.635 1.651)
			(layers "F.Cu" "F.Mask" "F.Paste")
			(net "P12V_HDD34")
		)
		(pad "8" smd rect
			(at -1.905 -2.54)
			(size 0.635 1.651)
			(layers "F.Cu" "F.Mask" "F.Paste")
			(net "P12V_HDD34")
		)
	)
	(footprint ""
		(layer "F.Cu")
		(at 349.812102 -292.169342 90)
		(property "Reference" "R291"
			(at 0 0 90)
			(layer "F.SilkS")
			(hide yes)
			(effects
				(font
					(size 1.27 1.27)
				)
			)
		)
		(property "Value" "10KR2F-2-GP"
			(at 0.064008 -3.993896 90)
			(unlocked yes)
			(layer "F.Fab")
			(hide yes)
			(effects
				(font
					(size 1.016 1.016)
					(thickness 0.1524)
				)
			)
		)
		(property "Device Type" "R402H16"
			(at 0.064008 -5.517896 90)
			(unlocked yes)
			(layer "F.Fab")
			(hide yes)
			(effects
				(font
					(size 1.016 1.016)
					(thickness 0.1524)
				)
			)
		)
		(duplicate_pad_numbers_are_jumpers no)
		(fp_line
			(start 0.508 -0.9398)
			(end -0.508 -0.9398)
			(stroke
				(width 0.1524)
				(type default)
			)
			(layer "F.SilkS")
		)
		(fp_line
			(start -0.508 -0.9398)
			(end -0.508 0.9398)
			(stroke
				(width 0.1524)
				(type default)
			)
			(layer "F.SilkS")
		)
		(fp_rect
			(start -0.508 0.9398)
			(end 0.508 -0.9398)
			(stroke
				(width 0)
				(type default)
			)
			(fill no)
			(layer "F.CrtYd")
		)
		(fp_rect
			(start -0.508 0.9398)
			(end 0.508 -0.9398)
			(stroke
				(width 0)
				(type default)
			)
			(fill no)
			(layer "F.Fab")
		)
		(pad "1" smd custom
			(at 0 -0.4445 90)
			(size 0.1397 0.1397)
			(layers "F.Cu" "F.Mask" "F.Paste")
			(net "P3V3_STBY_A")
			(options
				(clearance outline)
				(anchor circle)
			)
			(primitives
				(gr_poly
					(pts
						(arc
							(start -0.1778 -0.2794)
							(mid -0.249642 -0.249642)
							(end -0.2794 -0.1778)
						)
						(arc
							(start -0.2794 0.1778)
							(mid -0.249642 0.249642)
							(end -0.1778 0.2794)
						)
						(arc
							(start 0.1778 0.2794)
							(mid 0.249642 0.249642)
							(end 0.2794 0.1778)
						)
						(arc
							(start 0.2794 -0.1778)
							(mid 0.249642 -0.249642)
							(end 0.1778 -0.2794)
						)
					)
					(width 0)
					(fill yes)
				)
			)
		)
		(pad "2" smd custom
			(at 0 0.4445 90)
			(size 0.1397 0.1397)
			(layers "F.Cu" "F.Mask" "F.Paste")
			(net "HDD_PRSNT_7")
			(options
				(clearance outline)
				(anchor circle)
			)
			(primitives
				(gr_poly
					(pts
						(arc
							(start -0.1778 -0.2794)
							(mid -0.249642 -0.249642)
							(end -0.2794 -0.1778)
						)
						(arc
							(start -0.2794 0.1778)
							(mid -0.249642 0.249642)
							(end -0.1778 0.2794)
						)
						(arc
							(start 0.1778 0.2794)
							(mid 0.249642 0.249642)
							(end 0.2794 0.1778)
						)
						(arc
							(start 0.2794 -0.1778)
							(mid 0.249642 -0.249642)
							(end 0.1778 -0.2794)
						)
					)
					(width 0)
					(fill yes)
				)
			)
		)
	)
	(footprint ""
		(layer "F.Cu")
		(at 371.557042 -242.788694 180)
		(property "Reference" "Q271"
			(at 0 0 180)
			(layer "F.SilkS")
			(hide yes)
			(effects
				(font
					(size 1.27 1.27)
				)
			)
		)
		(property "Value" "SSM3K324R-GP"
			(at 0.127 -8.9662 180)
			(unlocked yes)
			(layer "F.Fab")
			(hide yes)
			(effects
				(font
					(size 1.016 1.016)
					(thickness 0.1524)
				)
			)
		)
		(property "Device Type" "SOT23DGS2D4H35"
			(at 0.127 -10.4902 180)
			(unlocked yes)
			(layer "F.Fab")
			(hide yes)
			(effects
				(font
					(size 1.016 1.016)
					(thickness 0.1524)
				)
			)
		)
		(duplicate_pad_numbers_are_jumpers no)
		(fp_line
			(start 1.651 1.778)
			(end 1.651 -1.778)
			(stroke
				(width 0.1524)
				(type default)
			)
			(layer "F.SilkS")
		)
		(fp_line
			(start 1.651 -1.778)
			(end -1.651 -1.778)
			(stroke
				(width 0.1524)
				(type default)
			)
			(layer "F.SilkS")
		)
		(fp_line
			(start -1.651 1.778)
			(end 1.651 1.778)
			(stroke
				(width 0.1524)
				(type default)
			)
			(layer "F.SilkS")
		)
		(fp_line
			(start -1.651 -1.778)
			(end -1.651 1.778)
			(stroke
				(width 0.1524)
				(type default)
			)
			(layer "F.SilkS")
		)
		(fp_poly
			(pts
				(xy -1.778 1.8796) (xy -1.778 -1.8796) (xy 1.778 -1.8796) (xy 1.778 1.8796)
			)
			(stroke
				(width 0)
				(type default)
			)
			(fill no)
			(layer "F.CrtYd")
		)
		(fp_poly
			(pts
				(xy -1.778 1.8796) (xy -1.778 -1.8796) (xy 1.778 -1.8796) (xy 1.778 1.8796)
			)
			(stroke
				(width 0)
				(type default)
			)
			(fill no)
			(layer "F.Fab")
		)
		(pad "D" smd custom
			(at 0 -0.9525 180)
			(size 0.1905 0.1905)
			(layers "F.Cu" "F.Mask" "F.Paste")
			(net "DRV_ACT_8_N")
			(options
				(clearance outline)
				(anchor circle)
			)
			(primitives
				(gr_poly
					(pts
						(arc
							(start -0.1778 0.5715)
							(mid -0.321484 0.511984)
							(end -0.381 0.3683)
						)
						(arc
							(start -0.381 -0.3683)
							(mid -0.321484 -0.511984)
							(end -0.1778 -0.5715)
						)
						(arc
							(start 0.1778 -0.5715)
							(mid 0.321484 -0.511984)
							(end 0.381 -0.3683)
						)
						(arc
							(start 0.381 0.3683)
							(mid 0.321484 0.511984)
							(end 0.1778 0.5715)
						)
					)
					(width 0)
					(fill yes)
				)
			)
		)
		(pad "G" smd custom
			(at -0.98425 0.9525 180)
			(size 0.1905 0.1905)
			(layers "F.Cu" "F.Mask" "F.Paste")
			(net "DRIVE_A_8_ACT")
			(options
				(clearance outline)
				(anchor circle)
			)
			(primitives
				(gr_poly
					(pts
						(arc
							(start -0.1778 0.5715)
							(mid -0.321484 0.511984)
							(end -0.381 0.3683)
						)
						(arc
							(start -0.381 -0.3683)
							(mid -0.321484 -0.511984)
							(end -0.1778 -0.5715)
						)
						(arc
							(start 0.1778 -0.5715)
							(mid 0.321484 -0.511984)
							(end 0.381 -0.3683)
						)
						(arc
							(start 0.381 0.3683)
							(mid 0.321484 0.511984)
							(end 0.1778 0.5715)
						)
					)
					(width 0)
					(fill yes)
				)
			)
		)
		(pad "S" smd custom
			(at 0.98425 0.9525 180)
			(size 0.1905 0.1905)
			(layers "F.Cu" "F.Mask" "F.Paste")
			(net "GND")
			(options
				(clearance outline)
				(anchor circle)
			)
			(primitives
				(gr_poly
					(pts
						(arc
							(start -0.1778 0.5715)
							(mid -0.321484 0.511984)
							(end -0.381 0.3683)
						)
						(arc
							(start -0.381 -0.3683)
							(mid -0.321484 -0.511984)
							(end -0.1778 -0.5715)
						)
						(arc
							(start 0.1778 -0.5715)
							(mid 0.321484 -0.511984)
							(end 0.381 -0.3683)
						)
						(arc
							(start 0.381 0.3683)
							(mid 0.321484 0.511984)
							(end 0.1778 0.5715)
						)
					)
					(width 0)
					(fill yes)
				)
			)
		)
	)
	(footprint ""
		(layer "F.Cu")
		(at 223.421448 -350.624648 -90)
		(property "Reference" "R22"
			(at 0 0 270)
			(layer "F.SilkS")
			(hide yes)
			(effects
				(font
					(size 1.27 1.27)
				)
			)
		)
		(property "Value" "0R2J-2-GP"
			(at 0.064008 -3.993896 270)
			(unlocked yes)
			(layer "F.Fab")
			(hide yes)
			(effects
				(font
					(size 1.016 1.016)
					(thickness 0.1524)
				)
			)
		)
		(property "Device Type" "R402H16"
			(at 0.064008 -5.517896 270)
			(unlocked yes)
			(layer "F.Fab")
			(hide yes)
			(effects
				(font
					(size 1.016 1.016)
					(thickness 0.1524)
				)
			)
		)
		(duplicate_pad_numbers_are_jumpers no)
		(fp_line
			(start -0.508 -0.9398)
			(end -0.508 0.9398)
			(stroke
				(width 0.1524)
				(type default)
			)
			(layer "F.SilkS")
		)
		(fp_line
			(start 0.508 -0.9398)
			(end -0.508 -0.9398)
			(stroke
				(width 0.1524)
				(type default)
			)
			(layer "F.SilkS")
		)
		(fp_rect
			(start -0.508 0.9398)
			(end 0.508 -0.9398)
			(stroke
				(width 0)
				(type default)
			)
			(fill no)
			(layer "F.CrtYd")
		)
		(fp_rect
			(start -0.508 0.9398)
			(end 0.508 -0.9398)
			(stroke
				(width 0)
				(type default)
			)
			(fill no)
			(layer "F.Fab")
		)
		(pad "1" smd custom
			(at 0 -0.4445 270)
			(size 0.1397 0.1397)
			(layers "F.Cu" "F.Mask" "F.Paste")
			(net "VOL_SEN_SDA")
			(options
				(clearance outline)
				(anchor circle)
			)
			(primitives
				(gr_poly
					(pts
						(arc
							(start -0.1778 -0.2794)
							(mid -0.249642 -0.249642)
							(end -0.2794 -0.1778)
						)
						(arc
							(start -0.2794 0.1778)
							(mid -0.249642 0.249642)
							(end -0.1778 0.2794)
						)
						(arc
							(start 0.1778 0.2794)
							(mid 0.249642 0.249642)
							(end 0.2794 0.1778)
						)
						(arc
							(start 0.2794 -0.1778)
							(mid 0.249642 -0.249642)
							(end 0.1778 -0.2794)
						)
					)
					(width 0)
					(fill yes)
				)
			)
		)
		(pad "2" smd custom
			(at 0 0.4445 270)
			(size 0.1397 0.1397)
			(layers "F.Cu" "F.Mask" "F.Paste")
			(net "I2C_DPB_A_SDA_BUF")
			(options
				(clearance outline)
				(anchor circle)
			)
			(primitives
				(gr_poly
					(pts
						(arc
							(start -0.1778 -0.2794)
							(mid -0.249642 -0.249642)
							(end -0.2794 -0.1778)
						)
						(arc
							(start -0.2794 0.1778)
							(mid -0.249642 0.249642)
							(end -0.1778 0.2794)
						)
						(arc
							(start 0.1778 0.2794)
							(mid 0.249642 0.249642)
							(end 0.2794 0.1778)
						)
						(arc
							(start 0.2794 -0.1778)
							(mid 0.249642 -0.249642)
							(end 0.1778 -0.2794)
						)
					)
					(width 0)
					(fill yes)
				)
			)
		)
	)
	(footprint ""
		(layer "F.Cu")
		(at 370.6368 -145.8214 180)
		(property "Reference" "C558"
			(at 0 0 180)
			(layer "F.SilkS")
			(hide yes)
			(effects
				(font
					(size 1.27 1.27)
				)
			)
		)
		(property "Value" "SCD1U16V2KX-3GP"
			(at 1.1811 -2.7051 180)
			(unlocked yes)
			(layer "F.Fab")
			(hide yes)
			(effects
				(font
					(size 1.016 1.016)
					(thickness 0.1524)
				)
			)
		)
		(property "Device Type" "C402H22"
			(at 1.1811 -4.2291 180)
			(unlocked yes)
			(layer "F.Fab")
			(hide yes)
			(effects
				(font
					(size 1.016 1.016)
					(thickness 0.1524)
				)
			)
		)
		(duplicate_pad_numbers_are_jumpers no)
		(fp_rect
			(start -0.4318 0.9525)
			(end 0.4318 -0.9525)
			(stroke
				(width 0)
				(type default)
			)
			(fill no)
			(layer "F.CrtYd")
		)
		(fp_rect
			(start -0.4318 0.9525)
			(end 0.4318 -0.9525)
			(stroke
				(width 0)
				(type default)
			)
			(fill no)
			(layer "F.Fab")
		)
		(pad "1" smd custom
			(at 0 -0.4445 180)
			(size 0.1524 0.1524)
			(layers "F.Cu" "F.Mask" "F.Paste")
			(net "MB1_CM_VOUT_R")
			(options
				(clearance outline)
				(anchor circle)
			)
			(primitives
				(gr_poly
					(pts
						(arc
							(start 0.3048 -0.2032)
							(mid 0.275042 -0.275042)
							(end 0.2032 -0.3048)
						)
						(arc
							(start -0.2032 -0.3048)
							(mid -0.275042 -0.275042)
							(end -0.3048 -0.2032)
						)
						(arc
							(start -0.3048 0.2032)
							(mid -0.275042 0.275042)
							(end -0.2032 0.3048)
						)
						(arc
							(start 0.2032 0.3048)
							(mid 0.275042 0.275042)
							(end 0.3048 0.2032)
						)
					)
					(width 0)
					(fill yes)
				)
			)
		)
		(pad "2" smd custom
			(at 0 0.4445 180)
			(size 0.1524 0.1524)
			(layers "F.Cu" "F.Mask" "F.Paste")
			(net "AGND_CURRENT_MONOB")
			(options
				(clearance outline)
				(anchor circle)
			)
			(primitives
				(gr_poly
					(pts
						(arc
							(start 0.3048 -0.2032)
							(mid 0.275042 -0.275042)
							(end 0.2032 -0.3048)
						)
						(arc
							(start -0.2032 -0.3048)
							(mid -0.275042 -0.275042)
							(end -0.3048 -0.2032)
						)
						(arc
							(start -0.3048 0.2032)
							(mid -0.275042 0.275042)
							(end -0.2032 0.3048)
						)
						(arc
							(start 0.2032 0.3048)
							(mid 0.275042 0.275042)
							(end 0.3048 0.2032)
						)
					)
					(width 0)
					(fill yes)
				)
			)
		)
	)
	(footprint ""
		(layer "F.Cu")
		(at 113.150396 -45.633894)
		(property "Reference" "R768"
			(at 0 0 0)
			(layer "F.SilkS")
			(hide yes)
			(effects
				(font
					(size 1.27 1.27)
				)
			)
		)
		(property "Value" "0R2J-2-GP"
			(at 0.064008 -3.993896 0)
			(unlocked yes)
			(layer "F.Fab")
			(hide yes)
			(effects
				(font
					(size 1.016 1.016)
					(thickness 0.1524)
				)
			)
		)
		(property "Device Type" "R402H16"
			(at 0.064008 -5.517896 0)
			(unlocked yes)
			(layer "F.Fab")
			(hide yes)
			(effects
				(font
					(size 1.016 1.016)
					(thickness 0.1524)
				)
			)
		)
		(duplicate_pad_numbers_are_jumpers no)
		(fp_line
			(start -0.508 -0.9398)
			(end -0.508 0.9398)
			(stroke
				(width 0.1524)
				(type default)
			)
			(layer "F.SilkS")
		)
		(fp_line
			(start 0.508 -0.9398)
			(end -0.508 -0.9398)
			(stroke
				(width 0.1524)
				(type default)
			)
			(layer "F.SilkS")
		)
		(fp_rect
			(start -0.508 0.9398)
			(end 0.508 -0.9398)
			(stroke
				(width 0)
				(type default)
			)
			(fill no)
			(layer "F.CrtYd")
		)
		(fp_rect
			(start -0.508 0.9398)
			(end 0.508 -0.9398)
			(stroke
				(width 0)
				(type default)
			)
			(fill no)
			(layer "F.Fab")
		)
		(pad "1" smd custom
			(at 0 -0.4445)
			(size 0.1397 0.1397)
			(layers "F.Cu" "F.Mask" "F.Paste")
			(net "SW_HDD_G27")
			(options
				(clearance outline)
				(anchor circle)
			)
			(primitives
				(gr_poly
					(pts
						(arc
							(start -0.1778 -0.2794)
							(mid -0.249642 -0.249642)
							(end -0.2794 -0.1778)
						)
						(arc
							(start -0.2794 0.1778)
							(mid -0.249642 0.249642)
							(end -0.1778 0.2794)
						)
						(arc
							(start 0.1778 0.2794)
							(mid 0.249642 0.249642)
							(end 0.2794 0.1778)
						)
						(arc
							(start 0.2794 -0.1778)
							(mid 0.249642 -0.249642)
							(end 0.1778 -0.2794)
						)
					)
					(width 0)
					(fill yes)
				)
			)
		)
		(pad "2" smd custom
			(at 0 0.4445)
			(size 0.1397 0.1397)
			(layers "F.Cu" "F.Mask" "F.Paste")
			(net "SW_HDD_R27")
			(options
				(clearance outline)
				(anchor circle)
			)
			(primitives
				(gr_poly
					(pts
						(arc
							(start -0.1778 -0.2794)
							(mid -0.249642 -0.249642)
							(end -0.2794 -0.1778)
						)
						(arc
							(start -0.2794 0.1778)
							(mid -0.249642 0.249642)
							(end -0.1778 0.2794)
						)
						(arc
							(start 0.1778 0.2794)
							(mid 0.249642 0.249642)
							(end 0.2794 0.1778)
						)
						(arc
							(start 0.2794 -0.1778)
							(mid 0.249642 -0.249642)
							(end 0.1778 -0.2794)
						)
					)
					(width 0)
					(fill yes)
				)
			)
		)
	)
	(footprint ""
		(layer "F.Cu")
		(at 178.435 -285.285942 180)
		(property "Reference" "Q30"
			(at 0 0 180)
			(layer "F.SilkS")
			(hide yes)
			(effects
				(font
					(size 1.27 1.27)
				)
			)
		)
		(property "Value" "AO4406AL-GP"
			(at -3.707384 -1.5367 180)
			(unlocked yes)
			(layer "F.Fab")
			(hide yes)
			(effects
				(font
					(size 1.016 1.016)
					(thickness 0.1524)
				)
			)
		)
		(property "Device Type" "SOIC8H69"
			(at -3.707384 -3.0607 180)
			(unlocked yes)
			(layer "F.Fab")
			(hide yes)
			(effects
				(font
					(size 1.016 1.016)
					(thickness 0.1524)
				)
			)
		)
		(duplicate_pad_numbers_are_jumpers no)
		(fp_line
			(start 2.1336 1.4224)
			(end 2.1336 -1.4224)
			(stroke
				(width 0.1524)
				(type default)
			)
			(layer "F.SilkS")
		)
		(fp_line
			(start 2.1336 -1.4224)
			(end -2.7432 -1.4224)
			(stroke
				(width 0.1524)
				(type default)
			)
			(layer "F.SilkS")
		)
		(fp_line
			(start -2.1844 -0.0508)
			(end -2.7178 0.508)
			(stroke
				(width 0.1524)
				(type default)
			)
			(layer "F.SilkS")
		)
		(fp_line
			(start -2.6289 3.4417)
			(end -2.6289 1.4732)
			(stroke
				(width 0.381)
				(type default)
			)
			(layer "F.SilkS")
		)
		(fp_line
			(start -2.7178 -0.508)
			(end -2.1844 -0.0508)
			(stroke
				(width 0.1524)
				(type default)
			)
			(layer "F.SilkS")
		)
		(fp_line
			(start -2.7432 1.4224)
			(end 2.1336 1.4224)
			(stroke
				(width 0.1524)
				(type default)
			)
			(layer "F.SilkS")
		)
		(fp_line
			(start -2.7432 1.4224)
			(end -2.6416 1.4224)
			(stroke
				(width 0.1524)
				(type default)
			)
			(layer "F.SilkS")
		)
		(fp_line
			(start -2.7432 -1.4224)
			(end -2.7432 1.4224)
			(stroke
				(width 0.1524)
				(type default)
			)
			(layer "F.SilkS")
		)
		(fp_poly
			(pts
				(xy -2.2098 -1.4224) (xy -2.2098 1.4224) (xy 2.2098 1.4224) (xy 2.2098 -1.4224)
			)
			(stroke
				(width 0)
				(type default)
			)
			(fill yes)
			(layer "F.SilkS")
		)
		(fp_rect
			(start -2.450084 2.999994)
			(end 2.450084 -2.999994)
			(stroke
				(width 0)
				(type default)
			)
			(fill no)
			(layer "F.CrtYd")
		)
		(fp_poly
			(pts
				(xy -2.8194 3.6322) (xy -2.8194 -3.6322) (xy 2.8194 -3.6322) (xy 2.8194 1.18364) (xy 2.450084 1.18364)
				(xy 2.450084 -2.999994) (xy -2.450084 -2.999994) (xy -2.450084 2.999994) (xy 2.450084 2.999994)
				(xy 2.450084 1.18618) (xy 2.8194 1.18618) (xy 2.8194 3.6322)
			)
			(stroke
				(width 0)
				(type default)
			)
			(fill no)
			(layer "F.CrtYd")
		)
		(fp_rect
			(start -2.8194 3.6322)
			(end 2.8194 -3.6322)
			(stroke
				(width 0)
				(type default)
			)
			(fill no)
			(layer "F.Fab")
		)
		(pad "1" smd rect
			(at -1.905 2.54 180)
			(size 0.635 1.651)
			(layers "F.Cu" "F.Mask" "F.Paste")
			(net "P5V_HDD5")
		)
		(pad "2" smd rect
			(at -0.635 2.54 180)
			(size 0.635 1.651)
			(layers "F.Cu" "F.Mask" "F.Paste")
			(net "P5V_HDD5")
		)
		(pad "3" smd rect
			(at 0.635 2.54 180)
			(size 0.635 1.651)
			(layers "F.Cu" "F.Mask" "F.Paste")
			(net "P5V_HDD5")
		)
		(pad "4" smd rect
			(at 1.905 2.54 180)
			(size 0.635 1.651)
			(layers "F.Cu" "F.Mask" "F.Paste")
			(net "SW_HDD_P5")
		)
		(pad "5" smd rect
			(at 1.905 -2.54 180)
			(size 0.635 1.651)
			(layers "F.Cu" "F.Mask" "F.Paste")
			(net "P5V_A_1")
		)
		(pad "6" smd rect
			(at 0.635 -2.54 180)
			(size 0.635 1.651)
			(layers "F.Cu" "F.Mask" "F.Paste")
			(net "P5V_A_1")
		)
		(pad "7" smd rect
			(at -0.635 -2.54 180)
			(size 0.635 1.651)
			(layers "F.Cu" "F.Mask" "F.Paste")
			(net "P5V_A_1")
		)
		(pad "8" smd rect
			(at -1.905 -2.54 180)
			(size 0.635 1.651)
			(layers "F.Cu" "F.Mask" "F.Paste")
			(net "P5V_A_1")
		)
	)
	(footprint ""
		(layer "F.Cu")
		(at 410.414978 -242.25377)
		(property "Reference" "R264"
			(at 0 0 0)
			(layer "F.SilkS")
			(hide yes)
			(effects
				(font
					(size 1.27 1.27)
				)
			)
		)
		(property "Value" "91R3F-1-GP"
			(at -0.0254 -2.5146 0)
			(unlocked yes)
			(layer "F.Fab")
			(hide yes)
			(effects
				(font
					(size 1.016 1.016)
					(thickness 0.1524)
				)
			)
		)
		(property "Device Type" "R603H22"
			(at -0.0254 -4.0386 0)
			(unlocked yes)
			(layer "F.Fab")
			(hide yes)
			(effects
				(font
					(size 1.016 1.016)
					(thickness 0.1524)
				)
			)
		)
		(duplicate_pad_numbers_are_jumpers no)
		(fp_line
			(start -0.4826 0)
			(end -0.2032 0)
			(stroke
				(width 0.2032)
				(type default)
			)
			(layer "F.SilkS")
		)
		(fp_line
			(start 0.2032 0)
			(end 0.4826 0)
			(stroke
				(width 0.2032)
				(type default)
			)
			(layer "F.SilkS")
		)
		(fp_rect
			(start -0.5842 1.3335)
			(end 0.5842 -1.3335)
			(stroke
				(width 0)
				(type default)
			)
			(fill no)
			(layer "F.CrtYd")
		)
		(fp_rect
			(start -0.5842 1.3335)
			(end 0.5842 -1.3335)
			(stroke
				(width 0)
				(type default)
			)
			(fill no)
			(layer "F.Fab")
		)
		(pad "1" smd custom
			(at 0 -0.762)
			(size 0.2159 0.2159)
			(layers "F.Cu" "F.Mask" "F.Paste")
			(net "P5V_A_3")
			(options
				(clearance outline)
				(anchor circle)
			)
			(primitives
				(gr_poly
					(pts
						(arc
							(start -0.3302 -0.4318)
							(mid -0.402042 -0.402042)
							(end -0.4318 -0.3302)
						)
						(arc
							(start -0.4318 0.3302)
							(mid -0.402042 0.402042)
							(end -0.3302 0.4318)
						)
						(arc
							(start 0.3302 0.4318)
							(mid 0.402042 0.402042)
							(end 0.4318 0.3302)
						)
						(arc
							(start 0.4318 -0.3302)
							(mid 0.402042 -0.402042)
							(end 0.3302 -0.4318)
						)
					)
					(width 0)
					(fill yes)
				)
			)
		)
		(pad "2" smd custom
			(at 0 0.762)
			(size 0.2159 0.2159)
			(layers "F.Cu" "F.Mask" "F.Paste")
			(net "DRV_ACT_9")
			(options
				(clearance outline)
				(anchor circle)
			)
			(primitives
				(gr_poly
					(pts
						(arc
							(start -0.3302 -0.4318)
							(mid -0.402042 -0.402042)
							(end -0.4318 -0.3302)
						)
						(arc
							(start -0.4318 0.3302)
							(mid -0.402042 0.402042)
							(end -0.3302 0.4318)
						)
						(arc
							(start 0.3302 0.4318)
							(mid 0.402042 0.402042)
							(end 0.4318 0.3302)
						)
						(arc
							(start 0.4318 -0.3302)
							(mid 0.402042 -0.402042)
							(end 0.3302 -0.4318)
						)
					)
					(width 0)
					(fill yes)
				)
			)
		)
	)
	(footprint ""
		(layer "F.Cu")
		(at 336.804 -292.016942)
		(property "Reference" "Q38"
			(at 0 0 0)
			(layer "F.SilkS")
			(hide yes)
			(effects
				(font
					(size 1.27 1.27)
				)
			)
		)
		(property "Value" "AO4407AL-GP"
			(at -3.707384 -1.5367 0)
			(unlocked yes)
			(layer "F.Fab")
			(hide yes)
			(effects
				(font
					(size 1.016 1.016)
					(thickness 0.1524)
				)
			)
		)
		(property "Device Type" "SOIC8H69"
			(at -3.707384 -3.0607 0)
			(unlocked yes)
			(layer "F.Fab")
			(hide yes)
			(effects
				(font
					(size 1.016 1.016)
					(thickness 0.1524)
				)
			)
		)
		(duplicate_pad_numbers_are_jumpers no)
		(fp_line
			(start -2.7432 -1.4224)
			(end -2.7432 1.4224)
			(stroke
				(width 0.1524)
				(type default)
			)
			(layer "F.SilkS")
		)
		(fp_line
			(start -2.7432 1.4224)
			(end -2.6416 1.4224)
			(stroke
				(width 0.1524)
				(type default)
			)
			(layer "F.SilkS")
		)
		(fp_line
			(start -2.7432 1.4224)
			(end 2.1336 1.4224)
			(stroke
				(width 0.1524)
				(type default)
			)
			(layer "F.SilkS")
		)
		(fp_line
			(start -2.7178 -0.508)
			(end -2.1844 -0.0508)
			(stroke
				(width 0.1524)
				(type default)
			)
			(layer "F.SilkS")
		)
		(fp_line
			(start -2.6289 3.4417)
			(end -2.6289 1.4732)
			(stroke
				(width 0.381)
				(type default)
			)
			(layer "F.SilkS")
		)
		(fp_line
			(start -2.1844 -0.0508)
			(end -2.7178 0.508)
			(stroke
				(width 0.1524)
				(type default)
			)
			(layer "F.SilkS")
		)
		(fp_line
			(start 2.1336 -1.4224)
			(end -2.7432 -1.4224)
			(stroke
				(width 0.1524)
				(type default)
			)
			(layer "F.SilkS")
		)
		(fp_line
			(start 2.1336 1.4224)
			(end 2.1336 -1.4224)
			(stroke
				(width 0.1524)
				(type default)
			)
			(layer "F.SilkS")
		)
		(fp_poly
			(pts
				(xy -2.2098 -1.4224) (xy -2.2098 1.4224) (xy 2.2098 1.4224) (xy 2.2098 -1.4224)
			)
			(stroke
				(width 0)
				(type default)
			)
			(fill yes)
			(layer "F.SilkS")
		)
		(fp_rect
			(start -2.450084 2.999994)
			(end 2.450084 -2.999994)
			(stroke
				(width 0)
				(type default)
			)
			(fill no)
			(layer "F.CrtYd")
		)
		(fp_poly
			(pts
				(xy -2.8194 3.6322) (xy -2.8194 -3.6322) (xy 2.8194 -3.6322) (xy 2.8194 1.18364) (xy 2.450084 1.18364)
				(xy 2.450084 -2.999994) (xy -2.450084 -2.999994) (xy -2.450084 2.999994) (xy 2.450084 2.999994)
				(xy 2.450084 1.18618) (xy 2.8194 1.18618) (xy 2.8194 3.6322)
			)
			(stroke
				(width 0)
				(type default)
			)
			(fill no)
			(layer "F.CrtYd")
		)
		(fp_rect
			(start -2.8194 3.6322)
			(end 2.8194 -3.6322)
			(stroke
				(width 0)
				(type default)
			)
			(fill no)
			(layer "F.Fab")
		)
		(pad "1" smd rect
			(at -1.905 2.54)
			(size 0.635 1.651)
			(layers "F.Cu" "F.Mask" "F.Paste")
			(net "P12V_A")
		)
		(pad "2" smd rect
			(at -0.635 2.54)
			(size 0.635 1.651)
			(layers "F.Cu" "F.Mask" "F.Paste")
			(net "P12V_A")
		)
		(pad "3" smd rect
			(at 0.635 2.54)
			(size 0.635 1.651)
			(layers "F.Cu" "F.Mask" "F.Paste")
			(net "P12V_A")
		)
		(pad "4" smd rect
			(at 1.905 2.54)
			(size 0.635 1.651)
			(layers "F.Cu" "F.Mask" "F.Paste")
			(net "SW_HDD_N6")
		)
		(pad "5" smd rect
			(at 1.905 -2.54)
			(size 0.635 1.651)
			(layers "F.Cu" "F.Mask" "F.Paste")
			(net "P12V_HDD6")
		)
		(pad "6" smd rect
			(at 0.635 -2.54)
			(size 0.635 1.651)
			(layers "F.Cu" "F.Mask" "F.Paste")
			(net "P12V_HDD6")
		)
		(pad "7" smd rect
			(at -0.635 -2.54)
			(size 0.635 1.651)
			(layers "F.Cu" "F.Mask" "F.Paste")
			(net "P12V_HDD6")
		)
		(pad "8" smd rect
			(at -1.905 -2.54)
			(size 0.635 1.651)
			(layers "F.Cu" "F.Mask" "F.Paste")
			(net "P12V_HDD6")
		)
	)
	(footprint ""
		(layer "F.Cu")
		(at 172.974 -47.157894 180)
		(property "Reference" "R813"
			(at 0 0 180)
			(layer "F.SilkS")
			(hide yes)
			(effects
				(font
					(size 1.27 1.27)
				)
			)
		)
		(property "Value" "200KR2F-L-GP"
			(at 0.064008 -3.993896 180)
			(unlocked yes)
			(layer "F.Fab")
			(hide yes)
			(effects
				(font
					(size 1.016 1.016)
					(thickness 0.1524)
				)
			)
		)
		(property "Device Type" "R402H16"
			(at 0.064008 -5.517896 180)
			(unlocked yes)
			(layer "F.Fab")
			(hide yes)
			(effects
				(font
					(size 1.016 1.016)
					(thickness 0.1524)
				)
			)
		)
		(duplicate_pad_numbers_are_jumpers no)
		(fp_line
			(start 0.508 -0.9398)
			(end -0.508 -0.9398)
			(stroke
				(width 0.1524)
				(type default)
			)
			(layer "F.SilkS")
		)
		(fp_line
			(start -0.508 -0.9398)
			(end -0.508 0.9398)
			(stroke
				(width 0.1524)
				(type default)
			)
			(layer "F.SilkS")
		)
		(fp_rect
			(start -0.508 0.9398)
			(end 0.508 -0.9398)
			(stroke
				(width 0)
				(type default)
			)
			(fill no)
			(layer "F.CrtYd")
		)
		(fp_rect
			(start -0.508 0.9398)
			(end 0.508 -0.9398)
			(stroke
				(width 0)
				(type default)
			)
			(fill no)
			(layer "F.Fab")
		)
		(pad "1" smd custom
			(at 0 -0.4445 180)
			(size 0.1397 0.1397)
			(layers "F.Cu" "F.Mask" "F.Paste")
			(net "SW_HDD_R29")
			(options
				(clearance outline)
				(anchor circle)
			)
			(primitives
				(gr_poly
					(pts
						(arc
							(start -0.1778 -0.2794)
							(mid -0.249642 -0.249642)
							(end -0.2794 -0.1778)
						)
						(arc
							(start -0.2794 0.1778)
							(mid -0.249642 0.249642)
							(end -0.1778 0.2794)
						)
						(arc
							(start 0.1778 0.2794)
							(mid 0.249642 0.249642)
							(end 0.2794 0.1778)
						)
						(arc
							(start 0.2794 -0.1778)
							(mid 0.249642 -0.249642)
							(end 0.1778 -0.2794)
						)
					)
					(width 0)
					(fill yes)
				)
			)
		)
		(pad "2" smd custom
			(at 0 0.4445 180)
			(size 0.1397 0.1397)
			(layers "F.Cu" "F.Mask" "F.Paste")
			(net "SW_HDD_N29")
			(options
				(clearance outline)
				(anchor circle)
			)
			(primitives
				(gr_poly
					(pts
						(arc
							(start -0.1778 -0.2794)
							(mid -0.249642 -0.249642)
							(end -0.2794 -0.1778)
						)
						(arc
							(start -0.2794 0.1778)
							(mid -0.249642 0.249642)
							(end -0.1778 0.2794)
						)
						(arc
							(start 0.1778 0.2794)
							(mid 0.249642 0.249642)
							(end 0.2794 0.1778)
						)
						(arc
							(start 0.2794 -0.1778)
							(mid 0.249642 -0.249642)
							(end 0.1778 -0.2794)
						)
					)
					(width 0)
					(fill yes)
				)
			)
		)
	)
	(footprint ""
		(layer "F.Cu")
		(at 67.347846 -177.169318 -90)
		(property "Reference" "R429"
			(at 0 0 270)
			(layer "F.SilkS")
			(hide yes)
			(effects
				(font
					(size 1.27 1.27)
				)
			)
		)
		(property "Value" "10KR2F-2-GP"
			(at 0.064008 -3.993896 270)
			(unlocked yes)
			(layer "F.Fab")
			(hide yes)
			(effects
				(font
					(size 1.016 1.016)
					(thickness 0.1524)
				)
			)
		)
		(property "Device Type" "R402H16"
			(at 0.064008 -5.517896 270)
			(unlocked yes)
			(layer "F.Fab")
			(hide yes)
			(effects
				(font
					(size 1.016 1.016)
					(thickness 0.1524)
				)
			)
		)
		(duplicate_pad_numbers_are_jumpers no)
		(fp_line
			(start -0.508 -0.9398)
			(end -0.508 0.9398)
			(stroke
				(width 0.1524)
				(type default)
			)
			(layer "F.SilkS")
		)
		(fp_line
			(start 0.508 -0.9398)
			(end -0.508 -0.9398)
			(stroke
				(width 0.1524)
				(type default)
			)
			(layer "F.SilkS")
		)
		(fp_rect
			(start -0.508 0.9398)
			(end 0.508 -0.9398)
			(stroke
				(width 0)
				(type default)
			)
			(fill no)
			(layer "F.CrtYd")
		)
		(fp_rect
			(start -0.508 0.9398)
			(end 0.508 -0.9398)
			(stroke
				(width 0)
				(type default)
			)
			(fill no)
			(layer "F.Fab")
		)
		(pad "1" smd custom
			(at 0 -0.4445 270)
			(size 0.1397 0.1397)
			(layers "F.Cu" "F.Mask" "F.Paste")
			(net "P3V3_STBY_A")
			(options
				(clearance outline)
				(anchor circle)
			)
			(primitives
				(gr_poly
					(pts
						(arc
							(start -0.1778 -0.2794)
							(mid -0.249642 -0.249642)
							(end -0.2794 -0.1778)
						)
						(arc
							(start -0.2794 0.1778)
							(mid -0.249642 0.249642)
							(end -0.1778 0.2794)
						)
						(arc
							(start 0.1778 0.2794)
							(mid 0.249642 0.249642)
							(end 0.2794 0.1778)
						)
						(arc
							(start 0.2794 -0.1778)
							(mid 0.249642 -0.249642)
							(end 0.1778 -0.2794)
						)
					)
					(width 0)
					(fill yes)
				)
			)
		)
		(pad "2" smd custom
			(at 0 0.4445 270)
			(size 0.1397 0.1397)
			(layers "F.Cu" "F.Mask" "F.Paste")
			(net "HDD_PRSNT_13")
			(options
				(clearance outline)
				(anchor circle)
			)
			(primitives
				(gr_poly
					(pts
						(arc
							(start -0.1778 -0.2794)
							(mid -0.249642 -0.249642)
							(end -0.2794 -0.1778)
						)
						(arc
							(start -0.2794 0.1778)
							(mid -0.249642 0.249642)
							(end -0.1778 0.2794)
						)
						(arc
							(start 0.1778 0.2794)
							(mid 0.249642 0.249642)
							(end 0.2794 0.1778)
						)
						(arc
							(start 0.2794 -0.1778)
							(mid 0.249642 -0.249642)
							(end 0.1778 -0.2794)
						)
					)
					(width 0)
					(fill yes)
				)
			)
		)
	)
	(footprint ""
		(layer "F.Cu")
		(at 17.145 -242.25377)
		(property "Reference" "R195"
			(at 0 0 0)
			(layer "F.SilkS")
			(hide yes)
			(effects
				(font
					(size 1.27 1.27)
				)
			)
		)
		(property "Value" "130R3F-GP"
			(at -0.0254 -2.5146 0)
			(unlocked yes)
			(layer "F.Fab")
			(hide yes)
			(effects
				(font
					(size 1.016 1.016)
					(thickness 0.1524)
				)
			)
		)
		(property "Device Type" "R603H22"
			(at -0.0254 -4.0386 0)
			(unlocked yes)
			(layer "F.Fab")
			(hide yes)
			(effects
				(font
					(size 1.016 1.016)
					(thickness 0.1524)
				)
			)
		)
		(duplicate_pad_numbers_are_jumpers no)
		(fp_line
			(start -0.4826 0)
			(end -0.2032 0)
			(stroke
				(width 0.2032)
				(type default)
			)
			(layer "F.SilkS")
		)
		(fp_line
			(start 0.2032 0)
			(end 0.4826 0)
			(stroke
				(width 0.2032)
				(type default)
			)
			(layer "F.SilkS")
		)
		(fp_rect
			(start -0.5842 1.3335)
			(end 0.5842 -1.3335)
			(stroke
				(width 0)
				(type default)
			)
			(fill no)
			(layer "F.CrtYd")
		)
		(fp_rect
			(start -0.5842 1.3335)
			(end 0.5842 -1.3335)
			(stroke
				(width 0)
				(type default)
			)
			(fill no)
			(layer "F.Fab")
		)
		(pad "1" smd custom
			(at 0 -0.762)
			(size 0.2159 0.2159)
			(layers "F.Cu" "F.Mask" "F.Paste")
			(net "P5V_A_1")
			(options
				(clearance outline)
				(anchor circle)
			)
			(primitives
				(gr_poly
					(pts
						(arc
							(start -0.3302 -0.4318)
							(mid -0.402042 -0.402042)
							(end -0.4318 -0.3302)
						)
						(arc
							(start -0.4318 0.3302)
							(mid -0.402042 0.402042)
							(end -0.3302 0.4318)
						)
						(arc
							(start 0.3302 0.4318)
							(mid 0.402042 0.402042)
							(end 0.4318 0.3302)
						)
						(arc
							(start 0.4318 -0.3302)
							(mid 0.402042 -0.402042)
							(end 0.3302 -0.4318)
						)
					)
					(width 0)
					(fill yes)
				)
			)
		)
		(pad "2" smd custom
			(at 0 0.762)
			(size 0.2159 0.2159)
			(layers "F.Cu" "F.Mask" "F.Paste")
			(net "FLT_HDD0")
			(options
				(clearance outline)
				(anchor circle)
			)
			(primitives
				(gr_poly
					(pts
						(arc
							(start -0.3302 -0.4318)
							(mid -0.402042 -0.402042)
							(end -0.4318 -0.3302)
						)
						(arc
							(start -0.4318 0.3302)
							(mid -0.402042 0.402042)
							(end -0.3302 0.4318)
						)
						(arc
							(start 0.3302 0.4318)
							(mid 0.402042 0.402042)
							(end 0.4318 0.3302)
						)
						(arc
							(start 0.4318 -0.3302)
							(mid 0.402042 -0.402042)
							(end 0.3302 -0.4318)
						)
					)
					(width 0)
					(fill yes)
				)
			)
		)
	)
	(footprint ""
		(layer "F.Cu")
		(at 433.359052 -172.851318 90)
		(property "Reference" "C322"
			(at 0 0 90)
			(layer "F.SilkS")
			(hide yes)
			(effects
				(font
					(size 1.27 1.27)
				)
			)
		)
		(property "Value" "SCD033U25V2KX-GP"
			(at 1.1811 -2.7051 90)
			(unlocked yes)
			(layer "F.Fab")
			(hide yes)
			(effects
				(font
					(size 1.016 1.016)
					(thickness 0.1524)
				)
			)
		)
		(property "Device Type" "C402H22"
			(at 1.1811 -4.2291 90)
			(unlocked yes)
			(layer "F.Fab")
			(hide yes)
			(effects
				(font
					(size 1.016 1.016)
					(thickness 0.1524)
				)
			)
		)
		(duplicate_pad_numbers_are_jumpers no)
		(fp_rect
			(start -0.4318 0.9525)
			(end 0.4318 -0.9525)
			(stroke
				(width 0)
				(type default)
			)
			(fill no)
			(layer "F.CrtYd")
		)
		(fp_rect
			(start -0.4318 0.9525)
			(end 0.4318 -0.9525)
			(stroke
				(width 0)
				(type default)
			)
			(fill no)
			(layer "F.Fab")
		)
		(pad "1" smd custom
			(at 0 -0.4445 90)
			(size 0.1524 0.1524)
			(layers "F.Cu" "F.Mask" "F.Paste")
			(net "P12V_A")
			(options
				(clearance outline)
				(anchor circle)
			)
			(primitives
				(gr_poly
					(pts
						(arc
							(start 0.3048 -0.2032)
							(mid 0.275042 -0.275042)
							(end 0.2032 -0.3048)
						)
						(arc
							(start -0.2032 -0.3048)
							(mid -0.275042 -0.275042)
							(end -0.3048 -0.2032)
						)
						(arc
							(start -0.3048 0.2032)
							(mid -0.275042 0.275042)
							(end -0.2032 0.3048)
						)
						(arc
							(start 0.2032 0.3048)
							(mid 0.275042 0.275042)
							(end 0.3048 0.2032)
						)
					)
					(width 0)
					(fill yes)
				)
			)
		)
		(pad "2" smd custom
			(at 0 0.4445 90)
			(size 0.1524 0.1524)
			(layers "F.Cu" "F.Mask" "F.Paste")
			(net "SW_HDD_N21")
			(options
				(clearance outline)
				(anchor circle)
			)
			(primitives
				(gr_poly
					(pts
						(arc
							(start 0.3048 -0.2032)
							(mid 0.275042 -0.275042)
							(end 0.2032 -0.3048)
						)
						(arc
							(start -0.2032 -0.3048)
							(mid -0.275042 -0.275042)
							(end -0.3048 -0.2032)
						)
						(arc
							(start -0.3048 0.2032)
							(mid -0.275042 0.275042)
							(end -0.2032 0.3048)
						)
						(arc
							(start 0.2032 0.3048)
							(mid 0.275042 0.275042)
							(end 0.3048 0.2032)
						)
					)
					(width 0)
					(fill yes)
				)
			)
		)
	)
	(footprint ""
		(layer "F.Cu")
		(at 280.549858 -414.221168)
		(property "Reference" ""
			(at 0 0 0)
			(layer "F.SilkS")
			(hide yes)
			(effects
				(font
					(size 1.27 1.27)
				)
			)
		)
		(property "Value" "*"
			(at -5.3594 -1.1811 0)
			(unlocked yes)
			(layer "F.Fab")
			(hide yes)
			(effects
				(font
					(size 1.016 1.016)
					(thickness 0.1524)
				)
			)
		)
		(duplicate_pad_numbers_are_jumpers no)
		(fp_poly
			(pts
				(arc
					(start 4.064 0)
					(mid -4.064 0)
					(end 4.064 0)
				)
			)
			(stroke
				(width 0)
				(type default)
			)
			(fill no)
			(layer "B.CrtYd")
		)
		(fp_poly
			(pts
				(arc
					(start 4.064 0)
					(mid -4.064 0)
					(end 4.064 0)
				)
			)
			(stroke
				(width 0)
				(type default)
			)
			(fill no)
			(layer "F.CrtYd")
		)
		(fp_poly
			(pts
				(arc
					(start 4.064 0)
					(mid -4.064 0)
					(end 4.064 0)
				)
			)
			(stroke
				(width 0)
				(type default)
			)
			(fill no)
			(layer "B.Fab")
		)
		(fp_poly
			(pts
				(arc
					(start 4.064 0)
					(mid -4.064 0)
					(end 4.064 0)
				)
			)
			(stroke
				(width 0)
				(type default)
			)
			(fill no)
			(layer "F.Fab")
		)
		(pad "1" thru_hole circle
			(at 0 0)
			(size 7.5184 7.5184)
			(drill 3.5052)
			(layers "*.Cu" "*.Mask")
			(remove_unused_layers no)
			(net "Net_62")
			(clearance -1.4986)
			(thermal_gap 0.3048)
			(padstack
				(mode front_inner_back)
				(layer "Inner"
					(shape circle)
					(size 3.9116 3.9116)
					(clearance 0.3048)
				)
				(layer "B.Cu"
					(shape circle)
					(size 7.5184 7.5184)
					(clearance -1.4986)
				)
			)
		)
	)
	(footprint ""
		(layer "F.Cu")
		(at 118.585996 -186.287918)
		(property "Reference" "C241"
			(at 0 0 0)
			(layer "F.SilkS")
			(hide yes)
			(effects
				(font
					(size 1.27 1.27)
				)
			)
		)
		(property "Value" "SC4D7U25V5KX-1-GP"
			(at -0.0762 -6.1214 0)
			(unlocked yes)
			(layer "F.Fab")
			(hide yes)
			(effects
				(font
					(size 1.016 1.016)
					(thickness 0.1524)
				)
			)
		)
		(property "Device Type" "C805H58"
			(at -0.0762 -8.1534 0)
			(unlocked yes)
			(layer "F.Fab")
			(hide yes)
			(effects
				(font
					(size 1.016 1.016)
					(thickness 0.1524)
				)
			)
		)
		(duplicate_pad_numbers_are_jumpers no)
		(fp_line
			(start 0.635 0)
			(end -0.635 0)
			(stroke
				(width 0.508)
				(type default)
			)
			(layer "F.SilkS")
		)
		(fp_rect
			(start -0.9652 1.778)
			(end 0.9652 -1.778)
			(stroke
				(width 0)
				(type default)
			)
			(fill no)
			(layer "F.CrtYd")
		)
		(fp_poly
			(pts
				(xy -0.9652 -1.778) (xy 0.9652 -1.778) (xy 0.9652 1.778) (xy -0.9652 1.778)
			)
			(stroke
				(width 0)
				(type default)
			)
			(fill no)
			(layer "F.Fab")
		)
		(pad "1" smd rect
			(at 0 -0.9652)
			(size 1.397 1.143)
			(layers "F.Cu" "F.Mask" "F.Paste")
			(net "P12V_HDD15")
		)
		(pad "2" smd rect
			(at 0 0.9652)
			(size 1.397 1.143)
			(layers "F.Cu" "F.Mask" "F.Paste")
			(net "GND")
		)
	)
	(footprint ""
		(layer "F.Cu")
		(at 479.384614 -43.660568 -90)
		(property "Reference" "C494"
			(at 0 0 270)
			(layer "F.SilkS")
			(hide yes)
			(effects
				(font
					(size 1.27 1.27)
				)
			)
		)
		(property "Value" "SCD01U16V1KX-GP"
			(at -2.8321 -1.7399 270)
			(unlocked yes)
			(layer "F.Fab")
			(hide yes)
			(effects
				(font
					(size 1.016 1.016)
					(thickness 0.1524)
				)
			)
		)
		(property "Device Type" "C0201H13"
			(at -2.8321 -3.2639 270)
			(unlocked yes)
			(layer "F.Fab")
			(hide yes)
			(effects
				(font
					(size 1.016 1.016)
					(thickness 0.1524)
				)
			)
		)
		(duplicate_pad_numbers_are_jumpers no)
		(fp_rect
			(start -0.2794 0.6477)
			(end 0.2794 -0.6477)
			(stroke
				(width 0)
				(type default)
			)
			(fill no)
			(layer "F.CrtYd")
		)
		(fp_rect
			(start -0.2794 0.6477)
			(end 0.2794 -0.6477)
			(stroke
				(width 0)
				(type default)
			)
			(fill no)
			(layer "F.Fab")
		)
		(pad "1" smd custom
			(at 0 -0.2794 270)
			(size 0.0762 0.0762)
			(layers "F.Cu" "F.Mask" "F.Paste")
			(net "SAS_HDD_RX_P35")
			(options
				(clearance outline)
				(anchor circle)
			)
			(primitives
				(gr_poly
					(pts
						(arc
							(start 0.1524 -0.127)
							(mid 0.137521 -0.162921)
							(end 0.1016 -0.1778)
						)
						(arc
							(start -0.1016 -0.1778)
							(mid -0.137521 -0.162921)
							(end -0.1524 -0.127)
						)
						(arc
							(start -0.1524 0.127)
							(mid -0.137521 0.162921)
							(end -0.1016 0.1778)
						)
						(arc
							(start 0.1016 0.1778)
							(mid 0.137521 0.162921)
							(end 0.1524 0.127)
						)
					)
					(width 0)
					(fill yes)
				)
			)
		)
		(pad "2" smd custom
			(at 0 0.2794 270)
			(size 0.0762 0.0762)
			(layers "F.Cu" "F.Mask" "F.Paste")
			(net "PHY_SCC_A_TO_DRV_A_35_DP")
			(options
				(clearance outline)
				(anchor circle)
			)
			(primitives
				(gr_poly
					(pts
						(arc
							(start 0.1524 -0.127)
							(mid 0.137521 -0.162921)
							(end 0.1016 -0.1778)
						)
						(arc
							(start -0.1016 -0.1778)
							(mid -0.137521 -0.162921)
							(end -0.1524 -0.127)
						)
						(arc
							(start -0.1524 0.127)
							(mid -0.137521 0.162921)
							(end -0.1016 0.1778)
						)
						(arc
							(start 0.1016 0.1778)
							(mid 0.137521 0.162921)
							(end 0.1524 0.127)
						)
					)
					(width 0)
					(fill yes)
				)
			)
		)
	)
	(footprint ""
		(layer "F.Cu")
		(at 87.340948 -304.462942 180)
		(property "Reference" "C73"
			(at 0 0 180)
			(layer "F.SilkS")
			(hide yes)
			(effects
				(font
					(size 1.27 1.27)
				)
			)
		)
		(property "Value" "SC1U25V3KX-GP"
			(at 0 -2.8194 180)
			(unlocked yes)
			(layer "F.Fab")
			(hide yes)
			(effects
				(font
					(size 1.016 1.016)
					(thickness 0.1524)
				)
			)
		)
		(property "Device Type" "C603H36"
			(at 0 -4.3434 180)
			(unlocked yes)
			(layer "F.Fab")
			(hide yes)
			(effects
				(font
					(size 1.016 1.016)
					(thickness 0.1524)
				)
			)
		)
		(duplicate_pad_numbers_are_jumpers no)
		(fp_line
			(start 0.508 0)
			(end -0.508 0)
			(stroke
				(width 0.2032)
				(type default)
			)
			(layer "F.SilkS")
		)
		(fp_rect
			(start -0.5842 1.3335)
			(end 0.5842 -1.3335)
			(stroke
				(width 0)
				(type default)
			)
			(fill no)
			(layer "F.CrtYd")
		)
		(fp_rect
			(start -0.5842 1.3335)
			(end 0.5842 -1.3335)
			(stroke
				(width 0)
				(type default)
			)
			(fill no)
			(layer "F.Fab")
		)
		(pad "1" smd custom
			(at 0 -0.762 180)
			(size 0.2159 0.2159)
			(layers "F.Cu" "F.Mask" "F.Paste")
			(net "P12V_HDD2")
			(options
				(clearance outline)
				(anchor circle)
			)
			(primitives
				(gr_poly
					(pts
						(arc
							(start -0.3302 -0.4318)
							(mid -0.402042 -0.402042)
							(end -0.4318 -0.3302)
						)
						(arc
							(start -0.4318 0.3302)
							(mid -0.402042 0.402042)
							(end -0.3302 0.4318)
						)
						(arc
							(start 0.3302 0.4318)
							(mid 0.402042 0.402042)
							(end 0.4318 0.3302)
						)
						(arc
							(start 0.4318 -0.3302)
							(mid 0.402042 -0.402042)
							(end 0.3302 -0.4318)
						)
					)
					(width 0)
					(fill yes)
				)
			)
		)
		(pad "2" smd custom
			(at 0 0.762 180)
			(size 0.2159 0.2159)
			(layers "F.Cu" "F.Mask" "F.Paste")
			(net "GND")
			(options
				(clearance outline)
				(anchor circle)
			)
			(primitives
				(gr_poly
					(pts
						(arc
							(start -0.3302 -0.4318)
							(mid -0.402042 -0.402042)
							(end -0.4318 -0.3302)
						)
						(arc
							(start -0.4318 0.3302)
							(mid -0.402042 0.402042)
							(end -0.3302 0.4318)
						)
						(arc
							(start 0.3302 0.4318)
							(mid 0.402042 0.402042)
							(end 0.4318 0.3302)
						)
						(arc
							(start 0.4318 -0.3302)
							(mid 0.402042 -0.402042)
							(end 0.3302 -0.4318)
						)
					)
					(width 0)
					(fill yes)
				)
			)
		)
	)
	(footprint ""
		(layer "F.Cu")
		(at 51.599846 -291.000942 -90)
		(property "Reference" "C54"
			(at 0 0 270)
			(layer "F.SilkS")
			(hide yes)
			(effects
				(font
					(size 1.27 1.27)
				)
			)
		)
		(property "Value" "SC10U16V6KX-2GP"
			(at -0.0762 -5.1308 270)
			(unlocked yes)
			(layer "F.Fab")
			(hide yes)
			(effects
				(font
					(size 1.016 1.016)
					(thickness 0.1524)
				)
			)
		)
		(property "Device Type" "C1206H71"
			(at -0.127 -6.6548 270)
			(unlocked yes)
			(layer "F.Fab")
			(hide yes)
			(effects
				(font
					(size 1.016 1.016)
					(thickness 0.1524)
				)
			)
		)
		(duplicate_pad_numbers_are_jumpers no)
		(fp_line
			(start -1.016 2.2352)
			(end -1.016 0.8382)
			(stroke
				(width 0.1524)
				(type default)
			)
			(layer "F.SilkS")
		)
		(fp_line
			(start 1.016 2.2352)
			(end -1.016 2.2352)
			(stroke
				(width 0.1524)
				(type default)
			)
			(layer "F.SilkS")
		)
		(fp_line
			(start 1.016 0.8382)
			(end 1.016 2.2352)
			(stroke
				(width 0.1524)
				(type default)
			)
			(layer "F.SilkS")
		)
		(fp_line
			(start -1.016 -0.8382)
			(end -1.016 -2.2352)
			(stroke
				(width 0.1524)
				(type default)
			)
			(layer "F.SilkS")
		)
		(fp_line
			(start -1.016 -2.2352)
			(end 1.016 -2.2352)
			(stroke
				(width 0.1524)
				(type default)
			)
			(layer "F.SilkS")
		)
		(fp_line
			(start 1.016 -2.2352)
			(end 1.016 -0.8382)
			(stroke
				(width 0.1524)
				(type default)
			)
			(layer "F.SilkS")
		)
		(fp_rect
			(start -1.0922 2.3114)
			(end 1.0922 -2.3114)
			(stroke
				(width 0)
				(type default)
			)
			(fill no)
			(layer "F.CrtYd")
		)
		(fp_poly
			(pts
				(xy 1.0922 -2.3114) (xy 1.0922 2.3114) (xy -1.0922 2.3114) (xy -1.0922 -2.3114)
			)
			(stroke
				(width 0)
				(type default)
			)
			(fill no)
			(layer "F.Fab")
		)
		(pad "1" smd rect
			(at 0 -1.397 270)
			(size 1.651 1.27)
			(layers "F.Cu" "F.Mask" "F.Paste")
			(net "P5V_HDD1")
		)
		(pad "2" smd rect
			(at 0 1.397 270)
			(size 1.651 1.27)
			(layers "F.Cu" "F.Mask" "F.Paste")
			(net "GND")
		)
	)
	(footprint ""
		(layer "F.Cu")
		(at 143.3449 -242.25377)
		(property "Reference" "R222"
			(at 0 0 0)
			(layer "F.SilkS")
			(hide yes)
			(effects
				(font
					(size 1.27 1.27)
				)
			)
		)
		(property "Value" "130R3F-GP"
			(at -0.0254 -2.5146 0)
			(unlocked yes)
			(layer "F.Fab")
			(hide yes)
			(effects
				(font
					(size 1.016 1.016)
					(thickness 0.1524)
				)
			)
		)
		(property "Device Type" "R603H22"
			(at -0.0254 -4.0386 0)
			(unlocked yes)
			(layer "F.Fab")
			(hide yes)
			(effects
				(font
					(size 1.016 1.016)
					(thickness 0.1524)
				)
			)
		)
		(duplicate_pad_numbers_are_jumpers no)
		(fp_line
			(start -0.4826 0)
			(end -0.2032 0)
			(stroke
				(width 0.2032)
				(type default)
			)
			(layer "F.SilkS")
		)
		(fp_line
			(start 0.2032 0)
			(end 0.4826 0)
			(stroke
				(width 0.2032)
				(type default)
			)
			(layer "F.SilkS")
		)
		(fp_rect
			(start -0.5842 1.3335)
			(end 0.5842 -1.3335)
			(stroke
				(width 0)
				(type default)
			)
			(fill no)
			(layer "F.CrtYd")
		)
		(fp_rect
			(start -0.5842 1.3335)
			(end 0.5842 -1.3335)
			(stroke
				(width 0)
				(type default)
			)
			(fill no)
			(layer "F.Fab")
		)
		(pad "1" smd custom
			(at 0 -0.762)
			(size 0.2159 0.2159)
			(layers "F.Cu" "F.Mask" "F.Paste")
			(net "P5V_A_1")
			(options
				(clearance outline)
				(anchor circle)
			)
			(primitives
				(gr_poly
					(pts
						(arc
							(start -0.3302 -0.4318)
							(mid -0.402042 -0.402042)
							(end -0.4318 -0.3302)
						)
						(arc
							(start -0.4318 0.3302)
							(mid -0.402042 0.402042)
							(end -0.3302 0.4318)
						)
						(arc
							(start 0.3302 0.4318)
							(mid 0.402042 0.402042)
							(end 0.4318 0.3302)
						)
						(arc
							(start 0.4318 -0.3302)
							(mid 0.402042 -0.402042)
							(end 0.3302 -0.4318)
						)
					)
					(width 0)
					(fill yes)
				)
			)
		)
		(pad "2" smd custom
			(at 0 0.762)
			(size 0.2159 0.2159)
			(layers "F.Cu" "F.Mask" "F.Paste")
			(net "FLT_HDD4")
			(options
				(clearance outline)
				(anchor circle)
			)
			(primitives
				(gr_poly
					(pts
						(arc
							(start -0.3302 -0.4318)
							(mid -0.402042 -0.402042)
							(end -0.4318 -0.3302)
						)
						(arc
							(start -0.4318 0.3302)
							(mid -0.402042 0.402042)
							(end -0.3302 0.4318)
						)
						(arc
							(start 0.3302 0.4318)
							(mid 0.402042 0.402042)
							(end 0.4318 0.3302)
						)
						(arc
							(start 0.4318 -0.3302)
							(mid 0.402042 -0.402042)
							(end 0.3302 -0.4318)
						)
					)
					(width 0)
					(fill yes)
				)
			)
		)
	)
	(footprint ""
		(layer "F.Cu")
		(at 130.447796 -176.127918 90)
		(property "Reference" "C237"
			(at 0 0 90)
			(layer "F.SilkS")
			(hide yes)
			(effects
				(font
					(size 1.27 1.27)
				)
			)
		)
		(property "Value" "SCD01U50V2KX-1GP"
			(at 1.1811 -2.7051 90)
			(unlocked yes)
			(layer "F.Fab")
			(hide yes)
			(effects
				(font
					(size 1.016 1.016)
					(thickness 0.1524)
				)
			)
		)
		(property "Device Type" "C402H22"
			(at 1.1811 -4.2291 90)
			(unlocked yes)
			(layer "F.Fab")
			(hide yes)
			(effects
				(font
					(size 1.016 1.016)
					(thickness 0.1524)
				)
			)
		)
		(duplicate_pad_numbers_are_jumpers no)
		(fp_rect
			(start -0.4318 0.9525)
			(end 0.4318 -0.9525)
			(stroke
				(width 0)
				(type default)
			)
			(fill no)
			(layer "F.CrtYd")
		)
		(fp_rect
			(start -0.4318 0.9525)
			(end 0.4318 -0.9525)
			(stroke
				(width 0)
				(type default)
			)
			(fill no)
			(layer "F.Fab")
		)
		(pad "1" smd custom
			(at 0 -0.4445 90)
			(size 0.1524 0.1524)
			(layers "F.Cu" "F.Mask" "F.Paste")
			(net "HDD_PRSNT_15")
			(options
				(clearance outline)
				(anchor circle)
			)
			(primitives
				(gr_poly
					(pts
						(arc
							(start 0.3048 -0.2032)
							(mid 0.275042 -0.275042)
							(end 0.2032 -0.3048)
						)
						(arc
							(start -0.2032 -0.3048)
							(mid -0.275042 -0.275042)
							(end -0.3048 -0.2032)
						)
						(arc
							(start -0.3048 0.2032)
							(mid -0.275042 0.275042)
							(end -0.2032 0.3048)
						)
						(arc
							(start 0.2032 0.3048)
							(mid 0.275042 0.275042)
							(end 0.3048 0.2032)
						)
					)
					(width 0)
					(fill yes)
				)
			)
		)
		(pad "2" smd custom
			(at 0 0.4445 90)
			(size 0.1524 0.1524)
			(layers "F.Cu" "F.Mask" "F.Paste")
			(net "GND")
			(options
				(clearance outline)
				(anchor circle)
			)
			(primitives
				(gr_poly
					(pts
						(arc
							(start 0.3048 -0.2032)
							(mid 0.275042 -0.275042)
							(end 0.2032 -0.3048)
						)
						(arc
							(start -0.2032 -0.3048)
							(mid -0.275042 -0.275042)
							(end -0.3048 -0.2032)
						)
						(arc
							(start -0.3048 0.2032)
							(mid -0.275042 0.275042)
							(end -0.2032 0.3048)
						)
						(arc
							(start 0.2032 0.3048)
							(mid 0.275042 0.275042)
							(end 0.3048 0.2032)
						)
					)
					(width 0)
					(fill yes)
				)
			)
		)
	)
	(footprint ""
		(layer "F.Cu")
		(at 172.466 -64.683894 -90)
		(property "Reference" "C422"
			(at 0 0 270)
			(layer "F.SilkS")
			(hide yes)
			(effects
				(font
					(size 1.27 1.27)
				)
			)
		)
		(property "Value" "SC4D7U25V5KX-1-GP"
			(at -0.0762 -6.1214 270)
			(unlocked yes)
			(layer "F.Fab")
			(hide yes)
			(effects
				(font
					(size 1.016 1.016)
					(thickness 0.1524)
				)
			)
		)
		(property "Device Type" "C805H58"
			(at -0.0762 -8.1534 270)
			(unlocked yes)
			(layer "F.Fab")
			(hide yes)
			(effects
				(font
					(size 1.016 1.016)
					(thickness 0.1524)
				)
			)
		)
		(duplicate_pad_numbers_are_jumpers no)
		(fp_line
			(start 0.635 0)
			(end -0.635 0)
			(stroke
				(width 0.508)
				(type default)
			)
			(layer "F.SilkS")
		)
		(fp_rect
			(start -0.9652 1.778)
			(end 0.9652 -1.778)
			(stroke
				(width 0)
				(type default)
			)
			(fill no)
			(layer "F.CrtYd")
		)
		(fp_poly
			(pts
				(xy -0.9652 -1.778) (xy 0.9652 -1.778) (xy 0.9652 1.778) (xy -0.9652 1.778)
			)
			(stroke
				(width 0)
				(type default)
			)
			(fill no)
			(layer "F.Fab")
		)
		(pad "1" smd rect
			(at 0 -0.9652 270)
			(size 1.397 1.143)
			(layers "F.Cu" "F.Mask" "F.Paste")
			(net "P12V_HDD29")
		)
		(pad "2" smd rect
			(at 0 0.9652 270)
			(size 1.397 1.143)
			(layers "F.Cu" "F.Mask" "F.Paste")
			(net "GND")
		)
	)
	(footprint ""
		(layer "F.Cu")
		(at 312.595768 -57.18175 -90)
		(property "Reference" "C82"
			(at 0 0 270)
			(layer "F.SilkS")
			(hide yes)
			(effects
				(font
					(size 1.27 1.27)
				)
			)
		)
		(property "Value" "SCD1U16V2KX-3GP"
			(at 1.1811 -2.7051 270)
			(unlocked yes)
			(layer "F.Fab")
			(hide yes)
			(effects
				(font
					(size 1.016 1.016)
					(thickness 0.1524)
				)
			)
		)
		(property "Device Type" "C402H22"
			(at 1.1811 -4.2291 270)
			(unlocked yes)
			(layer "F.Fab")
			(hide yes)
			(effects
				(font
					(size 1.016 1.016)
					(thickness 0.1524)
				)
			)
		)
		(duplicate_pad_numbers_are_jumpers no)
		(fp_rect
			(start -0.4318 0.9525)
			(end 0.4318 -0.9525)
			(stroke
				(width 0)
				(type default)
			)
			(fill no)
			(layer "F.CrtYd")
		)
		(fp_rect
			(start -0.4318 0.9525)
			(end 0.4318 -0.9525)
			(stroke
				(width 0)
				(type default)
			)
			(fill no)
			(layer "F.Fab")
		)
		(pad "1" smd custom
			(at 0 -0.4445 270)
			(size 0.1524 0.1524)
			(layers "F.Cu" "F.Mask" "F.Paste")
			(net "P3V3_STBY_B")
			(options
				(clearance outline)
				(anchor circle)
			)
			(primitives
				(gr_poly
					(pts
						(arc
							(start 0.3048 -0.2032)
							(mid 0.275042 -0.275042)
							(end 0.2032 -0.3048)
						)
						(arc
							(start -0.2032 -0.3048)
							(mid -0.275042 -0.275042)
							(end -0.3048 -0.2032)
						)
						(arc
							(start -0.3048 0.2032)
							(mid -0.275042 0.275042)
							(end -0.2032 0.3048)
						)
						(arc
							(start 0.2032 0.3048)
							(mid 0.275042 0.275042)
							(end 0.3048 0.2032)
						)
					)
					(width 0)
					(fill yes)
				)
			)
		)
		(pad "2" smd custom
			(at 0 0.4445 270)
			(size 0.1524 0.1524)
			(layers "F.Cu" "F.Mask" "F.Paste")
			(net "GND")
			(options
				(clearance outline)
				(anchor circle)
			)
			(primitives
				(gr_poly
					(pts
						(arc
							(start 0.3048 -0.2032)
							(mid 0.275042 -0.275042)
							(end 0.2032 -0.3048)
						)
						(arc
							(start -0.2032 -0.3048)
							(mid -0.275042 -0.275042)
							(end -0.3048 -0.2032)
						)
						(arc
							(start -0.3048 0.2032)
							(mid -0.275042 0.275042)
							(end -0.2032 0.3048)
						)
						(arc
							(start 0.2032 0.3048)
							(mid 0.275042 0.275042)
							(end 0.3048 0.2032)
						)
					)
					(width 0)
					(fill yes)
				)
			)
		)
	)
	(footprint ""
		(layer "F.Cu")
		(at 111.524796 -161.649918 180)
		(property "Reference" "D15"
			(at 0 0 180)
			(layer "F.SilkS")
			(hide yes)
			(effects
				(font
					(size 1.27 1.27)
				)
			)
		)
		(property "Value" "RB551V30-GP"
			(at 0 -6.7818 180)
			(unlocked yes)
			(layer "F.Fab")
			(hide yes)
			(effects
				(font
					(size 1.016 1.016)
					(thickness 0.1524)
				)
			)
		)
		(property "Device Type" "SOD323AKH38"
			(at 0 -8.6868 180)
			(unlocked yes)
			(layer "F.Fab")
			(hide yes)
			(effects
				(font
					(size 1.016 1.016)
					(thickness 0.1524)
				)
			)
		)
		(duplicate_pad_numbers_are_jumpers no)
		(fp_line
			(start 0.889 2.159)
			(end -0.889 2.159)
			(stroke
				(width 0.1524)
				(type default)
			)
			(layer "F.SilkS")
		)
		(fp_line
			(start 0.889 -1.9304)
			(end 0.889 2.159)
			(stroke
				(width 0.1524)
				(type default)
			)
			(layer "F.SilkS")
		)
		(fp_line
			(start 0.762 2.0574)
			(end -0.762 2.0574)
			(stroke
				(width 0.508)
				(type default)
			)
			(layer "F.SilkS")
		)
		(fp_line
			(start -0.889 2.159)
			(end -0.889 -1.9304)
			(stroke
				(width 0.1524)
				(type default)
			)
			(layer "F.SilkS")
		)
		(fp_line
			(start -0.889 -1.9304)
			(end 0.889 -1.9304)
			(stroke
				(width 0.1524)
				(type default)
			)
			(layer "F.SilkS")
		)
		(fp_rect
			(start -1.016 2.3114)
			(end 1.016 -2.0066)
			(stroke
				(width 0)
				(type default)
			)
			(fill no)
			(layer "F.CrtYd")
		)
		(fp_poly
			(pts
				(xy -1.016 -2.0066) (xy 1.016 -2.0066) (xy 1.016 2.3114) (xy -1.016 2.3114)
			)
			(stroke
				(width 0)
				(type default)
			)
			(fill no)
			(layer "F.Fab")
		)
		(pad "A" smd rect
			(at 0 -1.143 180)
			(size 0.5588 1.016)
			(layers "F.Cu" "F.Mask" "F.Paste")
			(net "SW_HDD_R15")
		)
		(pad "K" smd rect
			(at 0 1.143 180)
			(size 0.5588 1.016)
			(layers "F.Cu" "F.Mask" "F.Paste")
			(net "SW_HDD_N15")
		)
	)
	(footprint ""
		(layer "F.Cu")
		(at 275.515578 -396.682722 90)
		(property "Reference" "C593"
			(at 0 0 90)
			(layer "F.SilkS")
			(hide yes)
			(effects
				(font
					(size 1.27 1.27)
				)
			)
		)
		(property "Value" "SCD1U25V2KX-2-GP"
			(at 1.1811 -2.7051 90)
			(unlocked yes)
			(layer "F.Fab")
			(hide yes)
			(effects
				(font
					(size 1.016 1.016)
					(thickness 0.1524)
				)
			)
		)
		(property "Device Type" "C402H22"
			(at 1.1811 -4.2291 90)
			(unlocked yes)
			(layer "F.Fab")
			(hide yes)
			(effects
				(font
					(size 1.016 1.016)
					(thickness 0.1524)
				)
			)
		)
		(duplicate_pad_numbers_are_jumpers no)
		(fp_rect
			(start -0.4318 0.9525)
			(end 0.4318 -0.9525)
			(stroke
				(width 0)
				(type default)
			)
			(fill no)
			(layer "F.CrtYd")
		)
		(fp_rect
			(start -0.4318 0.9525)
			(end 0.4318 -0.9525)
			(stroke
				(width 0)
				(type default)
			)
			(fill no)
			(layer "F.Fab")
		)
		(pad "1" smd custom
			(at 0 -0.4445 90)
			(size 0.1524 0.1524)
			(layers "F.Cu" "F.Mask" "F.Paste")
			(net "P12V_IN")
			(options
				(clearance outline)
				(anchor circle)
			)
			(primitives
				(gr_poly
					(pts
						(arc
							(start 0.3048 -0.2032)
							(mid 0.275042 -0.275042)
							(end 0.2032 -0.3048)
						)
						(arc
							(start -0.2032 -0.3048)
							(mid -0.275042 -0.275042)
							(end -0.3048 -0.2032)
						)
						(arc
							(start -0.3048 0.2032)
							(mid -0.275042 0.275042)
							(end -0.2032 0.3048)
						)
						(arc
							(start 0.2032 0.3048)
							(mid 0.275042 0.275042)
							(end 0.3048 0.2032)
						)
					)
					(width 0)
					(fill yes)
				)
			)
		)
		(pad "2" smd custom
			(at 0 0.4445 90)
			(size 0.1524 0.1524)
			(layers "F.Cu" "F.Mask" "F.Paste")
			(net "GND")
			(options
				(clearance outline)
				(anchor circle)
			)
			(primitives
				(gr_poly
					(pts
						(arc
							(start 0.3048 -0.2032)
							(mid 0.275042 -0.275042)
							(end 0.2032 -0.3048)
						)
						(arc
							(start -0.2032 -0.3048)
							(mid -0.275042 -0.275042)
							(end -0.3048 -0.2032)
						)
						(arc
							(start -0.3048 0.2032)
							(mid -0.275042 0.275042)
							(end -0.2032 0.3048)
						)
						(arc
							(start 0.2032 0.3048)
							(mid 0.275042 0.275042)
							(end 0.3048 0.2032)
						)
					)
					(width 0)
					(fill yes)
				)
			)
		)
	)
	(footprint ""
		(layer "F.Cu")
		(at 346.045028 -242.25377)
		(property "Reference" "R243"
			(at 0 0 0)
			(layer "F.SilkS")
			(hide yes)
			(effects
				(font
					(size 1.27 1.27)
				)
			)
		)
		(property "Value" "130R3F-GP"
			(at -0.0254 -2.5146 0)
			(unlocked yes)
			(layer "F.Fab")
			(hide yes)
			(effects
				(font
					(size 1.016 1.016)
					(thickness 0.1524)
				)
			)
		)
		(property "Device Type" "R603H22"
			(at -0.0254 -4.0386 0)
			(unlocked yes)
			(layer "F.Fab")
			(hide yes)
			(effects
				(font
					(size 1.016 1.016)
					(thickness 0.1524)
				)
			)
		)
		(duplicate_pad_numbers_are_jumpers no)
		(fp_line
			(start -0.4826 0)
			(end -0.2032 0)
			(stroke
				(width 0.2032)
				(type default)
			)
			(layer "F.SilkS")
		)
		(fp_line
			(start 0.2032 0)
			(end 0.4826 0)
			(stroke
				(width 0.2032)
				(type default)
			)
			(layer "F.SilkS")
		)
		(fp_rect
			(start -0.5842 1.3335)
			(end 0.5842 -1.3335)
			(stroke
				(width 0)
				(type default)
			)
			(fill no)
			(layer "F.CrtYd")
		)
		(fp_rect
			(start -0.5842 1.3335)
			(end 0.5842 -1.3335)
			(stroke
				(width 0)
				(type default)
			)
			(fill no)
			(layer "F.Fab")
		)
		(pad "1" smd custom
			(at 0 -0.762)
			(size 0.2159 0.2159)
			(layers "F.Cu" "F.Mask" "F.Paste")
			(net "P5V_A_3")
			(options
				(clearance outline)
				(anchor circle)
			)
			(primitives
				(gr_poly
					(pts
						(arc
							(start -0.3302 -0.4318)
							(mid -0.402042 -0.402042)
							(end -0.4318 -0.3302)
						)
						(arc
							(start -0.4318 0.3302)
							(mid -0.402042 0.402042)
							(end -0.3302 0.4318)
						)
						(arc
							(start 0.3302 0.4318)
							(mid 0.402042 0.402042)
							(end 0.4318 0.3302)
						)
						(arc
							(start 0.4318 -0.3302)
							(mid 0.402042 -0.402042)
							(end 0.3302 -0.4318)
						)
					)
					(width 0)
					(fill yes)
				)
			)
		)
		(pad "2" smd custom
			(at 0 0.762)
			(size 0.2159 0.2159)
			(layers "F.Cu" "F.Mask" "F.Paste")
			(net "FLT_HDD7")
			(options
				(clearance outline)
				(anchor circle)
			)
			(primitives
				(gr_poly
					(pts
						(arc
							(start -0.3302 -0.4318)
							(mid -0.402042 -0.402042)
							(end -0.4318 -0.3302)
						)
						(arc
							(start -0.4318 0.3302)
							(mid -0.402042 0.402042)
							(end -0.3302 0.4318)
						)
						(arc
							(start 0.3302 0.4318)
							(mid 0.402042 0.402042)
							(end 0.4318 0.3302)
						)
						(arc
							(start 0.4318 -0.3302)
							(mid 0.402042 -0.402042)
							(end 0.3302 -0.4318)
						)
					)
					(width 0)
					(fill yes)
				)
			)
		)
	)
	(footprint ""
		(layer "F.Cu")
		(at 147.390866 -131.656074 180)
		(property "Reference" "R1050"
			(at 0 0 180)
			(layer "F.SilkS")
			(hide yes)
			(effects
				(font
					(size 1.27 1.27)
				)
			)
		)
		(property "Value" "100KR2F-L1-GP"
			(at 0.064008 -3.993896 180)
			(unlocked yes)
			(layer "F.Fab")
			(hide yes)
			(effects
				(font
					(size 1.016 1.016)
					(thickness 0.1524)
				)
			)
		)
		(property "Device Type" "R402H16"
			(at 0.064008 -5.517896 180)
			(unlocked yes)
			(layer "F.Fab")
			(hide yes)
			(effects
				(font
					(size 1.016 1.016)
					(thickness 0.1524)
				)
			)
		)
		(duplicate_pad_numbers_are_jumpers no)
		(fp_line
			(start 0.508 -0.9398)
			(end -0.508 -0.9398)
			(stroke
				(width 0.1524)
				(type default)
			)
			(layer "F.SilkS")
		)
		(fp_line
			(start -0.508 -0.9398)
			(end -0.508 0.9398)
			(stroke
				(width 0.1524)
				(type default)
			)
			(layer "F.SilkS")
		)
		(fp_rect
			(start -0.508 0.9398)
			(end 0.508 -0.9398)
			(stroke
				(width 0)
				(type default)
			)
			(fill no)
			(layer "F.CrtYd")
		)
		(fp_rect
			(start -0.508 0.9398)
			(end 0.508 -0.9398)
			(stroke
				(width 0)
				(type default)
			)
			(fill no)
			(layer "F.Fab")
		)
		(pad "1" smd custom
			(at 0 -0.4445 180)
			(size 0.1397 0.1397)
			(layers "F.Cu" "F.Mask" "F.Paste")
			(net "P12V_A_COMP")
			(options
				(clearance outline)
				(anchor circle)
			)
			(primitives
				(gr_poly
					(pts
						(arc
							(start -0.1778 -0.2794)
							(mid -0.249642 -0.249642)
							(end -0.2794 -0.1778)
						)
						(arc
							(start -0.2794 0.1778)
							(mid -0.249642 0.249642)
							(end -0.1778 0.2794)
						)
						(arc
							(start 0.1778 0.2794)
							(mid 0.249642 0.249642)
							(end 0.2794 0.1778)
						)
						(arc
							(start 0.2794 -0.1778)
							(mid 0.249642 -0.249642)
							(end 0.1778 -0.2794)
						)
					)
					(width 0)
					(fill yes)
				)
			)
		)
		(pad "2" smd custom
			(at 0 0.4445 180)
			(size 0.1397 0.1397)
			(layers "F.Cu" "F.Mask" "F.Paste")
			(net "MB0_P12V_PWGIN_R")
			(options
				(clearance outline)
				(anchor circle)
			)
			(primitives
				(gr_poly
					(pts
						(arc
							(start -0.1778 -0.2794)
							(mid -0.249642 -0.249642)
							(end -0.2794 -0.1778)
						)
						(arc
							(start -0.2794 0.1778)
							(mid -0.249642 0.249642)
							(end -0.1778 0.2794)
						)
						(arc
							(start 0.1778 0.2794)
							(mid 0.249642 0.249642)
							(end 0.2794 0.1778)
						)
						(arc
							(start 0.2794 -0.1778)
							(mid 0.249642 -0.249642)
							(end 0.1778 -0.2794)
						)
					)
					(width 0)
					(fill yes)
				)
			)
		)
	)
	(footprint ""
		(layer "F.Cu")
		(at 32.274002 -254.43815 -90)
		(property "Reference" "R1208"
			(at 0 0 270)
			(layer "F.SilkS")
			(hide yes)
			(effects
				(font
					(size 1.27 1.27)
				)
			)
		)
		(property "Value" "10KR2F-2-GP"
			(at 0.064008 -3.993896 270)
			(unlocked yes)
			(layer "F.Fab")
			(hide yes)
			(effects
				(font
					(size 1.016 1.016)
					(thickness 0.1524)
				)
			)
		)
		(property "Device Type" "R402H16"
			(at 0.064008 -5.517896 270)
			(unlocked yes)
			(layer "F.Fab")
			(hide yes)
			(effects
				(font
					(size 1.016 1.016)
					(thickness 0.1524)
				)
			)
		)
		(duplicate_pad_numbers_are_jumpers no)
		(fp_line
			(start -0.508 -0.9398)
			(end -0.508 0.9398)
			(stroke
				(width 0.1524)
				(type default)
			)
			(layer "F.SilkS")
		)
		(fp_line
			(start 0.508 -0.9398)
			(end -0.508 -0.9398)
			(stroke
				(width 0.1524)
				(type default)
			)
			(layer "F.SilkS")
		)
		(fp_rect
			(start -0.508 0.9398)
			(end 0.508 -0.9398)
			(stroke
				(width 0)
				(type default)
			)
			(fill no)
			(layer "F.CrtYd")
		)
		(fp_rect
			(start -0.508 0.9398)
			(end 0.508 -0.9398)
			(stroke
				(width 0)
				(type default)
			)
			(fill no)
			(layer "F.Fab")
		)
		(pad "1" smd custom
			(at 0 -0.4445 270)
			(size 0.1397 0.1397)
			(layers "F.Cu" "F.Mask" "F.Paste")
			(net "P5V_A_EN_R")
			(options
				(clearance outline)
				(anchor circle)
			)
			(primitives
				(gr_poly
					(pts
						(arc
							(start -0.1778 -0.2794)
							(mid -0.249642 -0.249642)
							(end -0.2794 -0.1778)
						)
						(arc
							(start -0.2794 0.1778)
							(mid -0.249642 0.249642)
							(end -0.1778 0.2794)
						)
						(arc
							(start 0.1778 0.2794)
							(mid 0.249642 0.249642)
							(end 0.2794 0.1778)
						)
						(arc
							(start 0.2794 -0.1778)
							(mid 0.249642 -0.249642)
							(end 0.1778 -0.2794)
						)
					)
					(width 0)
					(fill yes)
				)
			)
		)
		(pad "2" smd custom
			(at 0 0.4445 270)
			(size 0.1397 0.1397)
			(layers "F.Cu" "F.Mask" "F.Paste")
			(net "GND")
			(options
				(clearance outline)
				(anchor circle)
			)
			(primitives
				(gr_poly
					(pts
						(arc
							(start -0.1778 -0.2794)
							(mid -0.249642 -0.249642)
							(end -0.2794 -0.1778)
						)
						(arc
							(start -0.2794 0.1778)
							(mid -0.249642 0.249642)
							(end -0.1778 0.2794)
						)
						(arc
							(start 0.1778 0.2794)
							(mid 0.249642 0.249642)
							(end 0.2794 0.1778)
						)
						(arc
							(start 0.2794 -0.1778)
							(mid 0.249642 -0.249642)
							(end 0.1778 -0.2794)
						)
					)
					(width 0)
					(fill yes)
				)
			)
		)
	)
	(footprint ""
		(layer "F.Cu")
		(at 363.020102 -61.127894 -90)
		(property "Reference" "R842"
			(at 0 0 270)
			(layer "F.SilkS")
			(hide yes)
			(effects
				(font
					(size 1.27 1.27)
				)
			)
		)
		(property "Value" "2R6F-GP"
			(at -0.0508 -4.8514 270)
			(unlocked yes)
			(layer "F.Fab")
			(hide yes)
			(effects
				(font
					(size 1.016 1.016)
					(thickness 0.1524)
				)
			)
		)
		(property "Device Type" "R1206H26"
			(at 0 -6.3754 270)
			(unlocked yes)
			(layer "F.Fab")
			(hide yes)
			(effects
				(font
					(size 1.016 1.016)
					(thickness 0.1524)
				)
			)
		)
		(duplicate_pad_numbers_are_jumpers no)
		(fp_line
			(start -1.016 2.2352)
			(end -1.016 -2.2352)
			(stroke
				(width 0.1524)
				(type default)
			)
			(layer "F.SilkS")
		)
		(fp_line
			(start 1.016 2.2352)
			(end -1.016 2.2352)
			(stroke
				(width 0.1524)
				(type default)
			)
			(layer "F.SilkS")
		)
		(fp_line
			(start -1.016 -2.2352)
			(end 1.016 -2.2352)
			(stroke
				(width 0.1524)
				(type default)
			)
			(layer "F.SilkS")
		)
		(fp_line
			(start 1.016 -2.2352)
			(end 1.016 2.2352)
			(stroke
				(width 0.1524)
				(type default)
			)
			(layer "F.SilkS")
		)
		(fp_rect
			(start -1.0922 2.3114)
			(end 1.0922 -2.3114)
			(stroke
				(width 0)
				(type default)
			)
			(fill no)
			(layer "F.CrtYd")
		)
		(fp_poly
			(pts
				(xy -1.0922 -2.3114) (xy 1.0922 -2.3114) (xy 1.0922 2.3114) (xy -1.0922 2.3114)
			)
			(stroke
				(width 0)
				(type default)
			)
			(fill no)
			(layer "F.Fab")
		)
		(pad "1" smd rect
			(at 0 -1.397 270)
			(size 1.651 1.27)
			(layers "F.Cu" "F.Mask" "F.Paste")
			(net "P5V_HDD31")
		)
		(pad "2" smd rect
			(at 0 1.397 270)
			(size 1.651 1.27)
			(layers "F.Cu" "F.Mask" "F.Paste")
			(net "5V_PRE_31")
		)
	)
	(footprint ""
		(layer "F.Cu")
		(at 232.859326 -261.731506 180)
		(property "Reference" "R33"
			(at 0 0 180)
			(layer "F.SilkS")
			(hide yes)
			(effects
				(font
					(size 1.27 1.27)
				)
			)
		)
		(property "Value" "4K7R2F-GP"
			(at 0.064008 -3.993896 180)
			(unlocked yes)
			(layer "F.Fab")
			(hide yes)
			(effects
				(font
					(size 1.016 1.016)
					(thickness 0.1524)
				)
			)
		)
		(property "Device Type" "R402H16"
			(at 0.064008 -5.517896 180)
			(unlocked yes)
			(layer "F.Fab")
			(hide yes)
			(effects
				(font
					(size 1.016 1.016)
					(thickness 0.1524)
				)
			)
		)
		(duplicate_pad_numbers_are_jumpers no)
		(fp_line
			(start 0.508 -0.9398)
			(end -0.508 -0.9398)
			(stroke
				(width 0.1524)
				(type default)
			)
			(layer "F.SilkS")
		)
		(fp_line
			(start -0.508 -0.9398)
			(end -0.508 0.9398)
			(stroke
				(width 0.1524)
				(type default)
			)
			(layer "F.SilkS")
		)
		(fp_rect
			(start -0.508 0.9398)
			(end 0.508 -0.9398)
			(stroke
				(width 0)
				(type default)
			)
			(fill no)
			(layer "F.CrtYd")
		)
		(fp_rect
			(start -0.508 0.9398)
			(end 0.508 -0.9398)
			(stroke
				(width 0)
				(type default)
			)
			(fill no)
			(layer "F.Fab")
		)
		(pad "1" smd custom
			(at 0 -0.4445 180)
			(size 0.1397 0.1397)
			(layers "F.Cu" "F.Mask" "F.Paste")
			(net "IO_EXP4_A2")
			(options
				(clearance outline)
				(anchor circle)
			)
			(primitives
				(gr_poly
					(pts
						(arc
							(start -0.1778 -0.2794)
							(mid -0.249642 -0.249642)
							(end -0.2794 -0.1778)
						)
						(arc
							(start -0.2794 0.1778)
							(mid -0.249642 0.249642)
							(end -0.1778 0.2794)
						)
						(arc
							(start 0.1778 0.2794)
							(mid 0.249642 0.249642)
							(end 0.2794 0.1778)
						)
						(arc
							(start 0.2794 -0.1778)
							(mid 0.249642 -0.249642)
							(end 0.1778 -0.2794)
						)
					)
					(width 0)
					(fill yes)
				)
			)
		)
		(pad "2" smd custom
			(at 0 0.4445 180)
			(size 0.1397 0.1397)
			(layers "F.Cu" "F.Mask" "F.Paste")
			(net "GND")
			(options
				(clearance outline)
				(anchor circle)
			)
			(primitives
				(gr_poly
					(pts
						(arc
							(start -0.1778 -0.2794)
							(mid -0.249642 -0.249642)
							(end -0.2794 -0.1778)
						)
						(arc
							(start -0.2794 0.1778)
							(mid -0.249642 0.249642)
							(end -0.1778 0.2794)
						)
						(arc
							(start 0.1778 0.2794)
							(mid 0.249642 0.249642)
							(end 0.2794 0.1778)
						)
						(arc
							(start 0.2794 -0.1778)
							(mid 0.249642 -0.249642)
							(end 0.1778 -0.2794)
						)
					)
					(width 0)
					(fill yes)
				)
			)
		)
	)
	(footprint ""
		(layer "F.Cu")
		(at 205.232 -308.3052)
		(property "Reference" "TC13"
			(at 0 0 0)
			(layer "F.SilkS")
			(hide yes)
			(effects
				(font
					(size 1.27 1.27)
				)
			)
		)
		(property "Value" "SE270U16VM-8-GP"
			(at -4.5974 -2.54 0)
			(unlocked yes)
			(layer "F.Fab")
			(hide yes)
			(effects
				(font
					(size 1.016 1.016)
					(thickness 0.1524)
				)
			)
		)
		(property "Device Type" "SE361416H394"
			(at -4.5974 -4.064 0)
			(unlocked yes)
			(layer "F.Fab")
			(hide yes)
			(effects
				(font
					(size 1.016 1.016)
					(thickness 0.1524)
				)
			)
		)
		(duplicate_pad_numbers_are_jumpers no)
		(fp_line
			(start -3.556 -3.4163)
			(end -2.3622 -4.6101)
			(stroke
				(width 0.1524)
				(type default)
			)
			(layer "F.SilkS")
		)
		(fp_line
			(start -3.556 4.6101)
			(end -3.556 -3.4163)
			(stroke
				(width 0.1524)
				(type default)
			)
			(layer "F.SilkS")
		)
		(fp_line
			(start -2.3622 -4.6101)
			(end 2.3622 -4.6101)
			(stroke
				(width 0.1524)
				(type default)
			)
			(layer "F.SilkS")
		)
		(fp_line
			(start 2.3622 -4.6101)
			(end 3.556 -3.4163)
			(stroke
				(width 0.1524)
				(type default)
			)
			(layer "F.SilkS")
		)
		(fp_line
			(start 3.556 -3.4163)
			(end 3.556 4.6101)
			(stroke
				(width 0.1524)
				(type default)
			)
			(layer "F.SilkS")
		)
		(fp_line
			(start 3.556 4.6101)
			(end -3.556 4.6101)
			(stroke
				(width 0.1524)
				(type default)
			)
			(layer "F.SilkS")
		)
		(fp_rect
			(start -3.302 3.6449)
			(end 3.302 -3.6449)
			(stroke
				(width 0)
				(type default)
			)
			(fill no)
			(layer "F.CrtYd")
		)
		(fp_poly
			(pts
				(xy 3.81 4.6863) (xy 3.81 -3.4925) (xy 3.302 -3.4925) (xy 3.302 3.6449) (xy -3.302 3.6449) (xy -3.302 -3.6449)
				(xy 3.302 -3.6449) (xy 3.302 -3.5052) (xy 3.81 -3.5052) (xy 3.81 -4.6863) (xy -3.81 -4.6863) (xy -3.81 4.6863)
			)
			(stroke
				(width 0)
				(type default)
			)
			(fill no)
			(layer "F.CrtYd")
		)
		(fp_rect
			(start -3.81 4.6863)
			(end 3.81 -4.6863)
			(stroke
				(width 0)
				(type default)
			)
			(fill no)
			(layer "F.Fab")
		)
		(pad "1" smd rect
			(at 0 -2.574036)
			(size 1.4224 3.556)
			(layers "F.Cu" "F.Mask" "F.Paste")
			(net "P12V_A")
		)
		(pad "2" smd rect
			(at 0 2.574036)
			(size 1.4224 3.556)
			(layers "F.Cu" "F.Mask" "F.Paste")
			(net "GND")
		)
	)
	(footprint ""
		(layer "F.Cu")
		(at 461.9371 -275.735542 180)
		(property "Reference" "R377"
			(at 0 0 180)
			(layer "F.SilkS")
			(hide yes)
			(effects
				(font
					(size 1.27 1.27)
				)
			)
		)
		(property "Value" "0R2J-2-GP"
			(at 0.064008 -3.993896 180)
			(unlocked yes)
			(layer "F.Fab")
			(hide yes)
			(effects
				(font
					(size 1.016 1.016)
					(thickness 0.1524)
				)
			)
		)
		(property "Device Type" "R402H16"
			(at 0.064008 -5.517896 180)
			(unlocked yes)
			(layer "F.Fab")
			(hide yes)
			(effects
				(font
					(size 1.016 1.016)
					(thickness 0.1524)
				)
			)
		)
		(duplicate_pad_numbers_are_jumpers no)
		(fp_line
			(start 0.508 -0.9398)
			(end -0.508 -0.9398)
			(stroke
				(width 0.1524)
				(type default)
			)
			(layer "F.SilkS")
		)
		(fp_line
			(start -0.508 -0.9398)
			(end -0.508 0.9398)
			(stroke
				(width 0.1524)
				(type default)
			)
			(layer "F.SilkS")
		)
		(fp_rect
			(start -0.508 0.9398)
			(end 0.508 -0.9398)
			(stroke
				(width 0)
				(type default)
			)
			(fill no)
			(layer "F.CrtYd")
		)
		(fp_rect
			(start -0.508 0.9398)
			(end 0.508 -0.9398)
			(stroke
				(width 0)
				(type default)
			)
			(fill no)
			(layer "F.Fab")
		)
		(pad "1" smd custom
			(at 0 -0.4445 180)
			(size 0.1397 0.1397)
			(layers "F.Cu" "F.Mask" "F.Paste")
			(net "SW_HDD_G10")
			(options
				(clearance outline)
				(anchor circle)
			)
			(primitives
				(gr_poly
					(pts
						(arc
							(start -0.1778 -0.2794)
							(mid -0.249642 -0.249642)
							(end -0.2794 -0.1778)
						)
						(arc
							(start -0.2794 0.1778)
							(mid -0.249642 0.249642)
							(end -0.1778 0.2794)
						)
						(arc
							(start 0.1778 0.2794)
							(mid 0.249642 0.249642)
							(end 0.2794 0.1778)
						)
						(arc
							(start 0.2794 -0.1778)
							(mid 0.249642 -0.249642)
							(end 0.1778 -0.2794)
						)
					)
					(width 0)
					(fill yes)
				)
			)
		)
		(pad "2" smd custom
			(at 0 0.4445 180)
			(size 0.1397 0.1397)
			(layers "F.Cu" "F.Mask" "F.Paste")
			(net "SW_HDD_R10")
			(options
				(clearance outline)
				(anchor circle)
			)
			(primitives
				(gr_poly
					(pts
						(arc
							(start -0.1778 -0.2794)
							(mid -0.249642 -0.249642)
							(end -0.2794 -0.1778)
						)
						(arc
							(start -0.2794 0.1778)
							(mid -0.249642 0.249642)
							(end -0.1778 0.2794)
						)
						(arc
							(start 0.1778 0.2794)
							(mid 0.249642 0.249642)
							(end 0.2794 0.1778)
						)
						(arc
							(start 0.2794 -0.1778)
							(mid 0.249642 -0.249642)
							(end 0.1778 -0.2794)
						)
					)
					(width 0)
					(fill yes)
				)
			)
		)
	)
	(footprint ""
		(layer "F.Cu")
		(at 383.3368 -46.1518)
		(property "Reference" "VIA13"
			(at 0 0 0)
			(layer "F.SilkS")
			(hide yes)
			(effects
				(font
					(size 1.27 1.27)
				)
			)
		)
		(property "Value" "100OHM-8L-1D6MM-L18L16-GP"
			(at -3.7211 -4.5085 0)
			(unlocked yes)
			(layer "F.Fab")
			(hide yes)
			(effects
				(font
					(size 1.016 1.016)
					(thickness 0.1524)
				)
			)
		)
		(property "Device Type" "VIA-PCIE-4P-394076"
			(at -3.7211 -6.0325 0)
			(unlocked yes)
			(layer "F.Fab")
			(hide yes)
			(effects
				(font
					(size 1.016 1.016)
					(thickness 0.1524)
				)
			)
		)
		(duplicate_pad_numbers_are_jumpers no)
		(fp_rect
			(start -1.9685 0.381)
			(end 1.9685 -0.381)
			(stroke
				(width 0)
				(type default)
			)
			(fill no)
			(layer "F.CrtYd")
		)
		(fp_rect
			(start -1.9685 0.381)
			(end 1.9685 -0.381)
			(stroke
				(width 0)
				(type default)
			)
			(fill no)
			(layer "F.Fab")
		)
		(pad "1" thru_hole circle
			(at -1.5875 0)
			(size 0.508 0.508)
			(drill 0.254)
			(layers "*.Cu" "*.Mask")
			(remove_unused_layers no)
			(net "GND")
			(clearance 0.127)
			(thermal_gap 0.127)
		)
		(pad "2" thru_hole circle
			(at -0.5715 0)
			(size 0.508 0.508)
			(drill 0.254)
			(layers "*.Cu" "*.Mask")
			(remove_unused_layers no)
			(net "PHY_SCC_A_TO_DRV_A_32_DP")
			(clearance 0.127)
			(thermal_gap 0.127)
		)
		(pad "3" thru_hole circle
			(at 0.5715 0)
			(size 0.508 0.508)
			(drill 0.254)
			(layers "*.Cu" "*.Mask")
			(remove_unused_layers no)
			(net "PHY_SCC_A_TO_DRV_A_32_DN")
			(clearance 0.127)
			(thermal_gap 0.127)
		)
		(pad "4" thru_hole circle
			(at 1.5875 0)
			(size 0.508 0.508)
			(drill 0.254)
			(layers "*.Cu" "*.Mask")
			(remove_unused_layers no)
			(net "GND")
			(clearance 0.127)
			(thermal_gap 0.127)
		)
	)
	(footprint ""
		(layer "F.Cu")
		(at 223.839024 -347.4593 180)
		(property "Reference" "C4"
			(at 0 0 180)
			(layer "F.SilkS")
			(hide yes)
			(effects
				(font
					(size 1.27 1.27)
				)
			)
		)
		(property "Value" "SC1U16V3KX-5GP"
			(at 0 -2.8194 180)
			(unlocked yes)
			(layer "F.Fab")
			(hide yes)
			(effects
				(font
					(size 1.016 1.016)
					(thickness 0.1524)
				)
			)
		)
		(property "Device Type" "C603H36"
			(at 0 -4.3434 180)
			(unlocked yes)
			(layer "F.Fab")
			(hide yes)
			(effects
				(font
					(size 1.016 1.016)
					(thickness 0.1524)
				)
			)
		)
		(duplicate_pad_numbers_are_jumpers no)
		(fp_line
			(start 0.508 0)
			(end -0.508 0)
			(stroke
				(width 0.2032)
				(type default)
			)
			(layer "F.SilkS")
		)
		(fp_rect
			(start -0.5842 1.3335)
			(end 0.5842 -1.3335)
			(stroke
				(width 0)
				(type default)
			)
			(fill no)
			(layer "F.CrtYd")
		)
		(fp_rect
			(start -0.5842 1.3335)
			(end 0.5842 -1.3335)
			(stroke
				(width 0)
				(type default)
			)
			(fill no)
			(layer "F.Fab")
		)
		(pad "1" smd custom
			(at 0 -0.762 180)
			(size 0.2159 0.2159)
			(layers "F.Cu" "F.Mask" "F.Paste")
			(net "P3V3_STBY_A")
			(options
				(clearance outline)
				(anchor circle)
			)
			(primitives
				(gr_poly
					(pts
						(arc
							(start -0.3302 -0.4318)
							(mid -0.402042 -0.402042)
							(end -0.4318 -0.3302)
						)
						(arc
							(start -0.4318 0.3302)
							(mid -0.402042 0.402042)
							(end -0.3302 0.4318)
						)
						(arc
							(start 0.3302 0.4318)
							(mid 0.402042 0.402042)
							(end 0.4318 0.3302)
						)
						(arc
							(start 0.4318 -0.3302)
							(mid 0.402042 -0.402042)
							(end 0.3302 -0.4318)
						)
					)
					(width 0)
					(fill yes)
				)
			)
		)
		(pad "2" smd custom
			(at 0 0.762 180)
			(size 0.2159 0.2159)
			(layers "F.Cu" "F.Mask" "F.Paste")
			(net "GND")
			(options
				(clearance outline)
				(anchor circle)
			)
			(primitives
				(gr_poly
					(pts
						(arc
							(start -0.3302 -0.4318)
							(mid -0.402042 -0.402042)
							(end -0.4318 -0.3302)
						)
						(arc
							(start -0.4318 0.3302)
							(mid -0.402042 0.402042)
							(end -0.3302 0.4318)
						)
						(arc
							(start 0.3302 0.4318)
							(mid 0.402042 0.402042)
							(end 0.4318 0.3302)
						)
						(arc
							(start 0.4318 -0.3302)
							(mid 0.402042 -0.402042)
							(end 0.3302 -0.4318)
						)
					)
					(width 0)
					(fill yes)
				)
			)
		)
	)
	(footprint ""
		(layer "F.Cu")
		(at 242.189 -395.2748 180)
		(property "Reference" "C591"
			(at 0 0 180)
			(layer "F.SilkS")
			(hide yes)
			(effects
				(font
					(size 1.27 1.27)
				)
			)
		)
		(property "Value" "SC1U16V3KX-5GP"
			(at 0 -2.8194 180)
			(unlocked yes)
			(layer "F.Fab")
			(hide yes)
			(effects
				(font
					(size 1.016 1.016)
					(thickness 0.1524)
				)
			)
		)
		(property "Device Type" "C603H36"
			(at 0 -4.3434 180)
			(unlocked yes)
			(layer "F.Fab")
			(hide yes)
			(effects
				(font
					(size 1.016 1.016)
					(thickness 0.1524)
				)
			)
		)
		(duplicate_pad_numbers_are_jumpers no)
		(fp_line
			(start 0.508 0)
			(end -0.508 0)
			(stroke
				(width 0.2032)
				(type default)
			)
			(layer "F.SilkS")
		)
		(fp_rect
			(start -0.5842 1.3335)
			(end 0.5842 -1.3335)
			(stroke
				(width 0)
				(type default)
			)
			(fill no)
			(layer "F.CrtYd")
		)
		(fp_rect
			(start -0.5842 1.3335)
			(end 0.5842 -1.3335)
			(stroke
				(width 0)
				(type default)
			)
			(fill no)
			(layer "F.Fab")
		)
		(pad "1" smd custom
			(at 0 -0.762 180)
			(size 0.2159 0.2159)
			(layers "F.Cu" "F.Mask" "F.Paste")
			(net "MB3_VCAP_R")
			(options
				(clearance outline)
				(anchor circle)
			)
			(primitives
				(gr_poly
					(pts
						(arc
							(start -0.3302 -0.4318)
							(mid -0.402042 -0.402042)
							(end -0.4318 -0.3302)
						)
						(arc
							(start -0.4318 0.3302)
							(mid -0.402042 0.402042)
							(end -0.3302 0.4318)
						)
						(arc
							(start 0.3302 0.4318)
							(mid 0.402042 0.402042)
							(end 0.4318 0.3302)
						)
						(arc
							(start 0.4318 -0.3302)
							(mid 0.402042 -0.402042)
							(end 0.3302 -0.4318)
						)
					)
					(width 0)
					(fill yes)
				)
			)
		)
		(pad "2" smd custom
			(at 0 0.762 180)
			(size 0.2159 0.2159)
			(layers "F.Cu" "F.Mask" "F.Paste")
			(net "AGND_CURRENT_DPB")
			(options
				(clearance outline)
				(anchor circle)
			)
			(primitives
				(gr_poly
					(pts
						(arc
							(start -0.3302 -0.4318)
							(mid -0.402042 -0.402042)
							(end -0.4318 -0.3302)
						)
						(arc
							(start -0.4318 0.3302)
							(mid -0.402042 0.402042)
							(end -0.3302 0.4318)
						)
						(arc
							(start 0.3302 0.4318)
							(mid 0.402042 0.402042)
							(end 0.4318 0.3302)
						)
						(arc
							(start 0.4318 -0.3302)
							(mid 0.402042 -0.402042)
							(end 0.3302 -0.4318)
						)
					)
					(width 0)
					(fill yes)
				)
			)
		)
	)
	(footprint ""
		(layer "F.Cu")
		(at 346.680028 -127.254)
		(property "Reference" "R323"
			(at 0 0 0)
			(layer "F.SilkS")
			(hide yes)
			(effects
				(font
					(size 1.27 1.27)
				)
			)
		)
		(property "Value" "91R3F-1-GP"
			(at -0.0254 -2.5146 0)
			(unlocked yes)
			(layer "F.Fab")
			(hide yes)
			(effects
				(font
					(size 1.016 1.016)
					(thickness 0.1524)
				)
			)
		)
		(property "Device Type" "R603H22"
			(at -0.0254 -4.0386 0)
			(unlocked yes)
			(layer "F.Fab")
			(hide yes)
			(effects
				(font
					(size 1.016 1.016)
					(thickness 0.1524)
				)
			)
		)
		(duplicate_pad_numbers_are_jumpers no)
		(fp_line
			(start -0.4826 0)
			(end -0.2032 0)
			(stroke
				(width 0.2032)
				(type default)
			)
			(layer "F.SilkS")
		)
		(fp_line
			(start 0.2032 0)
			(end 0.4826 0)
			(stroke
				(width 0.2032)
				(type default)
			)
			(layer "F.SilkS")
		)
		(fp_rect
			(start -0.5842 1.3335)
			(end 0.5842 -1.3335)
			(stroke
				(width 0)
				(type default)
			)
			(fill no)
			(layer "F.CrtYd")
		)
		(fp_rect
			(start -0.5842 1.3335)
			(end 0.5842 -1.3335)
			(stroke
				(width 0)
				(type default)
			)
			(fill no)
			(layer "F.Fab")
		)
		(pad "1" smd custom
			(at 0 -0.762)
			(size 0.2159 0.2159)
			(layers "F.Cu" "F.Mask" "F.Paste")
			(net "P5V_A_3")
			(options
				(clearance outline)
				(anchor circle)
			)
			(primitives
				(gr_poly
					(pts
						(arc
							(start -0.3302 -0.4318)
							(mid -0.402042 -0.402042)
							(end -0.4318 -0.3302)
						)
						(arc
							(start -0.4318 0.3302)
							(mid -0.402042 0.402042)
							(end -0.3302 0.4318)
						)
						(arc
							(start 0.3302 0.4318)
							(mid 0.402042 0.402042)
							(end 0.4318 0.3302)
						)
						(arc
							(start 0.4318 -0.3302)
							(mid 0.402042 -0.402042)
							(end 0.3302 -0.4318)
						)
					)
					(width 0)
					(fill yes)
				)
			)
		)
		(pad "2" smd custom
			(at 0 0.762)
			(size 0.2159 0.2159)
			(layers "F.Cu" "F.Mask" "F.Paste")
			(net "DRV_ACT_19")
			(options
				(clearance outline)
				(anchor circle)
			)
			(primitives
				(gr_poly
					(pts
						(arc
							(start -0.3302 -0.4318)
							(mid -0.402042 -0.402042)
							(end -0.4318 -0.3302)
						)
						(arc
							(start -0.4318 0.3302)
							(mid -0.402042 0.402042)
							(end -0.3302 0.4318)
						)
						(arc
							(start 0.3302 0.4318)
							(mid 0.402042 0.402042)
							(end 0.4318 0.3302)
						)
						(arc
							(start 0.4318 -0.3302)
							(mid 0.402042 -0.402042)
							(end 0.3302 -0.4318)
						)
					)
					(width 0)
					(fill yes)
				)
			)
		)
	)
	(footprint ""
		(layer "F.Cu")
		(at 226.278694 -371.134894)
		(property "Reference" "U18"
			(at 0 0 0)
			(layer "F.SilkS")
			(hide yes)
			(effects
				(font
					(size 1.27 1.27)
				)
			)
		)
		(property "Value" "TCA9555PWR-GP"
			(at 0 -6.9342 0)
			(unlocked yes)
			(layer "F.Fab")
			(hide yes)
			(effects
				(font
					(size 1.016 1.016)
					(thickness 0.1524)
				)
			)
		)
		(property "Device Type" "TSOIC24H48"
			(at 0 -8.5852 0)
			(unlocked yes)
			(layer "F.Fab")
			(hide yes)
			(effects
				(font
					(size 1.016 1.016)
					(thickness 0.1524)
				)
			)
		)
		(duplicate_pad_numbers_are_jumpers no)
		(fp_line
			(start -4.2291 -1.397)
			(end 3.81 -1.397)
			(stroke
				(width 0.1524)
				(type default)
			)
			(layer "F.SilkS")
		)
		(fp_line
			(start -4.2291 -0.8001)
			(end -3.429 0)
			(stroke
				(width 0.1524)
				(type default)
			)
			(layer "F.SilkS")
		)
		(fp_line
			(start -4.2291 3.937)
			(end -4.2291 -1.397)
			(stroke
				(width 0.1524)
				(type default)
			)
			(layer "F.SilkS")
		)
		(fp_line
			(start -4.22656 3.81)
			(end -4.2291 1.397)
			(stroke
				(width 0.508)
				(type default)
			)
			(layer "F.SilkS")
		)
		(fp_line
			(start -3.429 0)
			(end -4.2291 0.8001)
			(stroke
				(width 0.1524)
				(type default)
			)
			(layer "F.SilkS")
		)
		(fp_line
			(start 3.81 -1.397)
			(end 3.81 1.397)
			(stroke
				(width 0.1524)
				(type default)
			)
			(layer "F.SilkS")
		)
		(fp_line
			(start 3.81 1.397)
			(end -4.2291 1.397)
			(stroke
				(width 0.1524)
				(type default)
			)
			(layer "F.SilkS")
		)
		(fp_poly
			(pts
				(xy -3.90652 -1.8542) (xy 3.90652 -1.8542) (xy 3.90652 1.8542) (xy -3.90652 1.8542)
			)
			(stroke
				(width 0)
				(type default)
			)
			(fill yes)
			(layer "F.SilkS")
		)
		(fp_poly
			(pts
				(xy -4.2164 3.81) (xy 4.2164 3.81) (xy 4.22656 -3.81) (xy -4.2164 -3.81)
			)
			(stroke
				(width 0)
				(type default)
			)
			(fill no)
			(layer "F.CrtYd")
		)
		(fp_poly
			(pts
				(xy -4.22656 -3.81) (xy 4.22656 -3.81) (xy 4.22656 3.81) (xy -4.22656 3.81)
			)
			(stroke
				(width 0)
				(type default)
			)
			(fill no)
			(layer "F.Fab")
		)
		(pad "1" smd rect
			(at -3.57632 2.8194)
			(size 0.3556 1.524)
			(layers "F.Cu" "F.Mask" "F.Paste")
			(net "IO_EXP3_HDD_FAULT_INT_N")
		)
		(pad "2" smd rect
			(at -2.92608 2.8194)
			(size 0.3556 1.524)
			(layers "F.Cu" "F.Mask" "F.Paste")
			(net "IO_EXP3_HDD_FAULT_A1")
		)
		(pad "3" smd rect
			(at -2.27584 2.8194)
			(size 0.3556 1.524)
			(layers "F.Cu" "F.Mask" "F.Paste")
			(net "IO_EXP3_HDD_FAULT_A2")
		)
		(pad "4" smd rect
			(at -1.6256 2.8194)
			(size 0.3556 1.524)
			(layers "F.Cu" "F.Mask" "F.Paste")
			(net "DRIVE_B_24_FLT_LED")
		)
		(pad "5" smd rect
			(at -0.97536 2.8194)
			(size 0.3556 1.524)
			(layers "F.Cu" "F.Mask" "F.Paste")
			(net "DRIVE_B_25_FLT_LED")
		)
		(pad "6" smd rect
			(at -0.32512 2.8194)
			(size 0.3556 1.524)
			(layers "F.Cu" "F.Mask" "F.Paste")
			(net "DRIVE_B_26_FLT_LED")
		)
		(pad "7" smd rect
			(at 0.32512 2.8194)
			(size 0.3556 1.524)
			(layers "F.Cu" "F.Mask" "F.Paste")
			(net "DRIVE_B_27_FLT_LED")
		)
		(pad "8" smd rect
			(at 0.97536 2.8194)
			(size 0.3556 1.524)
			(layers "F.Cu" "F.Mask" "F.Paste")
			(net "DRIVE_B_28_FLT_LED")
		)
		(pad "9" smd rect
			(at 1.6256 2.8194)
			(size 0.3556 1.524)
			(layers "F.Cu" "F.Mask" "F.Paste")
			(net "DRIVE_B_29_FLT_LED")
		)
		(pad "10" smd rect
			(at 2.27584 2.8194)
			(size 0.3556 1.524)
			(layers "F.Cu" "F.Mask" "F.Paste")
			(net "DRIVE_B_30_FLT_LED")
		)
		(pad "11" smd rect
			(at 2.92608 2.8194)
			(size 0.3556 1.524)
			(layers "F.Cu" "F.Mask" "F.Paste")
			(net "DRIVE_B_31_FLT_LED")
		)
		(pad "12" smd rect
			(at 3.57632 2.8194)
			(size 0.3556 1.524)
			(layers "F.Cu" "F.Mask" "F.Paste")
			(net "GND")
		)
		(pad "13" smd rect
			(at 3.57632 -2.8194)
			(size 0.3556 1.524)
			(layers "F.Cu" "F.Mask" "F.Paste")
			(net "DRIVE_B_32_FLT_LED")
		)
		(pad "14" smd rect
			(at 2.92608 -2.8194)
			(size 0.3556 1.524)
			(layers "F.Cu" "F.Mask" "F.Paste")
			(net "DRIVE_B_33_FLT_LED")
		)
		(pad "15" smd rect
			(at 2.27584 -2.8194)
			(size 0.3556 1.524)
			(layers "F.Cu" "F.Mask" "F.Paste")
			(net "DRIVE_B_34_FLT_LED")
		)
		(pad "16" smd rect
			(at 1.6256 -2.8194)
			(size 0.3556 1.524)
			(layers "F.Cu" "F.Mask" "F.Paste")
			(net "DRIVE_B_35_FLT_LED")
		)
		(pad "17" smd rect
			(at 0.97536 -2.8194)
			(size 0.3556 1.524)
			(layers "F.Cu" "F.Mask" "F.Paste")
			(net "Net_1194")
		)
		(pad "18" smd rect
			(at 0.32512 -2.8194)
			(size 0.3556 1.524)
			(layers "F.Cu" "F.Mask" "F.Paste")
			(net "Net_1193")
		)
		(pad "19" smd rect
			(at -0.32512 -2.8194)
			(size 0.3556 1.524)
			(layers "F.Cu" "F.Mask" "F.Paste")
			(net "Net_1192")
		)
		(pad "20" smd rect
			(at -0.97536 -2.8194)
			(size 0.3556 1.524)
			(layers "F.Cu" "F.Mask" "F.Paste")
			(net "Net_246")
		)
		(pad "21" smd rect
			(at -1.6256 -2.8194)
			(size 0.3556 1.524)
			(layers "F.Cu" "F.Mask" "F.Paste")
			(net "IO_EXP3_HDD_FAULT_A0")
		)
		(pad "22" smd rect
			(at -2.27584 -2.8194)
			(size 0.3556 1.524)
			(layers "F.Cu" "F.Mask" "F.Paste")
			(net "IO_EXP3_LED_SCL")
		)
		(pad "23" smd rect
			(at -2.92608 -2.8194)
			(size 0.3556 1.524)
			(layers "F.Cu" "F.Mask" "F.Paste")
			(net "IO_EXP3_LED_SDA")
		)
		(pad "24" smd rect
			(at -3.57632 -2.8194)
			(size 0.3556 1.524)
			(layers "F.Cu" "F.Mask" "F.Paste")
			(net "P3V3_STBY_B")
		)
	)
	(footprint ""
		(layer "F.Cu")
		(at 426.755052 -157.585918)
		(property "Reference" "R625"
			(at 0 0 0)
			(layer "F.SilkS")
			(hide yes)
			(effects
				(font
					(size 1.27 1.27)
				)
			)
		)
		(property "Value" "4K7R2J-2-GP"
			(at 0.064008 -3.993896 0)
			(unlocked yes)
			(layer "F.Fab")
			(hide yes)
			(effects
				(font
					(size 1.016 1.016)
					(thickness 0.1524)
				)
			)
		)
		(property "Device Type" "R402H16"
			(at 0.064008 -5.517896 0)
			(unlocked yes)
			(layer "F.Fab")
			(hide yes)
			(effects
				(font
					(size 1.016 1.016)
					(thickness 0.1524)
				)
			)
		)
		(duplicate_pad_numbers_are_jumpers no)
		(fp_line
			(start -0.508 -0.9398)
			(end -0.508 0.9398)
			(stroke
				(width 0.1524)
				(type default)
			)
			(layer "F.SilkS")
		)
		(fp_line
			(start 0.508 -0.9398)
			(end -0.508 -0.9398)
			(stroke
				(width 0.1524)
				(type default)
			)
			(layer "F.SilkS")
		)
		(fp_rect
			(start -0.508 0.9398)
			(end 0.508 -0.9398)
			(stroke
				(width 0)
				(type default)
			)
			(fill no)
			(layer "F.CrtYd")
		)
		(fp_rect
			(start -0.508 0.9398)
			(end 0.508 -0.9398)
			(stroke
				(width 0)
				(type default)
			)
			(fill no)
			(layer "F.Fab")
		)
		(pad "1" smd custom
			(at 0 -0.4445)
			(size 0.1397 0.1397)
			(layers "F.Cu" "F.Mask" "F.Paste")
			(net "SW_PWR_R_HDD21")
			(options
				(clearance outline)
				(anchor circle)
			)
			(primitives
				(gr_poly
					(pts
						(arc
							(start -0.1778 -0.2794)
							(mid -0.249642 -0.249642)
							(end -0.2794 -0.1778)
						)
						(arc
							(start -0.2794 0.1778)
							(mid -0.249642 0.249642)
							(end -0.1778 0.2794)
						)
						(arc
							(start 0.1778 0.2794)
							(mid 0.249642 0.249642)
							(end 0.2794 0.1778)
						)
						(arc
							(start 0.2794 -0.1778)
							(mid 0.249642 -0.249642)
							(end 0.1778 -0.2794)
						)
					)
					(width 0)
					(fill yes)
				)
			)
		)
		(pad "2" smd custom
			(at 0 0.4445)
			(size 0.1397 0.1397)
			(layers "F.Cu" "F.Mask" "F.Paste")
			(net "GND")
			(options
				(clearance outline)
				(anchor circle)
			)
			(primitives
				(gr_poly
					(pts
						(arc
							(start -0.1778 -0.2794)
							(mid -0.249642 -0.249642)
							(end -0.2794 -0.1778)
						)
						(arc
							(start -0.2794 0.1778)
							(mid -0.249642 0.249642)
							(end -0.1778 0.2794)
						)
						(arc
							(start 0.1778 0.2794)
							(mid 0.249642 0.249642)
							(end 0.2794 0.1778)
						)
						(arc
							(start 0.2794 -0.1778)
							(mid 0.249642 -0.249642)
							(end 0.1778 -0.2794)
						)
					)
					(width 0)
					(fill yes)
				)
			)
		)
	)
	(footprint ""
		(layer "F.Cu")
		(at 18.906998 -179.683918 90)
		(property "Reference" "R407"
			(at 0 0 90)
			(layer "F.SilkS")
			(hide yes)
			(effects
				(font
					(size 1.27 1.27)
				)
			)
		)
		(property "Value" "2R6F-GP"
			(at -0.0508 -4.8514 90)
			(unlocked yes)
			(layer "F.Fab")
			(hide yes)
			(effects
				(font
					(size 1.016 1.016)
					(thickness 0.1524)
				)
			)
		)
		(property "Device Type" "R1206H26"
			(at 0 -6.3754 90)
			(unlocked yes)
			(layer "F.Fab")
			(hide yes)
			(effects
				(font
					(size 1.016 1.016)
					(thickness 0.1524)
				)
			)
		)
		(duplicate_pad_numbers_are_jumpers no)
		(fp_line
			(start 1.016 -2.2352)
			(end 1.016 2.2352)
			(stroke
				(width 0.1524)
				(type default)
			)
			(layer "F.SilkS")
		)
		(fp_line
			(start -1.016 -2.2352)
			(end 1.016 -2.2352)
			(stroke
				(width 0.1524)
				(type default)
			)
			(layer "F.SilkS")
		)
		(fp_line
			(start 1.016 2.2352)
			(end -1.016 2.2352)
			(stroke
				(width 0.1524)
				(type default)
			)
			(layer "F.SilkS")
		)
		(fp_line
			(start -1.016 2.2352)
			(end -1.016 -2.2352)
			(stroke
				(width 0.1524)
				(type default)
			)
			(layer "F.SilkS")
		)
		(fp_rect
			(start -1.0922 2.3114)
			(end 1.0922 -2.3114)
			(stroke
				(width 0)
				(type default)
			)
			(fill no)
			(layer "F.CrtYd")
		)
		(fp_poly
			(pts
				(xy -1.0922 -2.3114) (xy 1.0922 -2.3114) (xy 1.0922 2.3114) (xy -1.0922 2.3114)
			)
			(stroke
				(width 0)
				(type default)
			)
			(fill no)
			(layer "F.Fab")
		)
		(pad "1" smd rect
			(at 0 -1.397 90)
			(size 1.651 1.27)
			(layers "F.Cu" "F.Mask" "F.Paste")
			(net "P12V_HDD12")
		)
		(pad "2" smd rect
			(at 0 1.397 90)
			(size 1.651 1.27)
			(layers "F.Cu" "F.Mask" "F.Paste")
			(net "12V_PRE_12")
		)
	)
	(footprint ""
		(layer "F.Cu")
		(at 149.932898 -177.270918)
		(property "Reference" "R497"
			(at 0 0 0)
			(layer "F.SilkS")
			(hide yes)
			(effects
				(font
					(size 1.27 1.27)
				)
			)
		)
		(property "Value" "2R6F-GP"
			(at -0.0508 -4.8514 0)
			(unlocked yes)
			(layer "F.Fab")
			(hide yes)
			(effects
				(font
					(size 1.016 1.016)
					(thickness 0.1524)
				)
			)
		)
		(property "Device Type" "R1206H26"
			(at 0 -6.3754 0)
			(unlocked yes)
			(layer "F.Fab")
			(hide yes)
			(effects
				(font
					(size 1.016 1.016)
					(thickness 0.1524)
				)
			)
		)
		(duplicate_pad_numbers_are_jumpers no)
		(fp_line
			(start -1.016 -2.2352)
			(end 1.016 -2.2352)
			(stroke
				(width 0.1524)
				(type default)
			)
			(layer "F.SilkS")
		)
		(fp_line
			(start -1.016 2.2352)
			(end -1.016 -2.2352)
			(stroke
				(width 0.1524)
				(type default)
			)
			(layer "F.SilkS")
		)
		(fp_line
			(start 1.016 -2.2352)
			(end 1.016 2.2352)
			(stroke
				(width 0.1524)
				(type default)
			)
			(layer "F.SilkS")
		)
		(fp_line
			(start 1.016 2.2352)
			(end -1.016 2.2352)
			(stroke
				(width 0.1524)
				(type default)
			)
			(layer "F.SilkS")
		)
		(fp_rect
			(start -1.0922 2.3114)
			(end 1.0922 -2.3114)
			(stroke
				(width 0)
				(type default)
			)
			(fill no)
			(layer "F.CrtYd")
		)
		(fp_poly
			(pts
				(xy -1.0922 -2.3114) (xy 1.0922 -2.3114) (xy 1.0922 2.3114) (xy -1.0922 2.3114)
			)
			(stroke
				(width 0)
				(type default)
			)
			(fill no)
			(layer "F.Fab")
		)
		(pad "1" smd rect
			(at 0 -1.397)
			(size 1.651 1.27)
			(layers "F.Cu" "F.Mask" "F.Paste")
			(net "P5V_HDD16")
		)
		(pad "2" smd rect
			(at 0 1.397)
			(size 1.651 1.27)
			(layers "F.Cu" "F.Mask" "F.Paste")
			(net "5V_PRE_16")
		)
	)
	(footprint ""
		(layer "F.Cu")
		(at 224.572322 -150.64867 -90)
		(property "Reference" "TP208"
			(at 0 0 270)
			(layer "F.SilkS")
			(hide yes)
			(effects
				(font
					(size 1.27 1.27)
				)
			)
		)
		(property "Value" "TPAD32-GP"
			(at -0.0508 -1.6764 270)
			(unlocked yes)
			(layer "F.Fab")
			(hide yes)
			(effects
				(font
					(size 1.016 1.016)
					(thickness 0.1524)
				)
			)
		)
		(property "Device Type" "TPAD32"
			(at -0.0508 -3.2004 270)
			(unlocked yes)
			(layer "F.Fab")
			(hide yes)
			(effects
				(font
					(size 1.016 1.016)
					(thickness 0.1524)
				)
			)
		)
		(duplicate_pad_numbers_are_jumpers no)
		(fp_poly
			(pts
				(arc
					(start 0 -0.4064)
					(mid 0 0.4064)
					(end 0 -0.4064)
				)
			)
			(stroke
				(width 0)
				(type default)
			)
			(fill no)
			(layer "F.CrtYd")
		)
		(fp_poly
			(pts
				(arc
					(start 0 -0.7112)
					(mid 0 0.7112)
					(end 0 -0.7112)
				)
			)
			(stroke
				(width 0)
				(type default)
			)
			(fill no)
			(layer "F.Fab")
		)
		(pad "1" smd circle
			(at 0 0 270)
			(size 0.8128 0.8128)
			(layers "F.Cu" "F.Mask" "F.Paste")
			(net "TP_COMP_A_KR_P0_RX_DN")
		)
	)
	(footprint ""
		(layer "F.Cu")
		(at 398.88795 -157.585918 180)
		(property "Reference" "R600"
			(at 0 0 180)
			(layer "F.SilkS")
			(hide yes)
			(effects
				(font
					(size 1.27 1.27)
				)
			)
		)
		(property "Value" "0R2J-2-GP"
			(at 0.064008 -3.993896 180)
			(unlocked yes)
			(layer "F.Fab")
			(hide yes)
			(effects
				(font
					(size 1.016 1.016)
					(thickness 0.1524)
				)
			)
		)
		(property "Device Type" "R402H16"
			(at 0.064008 -5.517896 180)
			(unlocked yes)
			(layer "F.Fab")
			(hide yes)
			(effects
				(font
					(size 1.016 1.016)
					(thickness 0.1524)
				)
			)
		)
		(duplicate_pad_numbers_are_jumpers no)
		(fp_line
			(start 0.508 -0.9398)
			(end -0.508 -0.9398)
			(stroke
				(width 0.1524)
				(type default)
			)
			(layer "F.SilkS")
		)
		(fp_line
			(start -0.508 -0.9398)
			(end -0.508 0.9398)
			(stroke
				(width 0.1524)
				(type default)
			)
			(layer "F.SilkS")
		)
		(fp_rect
			(start -0.508 0.9398)
			(end 0.508 -0.9398)
			(stroke
				(width 0)
				(type default)
			)
			(fill no)
			(layer "F.CrtYd")
		)
		(fp_rect
			(start -0.508 0.9398)
			(end 0.508 -0.9398)
			(stroke
				(width 0)
				(type default)
			)
			(fill no)
			(layer "F.Fab")
		)
		(pad "1" smd custom
			(at 0 -0.4445 180)
			(size 0.1397 0.1397)
			(layers "F.Cu" "F.Mask" "F.Paste")
			(net "DRIVE_A_20_PWR")
			(options
				(clearance outline)
				(anchor circle)
			)
			(primitives
				(gr_poly
					(pts
						(arc
							(start -0.1778 -0.2794)
							(mid -0.249642 -0.249642)
							(end -0.2794 -0.1778)
						)
						(arc
							(start -0.2794 0.1778)
							(mid -0.249642 0.249642)
							(end -0.1778 0.2794)
						)
						(arc
							(start 0.1778 0.2794)
							(mid 0.249642 0.249642)
							(end 0.2794 0.1778)
						)
						(arc
							(start 0.2794 -0.1778)
							(mid 0.249642 -0.249642)
							(end 0.1778 -0.2794)
						)
					)
					(width 0)
					(fill yes)
				)
			)
		)
		(pad "2" smd custom
			(at 0 0.4445 180)
			(size 0.1397 0.1397)
			(layers "F.Cu" "F.Mask" "F.Paste")
			(net "SW_PWR_R_HDD20")
			(options
				(clearance outline)
				(anchor circle)
			)
			(primitives
				(gr_poly
					(pts
						(arc
							(start -0.1778 -0.2794)
							(mid -0.249642 -0.249642)
							(end -0.2794 -0.1778)
						)
						(arc
							(start -0.2794 0.1778)
							(mid -0.249642 0.249642)
							(end -0.1778 0.2794)
						)
						(arc
							(start 0.1778 0.2794)
							(mid 0.249642 0.249642)
							(end 0.2794 0.1778)
						)
						(arc
							(start 0.2794 -0.1778)
							(mid 0.249642 -0.249642)
							(end 0.1778 -0.2794)
						)
					)
					(width 0)
					(fill yes)
				)
			)
		)
	)
	(footprint ""
		(layer "F.Cu")
		(at 364.290102 -279.596342 90)
		(property "Reference" "C139"
			(at 0 0 90)
			(layer "F.SilkS")
			(hide yes)
			(effects
				(font
					(size 1.27 1.27)
				)
			)
		)
		(property "Value" "SCD033U25V2KX-GP"
			(at 1.1811 -2.7051 90)
			(unlocked yes)
			(layer "F.Fab")
			(hide yes)
			(effects
				(font
					(size 1.016 1.016)
					(thickness 0.1524)
				)
			)
		)
		(property "Device Type" "C402H22"
			(at 1.1811 -4.2291 90)
			(unlocked yes)
			(layer "F.Fab")
			(hide yes)
			(effects
				(font
					(size 1.016 1.016)
					(thickness 0.1524)
				)
			)
		)
		(duplicate_pad_numbers_are_jumpers no)
		(fp_rect
			(start -0.4318 0.9525)
			(end 0.4318 -0.9525)
			(stroke
				(width 0)
				(type default)
			)
			(fill no)
			(layer "F.CrtYd")
		)
		(fp_rect
			(start -0.4318 0.9525)
			(end 0.4318 -0.9525)
			(stroke
				(width 0)
				(type default)
			)
			(fill no)
			(layer "F.Fab")
		)
		(pad "1" smd custom
			(at 0 -0.4445 90)
			(size 0.1524 0.1524)
			(layers "F.Cu" "F.Mask" "F.Paste")
			(net "SW_HDD_P7")
			(options
				(clearance outline)
				(anchor circle)
			)
			(primitives
				(gr_poly
					(pts
						(arc
							(start 0.3048 -0.2032)
							(mid 0.275042 -0.275042)
							(end 0.2032 -0.3048)
						)
						(arc
							(start -0.2032 -0.3048)
							(mid -0.275042 -0.275042)
							(end -0.3048 -0.2032)
						)
						(arc
							(start -0.3048 0.2032)
							(mid -0.275042 0.275042)
							(end -0.2032 0.3048)
						)
						(arc
							(start 0.2032 0.3048)
							(mid 0.275042 0.275042)
							(end 0.3048 0.2032)
						)
					)
					(width 0)
					(fill yes)
				)
			)
		)
		(pad "2" smd custom
			(at 0 0.4445 90)
			(size 0.1524 0.1524)
			(layers "F.Cu" "F.Mask" "F.Paste")
			(net "GND")
			(options
				(clearance outline)
				(anchor circle)
			)
			(primitives
				(gr_poly
					(pts
						(arc
							(start 0.3048 -0.2032)
							(mid 0.275042 -0.275042)
							(end 0.2032 -0.3048)
						)
						(arc
							(start -0.2032 -0.3048)
							(mid -0.275042 -0.275042)
							(end -0.3048 -0.2032)
						)
						(arc
							(start -0.3048 0.2032)
							(mid -0.275042 0.275042)
							(end -0.2032 0.3048)
						)
						(arc
							(start 0.2032 0.3048)
							(mid 0.275042 0.275042)
							(end 0.3048 0.2032)
						)
					)
					(width 0)
					(fill yes)
				)
			)
		)
	)
	(footprint ""
		(layer "F.Cu")
		(at 394.56995 -176.127918 -90)
		(property "Reference" "R589"
			(at 0 0 270)
			(layer "F.SilkS")
			(hide yes)
			(effects
				(font
					(size 1.27 1.27)
				)
			)
		)
		(property "Value" "2R6F-GP"
			(at -0.0508 -4.8514 270)
			(unlocked yes)
			(layer "F.Fab")
			(hide yes)
			(effects
				(font
					(size 1.016 1.016)
					(thickness 0.1524)
				)
			)
		)
		(property "Device Type" "R1206H26"
			(at 0 -6.3754 270)
			(unlocked yes)
			(layer "F.Fab")
			(hide yes)
			(effects
				(font
					(size 1.016 1.016)
					(thickness 0.1524)
				)
			)
		)
		(duplicate_pad_numbers_are_jumpers no)
		(fp_line
			(start -1.016 2.2352)
			(end -1.016 -2.2352)
			(stroke
				(width 0.1524)
				(type default)
			)
			(layer "F.SilkS")
		)
		(fp_line
			(start 1.016 2.2352)
			(end -1.016 2.2352)
			(stroke
				(width 0.1524)
				(type default)
			)
			(layer "F.SilkS")
		)
		(fp_line
			(start -1.016 -2.2352)
			(end 1.016 -2.2352)
			(stroke
				(width 0.1524)
				(type default)
			)
			(layer "F.SilkS")
		)
		(fp_line
			(start 1.016 -2.2352)
			(end 1.016 2.2352)
			(stroke
				(width 0.1524)
				(type default)
			)
			(layer "F.SilkS")
		)
		(fp_rect
			(start -1.0922 2.3114)
			(end 1.0922 -2.3114)
			(stroke
				(width 0)
				(type default)
			)
			(fill no)
			(layer "F.CrtYd")
		)
		(fp_poly
			(pts
				(xy -1.0922 -2.3114) (xy 1.0922 -2.3114) (xy 1.0922 2.3114) (xy -1.0922 2.3114)
			)
			(stroke
				(width 0)
				(type default)
			)
			(fill no)
			(layer "F.Fab")
		)
		(pad "1" smd rect
			(at 0 -1.397 270)
			(size 1.651 1.27)
			(layers "F.Cu" "F.Mask" "F.Paste")
			(net "P5V_HDD20")
		)
		(pad "2" smd rect
			(at 0 1.397 270)
			(size 1.651 1.27)
			(layers "F.Cu" "F.Mask" "F.Paste")
			(net "5V_PRE_20")
		)
	)
	(footprint ""
		(layer "F.Cu")
		(at 92.751148 -23.91918)
		(property "Reference" "R983"
			(at 0 0 0)
			(layer "F.SilkS")
			(hide yes)
			(effects
				(font
					(size 1.27 1.27)
				)
			)
		)
		(property "Value" "4K7R2F-GP"
			(at 0.064008 -3.993896 0)
			(unlocked yes)
			(layer "F.Fab")
			(hide yes)
			(effects
				(font
					(size 1.016 1.016)
					(thickness 0.1524)
				)
			)
		)
		(property "Device Type" "R402H16"
			(at 0.064008 -5.517896 0)
			(unlocked yes)
			(layer "F.Fab")
			(hide yes)
			(effects
				(font
					(size 1.016 1.016)
					(thickness 0.1524)
				)
			)
		)
		(duplicate_pad_numbers_are_jumpers no)
		(fp_line
			(start -0.508 -0.9398)
			(end -0.508 0.9398)
			(stroke
				(width 0.1524)
				(type default)
			)
			(layer "F.SilkS")
		)
		(fp_line
			(start 0.508 -0.9398)
			(end -0.508 -0.9398)
			(stroke
				(width 0.1524)
				(type default)
			)
			(layer "F.SilkS")
		)
		(fp_rect
			(start -0.508 0.9398)
			(end 0.508 -0.9398)
			(stroke
				(width 0)
				(type default)
			)
			(fill no)
			(layer "F.CrtYd")
		)
		(fp_rect
			(start -0.508 0.9398)
			(end 0.508 -0.9398)
			(stroke
				(width 0)
				(type default)
			)
			(fill no)
			(layer "F.Fab")
		)
		(pad "1" smd custom
			(at 0 -0.4445)
			(size 0.1397 0.1397)
			(layers "F.Cu" "F.Mask" "F.Paste")
			(net "IOM_A_SLOT_ID_1")
			(options
				(clearance outline)
				(anchor circle)
			)
			(primitives
				(gr_poly
					(pts
						(arc
							(start -0.1778 -0.2794)
							(mid -0.249642 -0.249642)
							(end -0.2794 -0.1778)
						)
						(arc
							(start -0.2794 0.1778)
							(mid -0.249642 0.249642)
							(end -0.1778 0.2794)
						)
						(arc
							(start 0.1778 0.2794)
							(mid 0.249642 0.249642)
							(end 0.2794 0.1778)
						)
						(arc
							(start 0.2794 -0.1778)
							(mid 0.249642 -0.249642)
							(end 0.1778 -0.2794)
						)
					)
					(width 0)
					(fill yes)
				)
			)
		)
		(pad "2" smd custom
			(at 0 0.4445)
			(size 0.1397 0.1397)
			(layers "F.Cu" "F.Mask" "F.Paste")
			(net "GND")
			(options
				(clearance outline)
				(anchor circle)
			)
			(primitives
				(gr_poly
					(pts
						(arc
							(start -0.1778 -0.2794)
							(mid -0.249642 -0.249642)
							(end -0.2794 -0.1778)
						)
						(arc
							(start -0.2794 0.1778)
							(mid -0.249642 0.249642)
							(end -0.1778 0.2794)
						)
						(arc
							(start 0.1778 0.2794)
							(mid 0.249642 0.249642)
							(end 0.2794 0.1778)
						)
						(arc
							(start 0.2794 -0.1778)
							(mid 0.249642 -0.249642)
							(end 0.1778 -0.2794)
						)
					)
					(width 0)
					(fill yes)
				)
			)
		)
	)
	(footprint ""
		(layer "F.Cu")
		(at 388.649972 -287.910016 -90)
		(property "Reference" "HDDSAS8"
			(at 0 0 270)
			(layer "F.SilkS")
			(hide yes)
			(effects
				(font
					(size 1.27 1.27)
				)
			)
		)
		(property "Value" "SKT-SAS15P-14P-45-GP"
			(at -20.7645 -8.9789 270)
			(unlocked yes)
			(layer "F.Fab")
			(hide yes)
			(effects
				(font
					(size 1.016 1.016)
					(thickness 0.1524)
				)
			)
		)
		(property "Device Type" "10120818-001C-TRLF"
			(at -20.7645 -10.5029 270)
			(unlocked yes)
			(layer "F.Fab")
			(hide yes)
			(effects
				(font
					(size 1.016 1.016)
					(thickness 0.1524)
				)
			)
		)
		(duplicate_pad_numbers_are_jumpers no)
		(fp_line
			(start 1.651 4.2926)
			(end 1.651 3.0099)
			(stroke
				(width 0.1524)
				(type default)
			)
			(layer "F.SilkS")
		)
		(fp_line
			(start 8.509 4.2926)
			(end 1.651 4.2926)
			(stroke
				(width 0.1524)
				(type default)
			)
			(layer "F.SilkS")
		)
		(fp_line
			(start -23.4188 3.0099)
			(end -23.4188 -3.2512)
			(stroke
				(width 0.1524)
				(type default)
			)
			(layer "F.SilkS")
		)
		(fp_line
			(start 1.651 3.0099)
			(end -23.4188 3.0099)
			(stroke
				(width 0.1524)
				(type default)
			)
			(layer "F.SilkS")
		)
		(fp_line
			(start 8.509 3.0099)
			(end 8.509 4.2926)
			(stroke
				(width 0.1524)
				(type default)
			)
			(layer "F.SilkS")
		)
		(fp_line
			(start 23.4188 3.0099)
			(end 8.509 3.0099)
			(stroke
				(width 0.1524)
				(type default)
			)
			(layer "F.SilkS")
		)
		(fp_line
			(start -23.4188 -3.2512)
			(end 23.4188 -3.2512)
			(stroke
				(width 0.1524)
				(type default)
			)
			(layer "F.SilkS")
		)
		(fp_line
			(start 23.4188 -3.2512)
			(end 23.4188 3.0099)
			(stroke
				(width 0.1524)
				(type default)
			)
			(layer "F.SilkS")
		)
		(fp_line
			(start 15.5067 -3.3401)
			(end 16.2687 -3.3401)
			(stroke
				(width 0.3302)
				(type default)
			)
			(layer "F.SilkS")
		)
		(fp_poly
			(pts
				(xy 15.868904 -3.230372) (xy 16.503904 -3.865372) (xy 15.233904 -3.865372)
			)
			(stroke
				(width 0)
				(type default)
			)
			(fill yes)
			(layer "F.SilkS")
		)
		(fp_poly
			(pts
				(xy -22.8727 -2.7559) (xy 22.8727 -2.7559) (xy 22.8727 2.7559) (xy 8.255 2.7559) (xy 8.255 3.5179)
				(xy 1.905 3.5179) (xy 1.905 2.7559) (xy -22.8727 2.7559)
			)
			(stroke
				(width 0)
				(type default)
			)
			(fill no)
			(layer "F.CrtYd")
		)
		(fp_poly
			(pts
				(xy 1.397 4.5466) (xy 1.397 3.2639) (xy -23.6728 3.2639) (xy -23.6728 -3.5052) (xy 23.6728 -3.5052)
				(xy 23.6728 -0.00635) (xy 22.8727 -0.00635) (xy 22.8727 -2.7559) (xy -22.8727 -2.7559) (xy -22.8727 2.7559)
				(xy 1.905 2.7559) (xy 1.905 3.5179) (xy 8.255 3.5179) (xy 8.255 2.7559) (xy 22.8727 2.7559) (xy 22.8727 0.00635)
				(xy 23.6728 0.00635) (xy 23.6728 3.2639) (xy 8.763 3.2639) (xy 8.763 4.5466)
			)
			(stroke
				(width 0)
				(type default)
			)
			(fill no)
			(layer "F.CrtYd")
		)
		(fp_poly
			(pts
				(xy 1.397 4.5466) (xy 1.397 3.2639) (xy -23.6728 3.2639) (xy -23.6728 -3.5052) (xy 23.6728 -3.5052)
				(xy 23.6728 3.2639) (xy 8.763 3.2639) (xy 8.763 4.5466)
			)
			(stroke
				(width 0)
				(type default)
			)
			(fill no)
			(layer "F.Fab")
		)
		(pad "" np_thru_hole circle
			(at -18.874994 0 270)
			(size 0.254 0.254)
			(drill 1.3462)
			(layers "*.Cu" "*.Mask")
			(clearance 0.9017)
			(thermal_gap 0.9017)
		)
		(pad "" np_thru_hole circle
			(at 18.874994 0 270)
			(size 0.254 0.254)
			(drill 0.9398)
			(layers "*.Cu" "*.Mask")
			(clearance 0.6985)
			(thermal_gap 0.6985)
		)
		(pad "G1" smd rect
			(at 21.874988 0 270)
			(size 2.5908 2.5908)
			(layers "F.Cu" "F.Mask" "F.Paste")
			(net "GND")
		)
		(pad "G2" smd rect
			(at -21.874988 0 270)
			(size 2.5908 2.5908)
			(layers "F.Cu" "F.Mask" "F.Paste")
			(net "GND")
		)
		(pad "P1" smd rect
			(at 1.905 -1.82499 270)
			(size 0.6096 2.3622)
			(layers "F.Cu" "F.Mask" "F.Paste")
			(net "Net_2001")
		)
		(pad "P2" smd rect
			(at 0.635 -1.82499 270)
			(size 0.6096 2.3622)
			(layers "F.Cu" "F.Mask" "F.Paste")
			(net "Net_2002")
		)
		(pad "P3" smd rect
			(at -0.635 -1.82499 270)
			(size 0.6096 2.3622)
			(layers "F.Cu" "F.Mask" "F.Paste")
			(net "Net_2003")
		)
		(pad "P4" smd rect
			(at -1.905 -1.82499 270)
			(size 0.6096 2.3622)
			(layers "F.Cu" "F.Mask" "F.Paste")
			(net "GND")
		)
		(pad "P5" smd rect
			(at -3.175 -1.82499 270)
			(size 0.6096 2.3622)
			(layers "F.Cu" "F.Mask" "F.Paste")
			(net "HDD_PRSNT_8")
		)
		(pad "P6" smd rect
			(at -4.445 -1.82499 270)
			(size 0.6096 2.3622)
			(layers "F.Cu" "F.Mask" "F.Paste")
			(net "GND")
		)
		(pad "P7" smd rect
			(at -5.715 -1.82499 270)
			(size 0.6096 2.3622)
			(layers "F.Cu" "F.Mask" "F.Paste")
			(net "5V_PRE_8")
		)
		(pad "P8" smd rect
			(at -6.985 -1.82499 270)
			(size 0.6096 2.3622)
			(layers "F.Cu" "F.Mask" "F.Paste")
			(net "P5V_HDD8")
		)
		(pad "P9" smd rect
			(at -8.255 -1.82499 270)
			(size 0.6096 2.3622)
			(layers "F.Cu" "F.Mask" "F.Paste")
			(net "P5V_HDD8")
		)
		(pad "P10" smd rect
			(at -9.525 -1.82499 270)
			(size 0.6096 2.3622)
			(layers "F.Cu" "F.Mask" "F.Paste")
			(net "GND")
		)
		(pad "P11" smd rect
			(at -10.795 -1.82499 270)
			(size 0.6096 2.3622)
			(layers "F.Cu" "F.Mask" "F.Paste")
			(net "ACT_HDD_8")
		)
		(pad "P12" smd rect
			(at -12.065 -1.82499 270)
			(size 0.6096 2.3622)
			(layers "F.Cu" "F.Mask" "F.Paste")
			(net "GND")
		)
		(pad "P13" smd rect
			(at -13.335 -1.82499 270)
			(size 0.6096 2.3622)
			(layers "F.Cu" "F.Mask" "F.Paste")
			(net "12V_PRE_8")
		)
		(pad "P14" smd rect
			(at -14.605 -1.82499 270)
			(size 0.6096 2.3622)
			(layers "F.Cu" "F.Mask" "F.Paste")
			(net "P12V_HDD8")
		)
		(pad "P15" smd rect
			(at -15.875 -1.82499 270)
			(size 0.6096 2.3622)
			(layers "F.Cu" "F.Mask" "F.Paste")
			(net "P12V_HDD8")
		)
		(pad "S1" smd rect
			(at 15.875 -1.82499 270)
			(size 0.6096 2.3622)
			(layers "F.Cu" "F.Mask" "F.Paste")
			(net "GND")
		)
		(pad "S2" smd rect
			(at 14.605 -1.82499 270)
			(size 0.6096 2.3622)
			(layers "F.Cu" "F.Mask" "F.Paste")
			(net "SAS_HDD_RX_P8")
		)
		(pad "S3" smd rect
			(at 13.335 -1.82499 270)
			(size 0.6096 2.3622)
			(layers "F.Cu" "F.Mask" "F.Paste")
			(net "SAS_HDD_RX_N8")
		)
		(pad "S4" smd rect
			(at 12.065 -1.82499 270)
			(size 0.6096 2.3622)
			(layers "F.Cu" "F.Mask" "F.Paste")
			(net "GND")
		)
		(pad "S5" smd rect
			(at 10.795 -1.82499 270)
			(size 0.6096 2.3622)
			(layers "F.Cu" "F.Mask" "F.Paste")
			(net "PHY_DRV_A_TO_SCC_A_8_DN")
		)
		(pad "S6" smd rect
			(at 9.525 -1.82499 270)
			(size 0.6096 2.3622)
			(layers "F.Cu" "F.Mask" "F.Paste")
			(net "PHY_DRV_A_TO_SCC_A_8_DP")
		)
		(pad "S7" smd rect
			(at 8.255 -1.82499 270)
			(size 0.6096 2.3622)
			(layers "F.Cu" "F.Mask" "F.Paste")
			(net "GND")
		)
		(pad "S8" smd rect
			(at 7.480046 2.845054 270)
			(size 0.508 2.3622)
			(layers "F.Cu" "F.Mask" "F.Paste")
			(net "GND")
		)
		(pad "S9" smd rect
			(at 6.679946 2.845054 270)
			(size 0.508 2.3622)
			(layers "F.Cu" "F.Mask" "F.Paste")
			(net "Net_480")
		)
		(pad "S10" smd rect
			(at 5.8801 2.845054 270)
			(size 0.508 2.3622)
			(layers "F.Cu" "F.Mask" "F.Paste")
			(net "Net_372")
		)
		(pad "S11" smd rect
			(at 5.08 2.845054 270)
			(size 0.508 2.3622)
			(layers "F.Cu" "F.Mask" "F.Paste")
			(net "GND")
		)
		(pad "S12" smd rect
			(at 4.2799 2.845054 270)
			(size 0.508 2.3622)
			(layers "F.Cu" "F.Mask" "F.Paste")
			(net "Net_408")
		)
		(pad "S13" smd rect
			(at 3.480054 2.845054 270)
			(size 0.508 2.3622)
			(layers "F.Cu" "F.Mask" "F.Paste")
			(net "Net_444")
		)
		(pad "S14" smd rect
			(at 2.679954 2.845054 270)
			(size 0.508 2.3622)
			(layers "F.Cu" "F.Mask" "F.Paste")
			(net "GND")
		)
		(zone
			(layer "F.Cu")
			(hatch none 0.5)
			(connect_pads
				(clearance 0)
			)
			(min_thickness 0.25)
			(keepout
				(tracks not_allowed)
				(vias allowed)
				(pads allowed)
				(copperpour not_allowed)
				(footprints allowed)
			)
			(placement
				(enabled no)
				(sheetname "")
			)
			(fill
				(thermal_gap 0.5)
				(thermal_bridge_width 0.5)
				(island_removal_mode 0)
			)
			(polygon
				(pts
					(xy 392.307572 -304.648616) (xy 385.233672 -304.648616) (xy 385.233672 -311.582816) (xy 386.338572 -311.582816)
					(xy 386.338572 -307.468016) (xy 390.961372 -307.468016) (xy 390.961372 -311.582816) (xy 392.307572 -311.582816)
				)
			)
		)
		(zone
			(layer "F.Cu")
			(hatch none 0.5)
			(connect_pads
				(clearance 0)
			)
			(min_thickness 0.25)
			(keepout
				(tracks allowed)
				(vias not_allowed)
				(pads allowed)
				(copperpour not_allowed)
				(footprints allowed)
			)
			(placement
				(enabled no)
				(sheetname "")
			)
			(fill
				(thermal_gap 0.5)
				(thermal_bridge_width 0.5)
				(island_removal_mode 0)
			)
			(polygon
				(pts
					(xy 392.307572 -304.648616) (xy 385.233672 -304.648616) (xy 385.233672 -311.582816) (xy 386.338572 -311.582816)
					(xy 386.338572 -307.468016) (xy 390.961372 -307.468016) (xy 390.961372 -311.582816) (xy 392.307572 -311.582816)
				)
			)
		)
		(zone
			(layer "F.Cu")
			(hatch none 0.5)
			(connect_pads
				(clearance 0)
			)
			(min_thickness 0.25)
			(keepout
				(tracks not_allowed)
				(vias allowed)
				(pads allowed)
				(copperpour not_allowed)
				(footprints allowed)
			)
			(placement
				(enabled no)
				(sheetname "")
			)
			(fill
				(thermal_gap 0.5)
				(thermal_bridge_width 0.5)
				(island_removal_mode 0)
			)
			(polygon
				(pts
					(xy 392.307572 -271.171416) (xy 385.233672 -271.171416) (xy 385.233672 -264.237216) (xy 386.338572 -264.237216)
					(xy 386.338572 -268.352016) (xy 390.961372 -268.352016) (xy 390.961372 -264.237216) (xy 392.307572 -264.237216)
				)
			)
		)
		(zone
			(layer "F.Cu")
			(hatch none 0.5)
			(connect_pads
				(clearance 0)
			)
			(min_thickness 0.25)
			(keepout
				(tracks allowed)
				(vias not_allowed)
				(pads allowed)
				(copperpour not_allowed)
				(footprints allowed)
			)
			(placement
				(enabled no)
				(sheetname "")
			)
			(fill
				(thermal_gap 0.5)
				(thermal_bridge_width 0.5)
				(island_removal_mode 0)
			)
			(polygon
				(pts
					(xy 392.307572 -271.171416) (xy 385.233672 -271.171416) (xy 385.233672 -264.237216) (xy 386.338572 -264.237216)
					(xy 386.338572 -268.352016) (xy 390.961372 -268.352016) (xy 390.961372 -264.237216) (xy 392.307572 -264.237216)
				)
			)
		)
		(zone
			(layers "F.Cu" "B.Cu" "In1.Cu" "In2.Cu" "In3.Cu" "In4.Cu" "In5.Cu" "In6.Cu"
				"In7.Cu" "In8.Cu" "In9.Cu" "In10.Cu"
			)
			(hatch none 0.5)
			(connect_pads
				(clearance 0)
			)
			(min_thickness 0.25)
			(keepout
				(tracks not_allowed)
				(vias allowed)
				(pads allowed)
				(copperpour not_allowed)
				(footprints allowed)
			)
			(placement
				(enabled no)
				(sheetname "")
			)
			(fill
				(thermal_gap 0.5)
				(thermal_bridge_width 0.5)
				(island_removal_mode 0)
			)
			(polygon
				(pts
					(arc
						(start 389.424672 -269.035022)
						(mid 387.875272 -269.035022)
						(end 389.424672 -269.035022)
					)
				)
			)
		)
		(zone
			(layers "F.Cu" "B.Cu" "In1.Cu" "In2.Cu" "In3.Cu" "In4.Cu" "In5.Cu" "In6.Cu"
				"In7.Cu" "In8.Cu" "In9.Cu" "In10.Cu"
			)
			(hatch none 0.5)
			(connect_pads
				(clearance 0)
			)
			(min_thickness 0.25)
			(keepout
				(tracks not_allowed)
				(vias allowed)
				(pads allowed)
				(copperpour not_allowed)
				(footprints allowed)
			)
			(placement
				(enabled no)
				(sheetname "")
			)
			(fill
				(thermal_gap 0.5)
				(thermal_bridge_width 0.5)
				(island_removal_mode 0)
			)
			(polygon
				(pts
					(arc
						(start 389.627872 -306.78501)
						(mid 387.672072 -306.78501)
						(end 389.627872 -306.78501)
					)
				)
			)
		)
	)
	(footprint ""
		(layer "F.Cu")
		(at 235.809536 -343.301828)
		(property "Reference" "C63"
			(at 0 0 0)
			(layer "F.SilkS")
			(hide yes)
			(effects
				(font
					(size 1.27 1.27)
				)
			)
		)
		(property "Value" "SCD1U16V2KX-3GP"
			(at 1.1811 -2.7051 0)
			(unlocked yes)
			(layer "F.Fab")
			(hide yes)
			(effects
				(font
					(size 1.016 1.016)
					(thickness 0.1524)
				)
			)
		)
		(property "Device Type" "C402H22"
			(at 1.1811 -4.2291 0)
			(unlocked yes)
			(layer "F.Fab")
			(hide yes)
			(effects
				(font
					(size 1.016 1.016)
					(thickness 0.1524)
				)
			)
		)
		(duplicate_pad_numbers_are_jumpers no)
		(fp_rect
			(start -0.4318 0.9525)
			(end 0.4318 -0.9525)
			(stroke
				(width 0)
				(type default)
			)
			(fill no)
			(layer "F.CrtYd")
		)
		(fp_rect
			(start -0.4318 0.9525)
			(end 0.4318 -0.9525)
			(stroke
				(width 0)
				(type default)
			)
			(fill no)
			(layer "F.Fab")
		)
		(pad "1" smd custom
			(at 0 -0.4445)
			(size 0.1524 0.1524)
			(layers "F.Cu" "F.Mask" "F.Paste")
			(net "P5V_A_4_SENSE")
			(options
				(clearance outline)
				(anchor circle)
			)
			(primitives
				(gr_poly
					(pts
						(arc
							(start 0.3048 -0.2032)
							(mid 0.275042 -0.275042)
							(end 0.2032 -0.3048)
						)
						(arc
							(start -0.2032 -0.3048)
							(mid -0.275042 -0.275042)
							(end -0.3048 -0.2032)
						)
						(arc
							(start -0.3048 0.2032)
							(mid -0.275042 0.275042)
							(end -0.2032 0.3048)
						)
						(arc
							(start 0.2032 0.3048)
							(mid 0.275042 0.275042)
							(end 0.3048 0.2032)
						)
					)
					(width 0)
					(fill yes)
				)
			)
		)
		(pad "2" smd custom
			(at 0 0.4445)
			(size 0.1524 0.1524)
			(layers "F.Cu" "F.Mask" "F.Paste")
			(net "GND")
			(options
				(clearance outline)
				(anchor circle)
			)
			(primitives
				(gr_poly
					(pts
						(arc
							(start 0.3048 -0.2032)
							(mid 0.275042 -0.275042)
							(end 0.2032 -0.3048)
						)
						(arc
							(start -0.2032 -0.3048)
							(mid -0.275042 -0.275042)
							(end -0.3048 -0.2032)
						)
						(arc
							(start -0.3048 0.2032)
							(mid -0.275042 0.275042)
							(end -0.2032 0.3048)
						)
						(arc
							(start 0.2032 0.3048)
							(mid 0.275042 0.275042)
							(end 0.3048 0.2032)
						)
					)
					(width 0)
					(fill yes)
				)
			)
		)
	)
	(footprint ""
		(layer "F.Cu")
		(at 55.044848 -242.20297)
		(property "Reference" "R197"
			(at 0 0 0)
			(layer "F.SilkS")
			(hide yes)
			(effects
				(font
					(size 1.27 1.27)
				)
			)
		)
		(property "Value" "130R3F-GP"
			(at -0.0254 -2.5146 0)
			(unlocked yes)
			(layer "F.Fab")
			(hide yes)
			(effects
				(font
					(size 1.016 1.016)
					(thickness 0.1524)
				)
			)
		)
		(property "Device Type" "R603H22"
			(at -0.0254 -4.0386 0)
			(unlocked yes)
			(layer "F.Fab")
			(hide yes)
			(effects
				(font
					(size 1.016 1.016)
					(thickness 0.1524)
				)
			)
		)
		(duplicate_pad_numbers_are_jumpers no)
		(fp_line
			(start -0.4826 0)
			(end -0.2032 0)
			(stroke
				(width 0.2032)
				(type default)
			)
			(layer "F.SilkS")
		)
		(fp_line
			(start 0.2032 0)
			(end 0.4826 0)
			(stroke
				(width 0.2032)
				(type default)
			)
			(layer "F.SilkS")
		)
		(fp_rect
			(start -0.5842 1.3335)
			(end 0.5842 -1.3335)
			(stroke
				(width 0)
				(type default)
			)
			(fill no)
			(layer "F.CrtYd")
		)
		(fp_rect
			(start -0.5842 1.3335)
			(end 0.5842 -1.3335)
			(stroke
				(width 0)
				(type default)
			)
			(fill no)
			(layer "F.Fab")
		)
		(pad "1" smd custom
			(at 0 -0.762)
			(size 0.2159 0.2159)
			(layers "F.Cu" "F.Mask" "F.Paste")
			(net "P5V_A_1")
			(options
				(clearance outline)
				(anchor circle)
			)
			(primitives
				(gr_poly
					(pts
						(arc
							(start -0.3302 -0.4318)
							(mid -0.402042 -0.402042)
							(end -0.4318 -0.3302)
						)
						(arc
							(start -0.4318 0.3302)
							(mid -0.402042 0.402042)
							(end -0.3302 0.4318)
						)
						(arc
							(start 0.3302 0.4318)
							(mid 0.402042 0.402042)
							(end 0.4318 0.3302)
						)
						(arc
							(start 0.4318 -0.3302)
							(mid 0.402042 -0.402042)
							(end 0.3302 -0.4318)
						)
					)
					(width 0)
					(fill yes)
				)
			)
		)
		(pad "2" smd custom
			(at 0 0.762)
			(size 0.2159 0.2159)
			(layers "F.Cu" "F.Mask" "F.Paste")
			(net "FLT_HDD1")
			(options
				(clearance outline)
				(anchor circle)
			)
			(primitives
				(gr_poly
					(pts
						(arc
							(start -0.3302 -0.4318)
							(mid -0.402042 -0.402042)
							(end -0.4318 -0.3302)
						)
						(arc
							(start -0.4318 0.3302)
							(mid -0.402042 0.402042)
							(end -0.3302 0.4318)
						)
						(arc
							(start 0.3302 0.4318)
							(mid 0.402042 0.402042)
							(end 0.4318 0.3302)
						)
						(arc
							(start 0.4318 -0.3302)
							(mid 0.402042 -0.402042)
							(end 0.3302 -0.4318)
						)
					)
					(width 0)
					(fill yes)
				)
			)
		)
	)
	(footprint ""
		(layer "F.Cu")
		(at 368.862102 -162.792918 90)
		(property "Reference" "D19"
			(at 0 0 90)
			(layer "F.SilkS")
			(hide yes)
			(effects
				(font
					(size 1.27 1.27)
				)
			)
		)
		(property "Value" "RB551V30-GP"
			(at 0 -6.7818 90)
			(unlocked yes)
			(layer "F.Fab")
			(hide yes)
			(effects
				(font
					(size 1.016 1.016)
					(thickness 0.1524)
				)
			)
		)
		(property "Device Type" "SOD323AKH38"
			(at 0 -8.6868 90)
			(unlocked yes)
			(layer "F.Fab")
			(hide yes)
			(effects
				(font
					(size 1.016 1.016)
					(thickness 0.1524)
				)
			)
		)
		(duplicate_pad_numbers_are_jumpers no)
		(fp_line
			(start 0.889 -1.9304)
			(end 0.889 2.159)
			(stroke
				(width 0.1524)
				(type default)
			)
			(layer "F.SilkS")
		)
		(fp_line
			(start -0.889 -1.9304)
			(end 0.889 -1.9304)
			(stroke
				(width 0.1524)
				(type default)
			)
			(layer "F.SilkS")
		)
		(fp_line
			(start 0.762 2.0574)
			(end -0.762 2.0574)
			(stroke
				(width 0.508)
				(type default)
			)
			(layer "F.SilkS")
		)
		(fp_line
			(start 0.889 2.159)
			(end -0.889 2.159)
			(stroke
				(width 0.1524)
				(type default)
			)
			(layer "F.SilkS")
		)
		(fp_line
			(start -0.889 2.159)
			(end -0.889 -1.9304)
			(stroke
				(width 0.1524)
				(type default)
			)
			(layer "F.SilkS")
		)
		(fp_rect
			(start -1.016 2.3114)
			(end 1.016 -2.0066)
			(stroke
				(width 0)
				(type default)
			)
			(fill no)
			(layer "F.CrtYd")
		)
		(fp_poly
			(pts
				(xy -1.016 -2.0066) (xy 1.016 -2.0066) (xy 1.016 2.3114) (xy -1.016 2.3114)
			)
			(stroke
				(width 0)
				(type default)
			)
			(fill no)
			(layer "F.Fab")
		)
		(pad "A" smd rect
			(at 0 -1.143 90)
			(size 0.5588 1.016)
			(layers "F.Cu" "F.Mask" "F.Paste")
			(net "SW_HDD_R19")
		)
		(pad "K" smd rect
			(at 0 1.143 90)
			(size 0.5588 1.016)
			(layers "F.Cu" "F.Mask" "F.Paste")
			(net "SW_HDD_N19")
		)
	)
	(footprint ""
		(layer "F.Cu")
		(at 255.309878 -147.079716 -90)
		(property "Reference" "TP224"
			(at 0 0 270)
			(layer "F.SilkS")
			(hide yes)
			(effects
				(font
					(size 1.27 1.27)
				)
			)
		)
		(property "Value" "TPAD32-GP"
			(at -0.0508 -1.6764 270)
			(unlocked yes)
			(layer "F.Fab")
			(hide yes)
			(effects
				(font
					(size 1.016 1.016)
					(thickness 0.1524)
				)
			)
		)
		(property "Device Type" "TPAD32"
			(at -0.0508 -3.2004 270)
			(unlocked yes)
			(layer "F.Fab")
			(hide yes)
			(effects
				(font
					(size 1.016 1.016)
					(thickness 0.1524)
				)
			)
		)
		(duplicate_pad_numbers_are_jumpers no)
		(fp_poly
			(pts
				(arc
					(start 0 -0.4064)
					(mid 0 0.4064)
					(end 0 -0.4064)
				)
			)
			(stroke
				(width 0)
				(type default)
			)
			(fill no)
			(layer "F.CrtYd")
		)
		(fp_poly
			(pts
				(arc
					(start 0 -0.7112)
					(mid 0 0.7112)
					(end 0 -0.7112)
				)
			)
			(stroke
				(width 0)
				(type default)
			)
			(fill no)
			(layer "F.Fab")
		)
		(pad "1" smd circle
			(at 0 0 270)
			(size 0.8128 0.8128)
			(layers "F.Cu" "F.Mask" "F.Paste")
			(net "TP_SMB_COMP_A_NIC_SCL")
		)
	)
	(footprint ""
		(layer "F.Cu")
		(at 257.328924 -140.851128 90)
		(property "Reference" "R18"
			(at 0 0 90)
			(layer "F.SilkS")
			(hide yes)
			(effects
				(font
					(size 1.27 1.27)
				)
			)
		)
		(property "Value" "4K7R2F-GP"
			(at 0.064008 -3.993896 90)
			(unlocked yes)
			(layer "F.Fab")
			(hide yes)
			(effects
				(font
					(size 1.016 1.016)
					(thickness 0.1524)
				)
			)
		)
		(property "Device Type" "R402H16"
			(at 0.064008 -5.517896 90)
			(unlocked yes)
			(layer "F.Fab")
			(hide yes)
			(effects
				(font
					(size 1.016 1.016)
					(thickness 0.1524)
				)
			)
		)
		(duplicate_pad_numbers_are_jumpers no)
		(fp_line
			(start 0.508 -0.9398)
			(end -0.508 -0.9398)
			(stroke
				(width 0.1524)
				(type default)
			)
			(layer "F.SilkS")
		)
		(fp_line
			(start -0.508 -0.9398)
			(end -0.508 0.9398)
			(stroke
				(width 0.1524)
				(type default)
			)
			(layer "F.SilkS")
		)
		(fp_rect
			(start -0.508 0.9398)
			(end 0.508 -0.9398)
			(stroke
				(width 0)
				(type default)
			)
			(fill no)
			(layer "F.CrtYd")
		)
		(fp_rect
			(start -0.508 0.9398)
			(end 0.508 -0.9398)
			(stroke
				(width 0)
				(type default)
			)
			(fill no)
			(layer "F.Fab")
		)
		(pad "1" smd custom
			(at 0 -0.4445 90)
			(size 0.1397 0.1397)
			(layers "F.Cu" "F.Mask" "F.Paste")
			(net "COMP_A_FAST_THROTTLE_N")
			(options
				(clearance outline)
				(anchor circle)
			)
			(primitives
				(gr_poly
					(pts
						(arc
							(start -0.1778 -0.2794)
							(mid -0.249642 -0.249642)
							(end -0.2794 -0.1778)
						)
						(arc
							(start -0.2794 0.1778)
							(mid -0.249642 0.249642)
							(end -0.1778 0.2794)
						)
						(arc
							(start 0.1778 0.2794)
							(mid 0.249642 0.249642)
							(end 0.2794 0.1778)
						)
						(arc
							(start 0.2794 -0.1778)
							(mid 0.249642 -0.249642)
							(end 0.1778 -0.2794)
						)
					)
					(width 0)
					(fill yes)
				)
			)
		)
		(pad "2" smd custom
			(at 0 0.4445 90)
			(size 0.1397 0.1397)
			(layers "F.Cu" "F.Mask" "F.Paste")
			(net "P3V3_STBY_A")
			(options
				(clearance outline)
				(anchor circle)
			)
			(primitives
				(gr_poly
					(pts
						(arc
							(start -0.1778 -0.2794)
							(mid -0.249642 -0.249642)
							(end -0.2794 -0.1778)
						)
						(arc
							(start -0.2794 0.1778)
							(mid -0.249642 0.249642)
							(end -0.1778 0.2794)
						)
						(arc
							(start 0.1778 0.2794)
							(mid 0.249642 0.249642)
							(end 0.2794 0.1778)
						)
						(arc
							(start 0.2794 -0.1778)
							(mid 0.249642 -0.249642)
							(end 0.1778 -0.2794)
						)
					)
					(width 0)
					(fill yes)
				)
			)
		)
	)
	(footprint ""
		(layer "F.Cu")
		(at 77.96657 -17.825466 180)
		(property "Reference" "R42"
			(at 0 0 180)
			(layer "F.SilkS")
			(hide yes)
			(effects
				(font
					(size 1.27 1.27)
				)
			)
		)
		(property "Value" "100KR2F-L1-GP"
			(at 0.064008 -3.993896 180)
			(unlocked yes)
			(layer "F.Fab")
			(hide yes)
			(effects
				(font
					(size 1.016 1.016)
					(thickness 0.1524)
				)
			)
		)
		(property "Device Type" "R402H16"
			(at 0.064008 -5.517896 180)
			(unlocked yes)
			(layer "F.Fab")
			(hide yes)
			(effects
				(font
					(size 1.016 1.016)
					(thickness 0.1524)
				)
			)
		)
		(duplicate_pad_numbers_are_jumpers no)
		(fp_line
			(start 0.508 -0.9398)
			(end -0.508 -0.9398)
			(stroke
				(width 0.1524)
				(type default)
			)
			(layer "F.SilkS")
		)
		(fp_line
			(start -0.508 -0.9398)
			(end -0.508 0.9398)
			(stroke
				(width 0.1524)
				(type default)
			)
			(layer "F.SilkS")
		)
		(fp_rect
			(start -0.508 0.9398)
			(end 0.508 -0.9398)
			(stroke
				(width 0)
				(type default)
			)
			(fill no)
			(layer "F.CrtYd")
		)
		(fp_rect
			(start -0.508 0.9398)
			(end 0.508 -0.9398)
			(stroke
				(width 0)
				(type default)
			)
			(fill no)
			(layer "F.Fab")
		)
		(pad "1" smd custom
			(at 0 -0.4445 180)
			(size 0.1397 0.1397)
			(layers "F.Cu" "F.Mask" "F.Paste")
			(net "P3V3_STBY_A")
			(options
				(clearance outline)
				(anchor circle)
			)
			(primitives
				(gr_poly
					(pts
						(arc
							(start -0.1778 -0.2794)
							(mid -0.249642 -0.249642)
							(end -0.2794 -0.1778)
						)
						(arc
							(start -0.2794 0.1778)
							(mid -0.249642 0.249642)
							(end -0.1778 0.2794)
						)
						(arc
							(start 0.1778 0.2794)
							(mid 0.249642 0.249642)
							(end 0.2794 0.1778)
						)
						(arc
							(start 0.2794 -0.1778)
							(mid 0.249642 -0.249642)
							(end 0.1778 -0.2794)
						)
					)
					(width 0)
					(fill yes)
				)
			)
		)
		(pad "2" smd custom
			(at 0 0.4445 180)
			(size 0.1397 0.1397)
			(layers "F.Cu" "F.Mask" "F.Paste")
			(net "BMC_A_MISC_ALERT_N")
			(options
				(clearance outline)
				(anchor circle)
			)
			(primitives
				(gr_poly
					(pts
						(arc
							(start -0.1778 -0.2794)
							(mid -0.249642 -0.249642)
							(end -0.2794 -0.1778)
						)
						(arc
							(start -0.2794 0.1778)
							(mid -0.249642 0.249642)
							(end -0.1778 0.2794)
						)
						(arc
							(start 0.1778 0.2794)
							(mid 0.249642 0.249642)
							(end 0.2794 0.1778)
						)
						(arc
							(start 0.2794 -0.1778)
							(mid 0.249642 -0.249642)
							(end 0.1778 -0.2794)
						)
					)
					(width 0)
					(fill yes)
				)
			)
		)
	)
	(footprint ""
		(layer "F.Cu")
		(at 333.57185 -299.405294 -90)
		(property "Reference" "R271"
			(at 0 0 270)
			(layer "F.SilkS")
			(hide yes)
			(effects
				(font
					(size 1.27 1.27)
				)
			)
		)
		(property "Value" "2R6F-GP"
			(at -0.0508 -4.8514 270)
			(unlocked yes)
			(layer "F.Fab")
			(hide yes)
			(effects
				(font
					(size 1.016 1.016)
					(thickness 0.1524)
				)
			)
		)
		(property "Device Type" "R1206H26"
			(at 0 -6.3754 270)
			(unlocked yes)
			(layer "F.Fab")
			(hide yes)
			(effects
				(font
					(size 1.016 1.016)
					(thickness 0.1524)
				)
			)
		)
		(duplicate_pad_numbers_are_jumpers no)
		(fp_line
			(start -1.016 2.2352)
			(end -1.016 -2.2352)
			(stroke
				(width 0.1524)
				(type default)
			)
			(layer "F.SilkS")
		)
		(fp_line
			(start 1.016 2.2352)
			(end -1.016 2.2352)
			(stroke
				(width 0.1524)
				(type default)
			)
			(layer "F.SilkS")
		)
		(fp_line
			(start -1.016 -2.2352)
			(end 1.016 -2.2352)
			(stroke
				(width 0.1524)
				(type default)
			)
			(layer "F.SilkS")
		)
		(fp_line
			(start 1.016 -2.2352)
			(end 1.016 2.2352)
			(stroke
				(width 0.1524)
				(type default)
			)
			(layer "F.SilkS")
		)
		(fp_rect
			(start -1.0922 2.3114)
			(end 1.0922 -2.3114)
			(stroke
				(width 0)
				(type default)
			)
			(fill no)
			(layer "F.CrtYd")
		)
		(fp_poly
			(pts
				(xy -1.0922 -2.3114) (xy 1.0922 -2.3114) (xy 1.0922 2.3114) (xy -1.0922 2.3114)
			)
			(stroke
				(width 0)
				(type default)
			)
			(fill no)
			(layer "F.Fab")
		)
		(pad "1" smd rect
			(at 0 -1.397 270)
			(size 1.651 1.27)
			(layers "F.Cu" "F.Mask" "F.Paste")
			(net "P12V_HDD6")
		)
		(pad "2" smd rect
			(at 0 1.397 270)
			(size 1.651 1.27)
			(layers "F.Cu" "F.Mask" "F.Paste")
			(net "12V_PRE_6")
		)
	)
	(footprint ""
		(layer "F.Cu")
		(at 43.999912 -269.999968)
		(property "Reference" ""
			(at 0 0 0)
			(layer "F.SilkS")
			(hide yes)
			(effects
				(font
					(size 1.27 1.27)
				)
			)
		)
		(property "Value" "*"
			(at -6.3373 -0.4572 0)
			(unlocked yes)
			(layer "F.Fab")
			(hide yes)
			(effects
				(font
					(size 1.016 1.016)
					(thickness 0.1524)
				)
			)
		)
		(duplicate_pad_numbers_are_jumpers no)
		(fp_poly
			(pts
				(arc
					(start 5.0673 0)
					(mid -5.0673 0)
					(end 5.0673 0)
				)
			)
			(stroke
				(width 0)
				(type default)
			)
			(fill no)
			(layer "B.CrtYd")
		)
		(fp_poly
			(pts
				(arc
					(start 5.0673 0)
					(mid -5.0673 0)
					(end 5.0673 0)
				)
			)
			(stroke
				(width 0)
				(type default)
			)
			(fill no)
			(layer "F.CrtYd")
		)
		(fp_poly
			(pts
				(arc
					(start 5.0673 0)
					(mid -5.0673 0)
					(end 5.0673 0)
				)
			)
			(stroke
				(width 0)
				(type default)
			)
			(fill no)
			(layer "B.Fab")
		)
		(fp_poly
			(pts
				(arc
					(start 5.0673 0)
					(mid -5.0673 0)
					(end 5.0673 0)
				)
			)
			(stroke
				(width 0)
				(type default)
			)
			(fill no)
			(layer "F.Fab")
		)
		(pad "1" thru_hole circle
			(at 0 0)
			(size 9.525 9.525)
			(drill 3.556)
			(layers "*.Cu" "*.Mask")
			(remove_unused_layers no)
			(net "Net_92")
			(clearance -2.4765)
			(thermal_gap 0.3048)
			(padstack
				(mode front_inner_back)
				(layer "Inner"
					(shape circle)
					(size 3.9624 3.9624)
					(clearance 0.3048)
				)
				(layer "B.Cu"
					(shape circle)
					(size 9.525 9.525)
					(clearance -2.4765)
				)
			)
		)
		(zone
			(layers "F.Cu" "B.Cu" "In1.Cu" "In2.Cu" "In3.Cu" "In4.Cu" "In5.Cu" "In6.Cu"
				"In7.Cu" "In8.Cu" "In9.Cu" "In10.Cu"
			)
			(hatch none 0.5)
			(connect_pads
				(clearance 0)
			)
			(min_thickness 0.25)
			(keepout
				(tracks not_allowed)
				(vias allowed)
				(pads allowed)
				(copperpour not_allowed)
				(footprints allowed)
			)
			(placement
				(enabled no)
				(sheetname "")
			)
			(fill
				(thermal_gap 0.5)
				(thermal_bridge_width 0.5)
				(island_removal_mode 0)
			)
			(polygon
				(pts
					(arc
						(start 48.762412 -269.999968)
						(mid 39.237412 -269.999968)
						(end 48.762412 -269.999968)
					)
				)
			)
		)
	)
	(footprint ""
		(layer "F.Cu")
		(at 396.34795 -157.585918 180)
		(property "Reference" "R598"
			(at 0 0 180)
			(layer "F.SilkS")
			(hide yes)
			(effects
				(font
					(size 1.27 1.27)
				)
			)
		)
		(property "Value" "1KR2F-3-GP"
			(at 0.064008 -3.993896 180)
			(unlocked yes)
			(layer "F.Fab")
			(hide yes)
			(effects
				(font
					(size 1.016 1.016)
					(thickness 0.1524)
				)
			)
		)
		(property "Device Type" "R402H16"
			(at 0.064008 -5.517896 180)
			(unlocked yes)
			(layer "F.Fab")
			(hide yes)
			(effects
				(font
					(size 1.016 1.016)
					(thickness 0.1524)
				)
			)
		)
		(duplicate_pad_numbers_are_jumpers no)
		(fp_line
			(start 0.508 -0.9398)
			(end -0.508 -0.9398)
			(stroke
				(width 0.1524)
				(type default)
			)
			(layer "F.SilkS")
		)
		(fp_line
			(start -0.508 -0.9398)
			(end -0.508 0.9398)
			(stroke
				(width 0.1524)
				(type default)
			)
			(layer "F.SilkS")
		)
		(fp_rect
			(start -0.508 0.9398)
			(end 0.508 -0.9398)
			(stroke
				(width 0)
				(type default)
			)
			(fill no)
			(layer "F.CrtYd")
		)
		(fp_rect
			(start -0.508 0.9398)
			(end 0.508 -0.9398)
			(stroke
				(width 0)
				(type default)
			)
			(fill no)
			(layer "F.Fab")
		)
		(pad "1" smd custom
			(at 0 -0.4445 180)
			(size 0.1397 0.1397)
			(layers "F.Cu" "F.Mask" "F.Paste")
			(net "P3V3_STBY_A")
			(options
				(clearance outline)
				(anchor circle)
			)
			(primitives
				(gr_poly
					(pts
						(arc
							(start -0.1778 -0.2794)
							(mid -0.249642 -0.249642)
							(end -0.2794 -0.1778)
						)
						(arc
							(start -0.2794 0.1778)
							(mid -0.249642 0.249642)
							(end -0.1778 0.2794)
						)
						(arc
							(start 0.1778 0.2794)
							(mid 0.249642 0.249642)
							(end 0.2794 0.1778)
						)
						(arc
							(start 0.2794 -0.1778)
							(mid 0.249642 -0.249642)
							(end 0.1778 -0.2794)
						)
					)
					(width 0)
					(fill yes)
				)
			)
		)
		(pad "2" smd custom
			(at 0 0.4445 180)
			(size 0.1397 0.1397)
			(layers "F.Cu" "F.Mask" "F.Paste")
			(net "SW_PWR_R_HDD20")
			(options
				(clearance outline)
				(anchor circle)
			)
			(primitives
				(gr_poly
					(pts
						(arc
							(start -0.1778 -0.2794)
							(mid -0.249642 -0.249642)
							(end -0.2794 -0.1778)
						)
						(arc
							(start -0.2794 0.1778)
							(mid -0.249642 0.249642)
							(end -0.1778 0.2794)
						)
						(arc
							(start 0.1778 0.2794)
							(mid 0.249642 0.249642)
							(end 0.2794 0.1778)
						)
						(arc
							(start 0.2794 -0.1778)
							(mid 0.249642 -0.249642)
							(end 0.1778 -0.2794)
						)
					)
					(width 0)
					(fill yes)
				)
			)
		)
	)
	(footprint ""
		(layer "F.Cu")
		(at 364.290102 -164.596318 90)
		(property "Reference" "C295"
			(at 0 0 90)
			(layer "F.SilkS")
			(hide yes)
			(effects
				(font
					(size 1.27 1.27)
				)
			)
		)
		(property "Value" "SCD033U25V2KX-GP"
			(at 1.1811 -2.7051 90)
			(unlocked yes)
			(layer "F.Fab")
			(hide yes)
			(effects
				(font
					(size 1.016 1.016)
					(thickness 0.1524)
				)
			)
		)
		(property "Device Type" "C402H22"
			(at 1.1811 -4.2291 90)
			(unlocked yes)
			(layer "F.Fab")
			(hide yes)
			(effects
				(font
					(size 1.016 1.016)
					(thickness 0.1524)
				)
			)
		)
		(duplicate_pad_numbers_are_jumpers no)
		(fp_rect
			(start -0.4318 0.9525)
			(end 0.4318 -0.9525)
			(stroke
				(width 0)
				(type default)
			)
			(fill no)
			(layer "F.CrtYd")
		)
		(fp_rect
			(start -0.4318 0.9525)
			(end 0.4318 -0.9525)
			(stroke
				(width 0)
				(type default)
			)
			(fill no)
			(layer "F.Fab")
		)
		(pad "1" smd custom
			(at 0 -0.4445 90)
			(size 0.1524 0.1524)
			(layers "F.Cu" "F.Mask" "F.Paste")
			(net "SW_HDD_P19")
			(options
				(clearance outline)
				(anchor circle)
			)
			(primitives
				(gr_poly
					(pts
						(arc
							(start 0.3048 -0.2032)
							(mid 0.275042 -0.275042)
							(end 0.2032 -0.3048)
						)
						(arc
							(start -0.2032 -0.3048)
							(mid -0.275042 -0.275042)
							(end -0.3048 -0.2032)
						)
						(arc
							(start -0.3048 0.2032)
							(mid -0.275042 0.275042)
							(end -0.2032 0.3048)
						)
						(arc
							(start 0.2032 0.3048)
							(mid 0.275042 0.275042)
							(end 0.3048 0.2032)
						)
					)
					(width 0)
					(fill yes)
				)
			)
		)
		(pad "2" smd custom
			(at 0 0.4445 90)
			(size 0.1524 0.1524)
			(layers "F.Cu" "F.Mask" "F.Paste")
			(net "GND")
			(options
				(clearance outline)
				(anchor circle)
			)
			(primitives
				(gr_poly
					(pts
						(arc
							(start 0.3048 -0.2032)
							(mid 0.275042 -0.275042)
							(end 0.2032 -0.3048)
						)
						(arc
							(start -0.2032 -0.3048)
							(mid -0.275042 -0.275042)
							(end -0.3048 -0.2032)
						)
						(arc
							(start -0.3048 0.2032)
							(mid -0.275042 0.275042)
							(end -0.2032 0.3048)
						)
						(arc
							(start 0.2032 0.3048)
							(mid 0.275042 0.275042)
							(end 0.3048 0.2032)
						)
					)
					(width 0)
					(fill yes)
				)
			)
		)
	)
	(footprint ""
		(layer "F.Cu")
		(at 35.5854 -298.704)
		(property "Reference" "TP182"
			(at 0 0 0)
			(layer "F.SilkS")
			(hide yes)
			(effects
				(font
					(size 1.27 1.27)
				)
			)
		)
		(property "Value" "TPAD32-GP"
			(at -0.0508 -1.6764 0)
			(unlocked yes)
			(layer "F.Fab")
			(hide yes)
			(effects
				(font
					(size 1.016 1.016)
					(thickness 0.1524)
				)
			)
		)
		(property "Device Type" "TPAD32"
			(at -0.0508 -3.2004 0)
			(unlocked yes)
			(layer "F.Fab")
			(hide yes)
			(effects
				(font
					(size 1.016 1.016)
					(thickness 0.1524)
				)
			)
		)
		(duplicate_pad_numbers_are_jumpers no)
		(fp_poly
			(pts
				(arc
					(start 0.4064 0)
					(mid -0.4064 0)
					(end 0.4064 0)
				)
			)
			(stroke
				(width 0)
				(type default)
			)
			(fill no)
			(layer "F.CrtYd")
		)
		(fp_poly
			(pts
				(arc
					(start 0.7112 0)
					(mid -0.7112 0)
					(end 0.7112 0)
				)
			)
			(stroke
				(width 0)
				(type default)
			)
			(fill no)
			(layer "F.Fab")
		)
		(pad "1" smd circle
			(at 0 0)
			(size 0.8128 0.8128)
			(layers "F.Cu" "F.Mask" "F.Paste")
			(net "ACT_HDD_0")
		)
	)
	(footprint ""
		(layer "F.Cu")
		(at 381.6096 -139.4841 180)
		(property "Reference" "R1008"
			(at 0 0 180)
			(layer "F.SilkS")
			(hide yes)
			(effects
				(font
					(size 1.27 1.27)
				)
			)
		)
		(property "Value" "100KR2F-L1-GP"
			(at 0.064008 -3.993896 180)
			(unlocked yes)
			(layer "F.Fab")
			(hide yes)
			(effects
				(font
					(size 1.016 1.016)
					(thickness 0.1524)
				)
			)
		)
		(property "Device Type" "R402H16"
			(at 0.064008 -5.517896 180)
			(unlocked yes)
			(layer "F.Fab")
			(hide yes)
			(effects
				(font
					(size 1.016 1.016)
					(thickness 0.1524)
				)
			)
		)
		(duplicate_pad_numbers_are_jumpers no)
		(fp_line
			(start 0.508 -0.9398)
			(end -0.508 -0.9398)
			(stroke
				(width 0.1524)
				(type default)
			)
			(layer "F.SilkS")
		)
		(fp_line
			(start -0.508 -0.9398)
			(end -0.508 0.9398)
			(stroke
				(width 0.1524)
				(type default)
			)
			(layer "F.SilkS")
		)
		(fp_rect
			(start -0.508 0.9398)
			(end 0.508 -0.9398)
			(stroke
				(width 0)
				(type default)
			)
			(fill no)
			(layer "F.CrtYd")
		)
		(fp_rect
			(start -0.508 0.9398)
			(end 0.508 -0.9398)
			(stroke
				(width 0)
				(type default)
			)
			(fill no)
			(layer "F.Fab")
		)
		(pad "1" smd custom
			(at 0 -0.4445 180)
			(size 0.1397 0.1397)
			(layers "F.Cu" "F.Mask" "F.Paste")
			(net "COMP_B_PWR_EN")
			(options
				(clearance outline)
				(anchor circle)
			)
			(primitives
				(gr_poly
					(pts
						(arc
							(start -0.1778 -0.2794)
							(mid -0.249642 -0.249642)
							(end -0.2794 -0.1778)
						)
						(arc
							(start -0.2794 0.1778)
							(mid -0.249642 0.249642)
							(end -0.1778 0.2794)
						)
						(arc
							(start 0.1778 0.2794)
							(mid 0.249642 0.249642)
							(end 0.2794 0.1778)
						)
						(arc
							(start 0.2794 -0.1778)
							(mid 0.249642 -0.249642)
							(end 0.1778 -0.2794)
						)
					)
					(width 0)
					(fill yes)
				)
			)
		)
		(pad "2" smd custom
			(at 0 0.4445 180)
			(size 0.1397 0.1397)
			(layers "F.Cu" "F.Mask" "F.Paste")
			(net "GND")
			(options
				(clearance outline)
				(anchor circle)
			)
			(primitives
				(gr_poly
					(pts
						(arc
							(start -0.1778 -0.2794)
							(mid -0.249642 -0.249642)
							(end -0.2794 -0.1778)
						)
						(arc
							(start -0.2794 0.1778)
							(mid -0.249642 0.249642)
							(end -0.1778 0.2794)
						)
						(arc
							(start 0.1778 0.2794)
							(mid 0.249642 0.249642)
							(end 0.2794 0.1778)
						)
						(arc
							(start 0.2794 -0.1778)
							(mid 0.249642 -0.249642)
							(end 0.1778 -0.2794)
						)
					)
					(width 0)
					(fill yes)
				)
			)
		)
	)
	(footprint ""
		(layer "F.Cu")
		(at 463.1309 -275.735542 180)
		(property "Reference" "R374"
			(at 0 0 180)
			(layer "F.SilkS")
			(hide yes)
			(effects
				(font
					(size 1.27 1.27)
				)
			)
		)
		(property "Value" "4K7R2J-2-GP"
			(at 0.064008 -3.993896 180)
			(unlocked yes)
			(layer "F.Fab")
			(hide yes)
			(effects
				(font
					(size 1.016 1.016)
					(thickness 0.1524)
				)
			)
		)
		(property "Device Type" "R402H16"
			(at 0.064008 -5.517896 180)
			(unlocked yes)
			(layer "F.Fab")
			(hide yes)
			(effects
				(font
					(size 1.016 1.016)
					(thickness 0.1524)
				)
			)
		)
		(duplicate_pad_numbers_are_jumpers no)
		(fp_line
			(start 0.508 -0.9398)
			(end -0.508 -0.9398)
			(stroke
				(width 0.1524)
				(type default)
			)
			(layer "F.SilkS")
		)
		(fp_line
			(start -0.508 -0.9398)
			(end -0.508 0.9398)
			(stroke
				(width 0.1524)
				(type default)
			)
			(layer "F.SilkS")
		)
		(fp_rect
			(start -0.508 0.9398)
			(end 0.508 -0.9398)
			(stroke
				(width 0)
				(type default)
			)
			(fill no)
			(layer "F.CrtYd")
		)
		(fp_rect
			(start -0.508 0.9398)
			(end 0.508 -0.9398)
			(stroke
				(width 0)
				(type default)
			)
			(fill no)
			(layer "F.Fab")
		)
		(pad "1" smd custom
			(at 0 -0.4445 180)
			(size 0.1397 0.1397)
			(layers "F.Cu" "F.Mask" "F.Paste")
			(net "P12V_A")
			(options
				(clearance outline)
				(anchor circle)
			)
			(primitives
				(gr_poly
					(pts
						(arc
							(start -0.1778 -0.2794)
							(mid -0.249642 -0.249642)
							(end -0.2794 -0.1778)
						)
						(arc
							(start -0.2794 0.1778)
							(mid -0.249642 0.249642)
							(end -0.1778 0.2794)
						)
						(arc
							(start 0.1778 0.2794)
							(mid 0.249642 0.249642)
							(end 0.2794 0.1778)
						)
						(arc
							(start 0.2794 -0.1778)
							(mid 0.249642 -0.249642)
							(end 0.1778 -0.2794)
						)
					)
					(width 0)
					(fill yes)
				)
			)
		)
		(pad "2" smd custom
			(at 0 0.4445 180)
			(size 0.1397 0.1397)
			(layers "F.Cu" "F.Mask" "F.Paste")
			(net "SW_HDD_R10")
			(options
				(clearance outline)
				(anchor circle)
			)
			(primitives
				(gr_poly
					(pts
						(arc
							(start -0.1778 -0.2794)
							(mid -0.249642 -0.249642)
							(end -0.2794 -0.1778)
						)
						(arc
							(start -0.2794 0.1778)
							(mid -0.249642 0.249642)
							(end -0.1778 0.2794)
						)
						(arc
							(start 0.1778 0.2794)
							(mid 0.249642 0.249642)
							(end 0.2794 0.1778)
						)
						(arc
							(start 0.2794 -0.1778)
							(mid 0.249642 -0.249642)
							(end 0.1778 -0.2794)
						)
					)
					(width 0)
					(fill yes)
				)
			)
		)
	)
	(footprint ""
		(layer "F.Cu")
		(at 226.8347 -377.0122 180)
		(property "Reference" "R174"
			(at 0 0 180)
			(layer "F.SilkS")
			(hide yes)
			(effects
				(font
					(size 1.27 1.27)
				)
			)
		)
		(property "Value" "4K7R2F-GP"
			(at 0.064008 -3.993896 180)
			(unlocked yes)
			(layer "F.Fab")
			(hide yes)
			(effects
				(font
					(size 1.016 1.016)
					(thickness 0.1524)
				)
			)
		)
		(property "Device Type" "R402H16"
			(at 0.064008 -5.517896 180)
			(unlocked yes)
			(layer "F.Fab")
			(hide yes)
			(effects
				(font
					(size 1.016 1.016)
					(thickness 0.1524)
				)
			)
		)
		(duplicate_pad_numbers_are_jumpers no)
		(fp_line
			(start 0.508 -0.9398)
			(end -0.508 -0.9398)
			(stroke
				(width 0.1524)
				(type default)
			)
			(layer "F.SilkS")
		)
		(fp_line
			(start -0.508 -0.9398)
			(end -0.508 0.9398)
			(stroke
				(width 0.1524)
				(type default)
			)
			(layer "F.SilkS")
		)
		(fp_rect
			(start -0.508 0.9398)
			(end 0.508 -0.9398)
			(stroke
				(width 0)
				(type default)
			)
			(fill no)
			(layer "F.CrtYd")
		)
		(fp_rect
			(start -0.508 0.9398)
			(end 0.508 -0.9398)
			(stroke
				(width 0)
				(type default)
			)
			(fill no)
			(layer "F.Fab")
		)
		(pad "1" smd custom
			(at 0 -0.4445 180)
			(size 0.1397 0.1397)
			(layers "F.Cu" "F.Mask" "F.Paste")
			(net "IO_EXP3_HDD_FAULT_A0")
			(options
				(clearance outline)
				(anchor circle)
			)
			(primitives
				(gr_poly
					(pts
						(arc
							(start -0.1778 -0.2794)
							(mid -0.249642 -0.249642)
							(end -0.2794 -0.1778)
						)
						(arc
							(start -0.2794 0.1778)
							(mid -0.249642 0.249642)
							(end -0.1778 0.2794)
						)
						(arc
							(start 0.1778 0.2794)
							(mid 0.249642 0.249642)
							(end 0.2794 0.1778)
						)
						(arc
							(start 0.2794 -0.1778)
							(mid 0.249642 -0.249642)
							(end 0.1778 -0.2794)
						)
					)
					(width 0)
					(fill yes)
				)
			)
		)
		(pad "2" smd custom
			(at 0 0.4445 180)
			(size 0.1397 0.1397)
			(layers "F.Cu" "F.Mask" "F.Paste")
			(net "GND")
			(options
				(clearance outline)
				(anchor circle)
			)
			(primitives
				(gr_poly
					(pts
						(arc
							(start -0.1778 -0.2794)
							(mid -0.249642 -0.249642)
							(end -0.2794 -0.1778)
						)
						(arc
							(start -0.2794 0.1778)
							(mid -0.249642 0.249642)
							(end -0.1778 0.2794)
						)
						(arc
							(start 0.1778 0.2794)
							(mid 0.249642 0.249642)
							(end 0.2794 0.1778)
						)
						(arc
							(start 0.2794 -0.1778)
							(mid 0.249642 -0.249642)
							(end 0.1778 -0.2794)
						)
					)
					(width 0)
					(fill yes)
				)
			)
		)
	)
	(footprint ""
		(layer "F.Cu")
		(at 32.508952 -162.749992 -90)
		(property "Reference" "VIA46"
			(at 0 0 270)
			(layer "F.SilkS")
			(hide yes)
			(effects
				(font
					(size 1.27 1.27)
				)
			)
		)
		(property "Value" "100OHM-8L-1D6MM-L18L16-GP"
			(at -3.7211 -4.5085 270)
			(unlocked yes)
			(layer "F.Fab")
			(hide yes)
			(effects
				(font
					(size 1.016 1.016)
					(thickness 0.1524)
				)
			)
		)
		(property "Device Type" "VIA-PCIE-4P-394076"
			(at -3.7211 -6.0325 270)
			(unlocked yes)
			(layer "F.Fab")
			(hide yes)
			(effects
				(font
					(size 1.016 1.016)
					(thickness 0.1524)
				)
			)
		)
		(duplicate_pad_numbers_are_jumpers no)
		(fp_rect
			(start -1.9685 0.381)
			(end 1.9685 -0.381)
			(stroke
				(width 0)
				(type default)
			)
			(fill no)
			(layer "F.CrtYd")
		)
		(fp_rect
			(start -1.9685 0.381)
			(end 1.9685 -0.381)
			(stroke
				(width 0)
				(type default)
			)
			(fill no)
			(layer "F.Fab")
		)
		(pad "1" thru_hole circle
			(at -1.5875 0 270)
			(size 0.508 0.508)
			(drill 0.254)
			(layers "*.Cu" "*.Mask")
			(remove_unused_layers no)
			(net "GND")
			(clearance 0.127)
			(thermal_gap 0.127)
		)
		(pad "2" thru_hole circle
			(at -0.5715 0 270)
			(size 0.508 0.508)
			(drill 0.254)
			(layers "*.Cu" "*.Mask")
			(remove_unused_layers no)
			(net "PHY_DRV_A_TO_SCC_A_12_DP")
			(clearance 0.127)
			(thermal_gap 0.127)
		)
		(pad "3" thru_hole circle
			(at 0.5715 0 270)
			(size 0.508 0.508)
			(drill 0.254)
			(layers "*.Cu" "*.Mask")
			(remove_unused_layers no)
			(net "PHY_DRV_A_TO_SCC_A_12_DN")
			(clearance 0.127)
			(thermal_gap 0.127)
		)
		(pad "4" thru_hole circle
			(at 1.5875 0 270)
			(size 0.508 0.508)
			(drill 0.254)
			(layers "*.Cu" "*.Mask")
			(remove_unused_layers no)
			(net "GND")
			(clearance 0.127)
			(thermal_gap 0.127)
		)
	)
	(footprint ""
		(layer "F.Cu")
		(at 164.835078 -181.406038 90)
		(property "Reference" "R472"
			(at 0 0 90)
			(layer "F.SilkS")
			(hide yes)
			(effects
				(font
					(size 1.27 1.27)
				)
			)
		)
		(property "Value" "4K7R2J-2-GP"
			(at 0.064008 -3.993896 90)
			(unlocked yes)
			(layer "F.Fab")
			(hide yes)
			(effects
				(font
					(size 1.016 1.016)
					(thickness 0.1524)
				)
			)
		)
		(property "Device Type" "R402H16"
			(at 0.064008 -5.517896 90)
			(unlocked yes)
			(layer "F.Fab")
			(hide yes)
			(effects
				(font
					(size 1.016 1.016)
					(thickness 0.1524)
				)
			)
		)
		(duplicate_pad_numbers_are_jumpers no)
		(fp_line
			(start 0.508 -0.9398)
			(end -0.508 -0.9398)
			(stroke
				(width 0.1524)
				(type default)
			)
			(layer "F.SilkS")
		)
		(fp_line
			(start -0.508 -0.9398)
			(end -0.508 0.9398)
			(stroke
				(width 0.1524)
				(type default)
			)
			(layer "F.SilkS")
		)
		(fp_rect
			(start -0.508 0.9398)
			(end 0.508 -0.9398)
			(stroke
				(width 0)
				(type default)
			)
			(fill no)
			(layer "F.CrtYd")
		)
		(fp_rect
			(start -0.508 0.9398)
			(end 0.508 -0.9398)
			(stroke
				(width 0)
				(type default)
			)
			(fill no)
			(layer "F.Fab")
		)
		(pad "1" smd custom
			(at 0 -0.4445 90)
			(size 0.1397 0.1397)
			(layers "F.Cu" "F.Mask" "F.Paste")
			(net "DRIVE_A_5_ACT")
			(options
				(clearance outline)
				(anchor circle)
			)
			(primitives
				(gr_poly
					(pts
						(arc
							(start -0.1778 -0.2794)
							(mid -0.249642 -0.249642)
							(end -0.2794 -0.1778)
						)
						(arc
							(start -0.2794 0.1778)
							(mid -0.249642 0.249642)
							(end -0.1778 0.2794)
						)
						(arc
							(start 0.1778 0.2794)
							(mid 0.249642 0.249642)
							(end 0.2794 0.1778)
						)
						(arc
							(start 0.2794 -0.1778)
							(mid 0.249642 -0.249642)
							(end 0.1778 -0.2794)
						)
					)
					(width 0)
					(fill yes)
				)
			)
		)
		(pad "2" smd custom
			(at 0 0.4445 90)
			(size 0.1397 0.1397)
			(layers "F.Cu" "F.Mask" "F.Paste")
			(net "GND")
			(options
				(clearance outline)
				(anchor circle)
			)
			(primitives
				(gr_poly
					(pts
						(arc
							(start -0.1778 -0.2794)
							(mid -0.249642 -0.249642)
							(end -0.2794 -0.1778)
						)
						(arc
							(start -0.2794 0.1778)
							(mid -0.249642 0.249642)
							(end -0.1778 0.2794)
						)
						(arc
							(start 0.1778 0.2794)
							(mid 0.249642 0.249642)
							(end 0.2794 0.1778)
						)
						(arc
							(start 0.2794 -0.1778)
							(mid 0.249642 -0.249642)
							(end 0.1778 -0.2794)
						)
					)
					(width 0)
					(fill yes)
				)
			)
		)
	)
	(footprint ""
		(layer "F.Cu")
		(at 158.663386 -159.219392 90)
		(property "Reference" "C246"
			(at 0 0 90)
			(layer "F.SilkS")
			(hide yes)
			(effects
				(font
					(size 1.27 1.27)
				)
			)
		)
		(property "Value" "SCD01U16V1KX-GP"
			(at -2.8321 -1.7399 90)
			(unlocked yes)
			(layer "F.Fab")
			(hide yes)
			(effects
				(font
					(size 1.016 1.016)
					(thickness 0.1524)
				)
			)
		)
		(property "Device Type" "C0201H13"
			(at -2.8321 -3.2639 90)
			(unlocked yes)
			(layer "F.Fab")
			(hide yes)
			(effects
				(font
					(size 1.016 1.016)
					(thickness 0.1524)
				)
			)
		)
		(duplicate_pad_numbers_are_jumpers no)
		(fp_rect
			(start -0.2794 0.6477)
			(end 0.2794 -0.6477)
			(stroke
				(width 0)
				(type default)
			)
			(fill no)
			(layer "F.CrtYd")
		)
		(fp_rect
			(start -0.2794 0.6477)
			(end 0.2794 -0.6477)
			(stroke
				(width 0)
				(type default)
			)
			(fill no)
			(layer "F.Fab")
		)
		(pad "1" smd custom
			(at 0 -0.2794 90)
			(size 0.0762 0.0762)
			(layers "F.Cu" "F.Mask" "F.Paste")
			(net "SAS_HDD_RX_N16")
			(options
				(clearance outline)
				(anchor circle)
			)
			(primitives
				(gr_poly
					(pts
						(arc
							(start 0.1524 -0.127)
							(mid 0.137521 -0.162921)
							(end 0.1016 -0.1778)
						)
						(arc
							(start -0.1016 -0.1778)
							(mid -0.137521 -0.162921)
							(end -0.1524 -0.127)
						)
						(arc
							(start -0.1524 0.127)
							(mid -0.137521 0.162921)
							(end -0.1016 0.1778)
						)
						(arc
							(start 0.1016 0.1778)
							(mid 0.137521 0.162921)
							(end 0.1524 0.127)
						)
					)
					(width 0)
					(fill yes)
				)
			)
		)
		(pad "2" smd custom
			(at 0 0.2794 90)
			(size 0.0762 0.0762)
			(layers "F.Cu" "F.Mask" "F.Paste")
			(net "PHY_SCC_A_TO_DRV_A_16_DN")
			(options
				(clearance outline)
				(anchor circle)
			)
			(primitives
				(gr_poly
					(pts
						(arc
							(start 0.1524 -0.127)
							(mid 0.137521 -0.162921)
							(end 0.1016 -0.1778)
						)
						(arc
							(start -0.1016 -0.1778)
							(mid -0.137521 -0.162921)
							(end -0.1524 -0.127)
						)
						(arc
							(start -0.1524 0.127)
							(mid -0.137521 0.162921)
							(end -0.1016 0.1778)
						)
						(arc
							(start 0.1016 0.1778)
							(mid 0.137521 0.162921)
							(end 0.1524 0.127)
						)
					)
					(width 0)
					(fill yes)
				)
			)
		)
	)
	(footprint ""
		(layer "F.Cu")
		(at 335.788 -42.585894 180)
		(property "Reference" "R831"
			(at 0 0 180)
			(layer "F.SilkS")
			(hide yes)
			(effects
				(font
					(size 1.27 1.27)
				)
			)
		)
		(property "Value" "0R2J-2-GP"
			(at 0.064008 -3.993896 180)
			(unlocked yes)
			(layer "F.Fab")
			(hide yes)
			(effects
				(font
					(size 1.016 1.016)
					(thickness 0.1524)
				)
			)
		)
		(property "Device Type" "R402H16"
			(at 0.064008 -5.517896 180)
			(unlocked yes)
			(layer "F.Fab")
			(hide yes)
			(effects
				(font
					(size 1.016 1.016)
					(thickness 0.1524)
				)
			)
		)
		(duplicate_pad_numbers_are_jumpers no)
		(fp_line
			(start 0.508 -0.9398)
			(end -0.508 -0.9398)
			(stroke
				(width 0.1524)
				(type default)
			)
			(layer "F.SilkS")
		)
		(fp_line
			(start -0.508 -0.9398)
			(end -0.508 0.9398)
			(stroke
				(width 0.1524)
				(type default)
			)
			(layer "F.SilkS")
		)
		(fp_rect
			(start -0.508 0.9398)
			(end 0.508 -0.9398)
			(stroke
				(width 0)
				(type default)
			)
			(fill no)
			(layer "F.CrtYd")
		)
		(fp_rect
			(start -0.508 0.9398)
			(end 0.508 -0.9398)
			(stroke
				(width 0)
				(type default)
			)
			(fill no)
			(layer "F.Fab")
		)
		(pad "1" smd custom
			(at 0 -0.4445 180)
			(size 0.1397 0.1397)
			(layers "F.Cu" "F.Mask" "F.Paste")
			(net "DRIVE_A_30_PWR")
			(options
				(clearance outline)
				(anchor circle)
			)
			(primitives
				(gr_poly
					(pts
						(arc
							(start -0.1778 -0.2794)
							(mid -0.249642 -0.249642)
							(end -0.2794 -0.1778)
						)
						(arc
							(start -0.2794 0.1778)
							(mid -0.249642 0.249642)
							(end -0.1778 0.2794)
						)
						(arc
							(start 0.1778 0.2794)
							(mid 0.249642 0.249642)
							(end 0.2794 0.1778)
						)
						(arc
							(start 0.2794 -0.1778)
							(mid 0.249642 -0.249642)
							(end 0.1778 -0.2794)
						)
					)
					(width 0)
					(fill yes)
				)
			)
		)
		(pad "2" smd custom
			(at 0 0.4445 180)
			(size 0.1397 0.1397)
			(layers "F.Cu" "F.Mask" "F.Paste")
			(net "SW_PWR_R_HDD30")
			(options
				(clearance outline)
				(anchor circle)
			)
			(primitives
				(gr_poly
					(pts
						(arc
							(start -0.1778 -0.2794)
							(mid -0.249642 -0.249642)
							(end -0.2794 -0.1778)
						)
						(arc
							(start -0.2794 0.1778)
							(mid -0.249642 0.249642)
							(end -0.1778 0.2794)
						)
						(arc
							(start 0.1778 0.2794)
							(mid 0.249642 0.249642)
							(end 0.2794 0.1778)
						)
						(arc
							(start 0.2794 -0.1778)
							(mid 0.249642 -0.249642)
							(end 0.1778 -0.2794)
						)
					)
					(width 0)
					(fill yes)
				)
			)
		)
	)
	(footprint ""
		(layer "F.Cu")
		(at 46.283118 -127.78867 180)
		(property "Reference" "Q240"
			(at 0 0 180)
			(layer "F.SilkS")
			(hide yes)
			(effects
				(font
					(size 1.27 1.27)
				)
			)
		)
		(property "Value" "2N7002K-2-GP"
			(at 0.127 -8.9662 180)
			(unlocked yes)
			(layer "F.Fab")
			(hide yes)
			(effects
				(font
					(size 1.016 1.016)
					(thickness 0.1524)
				)
			)
		)
		(property "Device Type" "SOT23DGS2D4H44"
			(at 0.127 -10.4902 180)
			(unlocked yes)
			(layer "F.Fab")
			(hide yes)
			(effects
				(font
					(size 1.016 1.016)
					(thickness 0.1524)
				)
			)
		)
		(duplicate_pad_numbers_are_jumpers no)
		(fp_line
			(start 1.651 1.778)
			(end 1.651 -1.778)
			(stroke
				(width 0.1524)
				(type default)
			)
			(layer "F.SilkS")
		)
		(fp_line
			(start 1.651 -1.778)
			(end -1.651 -1.778)
			(stroke
				(width 0.1524)
				(type default)
			)
			(layer "F.SilkS")
		)
		(fp_line
			(start -1.651 1.778)
			(end 1.651 1.778)
			(stroke
				(width 0.1524)
				(type default)
			)
			(layer "F.SilkS")
		)
		(fp_line
			(start -1.651 -1.778)
			(end -1.651 1.778)
			(stroke
				(width 0.1524)
				(type default)
			)
			(layer "F.SilkS")
		)
		(fp_poly
			(pts
				(xy -1.778 1.8796) (xy -1.778 -1.8796) (xy 1.778 -1.8796) (xy 1.778 1.8796)
			)
			(stroke
				(width 0)
				(type default)
			)
			(fill no)
			(layer "F.CrtYd")
		)
		(fp_poly
			(pts
				(xy -1.778 1.8796) (xy -1.778 -1.8796) (xy 1.778 -1.8796) (xy 1.778 1.8796)
			)
			(stroke
				(width 0)
				(type default)
			)
			(fill no)
			(layer "F.Fab")
		)
		(pad "D" smd custom
			(at 0 -0.9525 180)
			(size 0.1905 0.1905)
			(layers "F.Cu" "F.Mask" "F.Paste")
			(net "FLT_HDD13_N")
			(options
				(clearance outline)
				(anchor circle)
			)
			(primitives
				(gr_poly
					(pts
						(arc
							(start -0.1778 0.5715)
							(mid -0.321484 0.511984)
							(end -0.381 0.3683)
						)
						(arc
							(start -0.381 -0.3683)
							(mid -0.321484 -0.511984)
							(end -0.1778 -0.5715)
						)
						(arc
							(start 0.1778 -0.5715)
							(mid 0.321484 -0.511984)
							(end 0.381 -0.3683)
						)
						(arc
							(start 0.381 0.3683)
							(mid 0.321484 0.511984)
							(end 0.1778 0.5715)
						)
					)
					(width 0)
					(fill yes)
				)
			)
		)
		(pad "G" smd custom
			(at -0.98425 0.9525 180)
			(size 0.1905 0.1905)
			(layers "F.Cu" "F.Mask" "F.Paste")
			(net "DRIVE_A_13_FLT_LED")
			(options
				(clearance outline)
				(anchor circle)
			)
			(primitives
				(gr_poly
					(pts
						(arc
							(start -0.1778 0.5715)
							(mid -0.321484 0.511984)
							(end -0.381 0.3683)
						)
						(arc
							(start -0.381 -0.3683)
							(mid -0.321484 -0.511984)
							(end -0.1778 -0.5715)
						)
						(arc
							(start 0.1778 -0.5715)
							(mid 0.321484 -0.511984)
							(end 0.381 -0.3683)
						)
						(arc
							(start 0.381 0.3683)
							(mid 0.321484 0.511984)
							(end 0.1778 0.5715)
						)
					)
					(width 0)
					(fill yes)
				)
			)
		)
		(pad "S" smd custom
			(at 0.98425 0.9525 180)
			(size 0.1905 0.1905)
			(layers "F.Cu" "F.Mask" "F.Paste")
			(net "GND")
			(options
				(clearance outline)
				(anchor circle)
			)
			(primitives
				(gr_poly
					(pts
						(arc
							(start -0.1778 0.5715)
							(mid -0.321484 0.511984)
							(end -0.381 0.3683)
						)
						(arc
							(start -0.381 -0.3683)
							(mid -0.321484 -0.511984)
							(end -0.1778 -0.5715)
						)
						(arc
							(start 0.1778 -0.5715)
							(mid 0.321484 -0.511984)
							(end 0.381 -0.3683)
						)
						(arc
							(start 0.381 0.3683)
							(mid 0.321484 0.511984)
							(end 0.1778 0.5715)
						)
					)
					(width 0)
					(fill yes)
				)
			)
		)
	)
	(footprint ""
		(layer "F.Cu")
		(at 64.013334 -43.660568 90)
		(property "Reference" "C364"
			(at 0 0 90)
			(layer "F.SilkS")
			(hide yes)
			(effects
				(font
					(size 1.27 1.27)
				)
			)
		)
		(property "Value" "SCD01U16V1KX-GP"
			(at -2.8321 -1.7399 90)
			(unlocked yes)
			(layer "F.Fab")
			(hide yes)
			(effects
				(font
					(size 1.016 1.016)
					(thickness 0.1524)
				)
			)
		)
		(property "Device Type" "C0201H13"
			(at -2.8321 -3.2639 90)
			(unlocked yes)
			(layer "F.Fab")
			(hide yes)
			(effects
				(font
					(size 1.016 1.016)
					(thickness 0.1524)
				)
			)
		)
		(duplicate_pad_numbers_are_jumpers no)
		(fp_rect
			(start -0.2794 0.6477)
			(end 0.2794 -0.6477)
			(stroke
				(width 0)
				(type default)
			)
			(fill no)
			(layer "F.CrtYd")
		)
		(fp_rect
			(start -0.2794 0.6477)
			(end 0.2794 -0.6477)
			(stroke
				(width 0)
				(type default)
			)
			(fill no)
			(layer "F.Fab")
		)
		(pad "1" smd custom
			(at 0 -0.2794 90)
			(size 0.0762 0.0762)
			(layers "F.Cu" "F.Mask" "F.Paste")
			(net "SAS_HDD_RX_P25")
			(options
				(clearance outline)
				(anchor circle)
			)
			(primitives
				(gr_poly
					(pts
						(arc
							(start 0.1524 -0.127)
							(mid 0.137521 -0.162921)
							(end 0.1016 -0.1778)
						)
						(arc
							(start -0.1016 -0.1778)
							(mid -0.137521 -0.162921)
							(end -0.1524 -0.127)
						)
						(arc
							(start -0.1524 0.127)
							(mid -0.137521 0.162921)
							(end -0.1016 0.1778)
						)
						(arc
							(start 0.1016 0.1778)
							(mid 0.137521 0.162921)
							(end 0.1524 0.127)
						)
					)
					(width 0)
					(fill yes)
				)
			)
		)
		(pad "2" smd custom
			(at 0 0.2794 90)
			(size 0.0762 0.0762)
			(layers "F.Cu" "F.Mask" "F.Paste")
			(net "PHY_SCC_A_TO_DRV_A_25_DP")
			(options
				(clearance outline)
				(anchor circle)
			)
			(primitives
				(gr_poly
					(pts
						(arc
							(start 0.1524 -0.127)
							(mid 0.137521 -0.162921)
							(end 0.1016 -0.1778)
						)
						(arc
							(start -0.1016 -0.1778)
							(mid -0.137521 -0.162921)
							(end -0.1524 -0.127)
						)
						(arc
							(start -0.1524 0.127)
							(mid -0.137521 0.162921)
							(end -0.1016 0.1778)
						)
						(arc
							(start 0.1016 0.1778)
							(mid 0.137521 0.162921)
							(end 0.1524 0.127)
						)
					)
					(width 0)
					(fill yes)
				)
			)
		)
	)
	(footprint ""
		(layer "F.Cu")
		(at 388.649972 -172.909992 -90)
		(property "Reference" "HDDSAS20"
			(at 0 0 270)
			(layer "F.SilkS")
			(hide yes)
			(effects
				(font
					(size 1.27 1.27)
				)
			)
		)
		(property "Value" "SKT-SAS15P-14P-45-GP"
			(at -20.7645 -8.9789 270)
			(unlocked yes)
			(layer "F.Fab")
			(hide yes)
			(effects
				(font
					(size 1.016 1.016)
					(thickness 0.1524)
				)
			)
		)
		(property "Device Type" "10120818-001C-TRLF"
			(at -20.7645 -10.5029 270)
			(unlocked yes)
			(layer "F.Fab")
			(hide yes)
			(effects
				(font
					(size 1.016 1.016)
					(thickness 0.1524)
				)
			)
		)
		(duplicate_pad_numbers_are_jumpers no)
		(fp_line
			(start 1.651 4.2926)
			(end 1.651 3.0099)
			(stroke
				(width 0.1524)
				(type default)
			)
			(layer "F.SilkS")
		)
		(fp_line
			(start 8.509 4.2926)
			(end 1.651 4.2926)
			(stroke
				(width 0.1524)
				(type default)
			)
			(layer "F.SilkS")
		)
		(fp_line
			(start -23.4188 3.0099)
			(end -23.4188 -3.2512)
			(stroke
				(width 0.1524)
				(type default)
			)
			(layer "F.SilkS")
		)
		(fp_line
			(start 1.651 3.0099)
			(end -23.4188 3.0099)
			(stroke
				(width 0.1524)
				(type default)
			)
			(layer "F.SilkS")
		)
		(fp_line
			(start 8.509 3.0099)
			(end 8.509 4.2926)
			(stroke
				(width 0.1524)
				(type default)
			)
			(layer "F.SilkS")
		)
		(fp_line
			(start 23.4188 3.0099)
			(end 8.509 3.0099)
			(stroke
				(width 0.1524)
				(type default)
			)
			(layer "F.SilkS")
		)
		(fp_line
			(start -23.4188 -3.2512)
			(end 23.4188 -3.2512)
			(stroke
				(width 0.1524)
				(type default)
			)
			(layer "F.SilkS")
		)
		(fp_line
			(start 23.4188 -3.2512)
			(end 23.4188 3.0099)
			(stroke
				(width 0.1524)
				(type default)
			)
			(layer "F.SilkS")
		)
		(fp_line
			(start 15.5067 -3.3401)
			(end 16.2687 -3.3401)
			(stroke
				(width 0.3302)
				(type default)
			)
			(layer "F.SilkS")
		)
		(fp_poly
			(pts
				(xy 15.868904 -3.230372) (xy 16.503904 -3.865372) (xy 15.233904 -3.865372)
			)
			(stroke
				(width 0)
				(type default)
			)
			(fill yes)
			(layer "F.SilkS")
		)
		(fp_poly
			(pts
				(xy -22.8727 -2.7559) (xy 22.8727 -2.7559) (xy 22.8727 2.7559) (xy 8.255 2.7559) (xy 8.255 3.5179)
				(xy 1.905 3.5179) (xy 1.905 2.7559) (xy -22.8727 2.7559)
			)
			(stroke
				(width 0)
				(type default)
			)
			(fill no)
			(layer "F.CrtYd")
		)
		(fp_poly
			(pts
				(xy 1.397 4.5466) (xy 1.397 3.2639) (xy -23.6728 3.2639) (xy -23.6728 -3.5052) (xy 23.6728 -3.5052)
				(xy 23.6728 -0.00635) (xy 22.8727 -0.00635) (xy 22.8727 -2.7559) (xy -22.8727 -2.7559) (xy -22.8727 2.7559)
				(xy 1.905 2.7559) (xy 1.905 3.5179) (xy 8.255 3.5179) (xy 8.255 2.7559) (xy 22.8727 2.7559) (xy 22.8727 0.00635)
				(xy 23.6728 0.00635) (xy 23.6728 3.2639) (xy 8.763 3.2639) (xy 8.763 4.5466)
			)
			(stroke
				(width 0)
				(type default)
			)
			(fill no)
			(layer "F.CrtYd")
		)
		(fp_poly
			(pts
				(xy 1.397 4.5466) (xy 1.397 3.2639) (xy -23.6728 3.2639) (xy -23.6728 -3.5052) (xy 23.6728 -3.5052)
				(xy 23.6728 3.2639) (xy 8.763 3.2639) (xy 8.763 4.5466)
			)
			(stroke
				(width 0)
				(type default)
			)
			(fill no)
			(layer "F.Fab")
		)
		(pad "" np_thru_hole circle
			(at -18.874994 0 270)
			(size 0.254 0.254)
			(drill 1.3462)
			(layers "*.Cu" "*.Mask")
			(clearance 0.9017)
			(thermal_gap 0.9017)
		)
		(pad "" np_thru_hole circle
			(at 18.874994 0 270)
			(size 0.254 0.254)
			(drill 0.9398)
			(layers "*.Cu" "*.Mask")
			(clearance 0.6985)
			(thermal_gap 0.6985)
		)
		(pad "G1" smd rect
			(at 21.874988 0 270)
			(size 2.5908 2.5908)
			(layers "F.Cu" "F.Mask" "F.Paste")
			(net "GND")
		)
		(pad "G2" smd rect
			(at -21.874988 0 270)
			(size 2.5908 2.5908)
			(layers "F.Cu" "F.Mask" "F.Paste")
			(net "GND")
		)
		(pad "P1" smd rect
			(at 1.905 -1.82499 270)
			(size 0.6096 2.3622)
			(layers "F.Cu" "F.Mask" "F.Paste")
			(net "Net_2111")
		)
		(pad "P2" smd rect
			(at 0.635 -1.82499 270)
			(size 0.6096 2.3622)
			(layers "F.Cu" "F.Mask" "F.Paste")
			(net "Net_2112")
		)
		(pad "P3" smd rect
			(at -0.635 -1.82499 270)
			(size 0.6096 2.3622)
			(layers "F.Cu" "F.Mask" "F.Paste")
			(net "Net_2113")
		)
		(pad "P4" smd rect
			(at -1.905 -1.82499 270)
			(size 0.6096 2.3622)
			(layers "F.Cu" "F.Mask" "F.Paste")
			(net "GND")
		)
		(pad "P5" smd rect
			(at -3.175 -1.82499 270)
			(size 0.6096 2.3622)
			(layers "F.Cu" "F.Mask" "F.Paste")
			(net "HDD_PRSNT_20")
		)
		(pad "P6" smd rect
			(at -4.445 -1.82499 270)
			(size 0.6096 2.3622)
			(layers "F.Cu" "F.Mask" "F.Paste")
			(net "GND")
		)
		(pad "P7" smd rect
			(at -5.715 -1.82499 270)
			(size 0.6096 2.3622)
			(layers "F.Cu" "F.Mask" "F.Paste")
			(net "5V_PRE_20")
		)
		(pad "P8" smd rect
			(at -6.985 -1.82499 270)
			(size 0.6096 2.3622)
			(layers "F.Cu" "F.Mask" "F.Paste")
			(net "P5V_HDD20")
		)
		(pad "P9" smd rect
			(at -8.255 -1.82499 270)
			(size 0.6096 2.3622)
			(layers "F.Cu" "F.Mask" "F.Paste")
			(net "P5V_HDD20")
		)
		(pad "P10" smd rect
			(at -9.525 -1.82499 270)
			(size 0.6096 2.3622)
			(layers "F.Cu" "F.Mask" "F.Paste")
			(net "GND")
		)
		(pad "P11" smd rect
			(at -10.795 -1.82499 270)
			(size 0.6096 2.3622)
			(layers "F.Cu" "F.Mask" "F.Paste")
			(net "ACT_HDD_20")
		)
		(pad "P12" smd rect
			(at -12.065 -1.82499 270)
			(size 0.6096 2.3622)
			(layers "F.Cu" "F.Mask" "F.Paste")
			(net "GND")
		)
		(pad "P13" smd rect
			(at -13.335 -1.82499 270)
			(size 0.6096 2.3622)
			(layers "F.Cu" "F.Mask" "F.Paste")
			(net "12V_PRE_20")
		)
		(pad "P14" smd rect
			(at -14.605 -1.82499 270)
			(size 0.6096 2.3622)
			(layers "F.Cu" "F.Mask" "F.Paste")
			(net "P12V_HDD20")
		)
		(pad "P15" smd rect
			(at -15.875 -1.82499 270)
			(size 0.6096 2.3622)
			(layers "F.Cu" "F.Mask" "F.Paste")
			(net "P12V_HDD20")
		)
		(pad "S1" smd rect
			(at 15.875 -1.82499 270)
			(size 0.6096 2.3622)
			(layers "F.Cu" "F.Mask" "F.Paste")
			(net "GND")
		)
		(pad "S2" smd rect
			(at 14.605 -1.82499 270)
			(size 0.6096 2.3622)
			(layers "F.Cu" "F.Mask" "F.Paste")
			(net "SAS_HDD_RX_P20")
		)
		(pad "S3" smd rect
			(at 13.335 -1.82499 270)
			(size 0.6096 2.3622)
			(layers "F.Cu" "F.Mask" "F.Paste")
			(net "SAS_HDD_RX_N20")
		)
		(pad "S4" smd rect
			(at 12.065 -1.82499 270)
			(size 0.6096 2.3622)
			(layers "F.Cu" "F.Mask" "F.Paste")
			(net "GND")
		)
		(pad "S5" smd rect
			(at 10.795 -1.82499 270)
			(size 0.6096 2.3622)
			(layers "F.Cu" "F.Mask" "F.Paste")
			(net "PHY_DRV_A_TO_SCC_A_20_DN")
		)
		(pad "S6" smd rect
			(at 9.525 -1.82499 270)
			(size 0.6096 2.3622)
			(layers "F.Cu" "F.Mask" "F.Paste")
			(net "PHY_DRV_A_TO_SCC_A_20_DP")
		)
		(pad "S7" smd rect
			(at 8.255 -1.82499 270)
			(size 0.6096 2.3622)
			(layers "F.Cu" "F.Mask" "F.Paste")
			(net "GND")
		)
		(pad "S8" smd rect
			(at 7.480046 2.845054 270)
			(size 0.508 2.3622)
			(layers "F.Cu" "F.Mask" "F.Paste")
			(net "GND")
		)
		(pad "S9" smd rect
			(at 6.679946 2.845054 270)
			(size 0.508 2.3622)
			(layers "F.Cu" "F.Mask" "F.Paste")
			(net "Net_458")
		)
		(pad "S10" smd rect
			(at 5.8801 2.845054 270)
			(size 0.508 2.3622)
			(layers "F.Cu" "F.Mask" "F.Paste")
			(net "Net_350")
		)
		(pad "S11" smd rect
			(at 5.08 2.845054 270)
			(size 0.508 2.3622)
			(layers "F.Cu" "F.Mask" "F.Paste")
			(net "GND")
		)
		(pad "S12" smd rect
			(at 4.2799 2.845054 270)
			(size 0.508 2.3622)
			(layers "F.Cu" "F.Mask" "F.Paste")
			(net "Net_386")
		)
		(pad "S13" smd rect
			(at 3.480054 2.845054 270)
			(size 0.508 2.3622)
			(layers "F.Cu" "F.Mask" "F.Paste")
			(net "Net_422")
		)
		(pad "S14" smd rect
			(at 2.679954 2.845054 270)
			(size 0.508 2.3622)
			(layers "F.Cu" "F.Mask" "F.Paste")
			(net "GND")
		)
		(zone
			(layer "F.Cu")
			(hatch none 0.5)
			(connect_pads
				(clearance 0)
			)
			(min_thickness 0.25)
			(keepout
				(tracks allowed)
				(vias not_allowed)
				(pads allowed)
				(copperpour not_allowed)
				(footprints allowed)
			)
			(placement
				(enabled no)
				(sheetname "")
			)
			(fill
				(thermal_gap 0.5)
				(thermal_bridge_width 0.5)
				(island_removal_mode 0)
			)
			(polygon
				(pts
					(xy 392.307572 -189.648592) (xy 385.233672 -189.648592) (xy 385.233672 -196.582792) (xy 386.338572 -196.582792)
					(xy 386.338572 -192.467992) (xy 390.961372 -192.467992) (xy 390.961372 -196.582792) (xy 392.307572 -196.582792)
				)
			)
		)
		(zone
			(layer "F.Cu")
			(hatch none 0.5)
			(connect_pads
				(clearance 0)
			)
			(min_thickness 0.25)
			(keepout
				(tracks not_allowed)
				(vias allowed)
				(pads allowed)
				(copperpour not_allowed)
				(footprints allowed)
			)
			(placement
				(enabled no)
				(sheetname "")
			)
			(fill
				(thermal_gap 0.5)
				(thermal_bridge_width 0.5)
				(island_removal_mode 0)
			)
			(polygon
				(pts
					(xy 392.307572 -189.648592) (xy 385.233672 -189.648592) (xy 385.233672 -196.582792) (xy 386.338572 -196.582792)
					(xy 386.338572 -192.467992) (xy 390.961372 -192.467992) (xy 390.961372 -196.582792) (xy 392.307572 -196.582792)
				)
			)
		)
		(zone
			(layer "F.Cu")
			(hatch none 0.5)
			(connect_pads
				(clearance 0)
			)
			(min_thickness 0.25)
			(keepout
				(tracks allowed)
				(vias not_allowed)
				(pads allowed)
				(copperpour not_allowed)
				(footprints allowed)
			)
			(placement
				(enabled no)
				(sheetname "")
			)
			(fill
				(thermal_gap 0.5)
				(thermal_bridge_width 0.5)
				(island_removal_mode 0)
			)
			(polygon
				(pts
					(xy 392.307572 -156.171392) (xy 385.233672 -156.171392) (xy 385.233672 -149.237192) (xy 386.338572 -149.237192)
					(xy 386.338572 -153.351992) (xy 390.961372 -153.351992) (xy 390.961372 -149.237192) (xy 392.307572 -149.237192)
				)
			)
		)
		(zone
			(layer "F.Cu")
			(hatch none 0.5)
			(connect_pads
				(clearance 0)
			)
			(min_thickness 0.25)
			(keepout
				(tracks not_allowed)
				(vias allowed)
				(pads allowed)
				(copperpour not_allowed)
				(footprints allowed)
			)
			(placement
				(enabled no)
				(sheetname "")
			)
			(fill
				(thermal_gap 0.5)
				(thermal_bridge_width 0.5)
				(island_removal_mode 0)
			)
			(polygon
				(pts
					(xy 392.307572 -156.171392) (xy 385.233672 -156.171392) (xy 385.233672 -149.237192) (xy 386.338572 -149.237192)
					(xy 386.338572 -153.351992) (xy 390.961372 -153.351992) (xy 390.961372 -149.237192) (xy 392.307572 -149.237192)
				)
			)
		)
		(zone
			(layers "F.Cu" "B.Cu" "In1.Cu" "In2.Cu" "In3.Cu" "In4.Cu" "In5.Cu" "In6.Cu"
				"In7.Cu" "In8.Cu" "In9.Cu" "In10.Cu"
			)
			(hatch none 0.5)
			(connect_pads
				(clearance 0)
			)
			(min_thickness 0.25)
			(keepout
				(tracks not_allowed)
				(vias allowed)
				(pads allowed)
				(copperpour not_allowed)
				(footprints allowed)
			)
			(placement
				(enabled no)
				(sheetname "")
			)
			(fill
				(thermal_gap 0.5)
				(thermal_bridge_width 0.5)
				(island_removal_mode 0)
			)
			(polygon
				(pts
					(arc
						(start 389.424672 -154.034998)
						(mid 387.875272 -154.034998)
						(end 389.424672 -154.034998)
					)
				)
			)
		)
		(zone
			(layers "F.Cu" "B.Cu" "In1.Cu" "In2.Cu" "In3.Cu" "In4.Cu" "In5.Cu" "In6.Cu"
				"In7.Cu" "In8.Cu" "In9.Cu" "In10.Cu"
			)
			(hatch none 0.5)
			(connect_pads
				(clearance 0)
			)
			(min_thickness 0.25)
			(keepout
				(tracks not_allowed)
				(vias allowed)
				(pads allowed)
				(copperpour not_allowed)
				(footprints allowed)
			)
			(placement
				(enabled no)
				(sheetname "")
			)
			(fill
				(thermal_gap 0.5)
				(thermal_bridge_width 0.5)
				(island_removal_mode 0)
			)
			(polygon
				(pts
					(arc
						(start 389.627872 -191.784986)
						(mid 387.672072 -191.784986)
						(end 389.627872 -191.784986)
					)
				)
			)
		)
	)
	(footprint ""
		(layer "F.Cu")
		(at 51.980846 -48.554894 180)
		(property "Reference" "Q151"
			(at 0 0 180)
			(layer "F.SilkS")
			(hide yes)
			(effects
				(font
					(size 1.27 1.27)
				)
			)
		)
		(property "Value" "2N7002KDW-GP"
			(at -2.3622 -8.2042 180)
			(unlocked yes)
			(layer "F.Fab")
			(hide yes)
			(effects
				(font
					(size 1.016 1.016)
					(thickness 0.1524)
				)
			)
		)
		(property "Device Type" "SOT-363H44"
			(at -2.3622 -10.1092 180)
			(unlocked yes)
			(layer "F.Fab")
			(hide yes)
			(effects
				(font
					(size 1.016 1.016)
					(thickness 0.1524)
				)
			)
		)
		(duplicate_pad_numbers_are_jumpers no)
		(fp_line
			(start 1.4478 1.7018)
			(end 1.4478 -1.7018)
			(stroke
				(width 0.1524)
				(type default)
			)
			(layer "F.SilkS")
		)
		(fp_line
			(start 1.4478 -1.7018)
			(end -1.4478 -1.7018)
			(stroke
				(width 0.1524)
				(type default)
			)
			(layer "F.SilkS")
		)
		(fp_line
			(start -1.27 1.524)
			(end -1.27 0.6604)
			(stroke
				(width 0.4826)
				(type default)
			)
			(layer "F.SilkS")
		)
		(fp_line
			(start -1.4478 1.7018)
			(end 1.4478 1.7018)
			(stroke
				(width 0.1524)
				(type default)
			)
			(layer "F.SilkS")
		)
		(fp_line
			(start -1.4478 -1.7018)
			(end -1.4478 1.7018)
			(stroke
				(width 0.1524)
				(type default)
			)
			(layer "F.SilkS")
		)
		(fp_poly
			(pts
				(xy -1.524 -1.778) (xy 1.524 -1.778) (xy 1.524 1.778) (xy -1.524 1.778)
			)
			(stroke
				(width 0)
				(type default)
			)
			(fill no)
			(layer "F.CrtYd")
		)
		(fp_poly
			(pts
				(xy -1.524 -1.778) (xy 1.524 -1.778) (xy 1.524 1.778) (xy -1.524 1.778)
			)
			(stroke
				(width 0)
				(type default)
			)
			(fill no)
			(layer "F.Fab")
		)
		(pad "1" smd rect
			(at -0.65024 0.9398 180)
			(size 0.4064 1.016)
			(layers "F.Cu" "F.Mask" "F.Paste")
			(net "GND")
		)
		(pad "2" smd rect
			(at 0 0.9398 180)
			(size 0.4064 1.016)
			(layers "F.Cu" "F.Mask" "F.Paste")
			(net "SW_PWR_R_HDD25")
		)
		(pad "3" smd rect
			(at 0.65024 0.9398 180)
			(size 0.4064 1.016)
			(layers "F.Cu" "F.Mask" "F.Paste")
			(net "SW_HDD_P25")
		)
		(pad "4" smd rect
			(at 0.65024 -0.9398 180)
			(size 0.4064 1.016)
			(layers "F.Cu" "F.Mask" "F.Paste")
			(net "GND")
		)
		(pad "5" smd rect
			(at 0 -0.9398 180)
			(size 0.4064 1.016)
			(layers "F.Cu" "F.Mask" "F.Paste")
			(net "SW_HDD_G25")
		)
		(pad "6" smd rect
			(at -0.65024 -0.9398 180)
			(size 0.4064 1.016)
			(layers "F.Cu" "F.Mask" "F.Paste")
			(net "SW_HDD_R25")
		)
	)
	(footprint ""
		(layer "F.Cu")
		(at 156.275532 -137.85723 90)
		(property "Reference" "R1052"
			(at 0 0 90)
			(layer "F.SilkS")
			(hide yes)
			(effects
				(font
					(size 1.27 1.27)
				)
			)
		)
		(property "Value" "10R2F-L-GP"
			(at 0.064008 -3.993896 90)
			(unlocked yes)
			(layer "F.Fab")
			(hide yes)
			(effects
				(font
					(size 1.016 1.016)
					(thickness 0.1524)
				)
			)
		)
		(property "Device Type" "R402H14"
			(at 0.064008 -5.517896 90)
			(unlocked yes)
			(layer "F.Fab")
			(hide yes)
			(effects
				(font
					(size 1.016 1.016)
					(thickness 0.1524)
				)
			)
		)
		(duplicate_pad_numbers_are_jumpers no)
		(fp_line
			(start 0.508 -0.9398)
			(end -0.508 -0.9398)
			(stroke
				(width 0.1524)
				(type default)
			)
			(layer "F.SilkS")
		)
		(fp_line
			(start -0.508 -0.9398)
			(end -0.508 0.9398)
			(stroke
				(width 0.1524)
				(type default)
			)
			(layer "F.SilkS")
		)
		(fp_rect
			(start -0.508 0.9398)
			(end 0.508 -0.9398)
			(stroke
				(width 0)
				(type default)
			)
			(fill no)
			(layer "F.CrtYd")
		)
		(fp_rect
			(start -0.508 0.9398)
			(end 0.508 -0.9398)
			(stroke
				(width 0)
				(type default)
			)
			(fill no)
			(layer "F.Fab")
		)
		(pad "1" smd custom
			(at 0 -0.4445 90)
			(size 0.1397 0.1397)
			(layers "F.Cu" "F.Mask" "F.Paste")
			(net "MB0_CM_SENSE_R1_P")
			(options
				(clearance outline)
				(anchor circle)
			)
			(primitives
				(gr_poly
					(pts
						(arc
							(start -0.1778 -0.2794)
							(mid -0.249642 -0.249642)
							(end -0.2794 -0.1778)
						)
						(arc
							(start -0.2794 0.1778)
							(mid -0.249642 0.249642)
							(end -0.1778 0.2794)
						)
						(arc
							(start 0.1778 0.2794)
							(mid 0.249642 0.249642)
							(end 0.2794 0.1778)
						)
						(arc
							(start 0.2794 -0.1778)
							(mid 0.249642 -0.249642)
							(end 0.1778 -0.2794)
						)
					)
					(width 0)
					(fill yes)
				)
			)
		)
		(pad "2" smd custom
			(at 0 0.4445 90)
			(size 0.1397 0.1397)
			(layers "F.Cu" "F.Mask" "F.Paste")
			(net "MB0_CM_SENSE_P")
			(options
				(clearance outline)
				(anchor circle)
			)
			(primitives
				(gr_poly
					(pts
						(arc
							(start -0.1778 -0.2794)
							(mid -0.249642 -0.249642)
							(end -0.2794 -0.1778)
						)
						(arc
							(start -0.2794 0.1778)
							(mid -0.249642 0.249642)
							(end -0.1778 0.2794)
						)
						(arc
							(start 0.1778 0.2794)
							(mid 0.249642 0.249642)
							(end 0.2794 0.1778)
						)
						(arc
							(start 0.2794 -0.1778)
							(mid 0.249642 -0.249642)
							(end 0.1778 -0.2794)
						)
					)
					(width 0)
					(fill yes)
				)
			)
		)
	)
	(footprint ""
		(layer "F.Cu")
		(at 282.067 -272.3134)
		(property "Reference" "R122"
			(at 0 0 0)
			(layer "F.SilkS")
			(hide yes)
			(effects
				(font
					(size 1.27 1.27)
				)
			)
		)
		(property "Value" "4K7R2F-GP"
			(at 0.064008 -3.993896 0)
			(unlocked yes)
			(layer "F.Fab")
			(hide yes)
			(effects
				(font
					(size 1.016 1.016)
					(thickness 0.1524)
				)
			)
		)
		(property "Device Type" "R402H16"
			(at 0.064008 -5.517896 0)
			(unlocked yes)
			(layer "F.Fab")
			(hide yes)
			(effects
				(font
					(size 1.016 1.016)
					(thickness 0.1524)
				)
			)
		)
		(duplicate_pad_numbers_are_jumpers no)
		(fp_line
			(start -0.508 -0.9398)
			(end -0.508 0.9398)
			(stroke
				(width 0.1524)
				(type default)
			)
			(layer "F.SilkS")
		)
		(fp_line
			(start 0.508 -0.9398)
			(end -0.508 -0.9398)
			(stroke
				(width 0.1524)
				(type default)
			)
			(layer "F.SilkS")
		)
		(fp_rect
			(start -0.508 0.9398)
			(end 0.508 -0.9398)
			(stroke
				(width 0)
				(type default)
			)
			(fill no)
			(layer "F.CrtYd")
		)
		(fp_rect
			(start -0.508 0.9398)
			(end 0.508 -0.9398)
			(stroke
				(width 0)
				(type default)
			)
			(fill no)
			(layer "F.Fab")
		)
		(pad "1" smd custom
			(at 0 -0.4445)
			(size 0.1397 0.1397)
			(layers "F.Cu" "F.Mask" "F.Paste")
			(net "IO_EXP2_HDD_FAULT_INT_N")
			(options
				(clearance outline)
				(anchor circle)
			)
			(primitives
				(gr_poly
					(pts
						(arc
							(start -0.1778 -0.2794)
							(mid -0.249642 -0.249642)
							(end -0.2794 -0.1778)
						)
						(arc
							(start -0.2794 0.1778)
							(mid -0.249642 0.249642)
							(end -0.1778 0.2794)
						)
						(arc
							(start 0.1778 0.2794)
							(mid 0.249642 0.249642)
							(end 0.2794 0.1778)
						)
						(arc
							(start 0.2794 -0.1778)
							(mid 0.249642 -0.249642)
							(end 0.1778 -0.2794)
						)
					)
					(width 0)
					(fill yes)
				)
			)
		)
		(pad "2" smd custom
			(at 0 0.4445)
			(size 0.1397 0.1397)
			(layers "F.Cu" "F.Mask" "F.Paste")
			(net "P3V3_STBY_A")
			(options
				(clearance outline)
				(anchor circle)
			)
			(primitives
				(gr_poly
					(pts
						(arc
							(start -0.1778 -0.2794)
							(mid -0.249642 -0.249642)
							(end -0.2794 -0.1778)
						)
						(arc
							(start -0.2794 0.1778)
							(mid -0.249642 0.249642)
							(end -0.1778 0.2794)
						)
						(arc
							(start 0.1778 0.2794)
							(mid 0.249642 0.249642)
							(end 0.2794 0.1778)
						)
						(arc
							(start 0.2794 -0.1778)
							(mid 0.249642 -0.249642)
							(end 0.1778 -0.2794)
						)
					)
					(width 0)
					(fill yes)
				)
			)
		)
	)
	(footprint ""
		(layer "F.Cu")
		(at 414.639252 -158.939992 90)
		(property "Reference" "VIA10"
			(at 0 0 90)
			(layer "F.SilkS")
			(hide yes)
			(effects
				(font
					(size 1.27 1.27)
				)
			)
		)
		(property "Value" "100OHM-8L-1D6MM-L18L16-GP"
			(at -3.7211 -4.5085 90)
			(unlocked yes)
			(layer "F.Fab")
			(hide yes)
			(effects
				(font
					(size 1.016 1.016)
					(thickness 0.1524)
				)
			)
		)
		(property "Device Type" "VIA-PCIE-4P-394076"
			(at -3.7211 -6.0325 90)
			(unlocked yes)
			(layer "F.Fab")
			(hide yes)
			(effects
				(font
					(size 1.016 1.016)
					(thickness 0.1524)
				)
			)
		)
		(duplicate_pad_numbers_are_jumpers no)
		(fp_rect
			(start -1.9685 0.381)
			(end 1.9685 -0.381)
			(stroke
				(width 0)
				(type default)
			)
			(fill no)
			(layer "F.CrtYd")
		)
		(fp_rect
			(start -1.9685 0.381)
			(end 1.9685 -0.381)
			(stroke
				(width 0)
				(type default)
			)
			(fill no)
			(layer "F.Fab")
		)
		(pad "1" thru_hole circle
			(at -1.5875 0 90)
			(size 0.508 0.508)
			(drill 0.254)
			(layers "*.Cu" "*.Mask")
			(remove_unused_layers no)
			(net "GND")
			(clearance 0.127)
			(thermal_gap 0.127)
		)
		(pad "2" thru_hole circle
			(at -0.5715 0 90)
			(size 0.508 0.508)
			(drill 0.254)
			(layers "*.Cu" "*.Mask")
			(remove_unused_layers no)
			(net "PHY_SCC_A_TO_DRV_A_21_DP")
			(clearance 0.127)
			(thermal_gap 0.127)
		)
		(pad "3" thru_hole circle
			(at 0.5715 0 90)
			(size 0.508 0.508)
			(drill 0.254)
			(layers "*.Cu" "*.Mask")
			(remove_unused_layers no)
			(net "PHY_SCC_A_TO_DRV_A_21_DN")
			(clearance 0.127)
			(thermal_gap 0.127)
		)
		(pad "4" thru_hole circle
			(at 1.5875 0 90)
			(size 0.508 0.508)
			(drill 0.254)
			(layers "*.Cu" "*.Mask")
			(remove_unused_layers no)
			(net "GND")
			(clearance 0.127)
			(thermal_gap 0.127)
		)
	)
	(footprint ""
		(layer "F.Cu")
		(at 377.2154 -133.5786 90)
		(property "Reference" "R1075"
			(at 0 0 90)
			(layer "F.SilkS")
			(hide yes)
			(effects
				(font
					(size 1.27 1.27)
				)
			)
		)
		(property "Value" "0R2J-2-GP"
			(at 0.064008 -3.993896 90)
			(unlocked yes)
			(layer "F.Fab")
			(hide yes)
			(effects
				(font
					(size 1.016 1.016)
					(thickness 0.1524)
				)
			)
		)
		(property "Device Type" "R402H16"
			(at 0.064008 -5.517896 90)
			(unlocked yes)
			(layer "F.Fab")
			(hide yes)
			(effects
				(font
					(size 1.016 1.016)
					(thickness 0.1524)
				)
			)
		)
		(duplicate_pad_numbers_are_jumpers no)
		(fp_line
			(start 0.508 -0.9398)
			(end -0.508 -0.9398)
			(stroke
				(width 0.1524)
				(type default)
			)
			(layer "F.SilkS")
		)
		(fp_line
			(start -0.508 -0.9398)
			(end -0.508 0.9398)
			(stroke
				(width 0.1524)
				(type default)
			)
			(layer "F.SilkS")
		)
		(fp_rect
			(start -0.508 0.9398)
			(end 0.508 -0.9398)
			(stroke
				(width 0)
				(type default)
			)
			(fill no)
			(layer "F.CrtYd")
		)
		(fp_rect
			(start -0.508 0.9398)
			(end 0.508 -0.9398)
			(stroke
				(width 0)
				(type default)
			)
			(fill no)
			(layer "F.Fab")
		)
		(pad "1" smd custom
			(at 0 -0.4445 90)
			(size 0.1397 0.1397)
			(layers "F.Cu" "F.Mask" "F.Paste")
			(net "MB1_CM_ADR2_R")
			(options
				(clearance outline)
				(anchor circle)
			)
			(primitives
				(gr_poly
					(pts
						(arc
							(start -0.1778 -0.2794)
							(mid -0.249642 -0.249642)
							(end -0.2794 -0.1778)
						)
						(arc
							(start -0.2794 0.1778)
							(mid -0.249642 0.249642)
							(end -0.1778 0.2794)
						)
						(arc
							(start 0.1778 0.2794)
							(mid 0.249642 0.249642)
							(end 0.2794 0.1778)
						)
						(arc
							(start 0.2794 -0.1778)
							(mid 0.249642 -0.249642)
							(end 0.1778 -0.2794)
						)
					)
					(width 0)
					(fill yes)
				)
			)
		)
		(pad "2" smd custom
			(at 0 0.4445 90)
			(size 0.1397 0.1397)
			(layers "F.Cu" "F.Mask" "F.Paste")
			(net "AGND_CURRENT_MONOB")
			(options
				(clearance outline)
				(anchor circle)
			)
			(primitives
				(gr_poly
					(pts
						(arc
							(start -0.1778 -0.2794)
							(mid -0.249642 -0.249642)
							(end -0.2794 -0.1778)
						)
						(arc
							(start -0.2794 0.1778)
							(mid -0.249642 0.249642)
							(end -0.1778 0.2794)
						)
						(arc
							(start 0.1778 0.2794)
							(mid 0.249642 0.249642)
							(end 0.2794 0.1778)
						)
						(arc
							(start 0.2794 -0.1778)
							(mid 0.249642 -0.249642)
							(end 0.1778 -0.2794)
						)
					)
					(width 0)
					(fill yes)
				)
			)
		)
	)
	(footprint ""
		(layer "F.Cu")
		(at 440.694826 -242.25377)
		(property "Reference" "R265"
			(at 0 0 0)
			(layer "F.SilkS")
			(hide yes)
			(effects
				(font
					(size 1.27 1.27)
				)
			)
		)
		(property "Value" "130R3F-GP"
			(at -0.0254 -2.5146 0)
			(unlocked yes)
			(layer "F.Fab")
			(hide yes)
			(effects
				(font
					(size 1.016 1.016)
					(thickness 0.1524)
				)
			)
		)
		(property "Device Type" "R603H22"
			(at -0.0254 -4.0386 0)
			(unlocked yes)
			(layer "F.Fab")
			(hide yes)
			(effects
				(font
					(size 1.016 1.016)
					(thickness 0.1524)
				)
			)
		)
		(duplicate_pad_numbers_are_jumpers no)
		(fp_line
			(start -0.4826 0)
			(end -0.2032 0)
			(stroke
				(width 0.2032)
				(type default)
			)
			(layer "F.SilkS")
		)
		(fp_line
			(start 0.2032 0)
			(end 0.4826 0)
			(stroke
				(width 0.2032)
				(type default)
			)
			(layer "F.SilkS")
		)
		(fp_rect
			(start -0.5842 1.3335)
			(end 0.5842 -1.3335)
			(stroke
				(width 0)
				(type default)
			)
			(fill no)
			(layer "F.CrtYd")
		)
		(fp_rect
			(start -0.5842 1.3335)
			(end 0.5842 -1.3335)
			(stroke
				(width 0)
				(type default)
			)
			(fill no)
			(layer "F.Fab")
		)
		(pad "1" smd custom
			(at 0 -0.762)
			(size 0.2159 0.2159)
			(layers "F.Cu" "F.Mask" "F.Paste")
			(net "P5V_A_3")
			(options
				(clearance outline)
				(anchor circle)
			)
			(primitives
				(gr_poly
					(pts
						(arc
							(start -0.3302 -0.4318)
							(mid -0.402042 -0.402042)
							(end -0.4318 -0.3302)
						)
						(arc
							(start -0.4318 0.3302)
							(mid -0.402042 0.402042)
							(end -0.3302 0.4318)
						)
						(arc
							(start 0.3302 0.4318)
							(mid 0.402042 0.402042)
							(end 0.4318 0.3302)
						)
						(arc
							(start 0.4318 -0.3302)
							(mid 0.402042 -0.402042)
							(end 0.3302 -0.4318)
						)
					)
					(width 0)
					(fill yes)
				)
			)
		)
		(pad "2" smd custom
			(at 0 0.762)
			(size 0.2159 0.2159)
			(layers "F.Cu" "F.Mask" "F.Paste")
			(net "FLT_HDD10")
			(options
				(clearance outline)
				(anchor circle)
			)
			(primitives
				(gr_poly
					(pts
						(arc
							(start -0.3302 -0.4318)
							(mid -0.402042 -0.402042)
							(end -0.4318 -0.3302)
						)
						(arc
							(start -0.4318 0.3302)
							(mid -0.402042 0.402042)
							(end -0.3302 0.4318)
						)
						(arc
							(start 0.3302 0.4318)
							(mid 0.402042 0.402042)
							(end 0.4318 0.3302)
						)
						(arc
							(start 0.4318 -0.3302)
							(mid 0.402042 -0.402042)
							(end 0.3302 -0.4318)
						)
					)
					(width 0)
					(fill yes)
				)
			)
		)
	)
	(footprint ""
		(layer "F.Cu")
		(at 80.900016 -209.399886)
		(property "Reference" "FLED3"
			(at 0 0 0)
			(layer "F.SilkS")
			(hide yes)
			(effects
				(font
					(size 1.27 1.27)
				)
			)
		)
		(property "Value" "LED-BY-19-GP"
			(at -2.132076 1.414018 0)
			(unlocked yes)
			(layer "F.Fab")
			(hide yes)
			(effects
				(font
					(size 1.016 1.016)
					(thickness 0.1524)
				)
			)
		)
		(property "Device Type" "LED-1615-4PH26"
			(at -2.132076 -0.109982 0)
			(unlocked yes)
			(layer "F.Fab")
			(hide yes)
			(effects
				(font
					(size 1.016 1.016)
					(thickness 0.1524)
				)
			)
		)
		(duplicate_pad_numbers_are_jumpers no)
		(fp_line
			(start -1.2954 0.254)
			(end -1.2954 1.6002)
			(stroke
				(width 0.508)
				(type default)
			)
			(layer "F.SilkS")
		)
		(fp_line
			(start -1.2954 1.6002)
			(end 1.2954 1.6002)
			(stroke
				(width 0.508)
				(type default)
			)
			(layer "F.SilkS")
		)
		(fp_line
			(start -1.1176 -1.4224)
			(end 1.1176 -1.4224)
			(stroke
				(width 0.1524)
				(type default)
			)
			(layer "F.SilkS")
		)
		(fp_line
			(start -1.1176 1.4224)
			(end -1.1176 -1.4224)
			(stroke
				(width 0.1524)
				(type default)
			)
			(layer "F.SilkS")
		)
		(fp_line
			(start 1.1176 -1.4224)
			(end 1.1176 1.4224)
			(stroke
				(width 0.1524)
				(type default)
			)
			(layer "F.SilkS")
		)
		(fp_line
			(start 1.1176 1.4224)
			(end -1.1176 1.4224)
			(stroke
				(width 0.1524)
				(type default)
			)
			(layer "F.SilkS")
		)
		(fp_line
			(start 1.2954 1.6002)
			(end 1.2954 0.254)
			(stroke
				(width 0.508)
				(type default)
			)
			(layer "F.SilkS")
		)
		(fp_rect
			(start -0.7493 0.8001)
			(end 0.7493 -0.8001)
			(stroke
				(width 0)
				(type default)
			)
			(fill no)
			(layer "F.CrtYd")
		)
		(fp_poly
			(pts
				(xy -1.3716 1.6764) (xy -1.3716 -1.6764) (xy 1.3716 -1.6764) (xy 1.3716 0.0635) (xy 0.7493 0.0635)
				(xy 0.7493 -0.8001) (xy -0.7493 -0.8001) (xy -0.7493 0.8001) (xy 0.7493 0.8001) (xy 0.7493 0.0762)
				(xy 1.3716 0.0762) (xy 1.3716 1.6764)
			)
			(stroke
				(width 0)
				(type default)
			)
			(fill no)
			(layer "F.CrtYd")
		)
		(fp_rect
			(start -1.3716 1.6764)
			(end 1.3716 -1.6764)
			(stroke
				(width 0)
				(type default)
			)
			(fill no)
			(layer "F.Fab")
		)
		(pad "1" smd rect
			(at 0.50038 -0.73025)
			(size 0.7112 0.8636)
			(layers "F.Cu" "F.Mask" "F.Paste")
			(net "DRV_ACT_2")
		)
		(pad "2" smd rect
			(at -0.50038 -0.73025)
			(size 0.7112 0.8636)
			(layers "F.Cu" "F.Mask" "F.Paste")
			(net "FLT_HDD2")
		)
		(pad "3" smd rect
			(at 0.50038 0.73025)
			(size 0.7112 0.8636)
			(layers "F.Cu" "F.Mask" "F.Paste")
			(net "DRV_ACT_2_N")
		)
		(pad "4" smd rect
			(at -0.50038 0.73025)
			(size 0.7112 0.8636)
			(layers "F.Cu" "F.Mask" "F.Paste")
			(net "FLT_HDD2_N")
		)
	)
	(footprint ""
		(layer "F.Cu")
		(at 465.622132 -130.368294 -90)
		(property "Reference" "R547"
			(at 0 0 270)
			(layer "F.SilkS")
			(hide yes)
			(effects
				(font
					(size 1.27 1.27)
				)
			)
		)
		(property "Value" "4K7R2J-2-GP"
			(at 0.064008 -3.993896 270)
			(unlocked yes)
			(layer "F.Fab")
			(hide yes)
			(effects
				(font
					(size 1.016 1.016)
					(thickness 0.1524)
				)
			)
		)
		(property "Device Type" "R402H16"
			(at 0.064008 -5.517896 270)
			(unlocked yes)
			(layer "F.Fab")
			(hide yes)
			(effects
				(font
					(size 1.016 1.016)
					(thickness 0.1524)
				)
			)
		)
		(duplicate_pad_numbers_are_jumpers no)
		(fp_line
			(start -0.508 -0.9398)
			(end -0.508 0.9398)
			(stroke
				(width 0.1524)
				(type default)
			)
			(layer "F.SilkS")
		)
		(fp_line
			(start 0.508 -0.9398)
			(end -0.508 -0.9398)
			(stroke
				(width 0.1524)
				(type default)
			)
			(layer "F.SilkS")
		)
		(fp_rect
			(start -0.508 0.9398)
			(end 0.508 -0.9398)
			(stroke
				(width 0)
				(type default)
			)
			(fill no)
			(layer "F.CrtYd")
		)
		(fp_rect
			(start -0.508 0.9398)
			(end 0.508 -0.9398)
			(stroke
				(width 0)
				(type default)
			)
			(fill no)
			(layer "F.Fab")
		)
		(pad "1" smd custom
			(at 0 -0.4445 270)
			(size 0.1397 0.1397)
			(layers "F.Cu" "F.Mask" "F.Paste")
			(net "DRIVE_A_23_ACT")
			(options
				(clearance outline)
				(anchor circle)
			)
			(primitives
				(gr_poly
					(pts
						(arc
							(start -0.1778 -0.2794)
							(mid -0.249642 -0.249642)
							(end -0.2794 -0.1778)
						)
						(arc
							(start -0.2794 0.1778)
							(mid -0.249642 0.249642)
							(end -0.1778 0.2794)
						)
						(arc
							(start 0.1778 0.2794)
							(mid 0.249642 0.249642)
							(end 0.2794 0.1778)
						)
						(arc
							(start 0.2794 -0.1778)
							(mid 0.249642 -0.249642)
							(end 0.1778 -0.2794)
						)
					)
					(width 0)
					(fill yes)
				)
			)
		)
		(pad "2" smd custom
			(at 0 0.4445 270)
			(size 0.1397 0.1397)
			(layers "F.Cu" "F.Mask" "F.Paste")
			(net "GND")
			(options
				(clearance outline)
				(anchor circle)
			)
			(primitives
				(gr_poly
					(pts
						(arc
							(start -0.1778 -0.2794)
							(mid -0.249642 -0.249642)
							(end -0.2794 -0.1778)
						)
						(arc
							(start -0.2794 0.1778)
							(mid -0.249642 0.249642)
							(end -0.1778 0.2794)
						)
						(arc
							(start 0.1778 0.2794)
							(mid 0.249642 0.249642)
							(end 0.2794 0.1778)
						)
						(arc
							(start 0.2794 -0.1778)
							(mid 0.249642 -0.249642)
							(end 0.1778 -0.2794)
						)
					)
					(width 0)
					(fill yes)
				)
			)
		)
	)
	(footprint ""
		(layer "F.Cu")
		(at 174.5742 -167.110918 90)
		(property "Reference" "R528"
			(at 0 0 90)
			(layer "F.SilkS")
			(hide yes)
			(effects
				(font
					(size 1.27 1.27)
				)
			)
		)
		(property "Value" "4K7R2J-2-GP"
			(at 0.064008 -3.993896 90)
			(unlocked yes)
			(layer "F.Fab")
			(hide yes)
			(effects
				(font
					(size 1.016 1.016)
					(thickness 0.1524)
				)
			)
		)
		(property "Device Type" "R402H16"
			(at 0.064008 -5.517896 90)
			(unlocked yes)
			(layer "F.Fab")
			(hide yes)
			(effects
				(font
					(size 1.016 1.016)
					(thickness 0.1524)
				)
			)
		)
		(duplicate_pad_numbers_are_jumpers no)
		(fp_line
			(start 0.508 -0.9398)
			(end -0.508 -0.9398)
			(stroke
				(width 0.1524)
				(type default)
			)
			(layer "F.SilkS")
		)
		(fp_line
			(start -0.508 -0.9398)
			(end -0.508 0.9398)
			(stroke
				(width 0.1524)
				(type default)
			)
			(layer "F.SilkS")
		)
		(fp_rect
			(start -0.508 0.9398)
			(end 0.508 -0.9398)
			(stroke
				(width 0)
				(type default)
			)
			(fill no)
			(layer "F.CrtYd")
		)
		(fp_rect
			(start -0.508 0.9398)
			(end 0.508 -0.9398)
			(stroke
				(width 0)
				(type default)
			)
			(fill no)
			(layer "F.Fab")
		)
		(pad "1" smd custom
			(at 0 -0.4445 90)
			(size 0.1397 0.1397)
			(layers "F.Cu" "F.Mask" "F.Paste")
			(net "P12V_A")
			(options
				(clearance outline)
				(anchor circle)
			)
			(primitives
				(gr_poly
					(pts
						(arc
							(start -0.1778 -0.2794)
							(mid -0.249642 -0.249642)
							(end -0.2794 -0.1778)
						)
						(arc
							(start -0.2794 0.1778)
							(mid -0.249642 0.249642)
							(end -0.1778 0.2794)
						)
						(arc
							(start 0.1778 0.2794)
							(mid 0.249642 0.249642)
							(end 0.2794 0.1778)
						)
						(arc
							(start 0.2794 -0.1778)
							(mid 0.249642 -0.249642)
							(end 0.1778 -0.2794)
						)
					)
					(width 0)
					(fill yes)
				)
			)
		)
		(pad "2" smd custom
			(at 0 0.4445 90)
			(size 0.1397 0.1397)
			(layers "F.Cu" "F.Mask" "F.Paste")
			(net "SW_HDD_P17")
			(options
				(clearance outline)
				(anchor circle)
			)
			(primitives
				(gr_poly
					(pts
						(arc
							(start -0.1778 -0.2794)
							(mid -0.249642 -0.249642)
							(end -0.2794 -0.1778)
						)
						(arc
							(start -0.2794 0.1778)
							(mid -0.249642 0.249642)
							(end -0.1778 0.2794)
						)
						(arc
							(start 0.1778 0.2794)
							(mid 0.249642 0.249642)
							(end 0.2794 0.1778)
						)
						(arc
							(start 0.2794 -0.1778)
							(mid 0.249642 -0.249642)
							(end 0.1778 -0.2794)
						)
					)
					(width 0)
					(fill yes)
				)
			)
		)
	)
	(footprint ""
		(layer "F.Cu")
		(at 420.200074 -287.910016 -90)
		(property "Reference" "HDDSAS9"
			(at 0 0 270)
			(layer "F.SilkS")
			(hide yes)
			(effects
				(font
					(size 1.27 1.27)
				)
			)
		)
		(property "Value" "SKT-SAS15P-14P-45-GP"
			(at -20.7645 -8.9789 270)
			(unlocked yes)
			(layer "F.Fab")
			(hide yes)
			(effects
				(font
					(size 1.016 1.016)
					(thickness 0.1524)
				)
			)
		)
		(property "Device Type" "10120818-001C-TRLF"
			(at -20.7645 -10.5029 270)
			(unlocked yes)
			(layer "F.Fab")
			(hide yes)
			(effects
				(font
					(size 1.016 1.016)
					(thickness 0.1524)
				)
			)
		)
		(duplicate_pad_numbers_are_jumpers no)
		(fp_line
			(start 1.651 4.2926)
			(end 1.651 3.0099)
			(stroke
				(width 0.1524)
				(type default)
			)
			(layer "F.SilkS")
		)
		(fp_line
			(start 8.509 4.2926)
			(end 1.651 4.2926)
			(stroke
				(width 0.1524)
				(type default)
			)
			(layer "F.SilkS")
		)
		(fp_line
			(start -23.4188 3.0099)
			(end -23.4188 -3.2512)
			(stroke
				(width 0.1524)
				(type default)
			)
			(layer "F.SilkS")
		)
		(fp_line
			(start 1.651 3.0099)
			(end -23.4188 3.0099)
			(stroke
				(width 0.1524)
				(type default)
			)
			(layer "F.SilkS")
		)
		(fp_line
			(start 8.509 3.0099)
			(end 8.509 4.2926)
			(stroke
				(width 0.1524)
				(type default)
			)
			(layer "F.SilkS")
		)
		(fp_line
			(start 23.4188 3.0099)
			(end 8.509 3.0099)
			(stroke
				(width 0.1524)
				(type default)
			)
			(layer "F.SilkS")
		)
		(fp_line
			(start -23.4188 -3.2512)
			(end 23.4188 -3.2512)
			(stroke
				(width 0.1524)
				(type default)
			)
			(layer "F.SilkS")
		)
		(fp_line
			(start 23.4188 -3.2512)
			(end 23.4188 3.0099)
			(stroke
				(width 0.1524)
				(type default)
			)
			(layer "F.SilkS")
		)
		(fp_line
			(start 15.5067 -3.3401)
			(end 16.2687 -3.3401)
			(stroke
				(width 0.3302)
				(type default)
			)
			(layer "F.SilkS")
		)
		(fp_poly
			(pts
				(xy 15.868904 -3.230372) (xy 16.503904 -3.865372) (xy 15.233904 -3.865372)
			)
			(stroke
				(width 0)
				(type default)
			)
			(fill yes)
			(layer "F.SilkS")
		)
		(fp_poly
			(pts
				(xy -22.8727 -2.7559) (xy 22.8727 -2.7559) (xy 22.8727 2.7559) (xy 8.255 2.7559) (xy 8.255 3.5179)
				(xy 1.905 3.5179) (xy 1.905 2.7559) (xy -22.8727 2.7559)
			)
			(stroke
				(width 0)
				(type default)
			)
			(fill no)
			(layer "F.CrtYd")
		)
		(fp_poly
			(pts
				(xy 1.397 4.5466) (xy 1.397 3.2639) (xy -23.6728 3.2639) (xy -23.6728 -3.5052) (xy 23.6728 -3.5052)
				(xy 23.6728 -0.00635) (xy 22.8727 -0.00635) (xy 22.8727 -2.7559) (xy -22.8727 -2.7559) (xy -22.8727 2.7559)
				(xy 1.905 2.7559) (xy 1.905 3.5179) (xy 8.255 3.5179) (xy 8.255 2.7559) (xy 22.8727 2.7559) (xy 22.8727 0.00635)
				(xy 23.6728 0.00635) (xy 23.6728 3.2639) (xy 8.763 3.2639) (xy 8.763 4.5466)
			)
			(stroke
				(width 0)
				(type default)
			)
			(fill no)
			(layer "F.CrtYd")
		)
		(fp_poly
			(pts
				(xy 1.397 4.5466) (xy 1.397 3.2639) (xy -23.6728 3.2639) (xy -23.6728 -3.5052) (xy 23.6728 -3.5052)
				(xy 23.6728 3.2639) (xy 8.763 3.2639) (xy 8.763 4.5466)
			)
			(stroke
				(width 0)
				(type default)
			)
			(fill no)
			(layer "F.Fab")
		)
		(pad "" np_thru_hole circle
			(at -18.874994 0 270)
			(size 0.254 0.254)
			(drill 1.3462)
			(layers "*.Cu" "*.Mask")
			(clearance 0.9017)
			(thermal_gap 0.9017)
		)
		(pad "" np_thru_hole circle
			(at 18.874994 0 270)
			(size 0.254 0.254)
			(drill 0.9398)
			(layers "*.Cu" "*.Mask")
			(clearance 0.6985)
			(thermal_gap 0.6985)
		)
		(pad "G1" smd rect
			(at 21.874988 0 270)
			(size 2.5908 2.5908)
			(layers "F.Cu" "F.Mask" "F.Paste")
			(net "GND")
		)
		(pad "G2" smd rect
			(at -21.874988 0 270)
			(size 2.5908 2.5908)
			(layers "F.Cu" "F.Mask" "F.Paste")
			(net "GND")
		)
		(pad "P1" smd rect
			(at 1.905 -1.82499 270)
			(size 0.6096 2.3622)
			(layers "F.Cu" "F.Mask" "F.Paste")
			(net "Net_2171")
		)
		(pad "P2" smd rect
			(at 0.635 -1.82499 270)
			(size 0.6096 2.3622)
			(layers "F.Cu" "F.Mask" "F.Paste")
			(net "Net_2172")
		)
		(pad "P3" smd rect
			(at -0.635 -1.82499 270)
			(size 0.6096 2.3622)
			(layers "F.Cu" "F.Mask" "F.Paste")
			(net "Net_2173")
		)
		(pad "P4" smd rect
			(at -1.905 -1.82499 270)
			(size 0.6096 2.3622)
			(layers "F.Cu" "F.Mask" "F.Paste")
			(net "GND")
		)
		(pad "P5" smd rect
			(at -3.175 -1.82499 270)
			(size 0.6096 2.3622)
			(layers "F.Cu" "F.Mask" "F.Paste")
			(net "HDD_PRSNT_9")
		)
		(pad "P6" smd rect
			(at -4.445 -1.82499 270)
			(size 0.6096 2.3622)
			(layers "F.Cu" "F.Mask" "F.Paste")
			(net "GND")
		)
		(pad "P7" smd rect
			(at -5.715 -1.82499 270)
			(size 0.6096 2.3622)
			(layers "F.Cu" "F.Mask" "F.Paste")
			(net "5V_PRE_9")
		)
		(pad "P8" smd rect
			(at -6.985 -1.82499 270)
			(size 0.6096 2.3622)
			(layers "F.Cu" "F.Mask" "F.Paste")
			(net "P5V_HDD9")
		)
		(pad "P9" smd rect
			(at -8.255 -1.82499 270)
			(size 0.6096 2.3622)
			(layers "F.Cu" "F.Mask" "F.Paste")
			(net "P5V_HDD9")
		)
		(pad "P10" smd rect
			(at -9.525 -1.82499 270)
			(size 0.6096 2.3622)
			(layers "F.Cu" "F.Mask" "F.Paste")
			(net "GND")
		)
		(pad "P11" smd rect
			(at -10.795 -1.82499 270)
			(size 0.6096 2.3622)
			(layers "F.Cu" "F.Mask" "F.Paste")
			(net "ACT_HDD_9")
		)
		(pad "P12" smd rect
			(at -12.065 -1.82499 270)
			(size 0.6096 2.3622)
			(layers "F.Cu" "F.Mask" "F.Paste")
			(net "GND")
		)
		(pad "P13" smd rect
			(at -13.335 -1.82499 270)
			(size 0.6096 2.3622)
			(layers "F.Cu" "F.Mask" "F.Paste")
			(net "12V_PRE_9")
		)
		(pad "P14" smd rect
			(at -14.605 -1.82499 270)
			(size 0.6096 2.3622)
			(layers "F.Cu" "F.Mask" "F.Paste")
			(net "P12V_HDD9")
		)
		(pad "P15" smd rect
			(at -15.875 -1.82499 270)
			(size 0.6096 2.3622)
			(layers "F.Cu" "F.Mask" "F.Paste")
			(net "P12V_HDD9")
		)
		(pad "S1" smd rect
			(at 15.875 -1.82499 270)
			(size 0.6096 2.3622)
			(layers "F.Cu" "F.Mask" "F.Paste")
			(net "GND")
		)
		(pad "S2" smd rect
			(at 14.605 -1.82499 270)
			(size 0.6096 2.3622)
			(layers "F.Cu" "F.Mask" "F.Paste")
			(net "SAS_HDD_RX_P9")
		)
		(pad "S3" smd rect
			(at 13.335 -1.82499 270)
			(size 0.6096 2.3622)
			(layers "F.Cu" "F.Mask" "F.Paste")
			(net "SAS_HDD_RX_N9")
		)
		(pad "S4" smd rect
			(at 12.065 -1.82499 270)
			(size 0.6096 2.3622)
			(layers "F.Cu" "F.Mask" "F.Paste")
			(net "GND")
		)
		(pad "S5" smd rect
			(at 10.795 -1.82499 270)
			(size 0.6096 2.3622)
			(layers "F.Cu" "F.Mask" "F.Paste")
			(net "PHY_DRV_A_TO_SCC_A_9_DN")
		)
		(pad "S6" smd rect
			(at 9.525 -1.82499 270)
			(size 0.6096 2.3622)
			(layers "F.Cu" "F.Mask" "F.Paste")
			(net "PHY_DRV_A_TO_SCC_A_9_DP")
		)
		(pad "S7" smd rect
			(at 8.255 -1.82499 270)
			(size 0.6096 2.3622)
			(layers "F.Cu" "F.Mask" "F.Paste")
			(net "GND")
		)
		(pad "S8" smd rect
			(at 7.480046 2.845054 270)
			(size 0.508 2.3622)
			(layers "F.Cu" "F.Mask" "F.Paste")
			(net "GND")
		)
		(pad "S9" smd rect
			(at 6.679946 2.845054 270)
			(size 0.508 2.3622)
			(layers "F.Cu" "F.Mask" "F.Paste")
			(net "Net_446")
		)
		(pad "S10" smd rect
			(at 5.8801 2.845054 270)
			(size 0.508 2.3622)
			(layers "F.Cu" "F.Mask" "F.Paste")
			(net "Net_338")
		)
		(pad "S11" smd rect
			(at 5.08 2.845054 270)
			(size 0.508 2.3622)
			(layers "F.Cu" "F.Mask" "F.Paste")
			(net "GND")
		)
		(pad "S12" smd rect
			(at 4.2799 2.845054 270)
			(size 0.508 2.3622)
			(layers "F.Cu" "F.Mask" "F.Paste")
			(net "Net_374")
		)
		(pad "S13" smd rect
			(at 3.480054 2.845054 270)
			(size 0.508 2.3622)
			(layers "F.Cu" "F.Mask" "F.Paste")
			(net "Net_410")
		)
		(pad "S14" smd rect
			(at 2.679954 2.845054 270)
			(size 0.508 2.3622)
			(layers "F.Cu" "F.Mask" "F.Paste")
			(net "GND")
		)
		(zone
			(layer "F.Cu")
			(hatch none 0.5)
			(connect_pads
				(clearance 0)
			)
			(min_thickness 0.25)
			(keepout
				(tracks not_allowed)
				(vias allowed)
				(pads allowed)
				(copperpour not_allowed)
				(footprints allowed)
			)
			(placement
				(enabled no)
				(sheetname "")
			)
			(fill
				(thermal_gap 0.5)
				(thermal_bridge_width 0.5)
				(island_removal_mode 0)
			)
			(polygon
				(pts
					(xy 423.857674 -304.648616) (xy 416.783774 -304.648616) (xy 416.783774 -311.582816) (xy 417.888674 -311.582816)
					(xy 417.888674 -307.468016) (xy 422.511474 -307.468016) (xy 422.511474 -311.582816) (xy 423.857674 -311.582816)
				)
			)
		)
		(zone
			(layer "F.Cu")
			(hatch none 0.5)
			(connect_pads
				(clearance 0)
			)
			(min_thickness 0.25)
			(keepout
				(tracks allowed)
				(vias not_allowed)
				(pads allowed)
				(copperpour not_allowed)
				(footprints allowed)
			)
			(placement
				(enabled no)
				(sheetname "")
			)
			(fill
				(thermal_gap 0.5)
				(thermal_bridge_width 0.5)
				(island_removal_mode 0)
			)
			(polygon
				(pts
					(xy 423.857674 -304.648616) (xy 416.783774 -304.648616) (xy 416.783774 -311.582816) (xy 417.888674 -311.582816)
					(xy 417.888674 -307.468016) (xy 422.511474 -307.468016) (xy 422.511474 -311.582816) (xy 423.857674 -311.582816)
				)
			)
		)
		(zone
			(layer "F.Cu")
			(hatch none 0.5)
			(connect_pads
				(clearance 0)
			)
			(min_thickness 0.25)
			(keepout
				(tracks allowed)
				(vias not_allowed)
				(pads allowed)
				(copperpour not_allowed)
				(footprints allowed)
			)
			(placement
				(enabled no)
				(sheetname "")
			)
			(fill
				(thermal_gap 0.5)
				(thermal_bridge_width 0.5)
				(island_removal_mode 0)
			)
			(polygon
				(pts
					(xy 423.857674 -271.171416) (xy 416.783774 -271.171416) (xy 416.783774 -264.237216) (xy 417.888674 -264.237216)
					(xy 417.888674 -268.352016) (xy 422.511474 -268.352016) (xy 422.511474 -264.237216) (xy 423.857674 -264.237216)
				)
			)
		)
		(zone
			(layer "F.Cu")
			(hatch none 0.5)
			(connect_pads
				(clearance 0)
			)
			(min_thickness 0.25)
			(keepout
				(tracks not_allowed)
				(vias allowed)
				(pads allowed)
				(copperpour not_allowed)
				(footprints allowed)
			)
			(placement
				(enabled no)
				(sheetname "")
			)
			(fill
				(thermal_gap 0.5)
				(thermal_bridge_width 0.5)
				(island_removal_mode 0)
			)
			(polygon
				(pts
					(xy 423.857674 -271.171416) (xy 416.783774 -271.171416) (xy 416.783774 -264.237216) (xy 417.888674 -264.237216)
					(xy 417.888674 -268.352016) (xy 422.511474 -268.352016) (xy 422.511474 -264.237216) (xy 423.857674 -264.237216)
				)
			)
		)
		(zone
			(layers "F.Cu" "B.Cu" "In1.Cu" "In2.Cu" "In3.Cu" "In4.Cu" "In5.Cu" "In6.Cu"
				"In7.Cu" "In8.Cu" "In9.Cu" "In10.Cu"
			)
			(hatch none 0.5)
			(connect_pads
				(clearance 0)
			)
			(min_thickness 0.25)
			(keepout
				(tracks not_allowed)
				(vias allowed)
				(pads allowed)
				(copperpour not_allowed)
				(footprints allowed)
			)
			(placement
				(enabled no)
				(sheetname "")
			)
			(fill
				(thermal_gap 0.5)
				(thermal_bridge_width 0.5)
				(island_removal_mode 0)
			)
			(polygon
				(pts
					(arc
						(start 420.974774 -269.035022)
						(mid 419.425374 -269.035022)
						(end 420.974774 -269.035022)
					)
				)
			)
		)
		(zone
			(layers "F.Cu" "B.Cu" "In1.Cu" "In2.Cu" "In3.Cu" "In4.Cu" "In5.Cu" "In6.Cu"
				"In7.Cu" "In8.Cu" "In9.Cu" "In10.Cu"
			)
			(hatch none 0.5)
			(connect_pads
				(clearance 0)
			)
			(min_thickness 0.25)
			(keepout
				(tracks not_allowed)
				(vias allowed)
				(pads allowed)
				(copperpour not_allowed)
				(footprints allowed)
			)
			(placement
				(enabled no)
				(sheetname "")
			)
			(fill
				(thermal_gap 0.5)
				(thermal_bridge_width 0.5)
				(island_removal_mode 0)
			)
			(polygon
				(pts
					(arc
						(start 421.177974 -306.78501)
						(mid 419.222174 -306.78501)
						(end 421.177974 -306.78501)
					)
				)
			)
		)
	)
	(footprint ""
		(layer "F.Cu")
		(at 268.816582 15.772638)
		(property "Reference" "U35"
			(at 0 0 0)
			(layer "F.SilkS")
			(hide yes)
			(effects
				(font
					(size 1.27 1.27)
				)
			)
		)
		(property "Value" "TPS2065DBVT-GP"
			(at 0 -5.1308 0)
			(unlocked yes)
			(layer "F.Fab")
			(hide yes)
			(effects
				(font
					(size 1.016 1.016)
					(thickness 0.1524)
				)
			)
		)
		(property "Device Type" "SOT-23-5H58"
			(at 0 -6.7564 0)
			(unlocked yes)
			(layer "F.Fab")
			(hide yes)
			(effects
				(font
					(size 1.016 1.016)
					(thickness 0.1524)
				)
			)
		)
		(duplicate_pad_numbers_are_jumpers no)
		(fp_line
			(start -1.778 -2.286)
			(end -1.778 2.286)
			(stroke
				(width 0.1524)
				(type default)
			)
			(layer "F.SilkS")
		)
		(fp_line
			(start -1.778 2.286)
			(end -0.254 2.286)
			(stroke
				(width 0.1524)
				(type default)
			)
			(layer "F.SilkS")
		)
		(fp_line
			(start -1.778 2.286)
			(end 1.778 2.286)
			(stroke
				(width 0.1524)
				(type default)
			)
			(layer "F.SilkS")
		)
		(fp_line
			(start -1.7272 2.2352)
			(end -1.7272 0.762)
			(stroke
				(width 0.3302)
				(type default)
			)
			(layer "F.SilkS")
		)
		(fp_line
			(start -0.7112 2.2352)
			(end -1.7272 2.2352)
			(stroke
				(width 0.3302)
				(type default)
			)
			(layer "F.SilkS")
		)
		(fp_line
			(start -0.254 2.286)
			(end 1.778 2.286)
			(stroke
				(width 0.1524)
				(type default)
			)
			(layer "F.SilkS")
		)
		(fp_line
			(start 1.778 -2.286)
			(end -1.778 -2.286)
			(stroke
				(width 0.1524)
				(type default)
			)
			(layer "F.SilkS")
		)
		(fp_line
			(start 1.778 2.286)
			(end 1.778 -2.286)
			(stroke
				(width 0.1524)
				(type default)
			)
			(layer "F.SilkS")
		)
		(fp_poly
			(pts
				(xy -0.9652 2.4384) (xy -1.3208 2.794) (xy -0.6096 2.794)
			)
			(stroke
				(width 0)
				(type default)
			)
			(fill yes)
			(layer "F.SilkS")
		)
		(fp_rect
			(start -1.778 2.286)
			(end 1.778 -2.286)
			(stroke
				(width 0)
				(type default)
			)
			(fill no)
			(layer "F.CrtYd")
		)
		(fp_rect
			(start -1.778 2.286)
			(end 1.778 -2.286)
			(stroke
				(width 0)
				(type default)
			)
			(fill no)
			(layer "F.Fab")
		)
		(pad "1" smd rect
			(at -0.94996 1.143)
			(size 0.508 1.524)
			(layers "F.Cu" "F.Mask" "F.Paste")
			(net "P5V_USB_B")
		)
		(pad "2" smd rect
			(at 0 1.143)
			(size 0.508 1.524)
			(layers "F.Cu" "F.Mask" "F.Paste")
			(net "GND")
		)
		(pad "3" smd rect
			(at 0.94996 1.143)
			(size 0.508 1.524)
			(layers "F.Cu" "F.Mask" "F.Paste")
			(net "USB_OCS_N2")
		)
		(pad "4" smd rect
			(at 0.94996 -1.143)
			(size 0.508 1.524)
			(layers "F.Cu" "F.Mask" "F.Paste")
			(net "USB_EN_2")
		)
		(pad "5" smd rect
			(at -0.94996 -1.143)
			(size 0.508 1.524)
			(layers "F.Cu" "F.Mask" "F.Paste")
			(net "P5V_B")
		)
	)
	(footprint ""
		(layer "F.Cu")
		(at 319.9892 -273.940016 90)
		(property "Reference" "VIA1"
			(at 0 0 90)
			(layer "F.SilkS")
			(hide yes)
			(effects
				(font
					(size 1.27 1.27)
				)
			)
		)
		(property "Value" "100OHM-8L-1D6MM-L18L16-GP"
			(at -3.7211 -4.5085 90)
			(unlocked yes)
			(layer "F.Fab")
			(hide yes)
			(effects
				(font
					(size 1.016 1.016)
					(thickness 0.1524)
				)
			)
		)
		(property "Device Type" "VIA-PCIE-4P-394076"
			(at -3.7211 -6.0325 90)
			(unlocked yes)
			(layer "F.Fab")
			(hide yes)
			(effects
				(font
					(size 1.016 1.016)
					(thickness 0.1524)
				)
			)
		)
		(duplicate_pad_numbers_are_jumpers no)
		(fp_rect
			(start -1.9685 0.381)
			(end 1.9685 -0.381)
			(stroke
				(width 0)
				(type default)
			)
			(fill no)
			(layer "F.CrtYd")
		)
		(fp_rect
			(start -1.9685 0.381)
			(end 1.9685 -0.381)
			(stroke
				(width 0)
				(type default)
			)
			(fill no)
			(layer "F.Fab")
		)
		(pad "1" thru_hole circle
			(at -1.5875 0 90)
			(size 0.508 0.508)
			(drill 0.254)
			(layers "*.Cu" "*.Mask")
			(remove_unused_layers no)
			(net "GND")
			(clearance 0.127)
			(thermal_gap 0.127)
		)
		(pad "2" thru_hole circle
			(at -0.5715 0 90)
			(size 0.508 0.508)
			(drill 0.254)
			(layers "*.Cu" "*.Mask")
			(remove_unused_layers no)
			(net "PHY_SCC_A_TO_DRV_A_6_DP")
			(clearance 0.127)
			(thermal_gap 0.127)
		)
		(pad "3" thru_hole circle
			(at 0.5715 0 90)
			(size 0.508 0.508)
			(drill 0.254)
			(layers "*.Cu" "*.Mask")
			(remove_unused_layers no)
			(net "PHY_SCC_A_TO_DRV_A_6_DN")
			(clearance 0.127)
			(thermal_gap 0.127)
		)
		(pad "4" thru_hole circle
			(at 1.5875 0 90)
			(size 0.508 0.508)
			(drill 0.254)
			(layers "*.Cu" "*.Mask")
			(remove_unused_layers no)
			(net "GND")
			(clearance 0.127)
			(thermal_gap 0.127)
		)
	)
	(footprint ""
		(layer "F.Cu")
		(at 350.066102 -183.620918)
		(property "Reference" "TP97"
			(at 0 0 0)
			(layer "F.SilkS")
			(hide yes)
			(effects
				(font
					(size 1.27 1.27)
				)
			)
		)
		(property "Value" "TPAD32-GP"
			(at -0.0508 -1.6764 0)
			(unlocked yes)
			(layer "F.Fab")
			(hide yes)
			(effects
				(font
					(size 1.016 1.016)
					(thickness 0.1524)
				)
			)
		)
		(property "Device Type" "TPAD32"
			(at -0.0508 -3.2004 0)
			(unlocked yes)
			(layer "F.Fab")
			(hide yes)
			(effects
				(font
					(size 1.016 1.016)
					(thickness 0.1524)
				)
			)
		)
		(duplicate_pad_numbers_are_jumpers no)
		(fp_poly
			(pts
				(arc
					(start 0.4064 0)
					(mid -0.4064 0)
					(end 0.4064 0)
				)
			)
			(stroke
				(width 0)
				(type default)
			)
			(fill no)
			(layer "F.CrtYd")
		)
		(fp_poly
			(pts
				(arc
					(start 0.7112 0)
					(mid -0.7112 0)
					(end 0.7112 0)
				)
			)
			(stroke
				(width 0)
				(type default)
			)
			(fill no)
			(layer "F.Fab")
		)
		(pad "1" smd circle
			(at 0 0)
			(size 0.8128 0.8128)
			(layers "F.Cu" "F.Mask" "F.Paste")
			(net "ACT_HDD_19")
		)
	)
	(footprint ""
		(layer "F.Cu")
		(at 26.325068 -9.19988)
		(property "Reference" ""
			(at 0 0 0)
			(layer "F.SilkS")
			(hide yes)
			(effects
				(font
					(size 1.27 1.27)
				)
			)
		)
		(property "Value" "*"
			(at -6.1214 1.4351 0)
			(unlocked yes)
			(layer "F.Fab")
			(hide yes)
			(effects
				(font
					(size 1.016 1.016)
					(thickness 0.1524)
				)
			)
		)
		(duplicate_pad_numbers_are_jumpers no)
		(fp_poly
			(pts
				(arc
					(start 5.0673 0)
					(mid -5.0673 0)
					(end 5.0673 0)
				)
			)
			(stroke
				(width 0)
				(type default)
			)
			(fill no)
			(layer "B.CrtYd")
		)
		(fp_poly
			(pts
				(arc
					(start 5.0673 0)
					(mid -5.0673 0)
					(end 5.0673 0)
				)
			)
			(stroke
				(width 0)
				(type default)
			)
			(fill no)
			(layer "F.CrtYd")
		)
		(fp_poly
			(pts
				(arc
					(start 5.0673 0)
					(mid -5.0673 0)
					(end 5.0673 0)
				)
			)
			(stroke
				(width 0)
				(type default)
			)
			(fill no)
			(layer "B.Fab")
		)
		(fp_poly
			(pts
				(arc
					(start 5.0673 0)
					(mid -5.0673 0)
					(end 5.0673 0)
				)
			)
			(stroke
				(width 0)
				(type default)
			)
			(fill no)
			(layer "F.Fab")
		)
		(pad "1" thru_hole circle
			(at 0 0)
			(size 9.525 9.525)
			(drill 5.715)
			(layers "*.Cu" "*.Mask")
			(remove_unused_layers no)
			(net "Net_23")
			(clearance -1.397)
			(thermal_gap 0.3048)
			(padstack
				(mode front_inner_back)
				(layer "Inner"
					(shape circle)
					(size 6.1214 6.1214)
					(clearance 0.3048)
				)
				(layer "B.Cu"
					(shape circle)
					(size 9.525 9.525)
					(clearance -1.397)
				)
			)
		)
		(zone
			(layers "F.Cu" "B.Cu" "In1.Cu" "In2.Cu" "In3.Cu" "In4.Cu" "In5.Cu" "In6.Cu"
				"In7.Cu" "In8.Cu" "In9.Cu" "In10.Cu"
			)
			(hatch none 0.5)
			(connect_pads
				(clearance 0)
			)
			(min_thickness 0.25)
			(keepout
				(tracks not_allowed)
				(vias allowed)
				(pads allowed)
				(copperpour not_allowed)
				(footprints allowed)
			)
			(placement
				(enabled no)
				(sheetname "")
			)
			(fill
				(thermal_gap 0.5)
				(thermal_bridge_width 0.5)
				(island_removal_mode 0)
			)
			(polygon
				(pts
					(arc
						(start 31.087568 -9.19988)
						(mid 21.562568 -9.19988)
						(end 31.087568 -9.19988)
					)
				)
			)
		)
	)
	(footprint ""
		(layer "F.Cu")
		(at 22.996398 -276.014942 -90)
		(property "Reference" "R966"
			(at 0 0 270)
			(layer "F.SilkS")
			(hide yes)
			(effects
				(font
					(size 1.27 1.27)
				)
			)
		)
		(property "Value" "1KR2F-3-GP"
			(at 0.064008 -3.993896 270)
			(unlocked yes)
			(layer "F.Fab")
			(hide yes)
			(effects
				(font
					(size 1.016 1.016)
					(thickness 0.1524)
				)
			)
		)
		(property "Device Type" "R402H16"
			(at 0.064008 -5.517896 270)
			(unlocked yes)
			(layer "F.Fab")
			(hide yes)
			(effects
				(font
					(size 1.016 1.016)
					(thickness 0.1524)
				)
			)
		)
		(duplicate_pad_numbers_are_jumpers no)
		(fp_line
			(start -0.508 -0.9398)
			(end -0.508 0.9398)
			(stroke
				(width 0.1524)
				(type default)
			)
			(layer "F.SilkS")
		)
		(fp_line
			(start 0.508 -0.9398)
			(end -0.508 -0.9398)
			(stroke
				(width 0.1524)
				(type default)
			)
			(layer "F.SilkS")
		)
		(fp_rect
			(start -0.508 0.9398)
			(end 0.508 -0.9398)
			(stroke
				(width 0)
				(type default)
			)
			(fill no)
			(layer "F.CrtYd")
		)
		(fp_rect
			(start -0.508 0.9398)
			(end 0.508 -0.9398)
			(stroke
				(width 0)
				(type default)
			)
			(fill no)
			(layer "F.Fab")
		)
		(pad "1" smd custom
			(at 0 -0.4445 270)
			(size 0.1397 0.1397)
			(layers "F.Cu" "F.Mask" "F.Paste")
			(net "P3V3_STBY_A")
			(options
				(clearance outline)
				(anchor circle)
			)
			(primitives
				(gr_poly
					(pts
						(arc
							(start -0.1778 -0.2794)
							(mid -0.249642 -0.249642)
							(end -0.2794 -0.1778)
						)
						(arc
							(start -0.2794 0.1778)
							(mid -0.249642 0.249642)
							(end -0.1778 0.2794)
						)
						(arc
							(start 0.1778 0.2794)
							(mid 0.249642 0.249642)
							(end 0.2794 0.1778)
						)
						(arc
							(start 0.2794 -0.1778)
							(mid 0.249642 -0.249642)
							(end 0.1778 -0.2794)
						)
					)
					(width 0)
					(fill yes)
				)
			)
		)
		(pad "2" smd custom
			(at 0 0.4445 270)
			(size 0.1397 0.1397)
			(layers "F.Cu" "F.Mask" "F.Paste")
			(net "SW_PWR_R_HDD0")
			(options
				(clearance outline)
				(anchor circle)
			)
			(primitives
				(gr_poly
					(pts
						(arc
							(start -0.1778 -0.2794)
							(mid -0.249642 -0.249642)
							(end -0.2794 -0.1778)
						)
						(arc
							(start -0.2794 0.1778)
							(mid -0.249642 0.249642)
							(end -0.1778 0.2794)
						)
						(arc
							(start 0.1778 0.2794)
							(mid 0.249642 0.249642)
							(end 0.2794 0.1778)
						)
						(arc
							(start 0.2794 -0.1778)
							(mid 0.249642 -0.249642)
							(end 0.1778 -0.2794)
						)
					)
					(width 0)
					(fill yes)
				)
			)
		)
	)
	(footprint ""
		(layer "F.Cu")
		(at 434.710078 -127.724662 180)
		(property "Reference" "Q285"
			(at 0 0 180)
			(layer "F.SilkS")
			(hide yes)
			(effects
				(font
					(size 1.27 1.27)
				)
			)
		)
		(property "Value" "SSM3K324R-GP"
			(at 0.127 -8.9662 180)
			(unlocked yes)
			(layer "F.Fab")
			(hide yes)
			(effects
				(font
					(size 1.016 1.016)
					(thickness 0.1524)
				)
			)
		)
		(property "Device Type" "SOT23DGS2D4H35"
			(at 0.127 -10.4902 180)
			(unlocked yes)
			(layer "F.Fab")
			(hide yes)
			(effects
				(font
					(size 1.016 1.016)
					(thickness 0.1524)
				)
			)
		)
		(duplicate_pad_numbers_are_jumpers no)
		(fp_line
			(start 1.651 1.778)
			(end 1.651 -1.778)
			(stroke
				(width 0.1524)
				(type default)
			)
			(layer "F.SilkS")
		)
		(fp_line
			(start 1.651 -1.778)
			(end -1.651 -1.778)
			(stroke
				(width 0.1524)
				(type default)
			)
			(layer "F.SilkS")
		)
		(fp_line
			(start -1.651 1.778)
			(end 1.651 1.778)
			(stroke
				(width 0.1524)
				(type default)
			)
			(layer "F.SilkS")
		)
		(fp_line
			(start -1.651 -1.778)
			(end -1.651 1.778)
			(stroke
				(width 0.1524)
				(type default)
			)
			(layer "F.SilkS")
		)
		(fp_poly
			(pts
				(xy -1.778 1.8796) (xy -1.778 -1.8796) (xy 1.778 -1.8796) (xy 1.778 1.8796)
			)
			(stroke
				(width 0)
				(type default)
			)
			(fill no)
			(layer "F.CrtYd")
		)
		(fp_poly
			(pts
				(xy -1.778 1.8796) (xy -1.778 -1.8796) (xy 1.778 -1.8796) (xy 1.778 1.8796)
			)
			(stroke
				(width 0)
				(type default)
			)
			(fill no)
			(layer "F.Fab")
		)
		(pad "D" smd custom
			(at 0 -0.9525 180)
			(size 0.1905 0.1905)
			(layers "F.Cu" "F.Mask" "F.Paste")
			(net "DRV_ACT_22_N")
			(options
				(clearance outline)
				(anchor circle)
			)
			(primitives
				(gr_poly
					(pts
						(arc
							(start -0.1778 0.5715)
							(mid -0.321484 0.511984)
							(end -0.381 0.3683)
						)
						(arc
							(start -0.381 -0.3683)
							(mid -0.321484 -0.511984)
							(end -0.1778 -0.5715)
						)
						(arc
							(start 0.1778 -0.5715)
							(mid 0.321484 -0.511984)
							(end 0.381 -0.3683)
						)
						(arc
							(start 0.381 0.3683)
							(mid 0.321484 0.511984)
							(end 0.1778 0.5715)
						)
					)
					(width 0)
					(fill yes)
				)
			)
		)
		(pad "G" smd custom
			(at -0.98425 0.9525 180)
			(size 0.1905 0.1905)
			(layers "F.Cu" "F.Mask" "F.Paste")
			(net "DRIVE_A_22_ACT")
			(options
				(clearance outline)
				(anchor circle)
			)
			(primitives
				(gr_poly
					(pts
						(arc
							(start -0.1778 0.5715)
							(mid -0.321484 0.511984)
							(end -0.381 0.3683)
						)
						(arc
							(start -0.381 -0.3683)
							(mid -0.321484 -0.511984)
							(end -0.1778 -0.5715)
						)
						(arc
							(start 0.1778 -0.5715)
							(mid 0.321484 -0.511984)
							(end 0.381 -0.3683)
						)
						(arc
							(start 0.381 0.3683)
							(mid 0.321484 0.511984)
							(end 0.1778 0.5715)
						)
					)
					(width 0)
					(fill yes)
				)
			)
		)
		(pad "S" smd custom
			(at 0.98425 0.9525 180)
			(size 0.1905 0.1905)
			(layers "F.Cu" "F.Mask" "F.Paste")
			(net "GND")
			(options
				(clearance outline)
				(anchor circle)
			)
			(primitives
				(gr_poly
					(pts
						(arc
							(start -0.1778 0.5715)
							(mid -0.321484 0.511984)
							(end -0.381 0.3683)
						)
						(arc
							(start -0.381 -0.3683)
							(mid -0.321484 -0.511984)
							(end -0.1778 -0.5715)
						)
						(arc
							(start 0.1778 -0.5715)
							(mid 0.321484 -0.511984)
							(end 0.381 -0.3683)
						)
						(arc
							(start 0.381 0.3683)
							(mid 0.321484 0.511984)
							(end 0.1778 0.5715)
						)
					)
					(width 0)
					(fill yes)
				)
			)
		)
	)
	(footprint ""
		(layer "F.Cu")
		(at 178.181 -177.778918 -90)
		(property "Reference" "C261"
			(at 0 0 270)
			(layer "F.SilkS")
			(hide yes)
			(effects
				(font
					(size 1.27 1.27)
				)
			)
		)
		(property "Value" "SC1U16V3KX-5GP"
			(at 0 -2.8194 270)
			(unlocked yes)
			(layer "F.Fab")
			(hide yes)
			(effects
				(font
					(size 1.016 1.016)
					(thickness 0.1524)
				)
			)
		)
		(property "Device Type" "C603H36"
			(at 0 -4.3434 270)
			(unlocked yes)
			(layer "F.Fab")
			(hide yes)
			(effects
				(font
					(size 1.016 1.016)
					(thickness 0.1524)
				)
			)
		)
		(duplicate_pad_numbers_are_jumpers no)
		(fp_line
			(start 0.508 0)
			(end -0.508 0)
			(stroke
				(width 0.2032)
				(type default)
			)
			(layer "F.SilkS")
		)
		(fp_rect
			(start -0.5842 1.3335)
			(end 0.5842 -1.3335)
			(stroke
				(width 0)
				(type default)
			)
			(fill no)
			(layer "F.CrtYd")
		)
		(fp_rect
			(start -0.5842 1.3335)
			(end 0.5842 -1.3335)
			(stroke
				(width 0)
				(type default)
			)
			(fill no)
			(layer "F.Fab")
		)
		(pad "1" smd custom
			(at 0 -0.762 270)
			(size 0.2159 0.2159)
			(layers "F.Cu" "F.Mask" "F.Paste")
			(net "P5V_HDD17")
			(options
				(clearance outline)
				(anchor circle)
			)
			(primitives
				(gr_poly
					(pts
						(arc
							(start -0.3302 -0.4318)
							(mid -0.402042 -0.402042)
							(end -0.4318 -0.3302)
						)
						(arc
							(start -0.4318 0.3302)
							(mid -0.402042 0.402042)
							(end -0.3302 0.4318)
						)
						(arc
							(start 0.3302 0.4318)
							(mid 0.402042 0.402042)
							(end 0.4318 0.3302)
						)
						(arc
							(start 0.4318 -0.3302)
							(mid 0.402042 -0.402042)
							(end 0.3302 -0.4318)
						)
					)
					(width 0)
					(fill yes)
				)
			)
		)
		(pad "2" smd custom
			(at 0 0.762 270)
			(size 0.2159 0.2159)
			(layers "F.Cu" "F.Mask" "F.Paste")
			(net "GND")
			(options
				(clearance outline)
				(anchor circle)
			)
			(primitives
				(gr_poly
					(pts
						(arc
							(start -0.3302 -0.4318)
							(mid -0.402042 -0.402042)
							(end -0.4318 -0.3302)
						)
						(arc
							(start -0.4318 0.3302)
							(mid -0.402042 0.402042)
							(end -0.3302 0.4318)
						)
						(arc
							(start 0.3302 0.4318)
							(mid 0.402042 0.402042)
							(end 0.4318 0.3302)
						)
						(arc
							(start 0.4318 -0.3302)
							(mid 0.402042 -0.402042)
							(end 0.3302 -0.4318)
						)
					)
					(width 0)
					(fill yes)
				)
			)
		)
	)
	(footprint ""
		(layer "F.Cu")
		(at 395.20495 -275.252942 -90)
		(property "Reference" "Q49"
			(at 0 0 270)
			(layer "F.SilkS")
			(hide yes)
			(effects
				(font
					(size 1.27 1.27)
				)
			)
		)
		(property "Value" "2N7002KDW-GP"
			(at -2.3622 -8.2042 270)
			(unlocked yes)
			(layer "F.Fab")
			(hide yes)
			(effects
				(font
					(size 1.016 1.016)
					(thickness 0.1524)
				)
			)
		)
		(property "Device Type" "SOT-363H44"
			(at -2.3622 -10.1092 270)
			(unlocked yes)
			(layer "F.Fab")
			(hide yes)
			(effects
				(font
					(size 1.016 1.016)
					(thickness 0.1524)
				)
			)
		)
		(duplicate_pad_numbers_are_jumpers no)
		(fp_line
			(start -1.4478 1.7018)
			(end 1.4478 1.7018)
			(stroke
				(width 0.1524)
				(type default)
			)
			(layer "F.SilkS")
		)
		(fp_line
			(start 1.4478 1.7018)
			(end 1.4478 -1.7018)
			(stroke
				(width 0.1524)
				(type default)
			)
			(layer "F.SilkS")
		)
		(fp_line
			(start -1.27 1.524)
			(end -1.27 0.6604)
			(stroke
				(width 0.4826)
				(type default)
			)
			(layer "F.SilkS")
		)
		(fp_line
			(start -1.4478 -1.7018)
			(end -1.4478 1.7018)
			(stroke
				(width 0.1524)
				(type default)
			)
			(layer "F.SilkS")
		)
		(fp_line
			(start 1.4478 -1.7018)
			(end -1.4478 -1.7018)
			(stroke
				(width 0.1524)
				(type default)
			)
			(layer "F.SilkS")
		)
		(fp_poly
			(pts
				(xy -1.524 -1.778) (xy 1.524 -1.778) (xy 1.524 1.778) (xy -1.524 1.778)
			)
			(stroke
				(width 0)
				(type default)
			)
			(fill no)
			(layer "F.CrtYd")
		)
		(fp_poly
			(pts
				(xy -1.524 -1.778) (xy 1.524 -1.778) (xy 1.524 1.778) (xy -1.524 1.778)
			)
			(stroke
				(width 0)
				(type default)
			)
			(fill no)
			(layer "F.Fab")
		)
		(pad "1" smd rect
			(at -0.65024 0.9398 270)
			(size 0.4064 1.016)
			(layers "F.Cu" "F.Mask" "F.Paste")
			(net "GND")
		)
		(pad "2" smd rect
			(at 0 0.9398 270)
			(size 0.4064 1.016)
			(layers "F.Cu" "F.Mask" "F.Paste")
			(net "SW_PWR_R_HDD8")
		)
		(pad "3" smd rect
			(at 0.65024 0.9398 270)
			(size 0.4064 1.016)
			(layers "F.Cu" "F.Mask" "F.Paste")
			(net "SW_HDD_P8")
		)
		(pad "4" smd rect
			(at 0.65024 -0.9398 270)
			(size 0.4064 1.016)
			(layers "F.Cu" "F.Mask" "F.Paste")
			(net "GND")
		)
		(pad "5" smd rect
			(at 0 -0.9398 270)
			(size 0.4064 1.016)
			(layers "F.Cu" "F.Mask" "F.Paste")
			(net "SW_HDD_G8")
		)
		(pad "6" smd rect
			(at -0.65024 -0.9398 270)
			(size 0.4064 1.016)
			(layers "F.Cu" "F.Mask" "F.Paste")
			(net "SW_HDD_R8")
		)
	)
	(footprint ""
		(layer "F.Cu")
		(at 237.988856 -343.309448 180)
		(property "Reference" "R186"
			(at 0 0 180)
			(layer "F.SilkS")
			(hide yes)
			(effects
				(font
					(size 1.27 1.27)
				)
			)
		)
		(property "Value" "16K2R2F-GP"
			(at 0.064008 -3.993896 180)
			(unlocked yes)
			(layer "F.Fab")
			(hide yes)
			(effects
				(font
					(size 1.016 1.016)
					(thickness 0.1524)
				)
			)
		)
		(property "Device Type" "R402H16"
			(at 0.064008 -5.517896 180)
			(unlocked yes)
			(layer "F.Fab")
			(hide yes)
			(effects
				(font
					(size 1.016 1.016)
					(thickness 0.1524)
				)
			)
		)
		(duplicate_pad_numbers_are_jumpers no)
		(fp_line
			(start 0.508 -0.9398)
			(end -0.508 -0.9398)
			(stroke
				(width 0.1524)
				(type default)
			)
			(layer "F.SilkS")
		)
		(fp_line
			(start -0.508 -0.9398)
			(end -0.508 0.9398)
			(stroke
				(width 0.1524)
				(type default)
			)
			(layer "F.SilkS")
		)
		(fp_rect
			(start -0.508 0.9398)
			(end 0.508 -0.9398)
			(stroke
				(width 0)
				(type default)
			)
			(fill no)
			(layer "F.CrtYd")
		)
		(fp_rect
			(start -0.508 0.9398)
			(end 0.508 -0.9398)
			(stroke
				(width 0)
				(type default)
			)
			(fill no)
			(layer "F.Fab")
		)
		(pad "1" smd custom
			(at 0 -0.4445 180)
			(size 0.1397 0.1397)
			(layers "F.Cu" "F.Mask" "F.Paste")
			(net "P5V_A_4")
			(options
				(clearance outline)
				(anchor circle)
			)
			(primitives
				(gr_poly
					(pts
						(arc
							(start -0.1778 -0.2794)
							(mid -0.249642 -0.249642)
							(end -0.2794 -0.1778)
						)
						(arc
							(start -0.2794 0.1778)
							(mid -0.249642 0.249642)
							(end -0.1778 0.2794)
						)
						(arc
							(start 0.1778 0.2794)
							(mid 0.249642 0.249642)
							(end 0.2794 0.1778)
						)
						(arc
							(start 0.2794 -0.1778)
							(mid 0.249642 -0.249642)
							(end 0.1778 -0.2794)
						)
					)
					(width 0)
					(fill yes)
				)
			)
		)
		(pad "2" smd custom
			(at 0 0.4445 180)
			(size 0.1397 0.1397)
			(layers "F.Cu" "F.Mask" "F.Paste")
			(net "P5V_A_4_SENSE")
			(options
				(clearance outline)
				(anchor circle)
			)
			(primitives
				(gr_poly
					(pts
						(arc
							(start -0.1778 -0.2794)
							(mid -0.249642 -0.249642)
							(end -0.2794 -0.1778)
						)
						(arc
							(start -0.2794 0.1778)
							(mid -0.249642 0.249642)
							(end -0.1778 0.2794)
						)
						(arc
							(start 0.1778 0.2794)
							(mid 0.249642 0.249642)
							(end 0.2794 0.1778)
						)
						(arc
							(start 0.2794 -0.1778)
							(mid 0.249642 -0.249642)
							(end 0.1778 -0.2794)
						)
					)
					(width 0)
					(fill yes)
				)
			)
		)
	)
	(footprint ""
		(layer "F.Cu")
		(at 266.192 -112.268 -90)
		(property "Reference" "R623"
			(at 0 0 270)
			(layer "F.SilkS")
			(hide yes)
			(effects
				(font
					(size 1.27 1.27)
				)
			)
		)
		(property "Value" "4K7R2F-GP"
			(at 0.064008 -3.993896 270)
			(unlocked yes)
			(layer "F.Fab")
			(hide yes)
			(effects
				(font
					(size 1.016 1.016)
					(thickness 0.1524)
				)
			)
		)
		(property "Device Type" "R402H16"
			(at 0.064008 -5.517896 270)
			(unlocked yes)
			(layer "F.Fab")
			(hide yes)
			(effects
				(font
					(size 1.016 1.016)
					(thickness 0.1524)
				)
			)
		)
		(duplicate_pad_numbers_are_jumpers no)
		(fp_line
			(start -0.508 -0.9398)
			(end -0.508 0.9398)
			(stroke
				(width 0.1524)
				(type default)
			)
			(layer "F.SilkS")
		)
		(fp_line
			(start 0.508 -0.9398)
			(end -0.508 -0.9398)
			(stroke
				(width 0.1524)
				(type default)
			)
			(layer "F.SilkS")
		)
		(fp_rect
			(start -0.508 0.9398)
			(end 0.508 -0.9398)
			(stroke
				(width 0)
				(type default)
			)
			(fill no)
			(layer "F.CrtYd")
		)
		(fp_rect
			(start -0.508 0.9398)
			(end 0.508 -0.9398)
			(stroke
				(width 0)
				(type default)
			)
			(fill no)
			(layer "F.Fab")
		)
		(pad "1" smd custom
			(at 0 -0.4445 270)
			(size 0.1397 0.1397)
			(layers "F.Cu" "F.Mask" "F.Paste")
			(net "COMP_B_BMC_B_ALERT_N")
			(options
				(clearance outline)
				(anchor circle)
			)
			(primitives
				(gr_poly
					(pts
						(arc
							(start -0.1778 -0.2794)
							(mid -0.249642 -0.249642)
							(end -0.2794 -0.1778)
						)
						(arc
							(start -0.2794 0.1778)
							(mid -0.249642 0.249642)
							(end -0.1778 0.2794)
						)
						(arc
							(start 0.1778 0.2794)
							(mid 0.249642 0.249642)
							(end 0.2794 0.1778)
						)
						(arc
							(start 0.2794 -0.1778)
							(mid 0.249642 -0.249642)
							(end 0.1778 -0.2794)
						)
					)
					(width 0)
					(fill yes)
				)
			)
		)
		(pad "2" smd custom
			(at 0 0.4445 270)
			(size 0.1397 0.1397)
			(layers "F.Cu" "F.Mask" "F.Paste")
			(net "P3V3_STBY_B")
			(options
				(clearance outline)
				(anchor circle)
			)
			(primitives
				(gr_poly
					(pts
						(arc
							(start -0.1778 -0.2794)
							(mid -0.249642 -0.249642)
							(end -0.2794 -0.1778)
						)
						(arc
							(start -0.2794 0.1778)
							(mid -0.249642 0.249642)
							(end -0.1778 0.2794)
						)
						(arc
							(start 0.1778 0.2794)
							(mid 0.249642 0.249642)
							(end 0.2794 0.1778)
						)
						(arc
							(start 0.2794 -0.1778)
							(mid 0.249642 -0.249642)
							(end 0.1778 -0.2794)
						)
					)
					(width 0)
					(fill yes)
				)
			)
		)
	)
	(footprint ""
		(layer "F.Cu")
		(at 130.447796 -62.143894 -90)
		(property "Reference" "R751"
			(at 0 0 270)
			(layer "F.SilkS")
			(hide yes)
			(effects
				(font
					(size 1.27 1.27)
				)
			)
		)
		(property "Value" "10KR2F-2-GP"
			(at 0.064008 -3.993896 270)
			(unlocked yes)
			(layer "F.Fab")
			(hide yes)
			(effects
				(font
					(size 1.016 1.016)
					(thickness 0.1524)
				)
			)
		)
		(property "Device Type" "R402H16"
			(at 0.064008 -5.517896 270)
			(unlocked yes)
			(layer "F.Fab")
			(hide yes)
			(effects
				(font
					(size 1.016 1.016)
					(thickness 0.1524)
				)
			)
		)
		(duplicate_pad_numbers_are_jumpers no)
		(fp_line
			(start -0.508 -0.9398)
			(end -0.508 0.9398)
			(stroke
				(width 0.1524)
				(type default)
			)
			(layer "F.SilkS")
		)
		(fp_line
			(start 0.508 -0.9398)
			(end -0.508 -0.9398)
			(stroke
				(width 0.1524)
				(type default)
			)
			(layer "F.SilkS")
		)
		(fp_rect
			(start -0.508 0.9398)
			(end 0.508 -0.9398)
			(stroke
				(width 0)
				(type default)
			)
			(fill no)
			(layer "F.CrtYd")
		)
		(fp_rect
			(start -0.508 0.9398)
			(end 0.508 -0.9398)
			(stroke
				(width 0)
				(type default)
			)
			(fill no)
			(layer "F.Fab")
		)
		(pad "1" smd custom
			(at 0 -0.4445 270)
			(size 0.1397 0.1397)
			(layers "F.Cu" "F.Mask" "F.Paste")
			(net "P3V3_STBY_A")
			(options
				(clearance outline)
				(anchor circle)
			)
			(primitives
				(gr_poly
					(pts
						(arc
							(start -0.1778 -0.2794)
							(mid -0.249642 -0.249642)
							(end -0.2794 -0.1778)
						)
						(arc
							(start -0.2794 0.1778)
							(mid -0.249642 0.249642)
							(end -0.1778 0.2794)
						)
						(arc
							(start 0.1778 0.2794)
							(mid 0.249642 0.249642)
							(end 0.2794 0.1778)
						)
						(arc
							(start 0.2794 -0.1778)
							(mid 0.249642 -0.249642)
							(end 0.1778 -0.2794)
						)
					)
					(width 0)
					(fill yes)
				)
			)
		)
		(pad "2" smd custom
			(at 0 0.4445 270)
			(size 0.1397 0.1397)
			(layers "F.Cu" "F.Mask" "F.Paste")
			(net "HDD_PRSNT_27")
			(options
				(clearance outline)
				(anchor circle)
			)
			(primitives
				(gr_poly
					(pts
						(arc
							(start -0.1778 -0.2794)
							(mid -0.249642 -0.249642)
							(end -0.2794 -0.1778)
						)
						(arc
							(start -0.2794 0.1778)
							(mid -0.249642 0.249642)
							(end -0.1778 0.2794)
						)
						(arc
							(start 0.1778 0.2794)
							(mid 0.249642 0.249642)
							(end 0.2794 0.1778)
						)
						(arc
							(start 0.2794 -0.1778)
							(mid 0.249642 -0.249642)
							(end 0.1778 -0.2794)
						)
					)
					(width 0)
					(fill yes)
				)
			)
		)
	)
	(footprint ""
		(layer "F.Cu")
		(at 96.324928 -207.79994)
		(property "Reference" ""
			(at 0 0 0)
			(layer "F.SilkS")
			(hide yes)
			(effects
				(font
					(size 1.27 1.27)
				)
			)
		)
		(property "Value" "*"
			(at -8.398764 -8.057642 0)
			(unlocked yes)
			(layer "F.Fab")
			(hide yes)
			(effects
				(font
					(size 1.016 1.016)
					(thickness 0.1524)
				)
			)
		)
		(duplicate_pad_numbers_are_jumpers no)
		(fp_poly
			(pts
				(arc
					(start 7.3152 0)
					(mid 0 7.3152)
					(end -7.3152 0)
				)
				(arc
					(start -7.3152 -5.9944)
					(mid 0 -13.3096)
					(end 7.3152 -5.9944)
				)
			)
			(stroke
				(width 0)
				(type default)
			)
			(fill no)
			(layer "B.CrtYd")
		)
		(fp_poly
			(pts
				(arc
					(start 7.3152 0)
					(mid 0 7.3152)
					(end -7.3152 0)
				)
				(arc
					(start -7.3152 -5.9944)
					(mid 0 -13.3096)
					(end 7.3152 -5.9944)
				)
			)
			(stroke
				(width 0)
				(type default)
			)
			(fill no)
			(layer "F.CrtYd")
		)
		(fp_poly
			(pts
				(arc
					(start 7.3152 0)
					(mid 0 7.3152)
					(end -7.3152 0)
				)
				(arc
					(start -7.3152 -5.9944)
					(mid 0 -13.3096)
					(end 7.3152 -5.9944)
				)
			)
			(stroke
				(width 0)
				(type default)
			)
			(fill no)
			(layer "B.Fab")
		)
		(fp_poly
			(pts
				(arc
					(start 7.3152 0)
					(mid 0 7.3152)
					(end -7.3152 0)
				)
				(arc
					(start -7.3152 -5.9944)
					(mid 0 -13.3096)
					(end 7.3152 -5.9944)
				)
			)
			(stroke
				(width 0)
				(type default)
			)
			(fill no)
			(layer "F.Fab")
		)
		(pad "1" thru_hole oval
			(at 0 0)
			(size 14.0208 20.0152)
			(drill 0.0254
				(offset 0 -2.9972)
			)
			(layers "*.Cu" "*.Mask")
			(remove_unused_layers no)
			(net "Net_104")
			(clearance -1.002284)
			(thermal_gap 0.1524)
			(padstack
				(mode front_inner_back)
				(layer "Inner"
					(shape custom)
					(size 2.928012 2.928012)
					(options
						(anchor circle)
					)
					(primitives
						(gr_poly
							(pts
								(arc
									(start 4.571746 -2.084324)
									(mid 0.000333 7.430372)
									(end -4.571492 -2.084324)
								)
								(arc
									(start -4.571492 -2.084324)
									(mid -3.570296 -3.611977)
									(end -2.875026 -5.30098)
								)
								(arc
									(start -2.875026 -5.30098)
									(mid 0.000217 -7.43089)
									(end 2.87528 -5.30098)
								)
								(arc
									(start 2.87528 -5.30098)
									(mid 3.570511 -3.611956)
									(end 4.571746 -2.084324)
								)
							)
							(width 0)
							(fill yes)
						)
					)
					(clearance 0.1524)
				)
				(layer "B.Cu"
					(shape oval)
					(size 14.0208 20.0152)
					(offset 0 -2.9972)
					(clearance -1.002284)
				)
			)
		)
		(zone
			(layers "F.Cu" "B.Cu" "In1.Cu" "In2.Cu" "In3.Cu" "In4.Cu" "In5.Cu" "In6.Cu"
				"In7.Cu" "In8.Cu" "In9.Cu" "In10.Cu"
			)
			(hatch none 0.5)
			(connect_pads
				(clearance 0)
			)
			(min_thickness 0.25)
			(keepout
				(tracks not_allowed)
				(vias allowed)
				(pads allowed)
				(copperpour not_allowed)
				(footprints allowed)
			)
			(placement
				(enabled no)
				(sheetname "")
			)
			(fill
				(thermal_gap 0.5)
				(thermal_bridge_width 0.5)
				(island_removal_mode 0)
			)
			(polygon
				(pts
					(arc
						(start 89.314528 -213.79434)
						(mid 96.324928 -220.80474)
						(end 103.335328 -213.79434)
					)
					(arc
						(start 103.335328 -207.79994)
						(mid 96.324928 -200.78954)
						(end 89.314528 -207.79994)
					)
				)
			)
		)
	)
	(footprint ""
		(layer "F.Cu")
		(at 363.909102 -65.826894 180)
		(property "Reference" "C444"
			(at 0 0 180)
			(layer "F.SilkS")
			(hide yes)
			(effects
				(font
					(size 1.27 1.27)
				)
			)
		)
		(property "Value" "SC10U16V6KX-2GP"
			(at -0.0762 -5.1308 180)
			(unlocked yes)
			(layer "F.Fab")
			(hide yes)
			(effects
				(font
					(size 1.016 1.016)
					(thickness 0.1524)
				)
			)
		)
		(property "Device Type" "C1206H71"
			(at -0.127 -6.6548 180)
			(unlocked yes)
			(layer "F.Fab")
			(hide yes)
			(effects
				(font
					(size 1.016 1.016)
					(thickness 0.1524)
				)
			)
		)
		(duplicate_pad_numbers_are_jumpers no)
		(fp_line
			(start 1.016 2.2352)
			(end -1.016 2.2352)
			(stroke
				(width 0.1524)
				(type default)
			)
			(layer "F.SilkS")
		)
		(fp_line
			(start 1.016 0.8382)
			(end 1.016 2.2352)
			(stroke
				(width 0.1524)
				(type default)
			)
			(layer "F.SilkS")
		)
		(fp_line
			(start 1.016 -2.2352)
			(end 1.016 -0.8382)
			(stroke
				(width 0.1524)
				(type default)
			)
			(layer "F.SilkS")
		)
		(fp_line
			(start -1.016 2.2352)
			(end -1.016 0.8382)
			(stroke
				(width 0.1524)
				(type default)
			)
			(layer "F.SilkS")
		)
		(fp_line
			(start -1.016 -0.8382)
			(end -1.016 -2.2352)
			(stroke
				(width 0.1524)
				(type default)
			)
			(layer "F.SilkS")
		)
		(fp_line
			(start -1.016 -2.2352)
			(end 1.016 -2.2352)
			(stroke
				(width 0.1524)
				(type default)
			)
			(layer "F.SilkS")
		)
		(fp_rect
			(start -1.0922 2.3114)
			(end 1.0922 -2.3114)
			(stroke
				(width 0)
				(type default)
			)
			(fill no)
			(layer "F.CrtYd")
		)
		(fp_poly
			(pts
				(xy 1.0922 -2.3114) (xy 1.0922 2.3114) (xy -1.0922 2.3114) (xy -1.0922 -2.3114)
			)
			(stroke
				(width 0)
				(type default)
			)
			(fill no)
			(layer "F.Fab")
		)
		(pad "1" smd rect
			(at 0 -1.397 180)
			(size 1.651 1.27)
			(layers "F.Cu" "F.Mask" "F.Paste")
			(net "P5V_HDD31")
		)
		(pad "2" smd rect
			(at 0 1.397 180)
			(size 1.651 1.27)
			(layers "F.Cu" "F.Mask" "F.Paste")
			(net "GND")
		)
	)
	(footprint ""
		(layer "F.Cu")
		(at 427.390052 -49.596294 90)
		(property "Reference" "C477"
			(at 0 0 90)
			(layer "F.SilkS")
			(hide yes)
			(effects
				(font
					(size 1.27 1.27)
				)
			)
		)
		(property "Value" "SCD033U25V2KX-GP"
			(at 1.1811 -2.7051 90)
			(unlocked yes)
			(layer "F.Fab")
			(hide yes)
			(effects
				(font
					(size 1.016 1.016)
					(thickness 0.1524)
				)
			)
		)
		(property "Device Type" "C402H22"
			(at 1.1811 -4.2291 90)
			(unlocked yes)
			(layer "F.Fab")
			(hide yes)
			(effects
				(font
					(size 1.016 1.016)
					(thickness 0.1524)
				)
			)
		)
		(duplicate_pad_numbers_are_jumpers no)
		(fp_rect
			(start -0.4318 0.9525)
			(end 0.4318 -0.9525)
			(stroke
				(width 0)
				(type default)
			)
			(fill no)
			(layer "F.CrtYd")
		)
		(fp_rect
			(start -0.4318 0.9525)
			(end 0.4318 -0.9525)
			(stroke
				(width 0)
				(type default)
			)
			(fill no)
			(layer "F.Fab")
		)
		(pad "1" smd custom
			(at 0 -0.4445 90)
			(size 0.1524 0.1524)
			(layers "F.Cu" "F.Mask" "F.Paste")
			(net "SW_HDD_P33")
			(options
				(clearance outline)
				(anchor circle)
			)
			(primitives
				(gr_poly
					(pts
						(arc
							(start 0.3048 -0.2032)
							(mid 0.275042 -0.275042)
							(end 0.2032 -0.3048)
						)
						(arc
							(start -0.2032 -0.3048)
							(mid -0.275042 -0.275042)
							(end -0.3048 -0.2032)
						)
						(arc
							(start -0.3048 0.2032)
							(mid -0.275042 0.275042)
							(end -0.2032 0.3048)
						)
						(arc
							(start 0.2032 0.3048)
							(mid 0.275042 0.275042)
							(end 0.3048 0.2032)
						)
					)
					(width 0)
					(fill yes)
				)
			)
		)
		(pad "2" smd custom
			(at 0 0.4445 90)
			(size 0.1524 0.1524)
			(layers "F.Cu" "F.Mask" "F.Paste")
			(net "GND")
			(options
				(clearance outline)
				(anchor circle)
			)
			(primitives
				(gr_poly
					(pts
						(arc
							(start 0.3048 -0.2032)
							(mid 0.275042 -0.275042)
							(end 0.2032 -0.3048)
						)
						(arc
							(start -0.2032 -0.3048)
							(mid -0.275042 -0.275042)
							(end -0.3048 -0.2032)
						)
						(arc
							(start -0.3048 0.2032)
							(mid -0.275042 0.275042)
							(end -0.2032 0.3048)
						)
						(arc
							(start 0.2032 0.3048)
							(mid 0.275042 0.275042)
							(end 0.3048 0.2032)
						)
					)
					(width 0)
					(fill yes)
				)
			)
		)
	)
	(footprint ""
		(layer "F.Cu")
		(at 220.588332 -389.492998 180)
		(property "Reference" "Q22"
			(at 0 0 180)
			(layer "F.SilkS")
			(hide yes)
			(effects
				(font
					(size 1.27 1.27)
				)
			)
		)
		(property "Value" "2N7002K-1-GP"
			(at 0.127 -8.9662 180)
			(unlocked yes)
			(layer "F.Fab")
			(hide yes)
			(effects
				(font
					(size 1.016 1.016)
					(thickness 0.1524)
				)
			)
		)
		(property "Device Type" "SOT23DGS2D4H44"
			(at 0.127 -10.4902 180)
			(unlocked yes)
			(layer "F.Fab")
			(hide yes)
			(effects
				(font
					(size 1.016 1.016)
					(thickness 0.1524)
				)
			)
		)
		(duplicate_pad_numbers_are_jumpers no)
		(fp_line
			(start 1.651 1.778)
			(end 1.651 -1.778)
			(stroke
				(width 0.1524)
				(type default)
			)
			(layer "F.SilkS")
		)
		(fp_line
			(start 1.651 -1.778)
			(end -1.651 -1.778)
			(stroke
				(width 0.1524)
				(type default)
			)
			(layer "F.SilkS")
		)
		(fp_line
			(start -1.651 1.778)
			(end 1.651 1.778)
			(stroke
				(width 0.1524)
				(type default)
			)
			(layer "F.SilkS")
		)
		(fp_line
			(start -1.651 -1.778)
			(end -1.651 1.778)
			(stroke
				(width 0.1524)
				(type default)
			)
			(layer "F.SilkS")
		)
		(fp_poly
			(pts
				(xy -1.778 1.8796) (xy -1.778 -1.8796) (xy 1.778 -1.8796) (xy 1.778 1.8796)
			)
			(stroke
				(width 0)
				(type default)
			)
			(fill no)
			(layer "F.CrtYd")
		)
		(fp_poly
			(pts
				(xy -1.778 1.8796) (xy -1.778 -1.8796) (xy 1.778 -1.8796) (xy 1.778 1.8796)
			)
			(stroke
				(width 0)
				(type default)
			)
			(fill no)
			(layer "F.Fab")
		)
		(pad "D" smd custom
			(at 0 -0.9525 180)
			(size 0.1905 0.1905)
			(layers "F.Cu" "F.Mask" "F.Paste")
			(net "SCC_A_FULL_PWR_EN_12V")
			(options
				(clearance outline)
				(anchor circle)
			)
			(primitives
				(gr_poly
					(pts
						(arc
							(start -0.1778 0.5715)
							(mid -0.321484 0.511984)
							(end -0.381 0.3683)
						)
						(arc
							(start -0.381 -0.3683)
							(mid -0.321484 -0.511984)
							(end -0.1778 -0.5715)
						)
						(arc
							(start 0.1778 -0.5715)
							(mid 0.321484 -0.511984)
							(end 0.381 -0.3683)
						)
						(arc
							(start 0.381 0.3683)
							(mid 0.321484 0.511984)
							(end 0.1778 0.5715)
						)
					)
					(width 0)
					(fill yes)
				)
			)
		)
		(pad "G" smd custom
			(at -0.98425 0.9525 180)
			(size 0.1905 0.1905)
			(layers "F.Cu" "F.Mask" "F.Paste")
			(net "SCC_A_FULL_PWR_EN")
			(options
				(clearance outline)
				(anchor circle)
			)
			(primitives
				(gr_poly
					(pts
						(arc
							(start -0.1778 0.5715)
							(mid -0.321484 0.511984)
							(end -0.381 0.3683)
						)
						(arc
							(start -0.381 -0.3683)
							(mid -0.321484 -0.511984)
							(end -0.1778 -0.5715)
						)
						(arc
							(start 0.1778 -0.5715)
							(mid 0.321484 -0.511984)
							(end 0.381 -0.3683)
						)
						(arc
							(start 0.381 0.3683)
							(mid 0.321484 0.511984)
							(end 0.1778 0.5715)
						)
					)
					(width 0)
					(fill yes)
				)
			)
		)
		(pad "S" smd custom
			(at 0.98425 0.9525 180)
			(size 0.1905 0.1905)
			(layers "F.Cu" "F.Mask" "F.Paste")
			(net "GND")
			(options
				(clearance outline)
				(anchor circle)
			)
			(primitives
				(gr_poly
					(pts
						(arc
							(start -0.1778 0.5715)
							(mid -0.321484 0.511984)
							(end -0.381 0.3683)
						)
						(arc
							(start -0.381 -0.3683)
							(mid -0.321484 -0.511984)
							(end -0.1778 -0.5715)
						)
						(arc
							(start 0.1778 -0.5715)
							(mid 0.321484 -0.511984)
							(end 0.381 -0.3683)
						)
						(arc
							(start 0.381 0.3683)
							(mid 0.321484 0.511984)
							(end 0.1778 0.5715)
						)
					)
					(width 0)
					(fill yes)
				)
			)
		)
	)
	(footprint ""
		(layer "F.Cu")
		(at 48.694848 -127.254)
		(property "Reference" "R286"
			(at 0 0 0)
			(layer "F.SilkS")
			(hide yes)
			(effects
				(font
					(size 1.27 1.27)
				)
			)
		)
		(property "Value" "130R3F-GP"
			(at -0.0254 -2.5146 0)
			(unlocked yes)
			(layer "F.Fab")
			(hide yes)
			(effects
				(font
					(size 1.016 1.016)
					(thickness 0.1524)
				)
			)
		)
		(property "Device Type" "R603H22"
			(at -0.0254 -4.0386 0)
			(unlocked yes)
			(layer "F.Fab")
			(hide yes)
			(effects
				(font
					(size 1.016 1.016)
					(thickness 0.1524)
				)
			)
		)
		(duplicate_pad_numbers_are_jumpers no)
		(fp_line
			(start -0.4826 0)
			(end -0.2032 0)
			(stroke
				(width 0.2032)
				(type default)
			)
			(layer "F.SilkS")
		)
		(fp_line
			(start 0.2032 0)
			(end 0.4826 0)
			(stroke
				(width 0.2032)
				(type default)
			)
			(layer "F.SilkS")
		)
		(fp_rect
			(start -0.5842 1.3335)
			(end 0.5842 -1.3335)
			(stroke
				(width 0)
				(type default)
			)
			(fill no)
			(layer "F.CrtYd")
		)
		(fp_rect
			(start -0.5842 1.3335)
			(end 0.5842 -1.3335)
			(stroke
				(width 0)
				(type default)
			)
			(fill no)
			(layer "F.Fab")
		)
		(pad "1" smd custom
			(at 0 -0.762)
			(size 0.2159 0.2159)
			(layers "F.Cu" "F.Mask" "F.Paste")
			(net "P5V_A_1")
			(options
				(clearance outline)
				(anchor circle)
			)
			(primitives
				(gr_poly
					(pts
						(arc
							(start -0.3302 -0.4318)
							(mid -0.402042 -0.402042)
							(end -0.4318 -0.3302)
						)
						(arc
							(start -0.4318 0.3302)
							(mid -0.402042 0.402042)
							(end -0.3302 0.4318)
						)
						(arc
							(start 0.3302 0.4318)
							(mid 0.402042 0.402042)
							(end 0.4318 0.3302)
						)
						(arc
							(start 0.4318 -0.3302)
							(mid 0.402042 -0.402042)
							(end 0.3302 -0.4318)
						)
					)
					(width 0)
					(fill yes)
				)
			)
		)
		(pad "2" smd custom
			(at 0 0.762)
			(size 0.2159 0.2159)
			(layers "F.Cu" "F.Mask" "F.Paste")
			(net "FLT_HDD13")
			(options
				(clearance outline)
				(anchor circle)
			)
			(primitives
				(gr_poly
					(pts
						(arc
							(start -0.3302 -0.4318)
							(mid -0.402042 -0.402042)
							(end -0.4318 -0.3302)
						)
						(arc
							(start -0.4318 0.3302)
							(mid -0.402042 0.402042)
							(end -0.3302 0.4318)
						)
						(arc
							(start 0.3302 0.4318)
							(mid 0.402042 0.402042)
							(end 0.4318 0.3302)
						)
						(arc
							(start 0.4318 -0.3302)
							(mid 0.402042 -0.402042)
							(end 0.3302 -0.4318)
						)
					)
					(width 0)
					(fill yes)
				)
			)
		)
	)
	(footprint ""
		(layer "F.Cu")
		(at 51.599846 -176.000918 -90)
		(property "Reference" "C210"
			(at 0 0 270)
			(layer "F.SilkS")
			(hide yes)
			(effects
				(font
					(size 1.27 1.27)
				)
			)
		)
		(property "Value" "SC10U16V6KX-2GP"
			(at -0.0762 -5.1308 270)
			(unlocked yes)
			(layer "F.Fab")
			(hide yes)
			(effects
				(font
					(size 1.016 1.016)
					(thickness 0.1524)
				)
			)
		)
		(property "Device Type" "C1206H71"
			(at -0.127 -6.6548 270)
			(unlocked yes)
			(layer "F.Fab")
			(hide yes)
			(effects
				(font
					(size 1.016 1.016)
					(thickness 0.1524)
				)
			)
		)
		(duplicate_pad_numbers_are_jumpers no)
		(fp_line
			(start -1.016 2.2352)
			(end -1.016 0.8382)
			(stroke
				(width 0.1524)
				(type default)
			)
			(layer "F.SilkS")
		)
		(fp_line
			(start 1.016 2.2352)
			(end -1.016 2.2352)
			(stroke
				(width 0.1524)
				(type default)
			)
			(layer "F.SilkS")
		)
		(fp_line
			(start 1.016 0.8382)
			(end 1.016 2.2352)
			(stroke
				(width 0.1524)
				(type default)
			)
			(layer "F.SilkS")
		)
		(fp_line
			(start -1.016 -0.8382)
			(end -1.016 -2.2352)
			(stroke
				(width 0.1524)
				(type default)
			)
			(layer "F.SilkS")
		)
		(fp_line
			(start -1.016 -2.2352)
			(end 1.016 -2.2352)
			(stroke
				(width 0.1524)
				(type default)
			)
			(layer "F.SilkS")
		)
		(fp_line
			(start 1.016 -2.2352)
			(end 1.016 -0.8382)
			(stroke
				(width 0.1524)
				(type default)
			)
			(layer "F.SilkS")
		)
		(fp_rect
			(start -1.0922 2.3114)
			(end 1.0922 -2.3114)
			(stroke
				(width 0)
				(type default)
			)
			(fill no)
			(layer "F.CrtYd")
		)
		(fp_poly
			(pts
				(xy 1.0922 -2.3114) (xy 1.0922 2.3114) (xy -1.0922 2.3114) (xy -1.0922 -2.3114)
			)
			(stroke
				(width 0)
				(type default)
			)
			(fill no)
			(layer "F.Fab")
		)
		(pad "1" smd rect
			(at 0 -1.397 270)
			(size 1.651 1.27)
			(layers "F.Cu" "F.Mask" "F.Paste")
			(net "P5V_HDD13")
		)
		(pad "2" smd rect
			(at 0 1.397 270)
			(size 1.651 1.27)
			(layers "F.Cu" "F.Mask" "F.Paste")
			(net "GND")
		)
	)
	(footprint ""
		(layer "F.Cu")
		(at 411.539944 -294.438324 180)
		(property "Reference" "R303"
			(at 0 0 180)
			(layer "F.SilkS")
			(hide yes)
			(effects
				(font
					(size 1.27 1.27)
				)
			)
		)
		(property "Value" "130R3F-GP"
			(at -0.0254 -2.5146 180)
			(unlocked yes)
			(layer "F.Fab")
			(hide yes)
			(effects
				(font
					(size 1.016 1.016)
					(thickness 0.1524)
				)
			)
		)
		(property "Device Type" "R603H22"
			(at -0.0254 -4.0386 180)
			(unlocked yes)
			(layer "F.Fab")
			(hide yes)
			(effects
				(font
					(size 1.016 1.016)
					(thickness 0.1524)
				)
			)
		)
		(duplicate_pad_numbers_are_jumpers no)
		(fp_line
			(start 0.2032 0)
			(end 0.4826 0)
			(stroke
				(width 0.2032)
				(type default)
			)
			(layer "F.SilkS")
		)
		(fp_line
			(start -0.4826 0)
			(end -0.2032 0)
			(stroke
				(width 0.2032)
				(type default)
			)
			(layer "F.SilkS")
		)
		(fp_rect
			(start -0.5842 1.3335)
			(end 0.5842 -1.3335)
			(stroke
				(width 0)
				(type default)
			)
			(fill no)
			(layer "F.CrtYd")
		)
		(fp_rect
			(start -0.5842 1.3335)
			(end 0.5842 -1.3335)
			(stroke
				(width 0)
				(type default)
			)
			(fill no)
			(layer "F.Fab")
		)
		(pad "1" smd custom
			(at 0 -0.762 180)
			(size 0.2159 0.2159)
			(layers "F.Cu" "F.Mask" "F.Paste")
			(net "P5V_B")
			(options
				(clearance outline)
				(anchor circle)
			)
			(primitives
				(gr_poly
					(pts
						(arc
							(start -0.3302 -0.4318)
							(mid -0.402042 -0.402042)
							(end -0.4318 -0.3302)
						)
						(arc
							(start -0.4318 0.3302)
							(mid -0.402042 0.402042)
							(end -0.3302 0.4318)
						)
						(arc
							(start 0.3302 0.4318)
							(mid 0.402042 0.402042)
							(end 0.4318 0.3302)
						)
						(arc
							(start 0.4318 -0.3302)
							(mid 0.402042 -0.402042)
							(end 0.3302 -0.4318)
						)
					)
					(width 0)
					(fill yes)
				)
			)
		)
		(pad "2" smd custom
			(at 0 0.762 180)
			(size 0.2159 0.2159)
			(layers "F.Cu" "F.Mask" "F.Paste")
			(net "FLT_HDD33")
			(options
				(clearance outline)
				(anchor circle)
			)
			(primitives
				(gr_poly
					(pts
						(arc
							(start -0.3302 -0.4318)
							(mid -0.402042 -0.402042)
							(end -0.4318 -0.3302)
						)
						(arc
							(start -0.4318 0.3302)
							(mid -0.402042 0.402042)
							(end -0.3302 0.4318)
						)
						(arc
							(start 0.3302 0.4318)
							(mid 0.402042 0.402042)
							(end 0.4318 0.3302)
						)
						(arc
							(start 0.4318 -0.3302)
							(mid 0.402042 -0.402042)
							(end 0.3302 -0.4318)
						)
					)
					(width 0)
					(fill yes)
				)
			)
		)
	)
	(footprint ""
		(layer "F.Cu")
		(at 399.90395 -164.951918 90)
		(property "Reference" "R606"
			(at 0 0 90)
			(layer "F.SilkS")
			(hide yes)
			(effects
				(font
					(size 1.27 1.27)
				)
			)
		)
		(property "Value" "200KR2F-L-GP"
			(at 0.064008 -3.993896 90)
			(unlocked yes)
			(layer "F.Fab")
			(hide yes)
			(effects
				(font
					(size 1.016 1.016)
					(thickness 0.1524)
				)
			)
		)
		(property "Device Type" "R402H16"
			(at 0.064008 -5.517896 90)
			(unlocked yes)
			(layer "F.Fab")
			(hide yes)
			(effects
				(font
					(size 1.016 1.016)
					(thickness 0.1524)
				)
			)
		)
		(duplicate_pad_numbers_are_jumpers no)
		(fp_line
			(start 0.508 -0.9398)
			(end -0.508 -0.9398)
			(stroke
				(width 0.1524)
				(type default)
			)
			(layer "F.SilkS")
		)
		(fp_line
			(start -0.508 -0.9398)
			(end -0.508 0.9398)
			(stroke
				(width 0.1524)
				(type default)
			)
			(layer "F.SilkS")
		)
		(fp_rect
			(start -0.508 0.9398)
			(end 0.508 -0.9398)
			(stroke
				(width 0)
				(type default)
			)
			(fill no)
			(layer "F.CrtYd")
		)
		(fp_rect
			(start -0.508 0.9398)
			(end 0.508 -0.9398)
			(stroke
				(width 0)
				(type default)
			)
			(fill no)
			(layer "F.Fab")
		)
		(pad "1" smd custom
			(at 0 -0.4445 90)
			(size 0.1397 0.1397)
			(layers "F.Cu" "F.Mask" "F.Paste")
			(net "SW_HDD_R20")
			(options
				(clearance outline)
				(anchor circle)
			)
			(primitives
				(gr_poly
					(pts
						(arc
							(start -0.1778 -0.2794)
							(mid -0.249642 -0.249642)
							(end -0.2794 -0.1778)
						)
						(arc
							(start -0.2794 0.1778)
							(mid -0.249642 0.249642)
							(end -0.1778 0.2794)
						)
						(arc
							(start 0.1778 0.2794)
							(mid 0.249642 0.249642)
							(end 0.2794 0.1778)
						)
						(arc
							(start 0.2794 -0.1778)
							(mid 0.249642 -0.249642)
							(end 0.1778 -0.2794)
						)
					)
					(width 0)
					(fill yes)
				)
			)
		)
		(pad "2" smd custom
			(at 0 0.4445 90)
			(size 0.1397 0.1397)
			(layers "F.Cu" "F.Mask" "F.Paste")
			(net "SW_HDD_N20")
			(options
				(clearance outline)
				(anchor circle)
			)
			(primitives
				(gr_poly
					(pts
						(arc
							(start -0.1778 -0.2794)
							(mid -0.249642 -0.249642)
							(end -0.2794 -0.1778)
						)
						(arc
							(start -0.2794 0.1778)
							(mid -0.249642 0.249642)
							(end -0.1778 0.2794)
						)
						(arc
							(start 0.1778 0.2794)
							(mid 0.249642 0.249642)
							(end 0.2794 0.1778)
						)
						(arc
							(start 0.2794 -0.1778)
							(mid 0.249642 -0.249642)
							(end 0.1778 -0.2794)
						)
					)
					(width 0)
					(fill yes)
				)
			)
		)
	)
	(footprint ""
		(layer "F.Cu")
		(at 67.243706 -187.443872)
		(property "Reference" "R461"
			(at 0 0 0)
			(layer "F.SilkS")
			(hide yes)
			(effects
				(font
					(size 1.27 1.27)
				)
			)
		)
		(property "Value" "4K7R2J-2-GP"
			(at 0.064008 -3.993896 0)
			(unlocked yes)
			(layer "F.Fab")
			(hide yes)
			(effects
				(font
					(size 1.016 1.016)
					(thickness 0.1524)
				)
			)
		)
		(property "Device Type" "R402H16"
			(at 0.064008 -5.517896 0)
			(unlocked yes)
			(layer "F.Fab")
			(hide yes)
			(effects
				(font
					(size 1.016 1.016)
					(thickness 0.1524)
				)
			)
		)
		(duplicate_pad_numbers_are_jumpers no)
		(fp_line
			(start -0.508 -0.9398)
			(end -0.508 0.9398)
			(stroke
				(width 0.1524)
				(type default)
			)
			(layer "F.SilkS")
		)
		(fp_line
			(start 0.508 -0.9398)
			(end -0.508 -0.9398)
			(stroke
				(width 0.1524)
				(type default)
			)
			(layer "F.SilkS")
		)
		(fp_rect
			(start -0.508 0.9398)
			(end 0.508 -0.9398)
			(stroke
				(width 0)
				(type default)
			)
			(fill no)
			(layer "F.CrtYd")
		)
		(fp_rect
			(start -0.508 0.9398)
			(end 0.508 -0.9398)
			(stroke
				(width 0)
				(type default)
			)
			(fill no)
			(layer "F.Fab")
		)
		(pad "1" smd custom
			(at 0 -0.4445)
			(size 0.1397 0.1397)
			(layers "F.Cu" "F.Mask" "F.Paste")
			(net "DRIVE_A_2_FLT_LED")
			(options
				(clearance outline)
				(anchor circle)
			)
			(primitives
				(gr_poly
					(pts
						(arc
							(start -0.1778 -0.2794)
							(mid -0.249642 -0.249642)
							(end -0.2794 -0.1778)
						)
						(arc
							(start -0.2794 0.1778)
							(mid -0.249642 0.249642)
							(end -0.1778 0.2794)
						)
						(arc
							(start 0.1778 0.2794)
							(mid 0.249642 0.249642)
							(end 0.2794 0.1778)
						)
						(arc
							(start 0.2794 -0.1778)
							(mid 0.249642 -0.249642)
							(end 0.1778 -0.2794)
						)
					)
					(width 0)
					(fill yes)
				)
			)
		)
		(pad "2" smd custom
			(at 0 0.4445)
			(size 0.1397 0.1397)
			(layers "F.Cu" "F.Mask" "F.Paste")
			(net "GND")
			(options
				(clearance outline)
				(anchor circle)
			)
			(primitives
				(gr_poly
					(pts
						(arc
							(start -0.1778 -0.2794)
							(mid -0.249642 -0.249642)
							(end -0.2794 -0.1778)
						)
						(arc
							(start -0.2794 0.1778)
							(mid -0.249642 0.249642)
							(end -0.1778 0.2794)
						)
						(arc
							(start 0.1778 0.2794)
							(mid 0.249642 0.249642)
							(end 0.2794 0.1778)
						)
						(arc
							(start 0.2794 -0.1778)
							(mid 0.249642 -0.249642)
							(end 0.1778 -0.2794)
						)
					)
					(width 0)
					(fill yes)
				)
			)
		)
	)
	(footprint ""
		(layer "F.Cu")
		(at 190.213488 -159.219392 90)
		(property "Reference" "C259"
			(at 0 0 90)
			(layer "F.SilkS")
			(hide yes)
			(effects
				(font
					(size 1.27 1.27)
				)
			)
		)
		(property "Value" "SCD01U16V1KX-GP"
			(at -2.8321 -1.7399 90)
			(unlocked yes)
			(layer "F.Fab")
			(hide yes)
			(effects
				(font
					(size 1.016 1.016)
					(thickness 0.1524)
				)
			)
		)
		(property "Device Type" "C0201H13"
			(at -2.8321 -3.2639 90)
			(unlocked yes)
			(layer "F.Fab")
			(hide yes)
			(effects
				(font
					(size 1.016 1.016)
					(thickness 0.1524)
				)
			)
		)
		(duplicate_pad_numbers_are_jumpers no)
		(fp_rect
			(start -0.2794 0.6477)
			(end 0.2794 -0.6477)
			(stroke
				(width 0)
				(type default)
			)
			(fill no)
			(layer "F.CrtYd")
		)
		(fp_rect
			(start -0.2794 0.6477)
			(end 0.2794 -0.6477)
			(stroke
				(width 0)
				(type default)
			)
			(fill no)
			(layer "F.Fab")
		)
		(pad "1" smd custom
			(at 0 -0.2794 90)
			(size 0.0762 0.0762)
			(layers "F.Cu" "F.Mask" "F.Paste")
			(net "SAS_HDD_RX_N17")
			(options
				(clearance outline)
				(anchor circle)
			)
			(primitives
				(gr_poly
					(pts
						(arc
							(start 0.1524 -0.127)
							(mid 0.137521 -0.162921)
							(end 0.1016 -0.1778)
						)
						(arc
							(start -0.1016 -0.1778)
							(mid -0.137521 -0.162921)
							(end -0.1524 -0.127)
						)
						(arc
							(start -0.1524 0.127)
							(mid -0.137521 0.162921)
							(end -0.1016 0.1778)
						)
						(arc
							(start 0.1016 0.1778)
							(mid 0.137521 0.162921)
							(end 0.1524 0.127)
						)
					)
					(width 0)
					(fill yes)
				)
			)
		)
		(pad "2" smd custom
			(at 0 0.2794 90)
			(size 0.0762 0.0762)
			(layers "F.Cu" "F.Mask" "F.Paste")
			(net "PHY_SCC_A_TO_DRV_A_17_DN")
			(options
				(clearance outline)
				(anchor circle)
			)
			(primitives
				(gr_poly
					(pts
						(arc
							(start 0.1524 -0.127)
							(mid 0.137521 -0.162921)
							(end 0.1016 -0.1778)
						)
						(arc
							(start -0.1016 -0.1778)
							(mid -0.137521 -0.162921)
							(end -0.1524 -0.127)
						)
						(arc
							(start -0.1524 0.127)
							(mid -0.137521 0.162921)
							(end -0.1016 0.1778)
						)
						(arc
							(start 0.1016 0.1778)
							(mid 0.137521 0.162921)
							(end 0.1524 0.127)
						)
					)
					(width 0)
					(fill yes)
				)
			)
		)
	)
	(footprint ""
		(layer "F.Cu")
		(at 426.120052 -303.954942 180)
		(property "Reference" "C161"
			(at 0 0 180)
			(layer "F.SilkS")
			(hide yes)
			(effects
				(font
					(size 1.27 1.27)
				)
			)
		)
		(property "Value" "SC4D7U25V5KX-1-GP"
			(at -0.0762 -6.1214 180)
			(unlocked yes)
			(layer "F.Fab")
			(hide yes)
			(effects
				(font
					(size 1.016 1.016)
					(thickness 0.1524)
				)
			)
		)
		(property "Device Type" "C805H58"
			(at -0.0762 -8.1534 180)
			(unlocked yes)
			(layer "F.Fab")
			(hide yes)
			(effects
				(font
					(size 1.016 1.016)
					(thickness 0.1524)
				)
			)
		)
		(duplicate_pad_numbers_are_jumpers no)
		(fp_line
			(start 0.635 0)
			(end -0.635 0)
			(stroke
				(width 0.508)
				(type default)
			)
			(layer "F.SilkS")
		)
		(fp_rect
			(start -0.9652 1.778)
			(end 0.9652 -1.778)
			(stroke
				(width 0)
				(type default)
			)
			(fill no)
			(layer "F.CrtYd")
		)
		(fp_poly
			(pts
				(xy -0.9652 -1.778) (xy 0.9652 -1.778) (xy 0.9652 1.778) (xy -0.9652 1.778)
			)
			(stroke
				(width 0)
				(type default)
			)
			(fill no)
			(layer "F.Fab")
		)
		(pad "1" smd rect
			(at 0 -0.9652 180)
			(size 1.397 1.143)
			(layers "F.Cu" "F.Mask" "F.Paste")
			(net "P12V_HDD9")
		)
		(pad "2" smd rect
			(at 0 0.9652 180)
			(size 1.397 1.143)
			(layers "F.Cu" "F.Mask" "F.Paste")
			(net "GND")
		)
	)
	(footprint ""
		(layer "F.Cu")
		(at 248.466102 -394.580364 -90)
		(property "Reference" "R1167"
			(at 0 0 270)
			(layer "F.SilkS")
			(hide yes)
			(effects
				(font
					(size 1.27 1.27)
				)
			)
		)
		(property "Value" "49K9R2F-L-GP"
			(at 0.064008 -3.993896 270)
			(unlocked yes)
			(layer "F.Fab")
			(hide yes)
			(effects
				(font
					(size 1.016 1.016)
					(thickness 0.1524)
				)
			)
		)
		(property "Device Type" "R402H16"
			(at 0.064008 -5.517896 270)
			(unlocked yes)
			(layer "F.Fab")
			(hide yes)
			(effects
				(font
					(size 1.016 1.016)
					(thickness 0.1524)
				)
			)
		)
		(duplicate_pad_numbers_are_jumpers no)
		(fp_line
			(start -0.508 -0.9398)
			(end -0.508 0.9398)
			(stroke
				(width 0.1524)
				(type default)
			)
			(layer "F.SilkS")
		)
		(fp_line
			(start 0.508 -0.9398)
			(end -0.508 -0.9398)
			(stroke
				(width 0.1524)
				(type default)
			)
			(layer "F.SilkS")
		)
		(fp_rect
			(start -0.508 0.9398)
			(end 0.508 -0.9398)
			(stroke
				(width 0)
				(type default)
			)
			(fill no)
			(layer "F.CrtYd")
		)
		(fp_rect
			(start -0.508 0.9398)
			(end 0.508 -0.9398)
			(stroke
				(width 0)
				(type default)
			)
			(fill no)
			(layer "F.Fab")
		)
		(pad "1" smd custom
			(at 0 -0.4445 270)
			(size 0.1397 0.1397)
			(layers "F.Cu" "F.Mask" "F.Paste")
			(net "P12V_IN")
			(options
				(clearance outline)
				(anchor circle)
			)
			(primitives
				(gr_poly
					(pts
						(arc
							(start -0.1778 -0.2794)
							(mid -0.249642 -0.249642)
							(end -0.2794 -0.1778)
						)
						(arc
							(start -0.2794 0.1778)
							(mid -0.249642 0.249642)
							(end -0.1778 0.2794)
						)
						(arc
							(start 0.1778 0.2794)
							(mid 0.249642 0.249642)
							(end 0.2794 0.1778)
						)
						(arc
							(start 0.2794 -0.1778)
							(mid 0.249642 -0.249642)
							(end 0.1778 -0.2794)
						)
					)
					(width 0)
					(fill yes)
				)
			)
		)
		(pad "2" smd custom
			(at 0 0.4445 270)
			(size 0.1397 0.1397)
			(layers "F.Cu" "F.Mask" "F.Paste")
			(net "MB3_CM_OV_R")
			(options
				(clearance outline)
				(anchor circle)
			)
			(primitives
				(gr_poly
					(pts
						(arc
							(start -0.1778 -0.2794)
							(mid -0.249642 -0.249642)
							(end -0.2794 -0.1778)
						)
						(arc
							(start -0.2794 0.1778)
							(mid -0.249642 0.249642)
							(end -0.1778 0.2794)
						)
						(arc
							(start 0.1778 0.2794)
							(mid 0.249642 0.249642)
							(end 0.2794 0.1778)
						)
						(arc
							(start 0.2794 -0.1778)
							(mid 0.249642 -0.249642)
							(end 0.1778 -0.2794)
						)
					)
					(width 0)
					(fill yes)
				)
			)
		)
	)
	(footprint ""
		(layer "F.Cu")
		(at 48.961802 -143.46555)
		(property "Reference" "R1228"
			(at 0 0 0)
			(layer "F.SilkS")
			(hide yes)
			(effects
				(font
					(size 1.27 1.27)
				)
			)
		)
		(property "Value" "0R3J-0-U-GP"
			(at -0.0254 -2.5146 0)
			(unlocked yes)
			(layer "F.Fab")
			(hide yes)
			(effects
				(font
					(size 1.016 1.016)
					(thickness 0.1524)
				)
			)
		)
		(property "Device Type" "R603H22"
			(at -0.0254 -4.0386 0)
			(unlocked yes)
			(layer "F.Fab")
			(hide yes)
			(effects
				(font
					(size 1.016 1.016)
					(thickness 0.1524)
				)
			)
		)
		(duplicate_pad_numbers_are_jumpers no)
		(fp_line
			(start -0.4826 0)
			(end -0.2032 0)
			(stroke
				(width 0.2032)
				(type default)
			)
			(layer "F.SilkS")
		)
		(fp_line
			(start 0.2032 0)
			(end 0.4826 0)
			(stroke
				(width 0.2032)
				(type default)
			)
			(layer "F.SilkS")
		)
		(fp_rect
			(start -0.5842 1.3335)
			(end 0.5842 -1.3335)
			(stroke
				(width 0)
				(type default)
			)
			(fill no)
			(layer "F.CrtYd")
		)
		(fp_rect
			(start -0.5842 1.3335)
			(end 0.5842 -1.3335)
			(stroke
				(width 0)
				(type default)
			)
			(fill no)
			(layer "F.Fab")
		)
		(pad "1" smd custom
			(at 0 -0.762)
			(size 0.2159 0.2159)
			(layers "F.Cu" "F.Mask" "F.Paste")
			(net "P5V_B_VBST")
			(options
				(clearance outline)
				(anchor circle)
			)
			(primitives
				(gr_poly
					(pts
						(arc
							(start -0.3302 -0.4318)
							(mid -0.402042 -0.402042)
							(end -0.4318 -0.3302)
						)
						(arc
							(start -0.4318 0.3302)
							(mid -0.402042 0.402042)
							(end -0.3302 0.4318)
						)
						(arc
							(start 0.3302 0.4318)
							(mid 0.402042 0.402042)
							(end 0.4318 0.3302)
						)
						(arc
							(start 0.4318 -0.3302)
							(mid 0.402042 -0.402042)
							(end 0.3302 -0.4318)
						)
					)
					(width 0)
					(fill yes)
				)
			)
		)
		(pad "2" smd custom
			(at 0 0.762)
			(size 0.2159 0.2159)
			(layers "F.Cu" "F.Mask" "F.Paste")
			(net "P5V_B_VBST_RC")
			(options
				(clearance outline)
				(anchor circle)
			)
			(primitives
				(gr_poly
					(pts
						(arc
							(start -0.3302 -0.4318)
							(mid -0.402042 -0.402042)
							(end -0.4318 -0.3302)
						)
						(arc
							(start -0.4318 0.3302)
							(mid -0.402042 0.402042)
							(end -0.3302 0.4318)
						)
						(arc
							(start 0.3302 0.4318)
							(mid 0.402042 0.402042)
							(end 0.4318 0.3302)
						)
						(arc
							(start 0.4318 -0.3302)
							(mid 0.402042 -0.402042)
							(end 0.3302 -0.4318)
						)
					)
					(width 0)
					(fill yes)
				)
			)
		)
	)
	(footprint ""
		(layer "F.Cu")
		(at 276.242272 22.225 90)
		(property "Reference" "R633"
			(at 0 0 90)
			(layer "F.SilkS")
			(hide yes)
			(effects
				(font
					(size 1.27 1.27)
				)
			)
		)
		(property "Value" "10KR2F-2-GP"
			(at 0.064008 -3.993896 90)
			(unlocked yes)
			(layer "F.Fab")
			(hide yes)
			(effects
				(font
					(size 1.016 1.016)
					(thickness 0.1524)
				)
			)
		)
		(property "Device Type" "R402H16"
			(at 0.064008 -5.517896 90)
			(unlocked yes)
			(layer "F.Fab")
			(hide yes)
			(effects
				(font
					(size 1.016 1.016)
					(thickness 0.1524)
				)
			)
		)
		(duplicate_pad_numbers_are_jumpers no)
		(fp_line
			(start 0.508 -0.9398)
			(end -0.508 -0.9398)
			(stroke
				(width 0.1524)
				(type default)
			)
			(layer "F.SilkS")
		)
		(fp_line
			(start -0.508 -0.9398)
			(end -0.508 0.9398)
			(stroke
				(width 0.1524)
				(type default)
			)
			(layer "F.SilkS")
		)
		(fp_rect
			(start -0.508 0.9398)
			(end 0.508 -0.9398)
			(stroke
				(width 0)
				(type default)
			)
			(fill no)
			(layer "F.CrtYd")
		)
		(fp_rect
			(start -0.508 0.9398)
			(end 0.508 -0.9398)
			(stroke
				(width 0)
				(type default)
			)
			(fill no)
			(layer "F.Fab")
		)
		(pad "1" smd custom
			(at 0 -0.4445 90)
			(size 0.1397 0.1397)
			(layers "F.Cu" "F.Mask" "F.Paste")
			(net "P3V3_STBY_B")
			(options
				(clearance outline)
				(anchor circle)
			)
			(primitives
				(gr_poly
					(pts
						(arc
							(start -0.1778 -0.2794)
							(mid -0.249642 -0.249642)
							(end -0.2794 -0.1778)
						)
						(arc
							(start -0.2794 0.1778)
							(mid -0.249642 0.249642)
							(end -0.1778 0.2794)
						)
						(arc
							(start 0.1778 0.2794)
							(mid 0.249642 0.249642)
							(end 0.2794 0.1778)
						)
						(arc
							(start 0.2794 -0.1778)
							(mid 0.249642 -0.249642)
							(end 0.1778 -0.2794)
						)
					)
					(width 0)
					(fill yes)
				)
			)
		)
		(pad "2" smd custom
			(at 0 0.4445 90)
			(size 0.1397 0.1397)
			(layers "F.Cu" "F.Mask" "F.Paste")
			(net "SCC_B_PWR_LED")
			(options
				(clearance outline)
				(anchor circle)
			)
			(primitives
				(gr_poly
					(pts
						(arc
							(start -0.1778 -0.2794)
							(mid -0.249642 -0.249642)
							(end -0.2794 -0.1778)
						)
						(arc
							(start -0.2794 0.1778)
							(mid -0.249642 0.249642)
							(end -0.1778 0.2794)
						)
						(arc
							(start 0.1778 0.2794)
							(mid 0.249642 0.249642)
							(end 0.2794 0.1778)
						)
						(arc
							(start 0.2794 -0.1778)
							(mid 0.249642 -0.249642)
							(end 0.1778 -0.2794)
						)
					)
					(width 0)
					(fill yes)
				)
			)
		)
	)
	(footprint ""
		(layer "F.Cu")
		(at 318.2112 -295.0972 -90)
		(property "Reference" "R272"
			(at 0 0 270)
			(layer "F.SilkS")
			(hide yes)
			(effects
				(font
					(size 1.27 1.27)
				)
			)
		)
		(property "Value" "220R3F-1-GP"
			(at -0.0254 -2.5146 270)
			(unlocked yes)
			(layer "F.Fab")
			(hide yes)
			(effects
				(font
					(size 1.016 1.016)
					(thickness 0.1524)
				)
			)
		)
		(property "Device Type" "R603H22"
			(at -0.0254 -4.0386 270)
			(unlocked yes)
			(layer "F.Fab")
			(hide yes)
			(effects
				(font
					(size 1.016 1.016)
					(thickness 0.1524)
				)
			)
		)
		(duplicate_pad_numbers_are_jumpers no)
		(fp_line
			(start -0.4826 0)
			(end -0.2032 0)
			(stroke
				(width 0.2032)
				(type default)
			)
			(layer "F.SilkS")
		)
		(fp_line
			(start 0.2032 0)
			(end 0.4826 0)
			(stroke
				(width 0.2032)
				(type default)
			)
			(layer "F.SilkS")
		)
		(fp_rect
			(start -0.5842 1.3335)
			(end 0.5842 -1.3335)
			(stroke
				(width 0)
				(type default)
			)
			(fill no)
			(layer "F.CrtYd")
		)
		(fp_rect
			(start -0.5842 1.3335)
			(end 0.5842 -1.3335)
			(stroke
				(width 0)
				(type default)
			)
			(fill no)
			(layer "F.Fab")
		)
		(pad "1" smd custom
			(at 0 -0.762 270)
			(size 0.2159 0.2159)
			(layers "F.Cu" "F.Mask" "F.Paste")
			(net "HDD_PRSNT_6")
			(options
				(clearance outline)
				(anchor circle)
			)
			(primitives
				(gr_poly
					(pts
						(arc
							(start -0.3302 -0.4318)
							(mid -0.402042 -0.402042)
							(end -0.4318 -0.3302)
						)
						(arc
							(start -0.4318 0.3302)
							(mid -0.402042 0.402042)
							(end -0.3302 0.4318)
						)
						(arc
							(start 0.3302 0.4318)
							(mid 0.402042 0.402042)
							(end 0.4318 0.3302)
						)
						(arc
							(start 0.4318 -0.3302)
							(mid 0.402042 -0.402042)
							(end 0.3302 -0.4318)
						)
					)
					(width 0)
					(fill yes)
				)
			)
		)
		(pad "2" smd custom
			(at 0 0.762 270)
			(size 0.2159 0.2159)
			(layers "F.Cu" "F.Mask" "F.Paste")
			(net "DRIVE_A_6_INS")
			(options
				(clearance outline)
				(anchor circle)
			)
			(primitives
				(gr_poly
					(pts
						(arc
							(start -0.3302 -0.4318)
							(mid -0.402042 -0.402042)
							(end -0.4318 -0.3302)
						)
						(arc
							(start -0.4318 0.3302)
							(mid -0.402042 0.402042)
							(end -0.3302 0.4318)
						)
						(arc
							(start 0.3302 0.4318)
							(mid 0.402042 0.402042)
							(end 0.4318 0.3302)
						)
						(arc
							(start 0.4318 -0.3302)
							(mid 0.402042 -0.402042)
							(end 0.3302 -0.4318)
						)
					)
					(width 0)
					(fill yes)
				)
			)
		)
	)
	(footprint ""
		(layer "F.Cu")
		(at 242.5446 -242.6716 180)
		(property "Reference" "R82"
			(at 0 0 180)
			(layer "F.SilkS")
			(hide yes)
			(effects
				(font
					(size 1.27 1.27)
				)
			)
		)
		(property "Value" "0R2J-2-GP"
			(at 0.064008 -3.993896 180)
			(unlocked yes)
			(layer "F.Fab")
			(hide yes)
			(effects
				(font
					(size 1.016 1.016)
					(thickness 0.1524)
				)
			)
		)
		(property "Device Type" "R402H16"
			(at 0.064008 -5.517896 180)
			(unlocked yes)
			(layer "F.Fab")
			(hide yes)
			(effects
				(font
					(size 1.016 1.016)
					(thickness 0.1524)
				)
			)
		)
		(duplicate_pad_numbers_are_jumpers no)
		(fp_line
			(start 0.508 -0.9398)
			(end -0.508 -0.9398)
			(stroke
				(width 0.1524)
				(type default)
			)
			(layer "F.SilkS")
		)
		(fp_line
			(start -0.508 -0.9398)
			(end -0.508 0.9398)
			(stroke
				(width 0.1524)
				(type default)
			)
			(layer "F.SilkS")
		)
		(fp_rect
			(start -0.508 0.9398)
			(end 0.508 -0.9398)
			(stroke
				(width 0)
				(type default)
			)
			(fill no)
			(layer "F.CrtYd")
		)
		(fp_rect
			(start -0.508 0.9398)
			(end 0.508 -0.9398)
			(stroke
				(width 0)
				(type default)
			)
			(fill no)
			(layer "F.Fab")
		)
		(pad "1" smd custom
			(at 0 -0.4445 180)
			(size 0.1397 0.1397)
			(layers "F.Cu" "F.Mask" "F.Paste")
			(net "IO_EXP2_SCL")
			(options
				(clearance outline)
				(anchor circle)
			)
			(primitives
				(gr_poly
					(pts
						(arc
							(start -0.1778 -0.2794)
							(mid -0.249642 -0.249642)
							(end -0.2794 -0.1778)
						)
						(arc
							(start -0.2794 0.1778)
							(mid -0.249642 0.249642)
							(end -0.1778 0.2794)
						)
						(arc
							(start 0.1778 0.2794)
							(mid 0.249642 0.249642)
							(end 0.2794 0.1778)
						)
						(arc
							(start 0.2794 -0.1778)
							(mid 0.249642 -0.249642)
							(end 0.1778 -0.2794)
						)
					)
					(width 0)
					(fill yes)
				)
			)
		)
		(pad "2" smd custom
			(at 0 0.4445 180)
			(size 0.1397 0.1397)
			(layers "F.Cu" "F.Mask" "F.Paste")
			(net "I2C_DRIVE_A_PWR_SCL")
			(options
				(clearance outline)
				(anchor circle)
			)
			(primitives
				(gr_poly
					(pts
						(arc
							(start -0.1778 -0.2794)
							(mid -0.249642 -0.249642)
							(end -0.2794 -0.1778)
						)
						(arc
							(start -0.2794 0.1778)
							(mid -0.249642 0.249642)
							(end -0.1778 0.2794)
						)
						(arc
							(start 0.1778 0.2794)
							(mid 0.249642 0.249642)
							(end 0.2794 0.1778)
						)
						(arc
							(start 0.2794 -0.1778)
							(mid 0.249642 -0.249642)
							(end 0.1778 -0.2794)
						)
					)
					(width 0)
					(fill yes)
				)
			)
		)
	)
	(footprint ""
		(layer "F.Cu")
		(at 143.074898 -276.649942 180)
		(property "Reference" "D4"
			(at 0 0 180)
			(layer "F.SilkS")
			(hide yes)
			(effects
				(font
					(size 1.27 1.27)
				)
			)
		)
		(property "Value" "RB551V30-GP"
			(at 0 -6.7818 180)
			(unlocked yes)
			(layer "F.Fab")
			(hide yes)
			(effects
				(font
					(size 1.016 1.016)
					(thickness 0.1524)
				)
			)
		)
		(property "Device Type" "SOD323AKH38"
			(at 0 -8.6868 180)
			(unlocked yes)
			(layer "F.Fab")
			(hide yes)
			(effects
				(font
					(size 1.016 1.016)
					(thickness 0.1524)
				)
			)
		)
		(duplicate_pad_numbers_are_jumpers no)
		(fp_line
			(start 0.889 2.159)
			(end -0.889 2.159)
			(stroke
				(width 0.1524)
				(type default)
			)
			(layer "F.SilkS")
		)
		(fp_line
			(start 0.889 -1.9304)
			(end 0.889 2.159)
			(stroke
				(width 0.1524)
				(type default)
			)
			(layer "F.SilkS")
		)
		(fp_line
			(start 0.762 2.0574)
			(end -0.762 2.0574)
			(stroke
				(width 0.508)
				(type default)
			)
			(layer "F.SilkS")
		)
		(fp_line
			(start -0.889 2.159)
			(end -0.889 -1.9304)
			(stroke
				(width 0.1524)
				(type default)
			)
			(layer "F.SilkS")
		)
		(fp_line
			(start -0.889 -1.9304)
			(end 0.889 -1.9304)
			(stroke
				(width 0.1524)
				(type default)
			)
			(layer "F.SilkS")
		)
		(fp_rect
			(start -1.016 2.3114)
			(end 1.016 -2.0066)
			(stroke
				(width 0)
				(type default)
			)
			(fill no)
			(layer "F.CrtYd")
		)
		(fp_poly
			(pts
				(xy -1.016 -2.0066) (xy 1.016 -2.0066) (xy 1.016 2.3114) (xy -1.016 2.3114)
			)
			(stroke
				(width 0)
				(type default)
			)
			(fill no)
			(layer "F.Fab")
		)
		(pad "A" smd rect
			(at 0 -1.143 180)
			(size 0.5588 1.016)
			(layers "F.Cu" "F.Mask" "F.Paste")
			(net "SW_HDD_R4")
		)
		(pad "K" smd rect
			(at 0 1.143 180)
			(size 0.5588 1.016)
			(layers "F.Cu" "F.Mask" "F.Paste")
			(net "SW_HDD_N4")
		)
	)
	(footprint ""
		(layer "F.Cu")
		(at 222.746824 -347.3577 180)
		(property "Reference" "C5"
			(at 0 0 180)
			(layer "F.SilkS")
			(hide yes)
			(effects
				(font
					(size 1.27 1.27)
				)
			)
		)
		(property "Value" "SCD1U16V2KX-3GP"
			(at 1.1811 -2.7051 180)
			(unlocked yes)
			(layer "F.Fab")
			(hide yes)
			(effects
				(font
					(size 1.016 1.016)
					(thickness 0.1524)
				)
			)
		)
		(property "Device Type" "C402H22"
			(at 1.1811 -4.2291 180)
			(unlocked yes)
			(layer "F.Fab")
			(hide yes)
			(effects
				(font
					(size 1.016 1.016)
					(thickness 0.1524)
				)
			)
		)
		(duplicate_pad_numbers_are_jumpers no)
		(fp_rect
			(start -0.4318 0.9525)
			(end 0.4318 -0.9525)
			(stroke
				(width 0)
				(type default)
			)
			(fill no)
			(layer "F.CrtYd")
		)
		(fp_rect
			(start -0.4318 0.9525)
			(end 0.4318 -0.9525)
			(stroke
				(width 0)
				(type default)
			)
			(fill no)
			(layer "F.Fab")
		)
		(pad "1" smd custom
			(at 0 -0.4445 180)
			(size 0.1524 0.1524)
			(layers "F.Cu" "F.Mask" "F.Paste")
			(net "P3V3_STBY_A")
			(options
				(clearance outline)
				(anchor circle)
			)
			(primitives
				(gr_poly
					(pts
						(arc
							(start 0.3048 -0.2032)
							(mid 0.275042 -0.275042)
							(end 0.2032 -0.3048)
						)
						(arc
							(start -0.2032 -0.3048)
							(mid -0.275042 -0.275042)
							(end -0.3048 -0.2032)
						)
						(arc
							(start -0.3048 0.2032)
							(mid -0.275042 0.275042)
							(end -0.2032 0.3048)
						)
						(arc
							(start 0.2032 0.3048)
							(mid 0.275042 0.275042)
							(end 0.3048 0.2032)
						)
					)
					(width 0)
					(fill yes)
				)
			)
		)
		(pad "2" smd custom
			(at 0 0.4445 180)
			(size 0.1524 0.1524)
			(layers "F.Cu" "F.Mask" "F.Paste")
			(net "GND")
			(options
				(clearance outline)
				(anchor circle)
			)
			(primitives
				(gr_poly
					(pts
						(arc
							(start 0.3048 -0.2032)
							(mid 0.275042 -0.275042)
							(end 0.2032 -0.3048)
						)
						(arc
							(start -0.2032 -0.3048)
							(mid -0.275042 -0.275042)
							(end -0.3048 -0.2032)
						)
						(arc
							(start -0.3048 0.2032)
							(mid -0.275042 0.275042)
							(end -0.2032 0.3048)
						)
						(arc
							(start 0.2032 0.3048)
							(mid 0.275042 0.275042)
							(end 0.3048 0.2032)
						)
					)
					(width 0)
					(fill yes)
				)
			)
		)
	)
	(footprint ""
		(layer "F.Cu")
		(at 345.842844 -288.39287)
		(property "Reference" "Q294"
			(at 0 0 0)
			(layer "F.SilkS")
			(hide yes)
			(effects
				(font
					(size 1.27 1.27)
				)
			)
		)
		(property "Value" "SSM3K324R-GP"
			(at 0.127 -8.9662 0)
			(unlocked yes)
			(layer "F.Fab")
			(hide yes)
			(effects
				(font
					(size 1.016 1.016)
					(thickness 0.1524)
				)
			)
		)
		(property "Device Type" "SOT23DGS2D4H35"
			(at 0.127 -10.4902 0)
			(unlocked yes)
			(layer "F.Fab")
			(hide yes)
			(effects
				(font
					(size 1.016 1.016)
					(thickness 0.1524)
				)
			)
		)
		(duplicate_pad_numbers_are_jumpers no)
		(fp_line
			(start -1.651 -1.778)
			(end -1.651 1.778)
			(stroke
				(width 0.1524)
				(type default)
			)
			(layer "F.SilkS")
		)
		(fp_line
			(start -1.651 1.778)
			(end 1.651 1.778)
			(stroke
				(width 0.1524)
				(type default)
			)
			(layer "F.SilkS")
		)
		(fp_line
			(start 1.651 -1.778)
			(end -1.651 -1.778)
			(stroke
				(width 0.1524)
				(type default)
			)
			(layer "F.SilkS")
		)
		(fp_line
			(start 1.651 1.778)
			(end 1.651 -1.778)
			(stroke
				(width 0.1524)
				(type default)
			)
			(layer "F.SilkS")
		)
		(fp_poly
			(pts
				(xy -1.778 1.8796) (xy -1.778 -1.8796) (xy 1.778 -1.8796) (xy 1.778 1.8796)
			)
			(stroke
				(width 0)
				(type default)
			)
			(fill no)
			(layer "F.CrtYd")
		)
		(fp_poly
			(pts
				(xy -1.778 1.8796) (xy -1.778 -1.8796) (xy 1.778 -1.8796) (xy 1.778 1.8796)
			)
			(stroke
				(width 0)
				(type default)
			)
			(fill no)
			(layer "F.Fab")
		)
		(pad "D" smd custom
			(at 0 -0.9525)
			(size 0.1905 0.1905)
			(layers "F.Cu" "F.Mask" "F.Paste")
			(net "DRV_ACT_31_N")
			(options
				(clearance outline)
				(anchor circle)
			)
			(primitives
				(gr_poly
					(pts
						(arc
							(start -0.1778 0.5715)
							(mid -0.321484 0.511984)
							(end -0.381 0.3683)
						)
						(arc
							(start -0.381 -0.3683)
							(mid -0.321484 -0.511984)
							(end -0.1778 -0.5715)
						)
						(arc
							(start 0.1778 -0.5715)
							(mid 0.321484 -0.511984)
							(end 0.381 -0.3683)
						)
						(arc
							(start 0.381 0.3683)
							(mid 0.321484 0.511984)
							(end 0.1778 0.5715)
						)
					)
					(width 0)
					(fill yes)
				)
			)
		)
		(pad "G" smd custom
			(at -0.98425 0.9525)
			(size 0.1905 0.1905)
			(layers "F.Cu" "F.Mask" "F.Paste")
			(net "DRIVE_B_31_ACT")
			(options
				(clearance outline)
				(anchor circle)
			)
			(primitives
				(gr_poly
					(pts
						(arc
							(start -0.1778 0.5715)
							(mid -0.321484 0.511984)
							(end -0.381 0.3683)
						)
						(arc
							(start -0.381 -0.3683)
							(mid -0.321484 -0.511984)
							(end -0.1778 -0.5715)
						)
						(arc
							(start 0.1778 -0.5715)
							(mid 0.321484 -0.511984)
							(end 0.381 -0.3683)
						)
						(arc
							(start 0.381 0.3683)
							(mid 0.321484 0.511984)
							(end 0.1778 0.5715)
						)
					)
					(width 0)
					(fill yes)
				)
			)
		)
		(pad "S" smd custom
			(at 0.98425 0.9525)
			(size 0.1905 0.1905)
			(layers "F.Cu" "F.Mask" "F.Paste")
			(net "GND")
			(options
				(clearance outline)
				(anchor circle)
			)
			(primitives
				(gr_poly
					(pts
						(arc
							(start -0.1778 0.5715)
							(mid -0.321484 0.511984)
							(end -0.381 0.3683)
						)
						(arc
							(start -0.381 -0.3683)
							(mid -0.321484 -0.511984)
							(end -0.1778 -0.5715)
						)
						(arc
							(start 0.1778 -0.5715)
							(mid 0.321484 -0.511984)
							(end 0.381 -0.3683)
						)
						(arc
							(start 0.381 0.3683)
							(mid 0.321484 0.511984)
							(end 0.1778 0.5715)
						)
					)
					(width 0)
					(fill yes)
				)
			)
		)
	)
	(footprint ""
		(layer "F.Cu")
		(at 98.897948 -177.169318 -90)
		(property "Reference" "R452"
			(at 0 0 270)
			(layer "F.SilkS")
			(hide yes)
			(effects
				(font
					(size 1.27 1.27)
				)
			)
		)
		(property "Value" "10KR2F-2-GP"
			(at 0.064008 -3.993896 270)
			(unlocked yes)
			(layer "F.Fab")
			(hide yes)
			(effects
				(font
					(size 1.016 1.016)
					(thickness 0.1524)
				)
			)
		)
		(property "Device Type" "R402H16"
			(at 0.064008 -5.517896 270)
			(unlocked yes)
			(layer "F.Fab")
			(hide yes)
			(effects
				(font
					(size 1.016 1.016)
					(thickness 0.1524)
				)
			)
		)
		(duplicate_pad_numbers_are_jumpers no)
		(fp_line
			(start -0.508 -0.9398)
			(end -0.508 0.9398)
			(stroke
				(width 0.1524)
				(type default)
			)
			(layer "F.SilkS")
		)
		(fp_line
			(start 0.508 -0.9398)
			(end -0.508 -0.9398)
			(stroke
				(width 0.1524)
				(type default)
			)
			(layer "F.SilkS")
		)
		(fp_rect
			(start -0.508 0.9398)
			(end 0.508 -0.9398)
			(stroke
				(width 0)
				(type default)
			)
			(fill no)
			(layer "F.CrtYd")
		)
		(fp_rect
			(start -0.508 0.9398)
			(end 0.508 -0.9398)
			(stroke
				(width 0)
				(type default)
			)
			(fill no)
			(layer "F.Fab")
		)
		(pad "1" smd custom
			(at 0 -0.4445 270)
			(size 0.1397 0.1397)
			(layers "F.Cu" "F.Mask" "F.Paste")
			(net "P3V3_STBY_A")
			(options
				(clearance outline)
				(anchor circle)
			)
			(primitives
				(gr_poly
					(pts
						(arc
							(start -0.1778 -0.2794)
							(mid -0.249642 -0.249642)
							(end -0.2794 -0.1778)
						)
						(arc
							(start -0.2794 0.1778)
							(mid -0.249642 0.249642)
							(end -0.1778 0.2794)
						)
						(arc
							(start 0.1778 0.2794)
							(mid 0.249642 0.249642)
							(end 0.2794 0.1778)
						)
						(arc
							(start 0.2794 -0.1778)
							(mid 0.249642 -0.249642)
							(end 0.1778 -0.2794)
						)
					)
					(width 0)
					(fill yes)
				)
			)
		)
		(pad "2" smd custom
			(at 0 0.4445 270)
			(size 0.1397 0.1397)
			(layers "F.Cu" "F.Mask" "F.Paste")
			(net "HDD_PRSNT_14")
			(options
				(clearance outline)
				(anchor circle)
			)
			(primitives
				(gr_poly
					(pts
						(arc
							(start -0.1778 -0.2794)
							(mid -0.249642 -0.249642)
							(end -0.2794 -0.1778)
						)
						(arc
							(start -0.2794 0.1778)
							(mid -0.249642 0.249642)
							(end -0.1778 0.2794)
						)
						(arc
							(start 0.1778 0.2794)
							(mid 0.249642 0.249642)
							(end 0.2794 0.1778)
						)
						(arc
							(start 0.2794 -0.1778)
							(mid 0.249642 -0.249642)
							(end 0.1778 -0.2794)
						)
					)
					(width 0)
					(fill yes)
				)
			)
		)
	)
	(footprint ""
		(layer "F.Cu")
		(at 427.898052 -272.585942 180)
		(property "Reference" "R345"
			(at 0 0 180)
			(layer "F.SilkS")
			(hide yes)
			(effects
				(font
					(size 1.27 1.27)
				)
			)
		)
		(property "Value" "1KR2F-3-GP"
			(at 0.064008 -3.993896 180)
			(unlocked yes)
			(layer "F.Fab")
			(hide yes)
			(effects
				(font
					(size 1.016 1.016)
					(thickness 0.1524)
				)
			)
		)
		(property "Device Type" "R402H16"
			(at 0.064008 -5.517896 180)
			(unlocked yes)
			(layer "F.Fab")
			(hide yes)
			(effects
				(font
					(size 1.016 1.016)
					(thickness 0.1524)
				)
			)
		)
		(duplicate_pad_numbers_are_jumpers no)
		(fp_line
			(start 0.508 -0.9398)
			(end -0.508 -0.9398)
			(stroke
				(width 0.1524)
				(type default)
			)
			(layer "F.SilkS")
		)
		(fp_line
			(start -0.508 -0.9398)
			(end -0.508 0.9398)
			(stroke
				(width 0.1524)
				(type default)
			)
			(layer "F.SilkS")
		)
		(fp_rect
			(start -0.508 0.9398)
			(end 0.508 -0.9398)
			(stroke
				(width 0)
				(type default)
			)
			(fill no)
			(layer "F.CrtYd")
		)
		(fp_rect
			(start -0.508 0.9398)
			(end 0.508 -0.9398)
			(stroke
				(width 0)
				(type default)
			)
			(fill no)
			(layer "F.Fab")
		)
		(pad "1" smd custom
			(at 0 -0.4445 180)
			(size 0.1397 0.1397)
			(layers "F.Cu" "F.Mask" "F.Paste")
			(net "P3V3_STBY_A")
			(options
				(clearance outline)
				(anchor circle)
			)
			(primitives
				(gr_poly
					(pts
						(arc
							(start -0.1778 -0.2794)
							(mid -0.249642 -0.249642)
							(end -0.2794 -0.1778)
						)
						(arc
							(start -0.2794 0.1778)
							(mid -0.249642 0.249642)
							(end -0.1778 0.2794)
						)
						(arc
							(start 0.1778 0.2794)
							(mid 0.249642 0.249642)
							(end 0.2794 0.1778)
						)
						(arc
							(start 0.2794 -0.1778)
							(mid 0.249642 -0.249642)
							(end 0.1778 -0.2794)
						)
					)
					(width 0)
					(fill yes)
				)
			)
		)
		(pad "2" smd custom
			(at 0 0.4445 180)
			(size 0.1397 0.1397)
			(layers "F.Cu" "F.Mask" "F.Paste")
			(net "SW_PWR_R_HDD9")
			(options
				(clearance outline)
				(anchor circle)
			)
			(primitives
				(gr_poly
					(pts
						(arc
							(start -0.1778 -0.2794)
							(mid -0.249642 -0.249642)
							(end -0.2794 -0.1778)
						)
						(arc
							(start -0.2794 0.1778)
							(mid -0.249642 0.249642)
							(end -0.1778 0.2794)
						)
						(arc
							(start 0.1778 0.2794)
							(mid 0.249642 0.249642)
							(end 0.2794 0.1778)
						)
						(arc
							(start 0.2794 -0.1778)
							(mid 0.249642 -0.249642)
							(end 0.1778 -0.2794)
						)
					)
					(width 0)
					(fill yes)
				)
			)
		)
	)
	(footprint ""
		(layer "F.Cu")
		(at 338.829904 -130.378962 -90)
		(property "Reference" "R530"
			(at 0 0 270)
			(layer "F.SilkS")
			(hide yes)
			(effects
				(font
					(size 1.27 1.27)
				)
			)
		)
		(property "Value" "4K7R2J-2-GP"
			(at 0.064008 -3.993896 270)
			(unlocked yes)
			(layer "F.Fab")
			(hide yes)
			(effects
				(font
					(size 1.016 1.016)
					(thickness 0.1524)
				)
			)
		)
		(property "Device Type" "R402H16"
			(at 0.064008 -5.517896 270)
			(unlocked yes)
			(layer "F.Fab")
			(hide yes)
			(effects
				(font
					(size 1.016 1.016)
					(thickness 0.1524)
				)
			)
		)
		(duplicate_pad_numbers_are_jumpers no)
		(fp_line
			(start -0.508 -0.9398)
			(end -0.508 0.9398)
			(stroke
				(width 0.1524)
				(type default)
			)
			(layer "F.SilkS")
		)
		(fp_line
			(start 0.508 -0.9398)
			(end -0.508 -0.9398)
			(stroke
				(width 0.1524)
				(type default)
			)
			(layer "F.SilkS")
		)
		(fp_rect
			(start -0.508 0.9398)
			(end 0.508 -0.9398)
			(stroke
				(width 0)
				(type default)
			)
			(fill no)
			(layer "F.CrtYd")
		)
		(fp_rect
			(start -0.508 0.9398)
			(end 0.508 -0.9398)
			(stroke
				(width 0)
				(type default)
			)
			(fill no)
			(layer "F.Fab")
		)
		(pad "1" smd custom
			(at 0 -0.4445 270)
			(size 0.1397 0.1397)
			(layers "F.Cu" "F.Mask" "F.Paste")
			(net "DRIVE_A_19_ACT")
			(options
				(clearance outline)
				(anchor circle)
			)
			(primitives
				(gr_poly
					(pts
						(arc
							(start -0.1778 -0.2794)
							(mid -0.249642 -0.249642)
							(end -0.2794 -0.1778)
						)
						(arc
							(start -0.2794 0.1778)
							(mid -0.249642 0.249642)
							(end -0.1778 0.2794)
						)
						(arc
							(start 0.1778 0.2794)
							(mid 0.249642 0.249642)
							(end 0.2794 0.1778)
						)
						(arc
							(start 0.2794 -0.1778)
							(mid 0.249642 -0.249642)
							(end 0.1778 -0.2794)
						)
					)
					(width 0)
					(fill yes)
				)
			)
		)
		(pad "2" smd custom
			(at 0 0.4445 270)
			(size 0.1397 0.1397)
			(layers "F.Cu" "F.Mask" "F.Paste")
			(net "GND")
			(options
				(clearance outline)
				(anchor circle)
			)
			(primitives
				(gr_poly
					(pts
						(arc
							(start -0.1778 -0.2794)
							(mid -0.249642 -0.249642)
							(end -0.2794 -0.1778)
						)
						(arc
							(start -0.2794 0.1778)
							(mid -0.249642 0.249642)
							(end -0.1778 0.2794)
						)
						(arc
							(start 0.1778 0.2794)
							(mid 0.249642 0.249642)
							(end 0.2794 0.1778)
						)
						(arc
							(start 0.2794 -0.1778)
							(mid 0.249642 -0.249642)
							(end 0.1778 -0.2794)
						)
					)
					(width 0)
					(fill yes)
				)
			)
		)
	)
	(footprint ""
		(layer "F.Cu")
		(at 332.74 -278.554942 -90)
		(property "Reference" "R275"
			(at 0 0 270)
			(layer "F.SilkS")
			(hide yes)
			(effects
				(font
					(size 1.27 1.27)
				)
			)
		)
		(property "Value" "4K7R2J-2-GP"
			(at 0.064008 -3.993896 270)
			(unlocked yes)
			(layer "F.Fab")
			(hide yes)
			(effects
				(font
					(size 1.016 1.016)
					(thickness 0.1524)
				)
			)
		)
		(property "Device Type" "R402H16"
			(at 0.064008 -5.517896 270)
			(unlocked yes)
			(layer "F.Fab")
			(hide yes)
			(effects
				(font
					(size 1.016 1.016)
					(thickness 0.1524)
				)
			)
		)
		(duplicate_pad_numbers_are_jumpers no)
		(fp_line
			(start -0.508 -0.9398)
			(end -0.508 0.9398)
			(stroke
				(width 0.1524)
				(type default)
			)
			(layer "F.SilkS")
		)
		(fp_line
			(start 0.508 -0.9398)
			(end -0.508 -0.9398)
			(stroke
				(width 0.1524)
				(type default)
			)
			(layer "F.SilkS")
		)
		(fp_rect
			(start -0.508 0.9398)
			(end 0.508 -0.9398)
			(stroke
				(width 0)
				(type default)
			)
			(fill no)
			(layer "F.CrtYd")
		)
		(fp_rect
			(start -0.508 0.9398)
			(end 0.508 -0.9398)
			(stroke
				(width 0)
				(type default)
			)
			(fill no)
			(layer "F.Fab")
		)
		(pad "1" smd custom
			(at 0 -0.4445 270)
			(size 0.1397 0.1397)
			(layers "F.Cu" "F.Mask" "F.Paste")
			(net "P12V_A")
			(options
				(clearance outline)
				(anchor circle)
			)
			(primitives
				(gr_poly
					(pts
						(arc
							(start -0.1778 -0.2794)
							(mid -0.249642 -0.249642)
							(end -0.2794 -0.1778)
						)
						(arc
							(start -0.2794 0.1778)
							(mid -0.249642 0.249642)
							(end -0.1778 0.2794)
						)
						(arc
							(start 0.1778 0.2794)
							(mid 0.249642 0.249642)
							(end 0.2794 0.1778)
						)
						(arc
							(start 0.2794 -0.1778)
							(mid 0.249642 -0.249642)
							(end 0.1778 -0.2794)
						)
					)
					(width 0)
					(fill yes)
				)
			)
		)
		(pad "2" smd custom
			(at 0 0.4445 270)
			(size 0.1397 0.1397)
			(layers "F.Cu" "F.Mask" "F.Paste")
			(net "SW_HDD_P6")
			(options
				(clearance outline)
				(anchor circle)
			)
			(primitives
				(gr_poly
					(pts
						(arc
							(start -0.1778 -0.2794)
							(mid -0.249642 -0.249642)
							(end -0.2794 -0.1778)
						)
						(arc
							(start -0.2794 0.1778)
							(mid -0.249642 0.249642)
							(end -0.1778 0.2794)
						)
						(arc
							(start 0.1778 0.2794)
							(mid 0.249642 0.249642)
							(end 0.2794 0.1778)
						)
						(arc
							(start 0.2794 -0.1778)
							(mid 0.249642 -0.249642)
							(end 0.1778 -0.2794)
						)
					)
					(width 0)
					(fill yes)
				)
			)
		)
	)
	(footprint ""
		(layer "F.Cu")
		(at 48.98517 -147.503642 -90)
		(property "Reference" "R1233"
			(at 0 0 270)
			(layer "F.SilkS")
			(hide yes)
			(effects
				(font
					(size 1.27 1.27)
				)
			)
		)
		(property "Value" "15KR2F-GP"
			(at 0.064008 -3.993896 270)
			(unlocked yes)
			(layer "F.Fab")
			(hide yes)
			(effects
				(font
					(size 1.016 1.016)
					(thickness 0.1524)
				)
			)
		)
		(property "Device Type" "R402H16"
			(at 0.064008 -5.517896 270)
			(unlocked yes)
			(layer "F.Fab")
			(hide yes)
			(effects
				(font
					(size 1.016 1.016)
					(thickness 0.1524)
				)
			)
		)
		(duplicate_pad_numbers_are_jumpers no)
		(fp_line
			(start -0.508 -0.9398)
			(end -0.508 0.9398)
			(stroke
				(width 0.1524)
				(type default)
			)
			(layer "F.SilkS")
		)
		(fp_line
			(start 0.508 -0.9398)
			(end -0.508 -0.9398)
			(stroke
				(width 0.1524)
				(type default)
			)
			(layer "F.SilkS")
		)
		(fp_rect
			(start -0.508 0.9398)
			(end 0.508 -0.9398)
			(stroke
				(width 0)
				(type default)
			)
			(fill no)
			(layer "F.CrtYd")
		)
		(fp_rect
			(start -0.508 0.9398)
			(end 0.508 -0.9398)
			(stroke
				(width 0)
				(type default)
			)
			(fill no)
			(layer "F.Fab")
		)
		(pad "1" smd custom
			(at 0 -0.4445 270)
			(size 0.1397 0.1397)
			(layers "F.Cu" "F.Mask" "F.Paste")
			(net "P5V_A_2_PGOOD")
			(options
				(clearance outline)
				(anchor circle)
			)
			(primitives
				(gr_poly
					(pts
						(arc
							(start -0.1778 -0.2794)
							(mid -0.249642 -0.249642)
							(end -0.2794 -0.1778)
						)
						(arc
							(start -0.2794 0.1778)
							(mid -0.249642 0.249642)
							(end -0.1778 0.2794)
						)
						(arc
							(start 0.1778 0.2794)
							(mid 0.249642 0.249642)
							(end 0.2794 0.1778)
						)
						(arc
							(start 0.2794 -0.1778)
							(mid 0.249642 -0.249642)
							(end 0.1778 -0.2794)
						)
					)
					(width 0)
					(fill yes)
				)
			)
		)
		(pad "2" smd custom
			(at 0 0.4445 270)
			(size 0.1397 0.1397)
			(layers "F.Cu" "F.Mask" "F.Paste")
			(net "GND")
			(options
				(clearance outline)
				(anchor circle)
			)
			(primitives
				(gr_poly
					(pts
						(arc
							(start -0.1778 -0.2794)
							(mid -0.249642 -0.249642)
							(end -0.2794 -0.1778)
						)
						(arc
							(start -0.2794 0.1778)
							(mid -0.249642 0.249642)
							(end -0.1778 0.2794)
						)
						(arc
							(start 0.1778 0.2794)
							(mid 0.249642 0.249642)
							(end 0.2794 0.1778)
						)
						(arc
							(start 0.2794 -0.1778)
							(mid 0.249642 -0.249642)
							(end 0.1778 -0.2794)
						)
					)
					(width 0)
					(fill yes)
				)
			)
		)
	)
	(footprint ""
		(layer "F.Cu")
		(at 224.409 -10.541 90)
		(property "Reference" "R1004"
			(at 0 0 90)
			(layer "F.SilkS")
			(hide yes)
			(effects
				(font
					(size 1.27 1.27)
				)
			)
		)
		(property "Value" "100KR2F-L1-GP"
			(at 0.064008 -3.993896 90)
			(unlocked yes)
			(layer "F.Fab")
			(hide yes)
			(effects
				(font
					(size 1.016 1.016)
					(thickness 0.1524)
				)
			)
		)
		(property "Device Type" "R402H16"
			(at 0.064008 -5.517896 90)
			(unlocked yes)
			(layer "F.Fab")
			(hide yes)
			(effects
				(font
					(size 1.016 1.016)
					(thickness 0.1524)
				)
			)
		)
		(duplicate_pad_numbers_are_jumpers no)
		(fp_line
			(start 0.508 -0.9398)
			(end -0.508 -0.9398)
			(stroke
				(width 0.1524)
				(type default)
			)
			(layer "F.SilkS")
		)
		(fp_line
			(start -0.508 -0.9398)
			(end -0.508 0.9398)
			(stroke
				(width 0.1524)
				(type default)
			)
			(layer "F.SilkS")
		)
		(fp_rect
			(start -0.508 0.9398)
			(end 0.508 -0.9398)
			(stroke
				(width 0)
				(type default)
			)
			(fill no)
			(layer "F.CrtYd")
		)
		(fp_rect
			(start -0.508 0.9398)
			(end 0.508 -0.9398)
			(stroke
				(width 0)
				(type default)
			)
			(fill no)
			(layer "F.Fab")
		)
		(pad "1" smd custom
			(at 0 -0.4445 90)
			(size 0.1397 0.1397)
			(layers "F.Cu" "F.Mask" "F.Paste")
			(net "P3V3_STBY_A")
			(options
				(clearance outline)
				(anchor circle)
			)
			(primitives
				(gr_poly
					(pts
						(arc
							(start -0.1778 -0.2794)
							(mid -0.249642 -0.249642)
							(end -0.2794 -0.1778)
						)
						(arc
							(start -0.2794 0.1778)
							(mid -0.249642 0.249642)
							(end -0.1778 0.2794)
						)
						(arc
							(start 0.1778 0.2794)
							(mid 0.249642 0.249642)
							(end 0.2794 0.1778)
						)
						(arc
							(start 0.2794 -0.1778)
							(mid 0.249642 -0.249642)
							(end 0.1778 -0.2794)
						)
					)
					(width 0)
					(fill yes)
				)
			)
		)
		(pad "2" smd custom
			(at 0 0.4445 90)
			(size 0.1397 0.1397)
			(layers "F.Cu" "F.Mask" "F.Paste")
			(net "COMP_A_SEC_INS_N")
			(options
				(clearance outline)
				(anchor circle)
			)
			(primitives
				(gr_poly
					(pts
						(arc
							(start -0.1778 -0.2794)
							(mid -0.249642 -0.249642)
							(end -0.2794 -0.1778)
						)
						(arc
							(start -0.2794 0.1778)
							(mid -0.249642 0.249642)
							(end -0.1778 0.2794)
						)
						(arc
							(start 0.1778 0.2794)
							(mid 0.249642 0.249642)
							(end 0.2794 0.1778)
						)
						(arc
							(start 0.2794 -0.1778)
							(mid 0.249642 -0.249642)
							(end 0.1778 -0.2794)
						)
					)
					(width 0)
					(fill yes)
				)
			)
		)
	)
	(footprint ""
		(layer "F.Cu")
		(at 47.853346 -169.567606 -90)
		(property "Reference" "R442"
			(at 0 0 270)
			(layer "F.SilkS")
			(hide yes)
			(effects
				(font
					(size 1.27 1.27)
				)
			)
		)
		(property "Value" "300KR2F-GP"
			(at 0.064008 -3.993896 270)
			(unlocked yes)
			(layer "F.Fab")
			(hide yes)
			(effects
				(font
					(size 1.016 1.016)
					(thickness 0.1524)
				)
			)
		)
		(property "Device Type" "R402H16"
			(at 0.064008 -5.517896 270)
			(unlocked yes)
			(layer "F.Fab")
			(hide yes)
			(effects
				(font
					(size 1.016 1.016)
					(thickness 0.1524)
				)
			)
		)
		(duplicate_pad_numbers_are_jumpers no)
		(fp_line
			(start -0.508 -0.9398)
			(end -0.508 0.9398)
			(stroke
				(width 0.1524)
				(type default)
			)
			(layer "F.SilkS")
		)
		(fp_line
			(start 0.508 -0.9398)
			(end -0.508 -0.9398)
			(stroke
				(width 0.1524)
				(type default)
			)
			(layer "F.SilkS")
		)
		(fp_rect
			(start -0.508 0.9398)
			(end 0.508 -0.9398)
			(stroke
				(width 0)
				(type default)
			)
			(fill no)
			(layer "F.CrtYd")
		)
		(fp_rect
			(start -0.508 0.9398)
			(end 0.508 -0.9398)
			(stroke
				(width 0)
				(type default)
			)
			(fill no)
			(layer "F.Fab")
		)
		(pad "1" smd custom
			(at 0 -0.4445 270)
			(size 0.1397 0.1397)
			(layers "F.Cu" "F.Mask" "F.Paste")
			(net "SW_HDD_N13")
			(options
				(clearance outline)
				(anchor circle)
			)
			(primitives
				(gr_poly
					(pts
						(arc
							(start -0.1778 -0.2794)
							(mid -0.249642 -0.249642)
							(end -0.2794 -0.1778)
						)
						(arc
							(start -0.2794 0.1778)
							(mid -0.249642 0.249642)
							(end -0.1778 0.2794)
						)
						(arc
							(start 0.1778 0.2794)
							(mid 0.249642 0.249642)
							(end 0.2794 0.1778)
						)
						(arc
							(start 0.2794 -0.1778)
							(mid 0.249642 -0.249642)
							(end 0.1778 -0.2794)
						)
					)
					(width 0)
					(fill yes)
				)
			)
		)
		(pad "2" smd custom
			(at 0 0.4445 270)
			(size 0.1397 0.1397)
			(layers "F.Cu" "F.Mask" "F.Paste")
			(net "P12V_A")
			(options
				(clearance outline)
				(anchor circle)
			)
			(primitives
				(gr_poly
					(pts
						(arc
							(start -0.1778 -0.2794)
							(mid -0.249642 -0.249642)
							(end -0.2794 -0.1778)
						)
						(arc
							(start -0.2794 0.1778)
							(mid -0.249642 0.249642)
							(end -0.1778 0.2794)
						)
						(arc
							(start 0.1778 0.2794)
							(mid 0.249642 0.249642)
							(end 0.2794 0.1778)
						)
						(arc
							(start 0.2794 -0.1778)
							(mid 0.249642 -0.249642)
							(end 0.1778 -0.2794)
						)
					)
					(width 0)
					(fill yes)
				)
			)
		)
	)
	(footprint ""
		(layer "F.Cu")
		(at 155.42514 -140.556996)
		(property "Reference" "R1066"
			(at 0 0 0)
			(layer "F.SilkS")
			(hide yes)
			(effects
				(font
					(size 1.27 1.27)
				)
			)
		)
		(property "Value" "5K1R2F-3-GP"
			(at 0.064008 -3.993896 0)
			(unlocked yes)
			(layer "F.Fab")
			(hide yes)
			(effects
				(font
					(size 1.016 1.016)
					(thickness 0.1524)
				)
			)
		)
		(property "Device Type" "R402H16"
			(at 0.064008 -5.517896 0)
			(unlocked yes)
			(layer "F.Fab")
			(hide yes)
			(effects
				(font
					(size 1.016 1.016)
					(thickness 0.1524)
				)
			)
		)
		(duplicate_pad_numbers_are_jumpers no)
		(fp_line
			(start -0.508 -0.9398)
			(end -0.508 0.9398)
			(stroke
				(width 0.1524)
				(type default)
			)
			(layer "F.SilkS")
		)
		(fp_line
			(start 0.508 -0.9398)
			(end -0.508 -0.9398)
			(stroke
				(width 0.1524)
				(type default)
			)
			(layer "F.SilkS")
		)
		(fp_rect
			(start -0.508 0.9398)
			(end 0.508 -0.9398)
			(stroke
				(width 0)
				(type default)
			)
			(fill no)
			(layer "F.CrtYd")
		)
		(fp_rect
			(start -0.508 0.9398)
			(end 0.508 -0.9398)
			(stroke
				(width 0)
				(type default)
			)
			(fill no)
			(layer "F.Fab")
		)
		(pad "1" smd custom
			(at 0 -0.4445)
			(size 0.1397 0.1397)
			(layers "F.Cu" "F.Mask" "F.Paste")
			(net "MB0_CM_UV_R")
			(options
				(clearance outline)
				(anchor circle)
			)
			(primitives
				(gr_poly
					(pts
						(arc
							(start -0.1778 -0.2794)
							(mid -0.249642 -0.249642)
							(end -0.2794 -0.1778)
						)
						(arc
							(start -0.2794 0.1778)
							(mid -0.249642 0.249642)
							(end -0.1778 0.2794)
						)
						(arc
							(start 0.1778 0.2794)
							(mid 0.249642 0.249642)
							(end 0.2794 0.1778)
						)
						(arc
							(start 0.2794 -0.1778)
							(mid 0.249642 -0.249642)
							(end 0.1778 -0.2794)
						)
					)
					(width 0)
					(fill yes)
				)
			)
		)
		(pad "2" smd custom
			(at 0 0.4445)
			(size 0.1397 0.1397)
			(layers "F.Cu" "F.Mask" "F.Paste")
			(net "AGND_CURRENT_MONOA")
			(options
				(clearance outline)
				(anchor circle)
			)
			(primitives
				(gr_poly
					(pts
						(arc
							(start -0.1778 -0.2794)
							(mid -0.249642 -0.249642)
							(end -0.2794 -0.1778)
						)
						(arc
							(start -0.2794 0.1778)
							(mid -0.249642 0.249642)
							(end -0.1778 0.2794)
						)
						(arc
							(start 0.1778 0.2794)
							(mid 0.249642 0.249642)
							(end 0.2794 0.1778)
						)
						(arc
							(start 0.2794 -0.1778)
							(mid 0.249642 -0.249642)
							(end 0.1778 -0.2794)
						)
					)
					(width 0)
					(fill yes)
				)
			)
		)
	)
	(footprint ""
		(layer "F.Cu")
		(at 55.282846 -177.270918)
		(property "Reference" "R428"
			(at 0 0 0)
			(layer "F.SilkS")
			(hide yes)
			(effects
				(font
					(size 1.27 1.27)
				)
			)
		)
		(property "Value" "2R6F-GP"
			(at -0.0508 -4.8514 0)
			(unlocked yes)
			(layer "F.Fab")
			(hide yes)
			(effects
				(font
					(size 1.016 1.016)
					(thickness 0.1524)
				)
			)
		)
		(property "Device Type" "R1206H26"
			(at 0 -6.3754 0)
			(unlocked yes)
			(layer "F.Fab")
			(hide yes)
			(effects
				(font
					(size 1.016 1.016)
					(thickness 0.1524)
				)
			)
		)
		(duplicate_pad_numbers_are_jumpers no)
		(fp_line
			(start -1.016 -2.2352)
			(end 1.016 -2.2352)
			(stroke
				(width 0.1524)
				(type default)
			)
			(layer "F.SilkS")
		)
		(fp_line
			(start -1.016 2.2352)
			(end -1.016 -2.2352)
			(stroke
				(width 0.1524)
				(type default)
			)
			(layer "F.SilkS")
		)
		(fp_line
			(start 1.016 -2.2352)
			(end 1.016 2.2352)
			(stroke
				(width 0.1524)
				(type default)
			)
			(layer "F.SilkS")
		)
		(fp_line
			(start 1.016 2.2352)
			(end -1.016 2.2352)
			(stroke
				(width 0.1524)
				(type default)
			)
			(layer "F.SilkS")
		)
		(fp_rect
			(start -1.0922 2.3114)
			(end 1.0922 -2.3114)
			(stroke
				(width 0)
				(type default)
			)
			(fill no)
			(layer "F.CrtYd")
		)
		(fp_poly
			(pts
				(xy -1.0922 -2.3114) (xy 1.0922 -2.3114) (xy 1.0922 2.3114) (xy -1.0922 2.3114)
			)
			(stroke
				(width 0)
				(type default)
			)
			(fill no)
			(layer "F.Fab")
		)
		(pad "1" smd rect
			(at 0 -1.397)
			(size 1.651 1.27)
			(layers "F.Cu" "F.Mask" "F.Paste")
			(net "P5V_HDD13")
		)
		(pad "2" smd rect
			(at 0 1.397)
			(size 1.651 1.27)
			(layers "F.Cu" "F.Mask" "F.Paste")
			(net "5V_PRE_13")
		)
	)
	(footprint ""
		(layer "F.Cu")
		(at 376.9614 -141.2494 90)
		(property "Reference" "R1077"
			(at 0 0 90)
			(layer "F.SilkS")
			(hide yes)
			(effects
				(font
					(size 1.27 1.27)
				)
			)
		)
		(property "Value" "0R2J-2-GP"
			(at 0.064008 -3.993896 90)
			(unlocked yes)
			(layer "F.Fab")
			(hide yes)
			(effects
				(font
					(size 1.016 1.016)
					(thickness 0.1524)
				)
			)
		)
		(property "Device Type" "R402H16"
			(at 0.064008 -5.517896 90)
			(unlocked yes)
			(layer "F.Fab")
			(hide yes)
			(effects
				(font
					(size 1.016 1.016)
					(thickness 0.1524)
				)
			)
		)
		(duplicate_pad_numbers_are_jumpers no)
		(fp_line
			(start 0.508 -0.9398)
			(end -0.508 -0.9398)
			(stroke
				(width 0.1524)
				(type default)
			)
			(layer "F.SilkS")
		)
		(fp_line
			(start -0.508 -0.9398)
			(end -0.508 0.9398)
			(stroke
				(width 0.1524)
				(type default)
			)
			(layer "F.SilkS")
		)
		(fp_rect
			(start -0.508 0.9398)
			(end 0.508 -0.9398)
			(stroke
				(width 0)
				(type default)
			)
			(fill no)
			(layer "F.CrtYd")
		)
		(fp_rect
			(start -0.508 0.9398)
			(end 0.508 -0.9398)
			(stroke
				(width 0)
				(type default)
			)
			(fill no)
			(layer "F.Fab")
		)
		(pad "1" smd custom
			(at 0 -0.4445 90)
			(size 0.1397 0.1397)
			(layers "F.Cu" "F.Mask" "F.Paste")
			(net "MB1_SDA_R")
			(options
				(clearance outline)
				(anchor circle)
			)
			(primitives
				(gr_poly
					(pts
						(arc
							(start -0.1778 -0.2794)
							(mid -0.249642 -0.249642)
							(end -0.2794 -0.1778)
						)
						(arc
							(start -0.2794 0.1778)
							(mid -0.249642 0.249642)
							(end -0.1778 0.2794)
						)
						(arc
							(start 0.1778 0.2794)
							(mid 0.249642 0.249642)
							(end 0.2794 0.1778)
						)
						(arc
							(start 0.2794 -0.1778)
							(mid 0.249642 -0.249642)
							(end 0.1778 -0.2794)
						)
					)
					(width 0)
					(fill yes)
				)
			)
		)
		(pad "2" smd custom
			(at 0 0.4445 90)
			(size 0.1397 0.1397)
			(layers "F.Cu" "F.Mask" "F.Paste")
			(net "I2C_BMC_B_MISC_SDA")
			(options
				(clearance outline)
				(anchor circle)
			)
			(primitives
				(gr_poly
					(pts
						(arc
							(start -0.1778 -0.2794)
							(mid -0.249642 -0.249642)
							(end -0.2794 -0.1778)
						)
						(arc
							(start -0.2794 0.1778)
							(mid -0.249642 0.249642)
							(end -0.1778 0.2794)
						)
						(arc
							(start 0.1778 0.2794)
							(mid 0.249642 0.249642)
							(end 0.2794 0.1778)
						)
						(arc
							(start 0.2794 -0.1778)
							(mid 0.249642 -0.249642)
							(end 0.1778 -0.2794)
						)
					)
					(width 0)
					(fill yes)
				)
			)
		)
	)
	(footprint ""
		(layer "F.Cu")
		(at 347.315028 -242.25377)
		(property "Reference" "R246"
			(at 0 0 0)
			(layer "F.SilkS")
			(hide yes)
			(effects
				(font
					(size 1.27 1.27)
				)
			)
		)
		(property "Value" "91R3F-1-GP"
			(at -0.0254 -2.5146 0)
			(unlocked yes)
			(layer "F.Fab")
			(hide yes)
			(effects
				(font
					(size 1.016 1.016)
					(thickness 0.1524)
				)
			)
		)
		(property "Device Type" "R603H22"
			(at -0.0254 -4.0386 0)
			(unlocked yes)
			(layer "F.Fab")
			(hide yes)
			(effects
				(font
					(size 1.016 1.016)
					(thickness 0.1524)
				)
			)
		)
		(duplicate_pad_numbers_are_jumpers no)
		(fp_line
			(start -0.4826 0)
			(end -0.2032 0)
			(stroke
				(width 0.2032)
				(type default)
			)
			(layer "F.SilkS")
		)
		(fp_line
			(start 0.2032 0)
			(end 0.4826 0)
			(stroke
				(width 0.2032)
				(type default)
			)
			(layer "F.SilkS")
		)
		(fp_rect
			(start -0.5842 1.3335)
			(end 0.5842 -1.3335)
			(stroke
				(width 0)
				(type default)
			)
			(fill no)
			(layer "F.CrtYd")
		)
		(fp_rect
			(start -0.5842 1.3335)
			(end 0.5842 -1.3335)
			(stroke
				(width 0)
				(type default)
			)
			(fill no)
			(layer "F.Fab")
		)
		(pad "1" smd custom
			(at 0 -0.762)
			(size 0.2159 0.2159)
			(layers "F.Cu" "F.Mask" "F.Paste")
			(net "P5V_A_3")
			(options
				(clearance outline)
				(anchor circle)
			)
			(primitives
				(gr_poly
					(pts
						(arc
							(start -0.3302 -0.4318)
							(mid -0.402042 -0.402042)
							(end -0.4318 -0.3302)
						)
						(arc
							(start -0.4318 0.3302)
							(mid -0.402042 0.402042)
							(end -0.3302 0.4318)
						)
						(arc
							(start 0.3302 0.4318)
							(mid 0.402042 0.402042)
							(end 0.4318 0.3302)
						)
						(arc
							(start 0.4318 -0.3302)
							(mid 0.402042 -0.402042)
							(end 0.3302 -0.4318)
						)
					)
					(width 0)
					(fill yes)
				)
			)
		)
		(pad "2" smd custom
			(at 0 0.762)
			(size 0.2159 0.2159)
			(layers "F.Cu" "F.Mask" "F.Paste")
			(net "DRV_ACT_7")
			(options
				(clearance outline)
				(anchor circle)
			)
			(primitives
				(gr_poly
					(pts
						(arc
							(start -0.3302 -0.4318)
							(mid -0.402042 -0.402042)
							(end -0.4318 -0.3302)
						)
						(arc
							(start -0.4318 0.3302)
							(mid -0.402042 0.402042)
							(end -0.3302 0.4318)
						)
						(arc
							(start 0.3302 0.4318)
							(mid 0.402042 0.402042)
							(end 0.4318 0.3302)
						)
						(arc
							(start 0.4318 -0.3302)
							(mid 0.402042 -0.402042)
							(end 0.3302 -0.4318)
						)
					)
					(width 0)
					(fill yes)
				)
			)
		)
	)
	(footprint ""
		(layer "F.Cu")
		(at 475.812866 -281.371802 180)
		(property "Reference" "Q66"
			(at 0 0 180)
			(layer "F.SilkS")
			(hide yes)
			(effects
				(font
					(size 1.27 1.27)
				)
			)
		)
		(property "Value" "AO4406AL-GP"
			(at -3.707384 -1.5367 180)
			(unlocked yes)
			(layer "F.Fab")
			(hide yes)
			(effects
				(font
					(size 1.016 1.016)
					(thickness 0.1524)
				)
			)
		)
		(property "Device Type" "SOIC8H69"
			(at -3.707384 -3.0607 180)
			(unlocked yes)
			(layer "F.Fab")
			(hide yes)
			(effects
				(font
					(size 1.016 1.016)
					(thickness 0.1524)
				)
			)
		)
		(duplicate_pad_numbers_are_jumpers no)
		(fp_line
			(start 2.1336 1.4224)
			(end 2.1336 -1.4224)
			(stroke
				(width 0.1524)
				(type default)
			)
			(layer "F.SilkS")
		)
		(fp_line
			(start 2.1336 -1.4224)
			(end -2.7432 -1.4224)
			(stroke
				(width 0.1524)
				(type default)
			)
			(layer "F.SilkS")
		)
		(fp_line
			(start -2.1844 -0.0508)
			(end -2.7178 0.508)
			(stroke
				(width 0.1524)
				(type default)
			)
			(layer "F.SilkS")
		)
		(fp_line
			(start -2.6289 3.4417)
			(end -2.6289 1.4732)
			(stroke
				(width 0.381)
				(type default)
			)
			(layer "F.SilkS")
		)
		(fp_line
			(start -2.7178 -0.508)
			(end -2.1844 -0.0508)
			(stroke
				(width 0.1524)
				(type default)
			)
			(layer "F.SilkS")
		)
		(fp_line
			(start -2.7432 1.4224)
			(end 2.1336 1.4224)
			(stroke
				(width 0.1524)
				(type default)
			)
			(layer "F.SilkS")
		)
		(fp_line
			(start -2.7432 1.4224)
			(end -2.6416 1.4224)
			(stroke
				(width 0.1524)
				(type default)
			)
			(layer "F.SilkS")
		)
		(fp_line
			(start -2.7432 -1.4224)
			(end -2.7432 1.4224)
			(stroke
				(width 0.1524)
				(type default)
			)
			(layer "F.SilkS")
		)
		(fp_poly
			(pts
				(xy -2.2098 -1.4224) (xy -2.2098 1.4224) (xy 2.2098 1.4224) (xy 2.2098 -1.4224)
			)
			(stroke
				(width 0)
				(type default)
			)
			(fill yes)
			(layer "F.SilkS")
		)
		(fp_rect
			(start -2.450084 2.999994)
			(end 2.450084 -2.999994)
			(stroke
				(width 0)
				(type default)
			)
			(fill no)
			(layer "F.CrtYd")
		)
		(fp_poly
			(pts
				(xy -2.8194 3.6322) (xy -2.8194 -3.6322) (xy 2.8194 -3.6322) (xy 2.8194 1.18364) (xy 2.450084 1.18364)
				(xy 2.450084 -2.999994) (xy -2.450084 -2.999994) (xy -2.450084 2.999994) (xy 2.450084 2.999994)
				(xy 2.450084 1.18618) (xy 2.8194 1.18618) (xy 2.8194 3.6322)
			)
			(stroke
				(width 0)
				(type default)
			)
			(fill no)
			(layer "F.CrtYd")
		)
		(fp_rect
			(start -2.8194 3.6322)
			(end 2.8194 -3.6322)
			(stroke
				(width 0)
				(type default)
			)
			(fill no)
			(layer "F.Fab")
		)
		(pad "1" smd rect
			(at -1.905 2.54 180)
			(size 0.635 1.651)
			(layers "F.Cu" "F.Mask" "F.Paste")
			(net "P5V_HDD11")
		)
		(pad "2" smd rect
			(at -0.635 2.54 180)
			(size 0.635 1.651)
			(layers "F.Cu" "F.Mask" "F.Paste")
			(net "P5V_HDD11")
		)
		(pad "3" smd rect
			(at 0.635 2.54 180)
			(size 0.635 1.651)
			(layers "F.Cu" "F.Mask" "F.Paste")
			(net "P5V_HDD11")
		)
		(pad "4" smd rect
			(at 1.905 2.54 180)
			(size 0.635 1.651)
			(layers "F.Cu" "F.Mask" "F.Paste")
			(net "SW_HDD_P11")
		)
		(pad "5" smd rect
			(at 1.905 -2.54 180)
			(size 0.635 1.651)
			(layers "F.Cu" "F.Mask" "F.Paste")
			(net "P5V_A_3")
		)
		(pad "6" smd rect
			(at 0.635 -2.54 180)
			(size 0.635 1.651)
			(layers "F.Cu" "F.Mask" "F.Paste")
			(net "P5V_A_3")
		)
		(pad "7" smd rect
			(at -0.635 -2.54 180)
			(size 0.635 1.651)
			(layers "F.Cu" "F.Mask" "F.Paste")
			(net "P5V_A_3")
		)
		(pad "8" smd rect
			(at -1.905 -2.54 180)
			(size 0.635 1.651)
			(layers "F.Cu" "F.Mask" "F.Paste")
			(net "P5V_A_3")
		)
	)
	(footprint ""
		(layer "F.Cu")
		(at 361.180126 -134.532878 180)
		(property "Reference" "R1100"
			(at 0 0 180)
			(layer "F.SilkS")
			(hide yes)
			(effects
				(font
					(size 1.27 1.27)
				)
			)
		)
		(property "Value" "5K1R2F-3-GP"
			(at 0.064008 -3.993896 180)
			(unlocked yes)
			(layer "F.Fab")
			(hide yes)
			(effects
				(font
					(size 1.016 1.016)
					(thickness 0.1524)
				)
			)
		)
		(property "Device Type" "R402H16"
			(at 0.064008 -5.517896 180)
			(unlocked yes)
			(layer "F.Fab")
			(hide yes)
			(effects
				(font
					(size 1.016 1.016)
					(thickness 0.1524)
				)
			)
		)
		(duplicate_pad_numbers_are_jumpers no)
		(fp_line
			(start 0.508 -0.9398)
			(end -0.508 -0.9398)
			(stroke
				(width 0.1524)
				(type default)
			)
			(layer "F.SilkS")
		)
		(fp_line
			(start -0.508 -0.9398)
			(end -0.508 0.9398)
			(stroke
				(width 0.1524)
				(type default)
			)
			(layer "F.SilkS")
		)
		(fp_rect
			(start -0.508 0.9398)
			(end 0.508 -0.9398)
			(stroke
				(width 0)
				(type default)
			)
			(fill no)
			(layer "F.CrtYd")
		)
		(fp_rect
			(start -0.508 0.9398)
			(end 0.508 -0.9398)
			(stroke
				(width 0)
				(type default)
			)
			(fill no)
			(layer "F.Fab")
		)
		(pad "1" smd custom
			(at 0 -0.4445 180)
			(size 0.1397 0.1397)
			(layers "F.Cu" "F.Mask" "F.Paste")
			(net "MB1_CM_UV_R")
			(options
				(clearance outline)
				(anchor circle)
			)
			(primitives
				(gr_poly
					(pts
						(arc
							(start -0.1778 -0.2794)
							(mid -0.249642 -0.249642)
							(end -0.2794 -0.1778)
						)
						(arc
							(start -0.2794 0.1778)
							(mid -0.249642 0.249642)
							(end -0.1778 0.2794)
						)
						(arc
							(start 0.1778 0.2794)
							(mid 0.249642 0.249642)
							(end 0.2794 0.1778)
						)
						(arc
							(start 0.2794 -0.1778)
							(mid 0.249642 -0.249642)
							(end 0.1778 -0.2794)
						)
					)
					(width 0)
					(fill yes)
				)
			)
		)
		(pad "2" smd custom
			(at 0 0.4445 180)
			(size 0.1397 0.1397)
			(layers "F.Cu" "F.Mask" "F.Paste")
			(net "AGND_CURRENT_MONOB")
			(options
				(clearance outline)
				(anchor circle)
			)
			(primitives
				(gr_poly
					(pts
						(arc
							(start -0.1778 -0.2794)
							(mid -0.249642 -0.249642)
							(end -0.2794 -0.1778)
						)
						(arc
							(start -0.2794 0.1778)
							(mid -0.249642 0.249642)
							(end -0.1778 0.2794)
						)
						(arc
							(start 0.1778 0.2794)
							(mid 0.249642 0.249642)
							(end 0.2794 0.1778)
						)
						(arc
							(start 0.2794 -0.1778)
							(mid 0.249642 -0.249642)
							(end 0.1778 -0.2794)
						)
					)
					(width 0)
					(fill yes)
				)
			)
		)
	)
	(footprint ""
		(layer "F.Cu")
		(at 180.7464 -274.821142 -90)
		(property "Reference" "R256"
			(at 0 0 270)
			(layer "F.SilkS")
			(hide yes)
			(effects
				(font
					(size 1.27 1.27)
				)
			)
		)
		(property "Value" "0R2J-2-GP"
			(at 0.064008 -3.993896 270)
			(unlocked yes)
			(layer "F.Fab")
			(hide yes)
			(effects
				(font
					(size 1.016 1.016)
					(thickness 0.1524)
				)
			)
		)
		(property "Device Type" "R402H16"
			(at 0.064008 -5.517896 270)
			(unlocked yes)
			(layer "F.Fab")
			(hide yes)
			(effects
				(font
					(size 1.016 1.016)
					(thickness 0.1524)
				)
			)
		)
		(duplicate_pad_numbers_are_jumpers no)
		(fp_line
			(start -0.508 -0.9398)
			(end -0.508 0.9398)
			(stroke
				(width 0.1524)
				(type default)
			)
			(layer "F.SilkS")
		)
		(fp_line
			(start 0.508 -0.9398)
			(end -0.508 -0.9398)
			(stroke
				(width 0.1524)
				(type default)
			)
			(layer "F.SilkS")
		)
		(fp_rect
			(start -0.508 0.9398)
			(end 0.508 -0.9398)
			(stroke
				(width 0)
				(type default)
			)
			(fill no)
			(layer "F.CrtYd")
		)
		(fp_rect
			(start -0.508 0.9398)
			(end 0.508 -0.9398)
			(stroke
				(width 0)
				(type default)
			)
			(fill no)
			(layer "F.Fab")
		)
		(pad "1" smd custom
			(at 0 -0.4445 270)
			(size 0.1397 0.1397)
			(layers "F.Cu" "F.Mask" "F.Paste")
			(net "DRIVE_A_5_PWR")
			(options
				(clearance outline)
				(anchor circle)
			)
			(primitives
				(gr_poly
					(pts
						(arc
							(start -0.1778 -0.2794)
							(mid -0.249642 -0.249642)
							(end -0.2794 -0.1778)
						)
						(arc
							(start -0.2794 0.1778)
							(mid -0.249642 0.249642)
							(end -0.1778 0.2794)
						)
						(arc
							(start 0.1778 0.2794)
							(mid 0.249642 0.249642)
							(end 0.2794 0.1778)
						)
						(arc
							(start 0.2794 -0.1778)
							(mid 0.249642 -0.249642)
							(end 0.1778 -0.2794)
						)
					)
					(width 0)
					(fill yes)
				)
			)
		)
		(pad "2" smd custom
			(at 0 0.4445 270)
			(size 0.1397 0.1397)
			(layers "F.Cu" "F.Mask" "F.Paste")
			(net "SW_PWR_R_HDD5")
			(options
				(clearance outline)
				(anchor circle)
			)
			(primitives
				(gr_poly
					(pts
						(arc
							(start -0.1778 -0.2794)
							(mid -0.249642 -0.249642)
							(end -0.2794 -0.1778)
						)
						(arc
							(start -0.2794 0.1778)
							(mid -0.249642 0.249642)
							(end -0.1778 0.2794)
						)
						(arc
							(start 0.1778 0.2794)
							(mid 0.249642 0.249642)
							(end 0.2794 0.1778)
						)
						(arc
							(start 0.2794 -0.1778)
							(mid 0.249642 -0.249642)
							(end 0.1778 -0.2794)
						)
					)
					(width 0)
					(fill yes)
				)
			)
		)
	)
	(footprint ""
		(layer "F.Cu")
		(at 230.321104 -346.908882 -90)
		(property "Reference" "U3"
			(at 0 0 270)
			(layer "F.SilkS")
			(hide yes)
			(effects
				(font
					(size 1.27 1.27)
				)
			)
		)
		(property "Value" "ADC128D818CIMTX-NOPB-1-GP"
			(at 0.127 -12.573 270)
			(unlocked yes)
			(layer "F.Fab")
			(hide yes)
			(effects
				(font
					(size 1.016 1.016)
					(thickness 0.1524)
				)
			)
		)
		(property "Device Type" "TSOIC16H48"
			(at 0.1016 -14.5796 270)
			(unlocked yes)
			(layer "F.Fab")
			(hide yes)
			(effects
				(font
					(size 1.016 1.016)
					(thickness 0.1524)
				)
			)
		)
		(duplicate_pad_numbers_are_jumpers no)
		(fp_line
			(start -2.921 3.81)
			(end -2.921 1.778)
			(stroke
				(width 0.508)
				(type default)
			)
			(layer "F.SilkS")
		)
		(fp_line
			(start 2.3622 1.778)
			(end -2.921 1.778)
			(stroke
				(width 0.1524)
				(type default)
			)
			(layer "F.SilkS")
		)
		(fp_line
			(start -2.54 0)
			(end -3.0988 0.5588)
			(stroke
				(width 0.1524)
				(type default)
			)
			(layer "F.SilkS")
		)
		(fp_line
			(start -2.54 0)
			(end -3.0988 -0.5588)
			(stroke
				(width 0.1524)
				(type default)
			)
			(layer "F.SilkS")
		)
		(fp_line
			(start -3.0988 -1.778)
			(end -3.0988 1.778)
			(stroke
				(width 0.1524)
				(type default)
			)
			(layer "F.SilkS")
		)
		(fp_line
			(start -3.0988 -1.778)
			(end 2.3622 -1.778)
			(stroke
				(width 0.1524)
				(type default)
			)
			(layer "F.SilkS")
		)
		(fp_line
			(start 2.3622 -1.778)
			(end 2.3622 1.778)
			(stroke
				(width 0.1524)
				(type default)
			)
			(layer "F.SilkS")
		)
		(fp_poly
			(pts
				(xy -2.4638 -1.778) (xy -2.4638 1.778) (xy 2.3622 1.778) (xy 2.3622 -1.778)
			)
			(stroke
				(width 0)
				(type default)
			)
			(fill yes)
			(layer "F.SilkS")
		)
		(fp_rect
			(start -3.175 4.064)
			(end 3.175 -4.064)
			(stroke
				(width 0)
				(type default)
			)
			(fill no)
			(layer "F.CrtYd")
		)
		(fp_poly
			(pts
				(xy -3.175 -4.064) (xy 3.175 -4.064) (xy 3.175 4.064) (xy -3.175 4.064)
			)
			(stroke
				(width 0)
				(type default)
			)
			(fill no)
			(layer "F.Fab")
		)
		(pad "1" smd rect
			(at -2.27584 2.8194 270)
			(size 0.3556 1.524)
			(layers "F.Cu" "F.Mask" "F.Paste")
			(net "Net_333")
		)
		(pad "2" smd rect
			(at -1.6256 2.8194 270)
			(size 0.3556 1.524)
			(layers "F.Cu" "F.Mask" "F.Paste")
			(net "VOL_SEN_SDA")
		)
		(pad "3" smd rect
			(at -0.97536 2.8194 270)
			(size 0.3556 1.524)
			(layers "F.Cu" "F.Mask" "F.Paste")
			(net "VOL_SEN_SCL")
		)
		(pad "4" smd rect
			(at -0.32512 2.8194 270)
			(size 0.3556 1.524)
			(layers "F.Cu" "F.Mask" "F.Paste")
			(net "GND")
		)
		(pad "5" smd rect
			(at 0.32512 2.8194 270)
			(size 0.3556 1.524)
			(layers "F.Cu" "F.Mask" "F.Paste")
			(net "P3V3_STBY_A")
		)
		(pad "6" smd rect
			(at 0.97536 2.8194 270)
			(size 0.3556 1.524)
			(layers "F.Cu" "F.Mask" "F.Paste")
			(net "VOL_SEN_INT_N")
		)
		(pad "7" smd rect
			(at 1.6256 2.8194 270)
			(size 0.3556 1.524)
			(layers "F.Cu" "F.Mask" "F.Paste")
			(net "VOL_SEN_ADDR0")
		)
		(pad "8" smd rect
			(at 2.27584 2.8194 270)
			(size 0.3556 1.524)
			(layers "F.Cu" "F.Mask" "F.Paste")
			(net "VOL_SEN_ADDR1")
		)
		(pad "9" smd rect
			(at 2.27584 -2.8194 270)
			(size 0.3556 1.524)
			(layers "F.Cu" "F.Mask" "F.Paste")
			(net "Net_334")
		)
		(pad "10" smd rect
			(at 1.6256 -2.8194 270)
			(size 0.3556 1.524)
			(layers "F.Cu" "F.Mask" "F.Paste")
			(net "Net_335")
		)
		(pad "11" smd rect
			(at 0.97536 -2.8194 270)
			(size 0.3556 1.524)
			(layers "F.Cu" "F.Mask" "F.Paste")
			(net "Net_336")
		)
		(pad "12" smd rect
			(at 0.32512 -2.8194 270)
			(size 0.3556 1.524)
			(layers "F.Cu" "F.Mask" "F.Paste")
			(net "P5V_A_4_SENSE")
		)
		(pad "13" smd rect
			(at -0.32512 -2.8194 270)
			(size 0.3556 1.524)
			(layers "F.Cu" "F.Mask" "F.Paste")
			(net "P5V_A_3_SENSE")
		)
		(pad "14" smd rect
			(at -0.97536 -2.8194 270)
			(size 0.3556 1.524)
			(layers "F.Cu" "F.Mask" "F.Paste")
			(net "P5V_A_2_SENSE")
		)
		(pad "15" smd rect
			(at -1.6256 -2.8194 270)
			(size 0.3556 1.524)
			(layers "F.Cu" "F.Mask" "F.Paste")
			(net "P5V_A_1_SENSE")
		)
		(pad "16" smd rect
			(at -2.27584 -2.8194 270)
			(size 0.3556 1.524)
			(layers "F.Cu" "F.Mask" "F.Paste")
			(net "P3V3_SENSE")
		)
	)
	(footprint ""
		(layer "F.Cu")
		(at 336.348578 -33.554162 180)
		(property "Reference" "R1300"
			(at 0 0 180)
			(layer "F.SilkS")
			(hide yes)
			(effects
				(font
					(size 1.27 1.27)
				)
			)
		)
		(property "Value" "2K2R2F-GP"
			(at 0.064008 -3.993896 180)
			(unlocked yes)
			(layer "F.Fab")
			(hide yes)
			(effects
				(font
					(size 1.016 1.016)
					(thickness 0.1524)
				)
			)
		)
		(property "Device Type" "R402H16"
			(at 0.064008 -5.517896 180)
			(unlocked yes)
			(layer "F.Fab")
			(hide yes)
			(effects
				(font
					(size 1.016 1.016)
					(thickness 0.1524)
				)
			)
		)
		(duplicate_pad_numbers_are_jumpers no)
		(fp_line
			(start 0.508 -0.9398)
			(end -0.508 -0.9398)
			(stroke
				(width 0.1524)
				(type default)
			)
			(layer "F.SilkS")
		)
		(fp_line
			(start -0.508 -0.9398)
			(end -0.508 0.9398)
			(stroke
				(width 0.1524)
				(type default)
			)
			(layer "F.SilkS")
		)
		(fp_rect
			(start -0.508 0.9398)
			(end 0.508 -0.9398)
			(stroke
				(width 0)
				(type default)
			)
			(fill no)
			(layer "F.CrtYd")
		)
		(fp_rect
			(start -0.508 0.9398)
			(end 0.508 -0.9398)
			(stroke
				(width 0)
				(type default)
			)
			(fill no)
			(layer "F.Fab")
		)
		(pad "1" smd custom
			(at 0 -0.4445 180)
			(size 0.1397 0.1397)
			(layers "F.Cu" "F.Mask" "F.Paste")
			(net "P3V3_STBY_B")
			(options
				(clearance outline)
				(anchor circle)
			)
			(primitives
				(gr_poly
					(pts
						(arc
							(start -0.1778 -0.2794)
							(mid -0.249642 -0.249642)
							(end -0.2794 -0.1778)
						)
						(arc
							(start -0.2794 0.1778)
							(mid -0.249642 0.249642)
							(end -0.1778 0.2794)
						)
						(arc
							(start 0.1778 0.2794)
							(mid 0.249642 0.249642)
							(end 0.2794 0.1778)
						)
						(arc
							(start 0.2794 -0.1778)
							(mid 0.249642 -0.249642)
							(end 0.1778 -0.2794)
						)
					)
					(width 0)
					(fill yes)
				)
			)
		)
		(pad "2" smd custom
			(at 0 0.4445 180)
			(size 0.1397 0.1397)
			(layers "F.Cu" "F.Mask" "F.Paste")
			(net "I2C_BMC_B_MISC_SCL")
			(options
				(clearance outline)
				(anchor circle)
			)
			(primitives
				(gr_poly
					(pts
						(arc
							(start -0.1778 -0.2794)
							(mid -0.249642 -0.249642)
							(end -0.2794 -0.1778)
						)
						(arc
							(start -0.2794 0.1778)
							(mid -0.249642 0.249642)
							(end -0.1778 0.2794)
						)
						(arc
							(start 0.1778 0.2794)
							(mid 0.249642 0.249642)
							(end 0.2794 0.1778)
						)
						(arc
							(start 0.2794 -0.1778)
							(mid 0.249642 -0.249642)
							(end 0.1778 -0.2794)
						)
					)
					(width 0)
					(fill yes)
				)
			)
		)
	)
	(footprint ""
		(layer "F.Cu")
		(at 223.5708 -177.038)
		(property "Reference" "C133"
			(at 0 0 0)
			(layer "F.SilkS")
			(hide yes)
			(effects
				(font
					(size 1.27 1.27)
				)
			)
		)
		(property "Value" "SC2D2U25V5KX-2-GP"
			(at -0.0762 -6.1214 0)
			(unlocked yes)
			(layer "F.Fab")
			(hide yes)
			(effects
				(font
					(size 1.016 1.016)
					(thickness 0.1524)
				)
			)
		)
		(property "Device Type" "C805H54"
			(at -0.0762 -8.1534 0)
			(unlocked yes)
			(layer "F.Fab")
			(hide yes)
			(effects
				(font
					(size 1.016 1.016)
					(thickness 0.1524)
				)
			)
		)
		(duplicate_pad_numbers_are_jumpers no)
		(fp_line
			(start 0.635 0)
			(end -0.635 0)
			(stroke
				(width 0.508)
				(type default)
			)
			(layer "F.SilkS")
		)
		(fp_rect
			(start -0.9652 1.778)
			(end 0.9652 -1.778)
			(stroke
				(width 0)
				(type default)
			)
			(fill no)
			(layer "F.CrtYd")
		)
		(fp_poly
			(pts
				(xy -0.9652 -1.778) (xy 0.9652 -1.778) (xy 0.9652 1.778) (xy -0.9652 1.778)
			)
			(stroke
				(width 0)
				(type default)
			)
			(fill no)
			(layer "F.Fab")
		)
		(pad "1" smd rect
			(at 0 -0.9652)
			(size 1.397 1.143)
			(layers "F.Cu" "F.Mask" "F.Paste")
			(net "P12V_A_COMP")
		)
		(pad "2" smd rect
			(at 0 0.9652)
			(size 1.397 1.143)
			(layers "F.Cu" "F.Mask" "F.Paste")
			(net "GND")
		)
	)
	(footprint ""
		(layer "F.Cu")
		(at 272.669 -272.288)
		(property "Reference" "R111"
			(at 0 0 0)
			(layer "F.SilkS")
			(hide yes)
			(effects
				(font
					(size 1.27 1.27)
				)
			)
		)
		(property "Value" "4K7R2F-GP"
			(at 0.064008 -3.993896 0)
			(unlocked yes)
			(layer "F.Fab")
			(hide yes)
			(effects
				(font
					(size 1.016 1.016)
					(thickness 0.1524)
				)
			)
		)
		(property "Device Type" "R402H16"
			(at 0.064008 -5.517896 0)
			(unlocked yes)
			(layer "F.Fab")
			(hide yes)
			(effects
				(font
					(size 1.016 1.016)
					(thickness 0.1524)
				)
			)
		)
		(duplicate_pad_numbers_are_jumpers no)
		(fp_line
			(start -0.508 -0.9398)
			(end -0.508 0.9398)
			(stroke
				(width 0.1524)
				(type default)
			)
			(layer "F.SilkS")
		)
		(fp_line
			(start 0.508 -0.9398)
			(end -0.508 -0.9398)
			(stroke
				(width 0.1524)
				(type default)
			)
			(layer "F.SilkS")
		)
		(fp_rect
			(start -0.508 0.9398)
			(end 0.508 -0.9398)
			(stroke
				(width 0)
				(type default)
			)
			(fill no)
			(layer "F.CrtYd")
		)
		(fp_rect
			(start -0.508 0.9398)
			(end 0.508 -0.9398)
			(stroke
				(width 0)
				(type default)
			)
			(fill no)
			(layer "F.Fab")
		)
		(pad "1" smd custom
			(at 0 -0.4445)
			(size 0.1397 0.1397)
			(layers "F.Cu" "F.Mask" "F.Paste")
			(net "IO_EXP1_HDD_FAULT_A1")
			(options
				(clearance outline)
				(anchor circle)
			)
			(primitives
				(gr_poly
					(pts
						(arc
							(start -0.1778 -0.2794)
							(mid -0.249642 -0.249642)
							(end -0.2794 -0.1778)
						)
						(arc
							(start -0.2794 0.1778)
							(mid -0.249642 0.249642)
							(end -0.1778 0.2794)
						)
						(arc
							(start 0.1778 0.2794)
							(mid 0.249642 0.249642)
							(end 0.2794 0.1778)
						)
						(arc
							(start 0.2794 -0.1778)
							(mid 0.249642 -0.249642)
							(end 0.1778 -0.2794)
						)
					)
					(width 0)
					(fill yes)
				)
			)
		)
		(pad "2" smd custom
			(at 0 0.4445)
			(size 0.1397 0.1397)
			(layers "F.Cu" "F.Mask" "F.Paste")
			(net "GND")
			(options
				(clearance outline)
				(anchor circle)
			)
			(primitives
				(gr_poly
					(pts
						(arc
							(start -0.1778 -0.2794)
							(mid -0.249642 -0.249642)
							(end -0.2794 -0.1778)
						)
						(arc
							(start -0.2794 0.1778)
							(mid -0.249642 0.249642)
							(end -0.1778 0.2794)
						)
						(arc
							(start 0.1778 0.2794)
							(mid 0.249642 0.249642)
							(end 0.2794 0.1778)
						)
						(arc
							(start 0.2794 -0.1778)
							(mid 0.249642 -0.249642)
							(end 0.1778 -0.2794)
						)
					)
					(width 0)
					(fill yes)
				)
			)
		)
	)
	(footprint ""
		(layer "F.Cu")
		(at 239.973104 -238.252)
		(property "Reference" "C25"
			(at 0 0 0)
			(layer "F.SilkS")
			(hide yes)
			(effects
				(font
					(size 1.27 1.27)
				)
			)
		)
		(property "Value" "SC1U16V3KX-5GP"
			(at 0 -2.8194 0)
			(unlocked yes)
			(layer "F.Fab")
			(hide yes)
			(effects
				(font
					(size 1.016 1.016)
					(thickness 0.1524)
				)
			)
		)
		(property "Device Type" "C603H36"
			(at 0 -4.3434 0)
			(unlocked yes)
			(layer "F.Fab")
			(hide yes)
			(effects
				(font
					(size 1.016 1.016)
					(thickness 0.1524)
				)
			)
		)
		(duplicate_pad_numbers_are_jumpers no)
		(fp_line
			(start 0.508 0)
			(end -0.508 0)
			(stroke
				(width 0.2032)
				(type default)
			)
			(layer "F.SilkS")
		)
		(fp_rect
			(start -0.5842 1.3335)
			(end 0.5842 -1.3335)
			(stroke
				(width 0)
				(type default)
			)
			(fill no)
			(layer "F.CrtYd")
		)
		(fp_rect
			(start -0.5842 1.3335)
			(end 0.5842 -1.3335)
			(stroke
				(width 0)
				(type default)
			)
			(fill no)
			(layer "F.Fab")
		)
		(pad "1" smd custom
			(at 0 -0.762)
			(size 0.2159 0.2159)
			(layers "F.Cu" "F.Mask" "F.Paste")
			(net "GPIO_VCC_U8")
			(options
				(clearance outline)
				(anchor circle)
			)
			(primitives
				(gr_poly
					(pts
						(arc
							(start -0.3302 -0.4318)
							(mid -0.402042 -0.402042)
							(end -0.4318 -0.3302)
						)
						(arc
							(start -0.4318 0.3302)
							(mid -0.402042 0.402042)
							(end -0.3302 0.4318)
						)
						(arc
							(start 0.3302 0.4318)
							(mid 0.402042 0.402042)
							(end 0.4318 0.3302)
						)
						(arc
							(start 0.4318 -0.3302)
							(mid 0.402042 -0.402042)
							(end 0.3302 -0.4318)
						)
					)
					(width 0)
					(fill yes)
				)
			)
		)
		(pad "2" smd custom
			(at 0 0.762)
			(size 0.2159 0.2159)
			(layers "F.Cu" "F.Mask" "F.Paste")
			(net "GND")
			(options
				(clearance outline)
				(anchor circle)
			)
			(primitives
				(gr_poly
					(pts
						(arc
							(start -0.3302 -0.4318)
							(mid -0.402042 -0.402042)
							(end -0.4318 -0.3302)
						)
						(arc
							(start -0.4318 0.3302)
							(mid -0.402042 0.402042)
							(end -0.3302 0.4318)
						)
						(arc
							(start 0.3302 0.4318)
							(mid 0.402042 0.402042)
							(end 0.4318 0.3302)
						)
						(arc
							(start 0.4318 -0.3302)
							(mid 0.402042 -0.402042)
							(end 0.3302 -0.4318)
						)
					)
					(width 0)
					(fill yes)
				)
			)
		)
	)
	(footprint ""
		(layer "F.Cu")
		(at 239.491266 -346.343478 180)
		(property "Reference" "C50"
			(at 0 0 180)
			(layer "F.SilkS")
			(hide yes)
			(effects
				(font
					(size 1.27 1.27)
				)
			)
		)
		(property "Value" "SCD1U16V2KX-3GP"
			(at 1.1811 -2.7051 180)
			(unlocked yes)
			(layer "F.Fab")
			(hide yes)
			(effects
				(font
					(size 1.016 1.016)
					(thickness 0.1524)
				)
			)
		)
		(property "Device Type" "C402H22"
			(at 1.1811 -4.2291 180)
			(unlocked yes)
			(layer "F.Fab")
			(hide yes)
			(effects
				(font
					(size 1.016 1.016)
					(thickness 0.1524)
				)
			)
		)
		(duplicate_pad_numbers_are_jumpers no)
		(fp_rect
			(start -0.4318 0.9525)
			(end 0.4318 -0.9525)
			(stroke
				(width 0)
				(type default)
			)
			(fill no)
			(layer "F.CrtYd")
		)
		(fp_rect
			(start -0.4318 0.9525)
			(end 0.4318 -0.9525)
			(stroke
				(width 0)
				(type default)
			)
			(fill no)
			(layer "F.Fab")
		)
		(pad "1" smd custom
			(at 0 -0.4445 180)
			(size 0.1524 0.1524)
			(layers "F.Cu" "F.Mask" "F.Paste")
			(net "P5V_A_3_SENSE")
			(options
				(clearance outline)
				(anchor circle)
			)
			(primitives
				(gr_poly
					(pts
						(arc
							(start 0.3048 -0.2032)
							(mid 0.275042 -0.275042)
							(end 0.2032 -0.3048)
						)
						(arc
							(start -0.2032 -0.3048)
							(mid -0.275042 -0.275042)
							(end -0.3048 -0.2032)
						)
						(arc
							(start -0.3048 0.2032)
							(mid -0.275042 0.275042)
							(end -0.2032 0.3048)
						)
						(arc
							(start 0.2032 0.3048)
							(mid 0.275042 0.275042)
							(end 0.3048 0.2032)
						)
					)
					(width 0)
					(fill yes)
				)
			)
		)
		(pad "2" smd custom
			(at 0 0.4445 180)
			(size 0.1524 0.1524)
			(layers "F.Cu" "F.Mask" "F.Paste")
			(net "GND")
			(options
				(clearance outline)
				(anchor circle)
			)
			(primitives
				(gr_poly
					(pts
						(arc
							(start 0.3048 -0.2032)
							(mid 0.275042 -0.275042)
							(end 0.2032 -0.3048)
						)
						(arc
							(start -0.2032 -0.3048)
							(mid -0.275042 -0.275042)
							(end -0.3048 -0.2032)
						)
						(arc
							(start -0.3048 0.2032)
							(mid -0.275042 0.275042)
							(end -0.2032 0.3048)
						)
						(arc
							(start 0.2032 0.3048)
							(mid 0.275042 0.275042)
							(end 0.3048 0.2032)
						)
					)
					(width 0)
					(fill yes)
				)
			)
		)
	)
	(footprint ""
		(layer "F.Cu")
		(at 52.234846 -285.285942 180)
		(property "Reference" "Q5"
			(at 0 0 180)
			(layer "F.SilkS")
			(hide yes)
			(effects
				(font
					(size 1.27 1.27)
				)
			)
		)
		(property "Value" "AO4406AL-GP"
			(at -3.707384 -1.5367 180)
			(unlocked yes)
			(layer "F.Fab")
			(hide yes)
			(effects
				(font
					(size 1.016 1.016)
					(thickness 0.1524)
				)
			)
		)
		(property "Device Type" "SOIC8H69"
			(at -3.707384 -3.0607 180)
			(unlocked yes)
			(layer "F.Fab")
			(hide yes)
			(effects
				(font
					(size 1.016 1.016)
					(thickness 0.1524)
				)
			)
		)
		(duplicate_pad_numbers_are_jumpers no)
		(fp_line
			(start 2.1336 1.4224)
			(end 2.1336 -1.4224)
			(stroke
				(width 0.1524)
				(type default)
			)
			(layer "F.SilkS")
		)
		(fp_line
			(start 2.1336 -1.4224)
			(end -2.7432 -1.4224)
			(stroke
				(width 0.1524)
				(type default)
			)
			(layer "F.SilkS")
		)
		(fp_line
			(start -2.1844 -0.0508)
			(end -2.7178 0.508)
			(stroke
				(width 0.1524)
				(type default)
			)
			(layer "F.SilkS")
		)
		(fp_line
			(start -2.6289 3.4417)
			(end -2.6289 1.4732)
			(stroke
				(width 0.381)
				(type default)
			)
			(layer "F.SilkS")
		)
		(fp_line
			(start -2.7178 -0.508)
			(end -2.1844 -0.0508)
			(stroke
				(width 0.1524)
				(type default)
			)
			(layer "F.SilkS")
		)
		(fp_line
			(start -2.7432 1.4224)
			(end 2.1336 1.4224)
			(stroke
				(width 0.1524)
				(type default)
			)
			(layer "F.SilkS")
		)
		(fp_line
			(start -2.7432 1.4224)
			(end -2.6416 1.4224)
			(stroke
				(width 0.1524)
				(type default)
			)
			(layer "F.SilkS")
		)
		(fp_line
			(start -2.7432 -1.4224)
			(end -2.7432 1.4224)
			(stroke
				(width 0.1524)
				(type default)
			)
			(layer "F.SilkS")
		)
		(fp_poly
			(pts
				(xy -2.2098 -1.4224) (xy -2.2098 1.4224) (xy 2.2098 1.4224) (xy 2.2098 -1.4224)
			)
			(stroke
				(width 0)
				(type default)
			)
			(fill yes)
			(layer "F.SilkS")
		)
		(fp_rect
			(start -2.450084 2.999994)
			(end 2.450084 -2.999994)
			(stroke
				(width 0)
				(type default)
			)
			(fill no)
			(layer "F.CrtYd")
		)
		(fp_poly
			(pts
				(xy -2.8194 3.6322) (xy -2.8194 -3.6322) (xy 2.8194 -3.6322) (xy 2.8194 1.18364) (xy 2.450084 1.18364)
				(xy 2.450084 -2.999994) (xy -2.450084 -2.999994) (xy -2.450084 2.999994) (xy 2.450084 2.999994)
				(xy 2.450084 1.18618) (xy 2.8194 1.18618) (xy 2.8194 3.6322)
			)
			(stroke
				(width 0)
				(type default)
			)
			(fill no)
			(layer "F.CrtYd")
		)
		(fp_rect
			(start -2.8194 3.6322)
			(end 2.8194 -3.6322)
			(stroke
				(width 0)
				(type default)
			)
			(fill no)
			(layer "F.Fab")
		)
		(pad "1" smd rect
			(at -1.905 2.54 180)
			(size 0.635 1.651)
			(layers "F.Cu" "F.Mask" "F.Paste")
			(net "P5V_HDD1")
		)
		(pad "2" smd rect
			(at -0.635 2.54 180)
			(size 0.635 1.651)
			(layers "F.Cu" "F.Mask" "F.Paste")
			(net "P5V_HDD1")
		)
		(pad "3" smd rect
			(at 0.635 2.54 180)
			(size 0.635 1.651)
			(layers "F.Cu" "F.Mask" "F.Paste")
			(net "P5V_HDD1")
		)
		(pad "4" smd rect
			(at 1.905 2.54 180)
			(size 0.635 1.651)
			(layers "F.Cu" "F.Mask" "F.Paste")
			(net "SW_HDD_P1")
		)
		(pad "5" smd rect
			(at 1.905 -2.54 180)
			(size 0.635 1.651)
			(layers "F.Cu" "F.Mask" "F.Paste")
			(net "P5V_A_1")
		)
		(pad "6" smd rect
			(at 0.635 -2.54 180)
			(size 0.635 1.651)
			(layers "F.Cu" "F.Mask" "F.Paste")
			(net "P5V_A_1")
		)
		(pad "7" smd rect
			(at -0.635 -2.54 180)
			(size 0.635 1.651)
			(layers "F.Cu" "F.Mask" "F.Paste")
			(net "P5V_A_1")
		)
		(pad "8" smd rect
			(at -1.905 -2.54 180)
			(size 0.635 1.651)
			(layers "F.Cu" "F.Mask" "F.Paste")
			(net "P5V_A_1")
		)
	)
	(footprint ""
		(layer "F.Cu")
		(at 20.430998 -48.554894 180)
		(property "Reference" "Q145"
			(at 0 0 180)
			(layer "F.SilkS")
			(hide yes)
			(effects
				(font
					(size 1.27 1.27)
				)
			)
		)
		(property "Value" "2N7002KDW-GP"
			(at -2.3622 -8.2042 180)
			(unlocked yes)
			(layer "F.Fab")
			(hide yes)
			(effects
				(font
					(size 1.016 1.016)
					(thickness 0.1524)
				)
			)
		)
		(property "Device Type" "SOT-363H44"
			(at -2.3622 -10.1092 180)
			(unlocked yes)
			(layer "F.Fab")
			(hide yes)
			(effects
				(font
					(size 1.016 1.016)
					(thickness 0.1524)
				)
			)
		)
		(duplicate_pad_numbers_are_jumpers no)
		(fp_line
			(start 1.4478 1.7018)
			(end 1.4478 -1.7018)
			(stroke
				(width 0.1524)
				(type default)
			)
			(layer "F.SilkS")
		)
		(fp_line
			(start 1.4478 -1.7018)
			(end -1.4478 -1.7018)
			(stroke
				(width 0.1524)
				(type default)
			)
			(layer "F.SilkS")
		)
		(fp_line
			(start -1.27 1.524)
			(end -1.27 0.6604)
			(stroke
				(width 0.4826)
				(type default)
			)
			(layer "F.SilkS")
		)
		(fp_line
			(start -1.4478 1.7018)
			(end 1.4478 1.7018)
			(stroke
				(width 0.1524)
				(type default)
			)
			(layer "F.SilkS")
		)
		(fp_line
			(start -1.4478 -1.7018)
			(end -1.4478 1.7018)
			(stroke
				(width 0.1524)
				(type default)
			)
			(layer "F.SilkS")
		)
		(fp_poly
			(pts
				(xy -1.524 -1.778) (xy 1.524 -1.778) (xy 1.524 1.778) (xy -1.524 1.778)
			)
			(stroke
				(width 0)
				(type default)
			)
			(fill no)
			(layer "F.CrtYd")
		)
		(fp_poly
			(pts
				(xy -1.524 -1.778) (xy 1.524 -1.778) (xy 1.524 1.778) (xy -1.524 1.778)
			)
			(stroke
				(width 0)
				(type default)
			)
			(fill no)
			(layer "F.Fab")
		)
		(pad "1" smd rect
			(at -0.65024 0.9398 180)
			(size 0.4064 1.016)
			(layers "F.Cu" "F.Mask" "F.Paste")
			(net "GND")
		)
		(pad "2" smd rect
			(at 0 0.9398 180)
			(size 0.4064 1.016)
			(layers "F.Cu" "F.Mask" "F.Paste")
			(net "SW_PWR_R_HDD24")
		)
		(pad "3" smd rect
			(at 0.65024 0.9398 180)
			(size 0.4064 1.016)
			(layers "F.Cu" "F.Mask" "F.Paste")
			(net "SW_HDD_P24")
		)
		(pad "4" smd rect
			(at 0.65024 -0.9398 180)
			(size 0.4064 1.016)
			(layers "F.Cu" "F.Mask" "F.Paste")
			(net "GND")
		)
		(pad "5" smd rect
			(at 0 -0.9398 180)
			(size 0.4064 1.016)
			(layers "F.Cu" "F.Mask" "F.Paste")
			(net "SW_HDD_G24")
		)
		(pad "6" smd rect
			(at -0.65024 -0.9398 180)
			(size 0.4064 1.016)
			(layers "F.Cu" "F.Mask" "F.Paste")
			(net "SW_HDD_R24")
		)
	)
	(footprint ""
		(layer "F.Cu")
		(at 334.899 -282.872942 -90)
		(property "Reference" "Q36"
			(at 0 0 270)
			(layer "F.SilkS")
			(hide yes)
			(effects
				(font
					(size 1.27 1.27)
				)
			)
		)
		(property "Value" "AO4406AL-GP"
			(at -3.707384 -1.5367 270)
			(unlocked yes)
			(layer "F.Fab")
			(hide yes)
			(effects
				(font
					(size 1.016 1.016)
					(thickness 0.1524)
				)
			)
		)
		(property "Device Type" "SOIC8H69"
			(at -3.707384 -3.0607 270)
			(unlocked yes)
			(layer "F.Fab")
			(hide yes)
			(effects
				(font
					(size 1.016 1.016)
					(thickness 0.1524)
				)
			)
		)
		(duplicate_pad_numbers_are_jumpers no)
		(fp_line
			(start -2.6289 3.4417)
			(end -2.6289 1.4732)
			(stroke
				(width 0.381)
				(type default)
			)
			(layer "F.SilkS")
		)
		(fp_line
			(start -2.7432 1.4224)
			(end -2.6416 1.4224)
			(stroke
				(width 0.1524)
				(type default)
			)
			(layer "F.SilkS")
		)
		(fp_line
			(start -2.7432 1.4224)
			(end 2.1336 1.4224)
			(stroke
				(width 0.1524)
				(type default)
			)
			(layer "F.SilkS")
		)
		(fp_line
			(start 2.1336 1.4224)
			(end 2.1336 -1.4224)
			(stroke
				(width 0.1524)
				(type default)
			)
			(layer "F.SilkS")
		)
		(fp_line
			(start -2.1844 -0.0508)
			(end -2.7178 0.508)
			(stroke
				(width 0.1524)
				(type default)
			)
			(layer "F.SilkS")
		)
		(fp_line
			(start -2.7178 -0.508)
			(end -2.1844 -0.0508)
			(stroke
				(width 0.1524)
				(type default)
			)
			(layer "F.SilkS")
		)
		(fp_line
			(start -2.7432 -1.4224)
			(end -2.7432 1.4224)
			(stroke
				(width 0.1524)
				(type default)
			)
			(layer "F.SilkS")
		)
		(fp_line
			(start 2.1336 -1.4224)
			(end -2.7432 -1.4224)
			(stroke
				(width 0.1524)
				(type default)
			)
			(layer "F.SilkS")
		)
		(fp_poly
			(pts
				(xy -2.2098 -1.4224) (xy -2.2098 1.4224) (xy 2.2098 1.4224) (xy 2.2098 -1.4224)
			)
			(stroke
				(width 0)
				(type default)
			)
			(fill yes)
			(layer "F.SilkS")
		)
		(fp_rect
			(start -2.450084 2.999994)
			(end 2.450084 -2.999994)
			(stroke
				(width 0)
				(type default)
			)
			(fill no)
			(layer "F.CrtYd")
		)
		(fp_poly
			(pts
				(xy -2.8194 3.6322) (xy -2.8194 -3.6322) (xy 2.8194 -3.6322) (xy 2.8194 1.18364) (xy 2.450084 1.18364)
				(xy 2.450084 -2.999994) (xy -2.450084 -2.999994) (xy -2.450084 2.999994) (xy 2.450084 2.999994)
				(xy 2.450084 1.18618) (xy 2.8194 1.18618) (xy 2.8194 3.6322)
			)
			(stroke
				(width 0)
				(type default)
			)
			(fill no)
			(layer "F.CrtYd")
		)
		(fp_rect
			(start -2.8194 3.6322)
			(end 2.8194 -3.6322)
			(stroke
				(width 0)
				(type default)
			)
			(fill no)
			(layer "F.Fab")
		)
		(pad "1" smd rect
			(at -1.905 2.54 270)
			(size 0.635 1.651)
			(layers "F.Cu" "F.Mask" "F.Paste")
			(net "P5V_HDD6")
		)
		(pad "2" smd rect
			(at -0.635 2.54 270)
			(size 0.635 1.651)
			(layers "F.Cu" "F.Mask" "F.Paste")
			(net "P5V_HDD6")
		)
		(pad "3" smd rect
			(at 0.635 2.54 270)
			(size 0.635 1.651)
			(layers "F.Cu" "F.Mask" "F.Paste")
			(net "P5V_HDD6")
		)
		(pad "4" smd rect
			(at 1.905 2.54 270)
			(size 0.635 1.651)
			(layers "F.Cu" "F.Mask" "F.Paste")
			(net "SW_HDD_P6")
		)
		(pad "5" smd rect
			(at 1.905 -2.54 270)
			(size 0.635 1.651)
			(layers "F.Cu" "F.Mask" "F.Paste")
			(net "P5V_A_3")
		)
		(pad "6" smd rect
			(at 0.635 -2.54 270)
			(size 0.635 1.651)
			(layers "F.Cu" "F.Mask" "F.Paste")
			(net "P5V_A_3")
		)
		(pad "7" smd rect
			(at -0.635 -2.54 270)
			(size 0.635 1.651)
			(layers "F.Cu" "F.Mask" "F.Paste")
			(net "P5V_A_3")
		)
		(pad "8" smd rect
			(at -1.905 -2.54 270)
			(size 0.635 1.651)
			(layers "F.Cu" "F.Mask" "F.Paste")
			(net "P5V_A_3")
		)
	)
	(footprint ""
		(layer "F.Cu")
		(at 447.99631 -242.819936 180)
		(property "Reference" "Q237"
			(at 0 0 180)
			(layer "F.SilkS")
			(hide yes)
			(effects
				(font
					(size 1.27 1.27)
				)
			)
		)
		(property "Value" "2N7002K-2-GP"
			(at 0.127 -8.9662 180)
			(unlocked yes)
			(layer "F.Fab")
			(hide yes)
			(effects
				(font
					(size 1.016 1.016)
					(thickness 0.1524)
				)
			)
		)
		(property "Device Type" "SOT23DGS2D4H44"
			(at 0.127 -10.4902 180)
			(unlocked yes)
			(layer "F.Fab")
			(hide yes)
			(effects
				(font
					(size 1.016 1.016)
					(thickness 0.1524)
				)
			)
		)
		(duplicate_pad_numbers_are_jumpers no)
		(fp_line
			(start 1.651 1.778)
			(end 1.651 -1.778)
			(stroke
				(width 0.1524)
				(type default)
			)
			(layer "F.SilkS")
		)
		(fp_line
			(start 1.651 -1.778)
			(end -1.651 -1.778)
			(stroke
				(width 0.1524)
				(type default)
			)
			(layer "F.SilkS")
		)
		(fp_line
			(start -1.651 1.778)
			(end 1.651 1.778)
			(stroke
				(width 0.1524)
				(type default)
			)
			(layer "F.SilkS")
		)
		(fp_line
			(start -1.651 -1.778)
			(end -1.651 1.778)
			(stroke
				(width 0.1524)
				(type default)
			)
			(layer "F.SilkS")
		)
		(fp_poly
			(pts
				(xy -1.778 1.8796) (xy -1.778 -1.8796) (xy 1.778 -1.8796) (xy 1.778 1.8796)
			)
			(stroke
				(width 0)
				(type default)
			)
			(fill no)
			(layer "F.CrtYd")
		)
		(fp_poly
			(pts
				(xy -1.778 1.8796) (xy -1.778 -1.8796) (xy 1.778 -1.8796) (xy 1.778 1.8796)
			)
			(stroke
				(width 0)
				(type default)
			)
			(fill no)
			(layer "F.Fab")
		)
		(pad "D" smd custom
			(at 0 -0.9525 180)
			(size 0.1905 0.1905)
			(layers "F.Cu" "F.Mask" "F.Paste")
			(net "FLT_HDD10_N")
			(options
				(clearance outline)
				(anchor circle)
			)
			(primitives
				(gr_poly
					(pts
						(arc
							(start -0.1778 0.5715)
							(mid -0.321484 0.511984)
							(end -0.381 0.3683)
						)
						(arc
							(start -0.381 -0.3683)
							(mid -0.321484 -0.511984)
							(end -0.1778 -0.5715)
						)
						(arc
							(start 0.1778 -0.5715)
							(mid 0.321484 -0.511984)
							(end 0.381 -0.3683)
						)
						(arc
							(start 0.381 0.3683)
							(mid 0.321484 0.511984)
							(end 0.1778 0.5715)
						)
					)
					(width 0)
					(fill yes)
				)
			)
		)
		(pad "G" smd custom
			(at -0.98425 0.9525 180)
			(size 0.1905 0.1905)
			(layers "F.Cu" "F.Mask" "F.Paste")
			(net "DRIVE_A_10_FLT_LED")
			(options
				(clearance outline)
				(anchor circle)
			)
			(primitives
				(gr_poly
					(pts
						(arc
							(start -0.1778 0.5715)
							(mid -0.321484 0.511984)
							(end -0.381 0.3683)
						)
						(arc
							(start -0.381 -0.3683)
							(mid -0.321484 -0.511984)
							(end -0.1778 -0.5715)
						)
						(arc
							(start 0.1778 -0.5715)
							(mid 0.321484 -0.511984)
							(end 0.381 -0.3683)
						)
						(arc
							(start 0.381 0.3683)
							(mid 0.321484 0.511984)
							(end 0.1778 0.5715)
						)
					)
					(width 0)
					(fill yes)
				)
			)
		)
		(pad "S" smd custom
			(at 0.98425 0.9525 180)
			(size 0.1905 0.1905)
			(layers "F.Cu" "F.Mask" "F.Paste")
			(net "GND")
			(options
				(clearance outline)
				(anchor circle)
			)
			(primitives
				(gr_poly
					(pts
						(arc
							(start -0.1778 0.5715)
							(mid -0.321484 0.511984)
							(end -0.381 0.3683)
						)
						(arc
							(start -0.381 -0.3683)
							(mid -0.321484 -0.511984)
							(end -0.1778 -0.5715)
						)
						(arc
							(start 0.1778 -0.5715)
							(mid 0.321484 -0.511984)
							(end 0.381 -0.3683)
						)
						(arc
							(start 0.381 0.3683)
							(mid 0.321484 0.511984)
							(end 0.1778 0.5715)
						)
					)
					(width 0)
					(fill yes)
				)
			)
		)
	)
	(footprint ""
		(layer "F.Cu")
		(at 150.440898 -74.462894 180)
		(property "Reference" "C411"
			(at 0 0 180)
			(layer "F.SilkS")
			(hide yes)
			(effects
				(font
					(size 1.27 1.27)
				)
			)
		)
		(property "Value" "SC1U25V3KX-GP"
			(at 0 -2.8194 180)
			(unlocked yes)
			(layer "F.Fab")
			(hide yes)
			(effects
				(font
					(size 1.016 1.016)
					(thickness 0.1524)
				)
			)
		)
		(property "Device Type" "C603H36"
			(at 0 -4.3434 180)
			(unlocked yes)
			(layer "F.Fab")
			(hide yes)
			(effects
				(font
					(size 1.016 1.016)
					(thickness 0.1524)
				)
			)
		)
		(duplicate_pad_numbers_are_jumpers no)
		(fp_line
			(start 0.508 0)
			(end -0.508 0)
			(stroke
				(width 0.2032)
				(type default)
			)
			(layer "F.SilkS")
		)
		(fp_rect
			(start -0.5842 1.3335)
			(end 0.5842 -1.3335)
			(stroke
				(width 0)
				(type default)
			)
			(fill no)
			(layer "F.CrtYd")
		)
		(fp_rect
			(start -0.5842 1.3335)
			(end 0.5842 -1.3335)
			(stroke
				(width 0)
				(type default)
			)
			(fill no)
			(layer "F.Fab")
		)
		(pad "1" smd custom
			(at 0 -0.762 180)
			(size 0.2159 0.2159)
			(layers "F.Cu" "F.Mask" "F.Paste")
			(net "P12V_HDD28")
			(options
				(clearance outline)
				(anchor circle)
			)
			(primitives
				(gr_poly
					(pts
						(arc
							(start -0.3302 -0.4318)
							(mid -0.402042 -0.402042)
							(end -0.4318 -0.3302)
						)
						(arc
							(start -0.4318 0.3302)
							(mid -0.402042 0.402042)
							(end -0.3302 0.4318)
						)
						(arc
							(start 0.3302 0.4318)
							(mid 0.402042 0.402042)
							(end 0.4318 0.3302)
						)
						(arc
							(start 0.4318 -0.3302)
							(mid 0.402042 -0.402042)
							(end 0.3302 -0.4318)
						)
					)
					(width 0)
					(fill yes)
				)
			)
		)
		(pad "2" smd custom
			(at 0 0.762 180)
			(size 0.2159 0.2159)
			(layers "F.Cu" "F.Mask" "F.Paste")
			(net "GND")
			(options
				(clearance outline)
				(anchor circle)
			)
			(primitives
				(gr_poly
					(pts
						(arc
							(start -0.3302 -0.4318)
							(mid -0.402042 -0.402042)
							(end -0.4318 -0.3302)
						)
						(arc
							(start -0.4318 0.3302)
							(mid -0.402042 0.402042)
							(end -0.3302 0.4318)
						)
						(arc
							(start 0.3302 0.4318)
							(mid 0.402042 0.402042)
							(end 0.4318 0.3302)
						)
						(arc
							(start 0.4318 -0.3302)
							(mid 0.402042 -0.402042)
							(end 0.3302 -0.4318)
						)
					)
					(width 0)
					(fill yes)
				)
			)
		)
	)
	(footprint ""
		(layer "F.Cu")
		(at 440.68873 -284.512258 90)
		(property "Reference" "R586"
			(at 0 0 90)
			(layer "F.SilkS")
			(hide yes)
			(effects
				(font
					(size 1.27 1.27)
				)
			)
		)
		(property "Value" "4K7R2J-2-GP"
			(at 0.064008 -3.993896 90)
			(unlocked yes)
			(layer "F.Fab")
			(hide yes)
			(effects
				(font
					(size 1.016 1.016)
					(thickness 0.1524)
				)
			)
		)
		(property "Device Type" "R402H16"
			(at 0.064008 -5.517896 90)
			(unlocked yes)
			(layer "F.Fab")
			(hide yes)
			(effects
				(font
					(size 1.016 1.016)
					(thickness 0.1524)
				)
			)
		)
		(duplicate_pad_numbers_are_jumpers no)
		(fp_line
			(start 0.508 -0.9398)
			(end -0.508 -0.9398)
			(stroke
				(width 0.1524)
				(type default)
			)
			(layer "F.SilkS")
		)
		(fp_line
			(start -0.508 -0.9398)
			(end -0.508 0.9398)
			(stroke
				(width 0.1524)
				(type default)
			)
			(layer "F.SilkS")
		)
		(fp_rect
			(start -0.508 0.9398)
			(end 0.508 -0.9398)
			(stroke
				(width 0)
				(type default)
			)
			(fill no)
			(layer "F.CrtYd")
		)
		(fp_rect
			(start -0.508 0.9398)
			(end 0.508 -0.9398)
			(stroke
				(width 0)
				(type default)
			)
			(fill no)
			(layer "F.Fab")
		)
		(pad "1" smd custom
			(at 0 -0.4445 90)
			(size 0.1397 0.1397)
			(layers "F.Cu" "F.Mask" "F.Paste")
			(net "DRIVE_B_34_ACT")
			(options
				(clearance outline)
				(anchor circle)
			)
			(primitives
				(gr_poly
					(pts
						(arc
							(start -0.1778 -0.2794)
							(mid -0.249642 -0.249642)
							(end -0.2794 -0.1778)
						)
						(arc
							(start -0.2794 0.1778)
							(mid -0.249642 0.249642)
							(end -0.1778 0.2794)
						)
						(arc
							(start 0.1778 0.2794)
							(mid 0.249642 0.249642)
							(end 0.2794 0.1778)
						)
						(arc
							(start 0.2794 -0.1778)
							(mid 0.249642 -0.249642)
							(end 0.1778 -0.2794)
						)
					)
					(width 0)
					(fill yes)
				)
			)
		)
		(pad "2" smd custom
			(at 0 0.4445 90)
			(size 0.1397 0.1397)
			(layers "F.Cu" "F.Mask" "F.Paste")
			(net "GND")
			(options
				(clearance outline)
				(anchor circle)
			)
			(primitives
				(gr_poly
					(pts
						(arc
							(start -0.1778 -0.2794)
							(mid -0.249642 -0.249642)
							(end -0.2794 -0.1778)
						)
						(arc
							(start -0.2794 0.1778)
							(mid -0.249642 0.249642)
							(end -0.1778 0.2794)
						)
						(arc
							(start 0.1778 0.2794)
							(mid 0.249642 0.249642)
							(end 0.2794 0.1778)
						)
						(arc
							(start 0.2794 -0.1778)
							(mid 0.249642 -0.249642)
							(end 0.1778 -0.2794)
						)
					)
					(width 0)
					(fill yes)
				)
			)
		)
	)
	(footprint ""
		(layer "F.Cu")
		(at 361.369102 -66.842894 180)
		(property "Reference" "C443"
			(at 0 0 180)
			(layer "F.SilkS")
			(hide yes)
			(effects
				(font
					(size 1.27 1.27)
				)
			)
		)
		(property "Value" "SC1U16V3KX-5GP"
			(at 0 -2.8194 180)
			(unlocked yes)
			(layer "F.Fab")
			(hide yes)
			(effects
				(font
					(size 1.016 1.016)
					(thickness 0.1524)
				)
			)
		)
		(property "Device Type" "C603H36"
			(at 0 -4.3434 180)
			(unlocked yes)
			(layer "F.Fab")
			(hide yes)
			(effects
				(font
					(size 1.016 1.016)
					(thickness 0.1524)
				)
			)
		)
		(duplicate_pad_numbers_are_jumpers no)
		(fp_line
			(start 0.508 0)
			(end -0.508 0)
			(stroke
				(width 0.2032)
				(type default)
			)
			(layer "F.SilkS")
		)
		(fp_rect
			(start -0.5842 1.3335)
			(end 0.5842 -1.3335)
			(stroke
				(width 0)
				(type default)
			)
			(fill no)
			(layer "F.CrtYd")
		)
		(fp_rect
			(start -0.5842 1.3335)
			(end 0.5842 -1.3335)
			(stroke
				(width 0)
				(type default)
			)
			(fill no)
			(layer "F.Fab")
		)
		(pad "1" smd custom
			(at 0 -0.762 180)
			(size 0.2159 0.2159)
			(layers "F.Cu" "F.Mask" "F.Paste")
			(net "P5V_HDD31")
			(options
				(clearance outline)
				(anchor circle)
			)
			(primitives
				(gr_poly
					(pts
						(arc
							(start -0.3302 -0.4318)
							(mid -0.402042 -0.402042)
							(end -0.4318 -0.3302)
						)
						(arc
							(start -0.4318 0.3302)
							(mid -0.402042 0.402042)
							(end -0.3302 0.4318)
						)
						(arc
							(start 0.3302 0.4318)
							(mid 0.402042 0.402042)
							(end 0.4318 0.3302)
						)
						(arc
							(start 0.4318 -0.3302)
							(mid 0.402042 -0.402042)
							(end 0.3302 -0.4318)
						)
					)
					(width 0)
					(fill yes)
				)
			)
		)
		(pad "2" smd custom
			(at 0 0.762 180)
			(size 0.2159 0.2159)
			(layers "F.Cu" "F.Mask" "F.Paste")
			(net "GND")
			(options
				(clearance outline)
				(anchor circle)
			)
			(primitives
				(gr_poly
					(pts
						(arc
							(start -0.3302 -0.4318)
							(mid -0.402042 -0.402042)
							(end -0.4318 -0.3302)
						)
						(arc
							(start -0.4318 0.3302)
							(mid -0.402042 0.402042)
							(end -0.3302 0.4318)
						)
						(arc
							(start 0.3302 0.4318)
							(mid 0.402042 0.402042)
							(end 0.4318 0.3302)
						)
						(arc
							(start 0.4318 -0.3302)
							(mid 0.402042 -0.402042)
							(end 0.3302 -0.4318)
						)
					)
					(width 0)
					(fill yes)
				)
			)
		)
	)
	(footprint ""
		(layer "F.Cu")
		(at 158.663386 -158.660592 90)
		(property "Reference" "C247"
			(at 0 0 90)
			(layer "F.SilkS")
			(hide yes)
			(effects
				(font
					(size 1.27 1.27)
				)
			)
		)
		(property "Value" "SCD01U16V1KX-GP"
			(at -2.8321 -1.7399 90)
			(unlocked yes)
			(layer "F.Fab")
			(hide yes)
			(effects
				(font
					(size 1.016 1.016)
					(thickness 0.1524)
				)
			)
		)
		(property "Device Type" "C0201H13"
			(at -2.8321 -3.2639 90)
			(unlocked yes)
			(layer "F.Fab")
			(hide yes)
			(effects
				(font
					(size 1.016 1.016)
					(thickness 0.1524)
				)
			)
		)
		(duplicate_pad_numbers_are_jumpers no)
		(fp_rect
			(start -0.2794 0.6477)
			(end 0.2794 -0.6477)
			(stroke
				(width 0)
				(type default)
			)
			(fill no)
			(layer "F.CrtYd")
		)
		(fp_rect
			(start -0.2794 0.6477)
			(end 0.2794 -0.6477)
			(stroke
				(width 0)
				(type default)
			)
			(fill no)
			(layer "F.Fab")
		)
		(pad "1" smd custom
			(at 0 -0.2794 90)
			(size 0.0762 0.0762)
			(layers "F.Cu" "F.Mask" "F.Paste")
			(net "SAS_HDD_RX_P16")
			(options
				(clearance outline)
				(anchor circle)
			)
			(primitives
				(gr_poly
					(pts
						(arc
							(start 0.1524 -0.127)
							(mid 0.137521 -0.162921)
							(end 0.1016 -0.1778)
						)
						(arc
							(start -0.1016 -0.1778)
							(mid -0.137521 -0.162921)
							(end -0.1524 -0.127)
						)
						(arc
							(start -0.1524 0.127)
							(mid -0.137521 0.162921)
							(end -0.1016 0.1778)
						)
						(arc
							(start 0.1016 0.1778)
							(mid 0.137521 0.162921)
							(end 0.1524 0.127)
						)
					)
					(width 0)
					(fill yes)
				)
			)
		)
		(pad "2" smd custom
			(at 0 0.2794 90)
			(size 0.0762 0.0762)
			(layers "F.Cu" "F.Mask" "F.Paste")
			(net "PHY_SCC_A_TO_DRV_A_16_DP")
			(options
				(clearance outline)
				(anchor circle)
			)
			(primitives
				(gr_poly
					(pts
						(arc
							(start 0.1524 -0.127)
							(mid 0.137521 -0.162921)
							(end 0.1016 -0.1778)
						)
						(arc
							(start -0.1016 -0.1778)
							(mid -0.137521 -0.162921)
							(end -0.1524 -0.127)
						)
						(arc
							(start -0.1524 0.127)
							(mid -0.137521 0.162921)
							(end -0.1016 0.1778)
						)
						(arc
							(start 0.1016 0.1778)
							(mid 0.137521 0.162921)
							(end 0.1524 0.127)
						)
					)
					(width 0)
					(fill yes)
				)
			)
		)
	)
	(footprint ""
		(layer "F.Cu")
		(at 245.824502 -395.418564 180)
		(property "Reference" "C594"
			(at 0 0 180)
			(layer "F.SilkS")
			(hide yes)
			(effects
				(font
					(size 1.27 1.27)
				)
			)
		)
		(property "Value" "SC1U16V3KX-5GP"
			(at 0 -2.8194 180)
			(unlocked yes)
			(layer "F.Fab")
			(hide yes)
			(effects
				(font
					(size 1.016 1.016)
					(thickness 0.1524)
				)
			)
		)
		(property "Device Type" "C603H36"
			(at 0 -4.3434 180)
			(unlocked yes)
			(layer "F.Fab")
			(hide yes)
			(effects
				(font
					(size 1.016 1.016)
					(thickness 0.1524)
				)
			)
		)
		(duplicate_pad_numbers_are_jumpers no)
		(fp_line
			(start 0.508 0)
			(end -0.508 0)
			(stroke
				(width 0.2032)
				(type default)
			)
			(layer "F.SilkS")
		)
		(fp_rect
			(start -0.5842 1.3335)
			(end 0.5842 -1.3335)
			(stroke
				(width 0)
				(type default)
			)
			(fill no)
			(layer "F.CrtYd")
		)
		(fp_rect
			(start -0.5842 1.3335)
			(end 0.5842 -1.3335)
			(stroke
				(width 0)
				(type default)
			)
			(fill no)
			(layer "F.Fab")
		)
		(pad "1" smd custom
			(at 0 -0.762 180)
			(size 0.2159 0.2159)
			(layers "F.Cu" "F.Mask" "F.Paste")
			(net "MB3_CM_OV_R")
			(options
				(clearance outline)
				(anchor circle)
			)
			(primitives
				(gr_poly
					(pts
						(arc
							(start -0.3302 -0.4318)
							(mid -0.402042 -0.402042)
							(end -0.4318 -0.3302)
						)
						(arc
							(start -0.4318 0.3302)
							(mid -0.402042 0.402042)
							(end -0.3302 0.4318)
						)
						(arc
							(start 0.3302 0.4318)
							(mid 0.402042 0.402042)
							(end 0.4318 0.3302)
						)
						(arc
							(start 0.4318 -0.3302)
							(mid 0.402042 -0.402042)
							(end 0.3302 -0.4318)
						)
					)
					(width 0)
					(fill yes)
				)
			)
		)
		(pad "2" smd custom
			(at 0 0.762 180)
			(size 0.2159 0.2159)
			(layers "F.Cu" "F.Mask" "F.Paste")
			(net "AGND_CURRENT_DPB")
			(options
				(clearance outline)
				(anchor circle)
			)
			(primitives
				(gr_poly
					(pts
						(arc
							(start -0.3302 -0.4318)
							(mid -0.402042 -0.402042)
							(end -0.4318 -0.3302)
						)
						(arc
							(start -0.4318 0.3302)
							(mid -0.402042 0.402042)
							(end -0.3302 0.4318)
						)
						(arc
							(start 0.3302 0.4318)
							(mid 0.402042 0.402042)
							(end 0.4318 0.3302)
						)
						(arc
							(start 0.4318 -0.3302)
							(mid 0.402042 -0.402042)
							(end 0.3302 -0.4318)
						)
					)
					(width 0)
					(fill yes)
				)
			)
		)
	)
	(footprint ""
		(layer "F.Cu")
		(at 247.849898 6.49986)
		(property "Reference" ""
			(at 0 0 0)
			(layer "F.SilkS")
			(hide yes)
			(effects
				(font
					(size 1.27 1.27)
				)
			)
		)
		(property "Value" "*"
			(at -5.5499 1.3716 0)
			(unlocked yes)
			(layer "F.Fab")
			(hide yes)
			(effects
				(font
					(size 1.016 1.016)
					(thickness 0.1524)
				)
			)
		)
		(duplicate_pad_numbers_are_jumpers no)
		(fp_poly
			(pts
				(arc
					(start 4.064 0)
					(mid -4.064 0)
					(end 4.064 0)
				)
			)
			(stroke
				(width 0)
				(type default)
			)
			(fill no)
			(layer "B.CrtYd")
		)
		(fp_poly
			(pts
				(arc
					(start 4.064 0)
					(mid -4.064 0)
					(end 4.064 0)
				)
			)
			(stroke
				(width 0)
				(type default)
			)
			(fill no)
			(layer "F.CrtYd")
		)
		(fp_poly
			(pts
				(arc
					(start 4.064 0)
					(mid -4.064 0)
					(end 4.064 0)
				)
			)
			(stroke
				(width 0)
				(type default)
			)
			(fill no)
			(layer "B.Fab")
		)
		(fp_poly
			(pts
				(arc
					(start 4.064 0)
					(mid -4.064 0)
					(end 4.064 0)
				)
			)
			(stroke
				(width 0)
				(type default)
			)
			(fill no)
			(layer "F.Fab")
		)
		(pad "1" thru_hole circle
			(at 0 0)
			(size 7.5184 7.5184)
			(drill oval 5.0038 3.0226)
			(layers "*.Cu" "*.Mask")
			(remove_unused_layers no)
			(net "Net_33")
			(clearance -1.7399)
			(thermal_gap 0.1524)
			(padstack
				(mode front_inner_back)
				(layer "Inner"
					(shape oval)
					(size 3.7338 5.715)
					(clearance 0.1524)
				)
				(layer "B.Cu"
					(shape circle)
					(size 7.5184 7.5184)
					(clearance -1.7399)
				)
			)
		)
		(zone
			(layers "F.Cu" "B.Cu" "In1.Cu" "In2.Cu" "In3.Cu" "In4.Cu" "In5.Cu" "In6.Cu"
				"In7.Cu" "In8.Cu" "In9.Cu" "In10.Cu"
			)
			(hatch none 0.5)
			(connect_pads
				(clearance 0)
			)
			(min_thickness 0.25)
			(keepout
				(tracks not_allowed)
				(vias allowed)
				(pads allowed)
				(copperpour not_allowed)
				(footprints allowed)
			)
			(placement
				(enabled no)
				(sheetname "")
			)
			(fill
				(thermal_gap 0.5)
				(thermal_bridge_width 0.5)
				(island_removal_mode 0)
			)
			(polygon
				(pts
					(arc
						(start 251.609098 6.49986)
						(mid 244.090698 6.49986)
						(end 251.609098 6.49986)
					)
				)
			)
		)
	)
	(footprint ""
		(layer "F.Cu")
		(at 381.2286 -67.4624)
		(property "Reference" "TP162"
			(at 0 0 0)
			(layer "F.SilkS")
			(hide yes)
			(effects
				(font
					(size 1.27 1.27)
				)
			)
		)
		(property "Value" "TPAD32-GP"
			(at -0.0508 -1.6764 0)
			(unlocked yes)
			(layer "F.Fab")
			(hide yes)
			(effects
				(font
					(size 1.016 1.016)
					(thickness 0.1524)
				)
			)
		)
		(property "Device Type" "TPAD32"
			(at -0.0508 -3.2004 0)
			(unlocked yes)
			(layer "F.Fab")
			(hide yes)
			(effects
				(font
					(size 1.016 1.016)
					(thickness 0.1524)
				)
			)
		)
		(duplicate_pad_numbers_are_jumpers no)
		(fp_poly
			(pts
				(arc
					(start 0.4064 0)
					(mid -0.4064 0)
					(end 0.4064 0)
				)
			)
			(stroke
				(width 0)
				(type default)
			)
			(fill no)
			(layer "F.CrtYd")
		)
		(fp_poly
			(pts
				(arc
					(start 0.7112 0)
					(mid -0.7112 0)
					(end 0.7112 0)
				)
			)
			(stroke
				(width 0)
				(type default)
			)
			(fill no)
			(layer "F.Fab")
		)
		(pad "1" smd circle
			(at 0 0)
			(size 0.8128 0.8128)
			(layers "F.Cu" "F.Mask" "F.Paste")
			(net "ACT_HDD_32")
		)
	)
	(footprint ""
		(layer "F.Cu")
		(at 282.351734 21.726652 -90)
		(property "Reference" "R1136"
			(at 0 0 270)
			(layer "F.SilkS")
			(hide yes)
			(effects
				(font
					(size 1.27 1.27)
				)
			)
		)
		(property "Value" "10KR2F-2-GP"
			(at 0.064008 -3.993896 270)
			(unlocked yes)
			(layer "F.Fab")
			(hide yes)
			(effects
				(font
					(size 1.016 1.016)
					(thickness 0.1524)
				)
			)
		)
		(property "Device Type" "R402H16"
			(at 0.064008 -5.517896 270)
			(unlocked yes)
			(layer "F.Fab")
			(hide yes)
			(effects
				(font
					(size 1.016 1.016)
					(thickness 0.1524)
				)
			)
		)
		(duplicate_pad_numbers_are_jumpers no)
		(fp_line
			(start -0.508 -0.9398)
			(end -0.508 0.9398)
			(stroke
				(width 0.1524)
				(type default)
			)
			(layer "F.SilkS")
		)
		(fp_line
			(start 0.508 -0.9398)
			(end -0.508 -0.9398)
			(stroke
				(width 0.1524)
				(type default)
			)
			(layer "F.SilkS")
		)
		(fp_rect
			(start -0.508 0.9398)
			(end 0.508 -0.9398)
			(stroke
				(width 0)
				(type default)
			)
			(fill no)
			(layer "F.CrtYd")
		)
		(fp_rect
			(start -0.508 0.9398)
			(end 0.508 -0.9398)
			(stroke
				(width 0)
				(type default)
			)
			(fill no)
			(layer "F.Fab")
		)
		(pad "1" smd custom
			(at 0 -0.4445 270)
			(size 0.1397 0.1397)
			(layers "F.Cu" "F.Mask" "F.Paste")
			(net "P12V_IN")
			(options
				(clearance outline)
				(anchor circle)
			)
			(primitives
				(gr_poly
					(pts
						(arc
							(start -0.1778 -0.2794)
							(mid -0.249642 -0.249642)
							(end -0.2794 -0.1778)
						)
						(arc
							(start -0.2794 0.1778)
							(mid -0.249642 0.249642)
							(end -0.1778 0.2794)
						)
						(arc
							(start 0.1778 0.2794)
							(mid 0.249642 0.249642)
							(end 0.2794 0.1778)
						)
						(arc
							(start 0.2794 -0.1778)
							(mid 0.249642 -0.249642)
							(end 0.1778 -0.2794)
						)
					)
					(width 0)
					(fill yes)
				)
			)
		)
		(pad "2" smd custom
			(at 0 0.4445 270)
			(size 0.1397 0.1397)
			(layers "F.Cu" "F.Mask" "F.Paste")
			(net "DPB_PWR_BTN_B")
			(options
				(clearance outline)
				(anchor circle)
			)
			(primitives
				(gr_poly
					(pts
						(arc
							(start -0.1778 -0.2794)
							(mid -0.249642 -0.249642)
							(end -0.2794 -0.1778)
						)
						(arc
							(start -0.2794 0.1778)
							(mid -0.249642 0.249642)
							(end -0.1778 0.2794)
						)
						(arc
							(start 0.1778 0.2794)
							(mid 0.249642 0.249642)
							(end 0.2794 0.1778)
						)
						(arc
							(start 0.2794 -0.1778)
							(mid 0.249642 -0.249642)
							(end 0.1778 -0.2794)
						)
					)
					(width 0)
					(fill yes)
				)
			)
		)
	)
	(footprint ""
		(layer "F.Cu")
		(at 14.817598 -160.608518 90)
		(property "Reference" "R420"
			(at 0 0 90)
			(layer "F.SilkS")
			(hide yes)
			(effects
				(font
					(size 1.27 1.27)
				)
			)
		)
		(property "Value" "4K7R2J-2-GP"
			(at 0.064008 -3.993896 90)
			(unlocked yes)
			(layer "F.Fab")
			(hide yes)
			(effects
				(font
					(size 1.016 1.016)
					(thickness 0.1524)
				)
			)
		)
		(property "Device Type" "R402H16"
			(at 0.064008 -5.517896 90)
			(unlocked yes)
			(layer "F.Fab")
			(hide yes)
			(effects
				(font
					(size 1.016 1.016)
					(thickness 0.1524)
				)
			)
		)
		(duplicate_pad_numbers_are_jumpers no)
		(fp_line
			(start 0.508 -0.9398)
			(end -0.508 -0.9398)
			(stroke
				(width 0.1524)
				(type default)
			)
			(layer "F.SilkS")
		)
		(fp_line
			(start -0.508 -0.9398)
			(end -0.508 0.9398)
			(stroke
				(width 0.1524)
				(type default)
			)
			(layer "F.SilkS")
		)
		(fp_rect
			(start -0.508 0.9398)
			(end 0.508 -0.9398)
			(stroke
				(width 0)
				(type default)
			)
			(fill no)
			(layer "F.CrtYd")
		)
		(fp_rect
			(start -0.508 0.9398)
			(end 0.508 -0.9398)
			(stroke
				(width 0)
				(type default)
			)
			(fill no)
			(layer "F.Fab")
		)
		(pad "1" smd custom
			(at 0 -0.4445 90)
			(size 0.1397 0.1397)
			(layers "F.Cu" "F.Mask" "F.Paste")
			(net "P12V_A")
			(options
				(clearance outline)
				(anchor circle)
			)
			(primitives
				(gr_poly
					(pts
						(arc
							(start -0.1778 -0.2794)
							(mid -0.249642 -0.249642)
							(end -0.2794 -0.1778)
						)
						(arc
							(start -0.2794 0.1778)
							(mid -0.249642 0.249642)
							(end -0.1778 0.2794)
						)
						(arc
							(start 0.1778 0.2794)
							(mid 0.249642 0.249642)
							(end 0.2794 0.1778)
						)
						(arc
							(start 0.2794 -0.1778)
							(mid 0.249642 -0.249642)
							(end 0.1778 -0.2794)
						)
					)
					(width 0)
					(fill yes)
				)
			)
		)
		(pad "2" smd custom
			(at 0 0.4445 90)
			(size 0.1397 0.1397)
			(layers "F.Cu" "F.Mask" "F.Paste")
			(net "SW_HDD_R12")
			(options
				(clearance outline)
				(anchor circle)
			)
			(primitives
				(gr_poly
					(pts
						(arc
							(start -0.1778 -0.2794)
							(mid -0.249642 -0.249642)
							(end -0.2794 -0.1778)
						)
						(arc
							(start -0.2794 0.1778)
							(mid -0.249642 0.249642)
							(end -0.1778 0.2794)
						)
						(arc
							(start 0.1778 0.2794)
							(mid 0.249642 0.249642)
							(end 0.2794 0.1778)
						)
						(arc
							(start 0.2794 -0.1778)
							(mid 0.249642 -0.249642)
							(end 0.1778 -0.2794)
						)
					)
					(width 0)
					(fill yes)
				)
			)
		)
	)
	(footprint ""
		(layer "F.Cu")
		(at 77.822552 -127.78867 180)
		(property "Reference" "Q241"
			(at 0 0 180)
			(layer "F.SilkS")
			(hide yes)
			(effects
				(font
					(size 1.27 1.27)
				)
			)
		)
		(property "Value" "2N7002K-2-GP"
			(at 0.127 -8.9662 180)
			(unlocked yes)
			(layer "F.Fab")
			(hide yes)
			(effects
				(font
					(size 1.016 1.016)
					(thickness 0.1524)
				)
			)
		)
		(property "Device Type" "SOT23DGS2D4H44"
			(at 0.127 -10.4902 180)
			(unlocked yes)
			(layer "F.Fab")
			(hide yes)
			(effects
				(font
					(size 1.016 1.016)
					(thickness 0.1524)
				)
			)
		)
		(duplicate_pad_numbers_are_jumpers no)
		(fp_line
			(start 1.651 1.778)
			(end 1.651 -1.778)
			(stroke
				(width 0.1524)
				(type default)
			)
			(layer "F.SilkS")
		)
		(fp_line
			(start 1.651 -1.778)
			(end -1.651 -1.778)
			(stroke
				(width 0.1524)
				(type default)
			)
			(layer "F.SilkS")
		)
		(fp_line
			(start -1.651 1.778)
			(end 1.651 1.778)
			(stroke
				(width 0.1524)
				(type default)
			)
			(layer "F.SilkS")
		)
		(fp_line
			(start -1.651 -1.778)
			(end -1.651 1.778)
			(stroke
				(width 0.1524)
				(type default)
			)
			(layer "F.SilkS")
		)
		(fp_poly
			(pts
				(xy -1.778 1.8796) (xy -1.778 -1.8796) (xy 1.778 -1.8796) (xy 1.778 1.8796)
			)
			(stroke
				(width 0)
				(type default)
			)
			(fill no)
			(layer "F.CrtYd")
		)
		(fp_poly
			(pts
				(xy -1.778 1.8796) (xy -1.778 -1.8796) (xy 1.778 -1.8796) (xy 1.778 1.8796)
			)
			(stroke
				(width 0)
				(type default)
			)
			(fill no)
			(layer "F.Fab")
		)
		(pad "D" smd custom
			(at 0 -0.9525 180)
			(size 0.1905 0.1905)
			(layers "F.Cu" "F.Mask" "F.Paste")
			(net "FLT_HDD14_N")
			(options
				(clearance outline)
				(anchor circle)
			)
			(primitives
				(gr_poly
					(pts
						(arc
							(start -0.1778 0.5715)
							(mid -0.321484 0.511984)
							(end -0.381 0.3683)
						)
						(arc
							(start -0.381 -0.3683)
							(mid -0.321484 -0.511984)
							(end -0.1778 -0.5715)
						)
						(arc
							(start 0.1778 -0.5715)
							(mid 0.321484 -0.511984)
							(end 0.381 -0.3683)
						)
						(arc
							(start 0.381 0.3683)
							(mid 0.321484 0.511984)
							(end 0.1778 0.5715)
						)
					)
					(width 0)
					(fill yes)
				)
			)
		)
		(pad "G" smd custom
			(at -0.98425 0.9525 180)
			(size 0.1905 0.1905)
			(layers "F.Cu" "F.Mask" "F.Paste")
			(net "DRIVE_A_14_FLT_LED")
			(options
				(clearance outline)
				(anchor circle)
			)
			(primitives
				(gr_poly
					(pts
						(arc
							(start -0.1778 0.5715)
							(mid -0.321484 0.511984)
							(end -0.381 0.3683)
						)
						(arc
							(start -0.381 -0.3683)
							(mid -0.321484 -0.511984)
							(end -0.1778 -0.5715)
						)
						(arc
							(start 0.1778 -0.5715)
							(mid 0.321484 -0.511984)
							(end 0.381 -0.3683)
						)
						(arc
							(start 0.381 0.3683)
							(mid 0.321484 0.511984)
							(end 0.1778 0.5715)
						)
					)
					(width 0)
					(fill yes)
				)
			)
		)
		(pad "S" smd custom
			(at 0.98425 0.9525 180)
			(size 0.1905 0.1905)
			(layers "F.Cu" "F.Mask" "F.Paste")
			(net "GND")
			(options
				(clearance outline)
				(anchor circle)
			)
			(primitives
				(gr_poly
					(pts
						(arc
							(start -0.1778 0.5715)
							(mid -0.321484 0.511984)
							(end -0.381 0.3683)
						)
						(arc
							(start -0.381 -0.3683)
							(mid -0.321484 -0.511984)
							(end -0.1778 -0.5715)
						)
						(arc
							(start 0.1778 -0.5715)
							(mid 0.321484 -0.511984)
							(end 0.381 -0.3683)
						)
						(arc
							(start 0.381 0.3683)
							(mid 0.321484 0.511984)
							(end 0.1778 0.5715)
						)
					)
					(width 0)
					(fill yes)
				)
			)
		)
	)
	(footprint ""
		(layer "F.Cu")
		(at 440.144662 -287.44799)
		(property "Reference" "Q297"
			(at 0 0 0)
			(layer "F.SilkS")
			(hide yes)
			(effects
				(font
					(size 1.27 1.27)
				)
			)
		)
		(property "Value" "SSM3K324R-GP"
			(at 0.127 -8.9662 0)
			(unlocked yes)
			(layer "F.Fab")
			(hide yes)
			(effects
				(font
					(size 1.016 1.016)
					(thickness 0.1524)
				)
			)
		)
		(property "Device Type" "SOT23DGS2D4H35"
			(at 0.127 -10.4902 0)
			(unlocked yes)
			(layer "F.Fab")
			(hide yes)
			(effects
				(font
					(size 1.016 1.016)
					(thickness 0.1524)
				)
			)
		)
		(duplicate_pad_numbers_are_jumpers no)
		(fp_line
			(start -1.651 -1.778)
			(end -1.651 1.778)
			(stroke
				(width 0.1524)
				(type default)
			)
			(layer "F.SilkS")
		)
		(fp_line
			(start -1.651 1.778)
			(end 1.651 1.778)
			(stroke
				(width 0.1524)
				(type default)
			)
			(layer "F.SilkS")
		)
		(fp_line
			(start 1.651 -1.778)
			(end -1.651 -1.778)
			(stroke
				(width 0.1524)
				(type default)
			)
			(layer "F.SilkS")
		)
		(fp_line
			(start 1.651 1.778)
			(end 1.651 -1.778)
			(stroke
				(width 0.1524)
				(type default)
			)
			(layer "F.SilkS")
		)
		(fp_poly
			(pts
				(xy -1.778 1.8796) (xy -1.778 -1.8796) (xy 1.778 -1.8796) (xy 1.778 1.8796)
			)
			(stroke
				(width 0)
				(type default)
			)
			(fill no)
			(layer "F.CrtYd")
		)
		(fp_poly
			(pts
				(xy -1.778 1.8796) (xy -1.778 -1.8796) (xy 1.778 -1.8796) (xy 1.778 1.8796)
			)
			(stroke
				(width 0)
				(type default)
			)
			(fill no)
			(layer "F.Fab")
		)
		(pad "D" smd custom
			(at 0 -0.9525)
			(size 0.1905 0.1905)
			(layers "F.Cu" "F.Mask" "F.Paste")
			(net "DRV_ACT_34_N")
			(options
				(clearance outline)
				(anchor circle)
			)
			(primitives
				(gr_poly
					(pts
						(arc
							(start -0.1778 0.5715)
							(mid -0.321484 0.511984)
							(end -0.381 0.3683)
						)
						(arc
							(start -0.381 -0.3683)
							(mid -0.321484 -0.511984)
							(end -0.1778 -0.5715)
						)
						(arc
							(start 0.1778 -0.5715)
							(mid 0.321484 -0.511984)
							(end 0.381 -0.3683)
						)
						(arc
							(start 0.381 0.3683)
							(mid 0.321484 0.511984)
							(end 0.1778 0.5715)
						)
					)
					(width 0)
					(fill yes)
				)
			)
		)
		(pad "G" smd custom
			(at -0.98425 0.9525)
			(size 0.1905 0.1905)
			(layers "F.Cu" "F.Mask" "F.Paste")
			(net "DRIVE_B_34_ACT")
			(options
				(clearance outline)
				(anchor circle)
			)
			(primitives
				(gr_poly
					(pts
						(arc
							(start -0.1778 0.5715)
							(mid -0.321484 0.511984)
							(end -0.381 0.3683)
						)
						(arc
							(start -0.381 -0.3683)
							(mid -0.321484 -0.511984)
							(end -0.1778 -0.5715)
						)
						(arc
							(start 0.1778 -0.5715)
							(mid 0.321484 -0.511984)
							(end 0.381 -0.3683)
						)
						(arc
							(start 0.381 0.3683)
							(mid 0.321484 0.511984)
							(end 0.1778 0.5715)
						)
					)
					(width 0)
					(fill yes)
				)
			)
		)
		(pad "S" smd custom
			(at 0.98425 0.9525)
			(size 0.1905 0.1905)
			(layers "F.Cu" "F.Mask" "F.Paste")
			(net "GND")
			(options
				(clearance outline)
				(anchor circle)
			)
			(primitives
				(gr_poly
					(pts
						(arc
							(start -0.1778 0.5715)
							(mid -0.321484 0.511984)
							(end -0.381 0.3683)
						)
						(arc
							(start -0.381 -0.3683)
							(mid -0.321484 -0.511984)
							(end -0.1778 -0.5715)
						)
						(arc
							(start 0.1778 -0.5715)
							(mid 0.321484 -0.511984)
							(end 0.381 -0.3683)
						)
						(arc
							(start 0.381 0.3683)
							(mid 0.321484 0.511984)
							(end 0.1778 0.5715)
						)
					)
					(width 0)
					(fill yes)
				)
			)
		)
	)
	(footprint ""
		(layer "F.Cu")
		(at 150.440898 -189.462918 180)
		(property "Reference" "C255"
			(at 0 0 180)
			(layer "F.SilkS")
			(hide yes)
			(effects
				(font
					(size 1.27 1.27)
				)
			)
		)
		(property "Value" "SC1U25V3KX-GP"
			(at 0 -2.8194 180)
			(unlocked yes)
			(layer "F.Fab")
			(hide yes)
			(effects
				(font
					(size 1.016 1.016)
					(thickness 0.1524)
				)
			)
		)
		(property "Device Type" "C603H36"
			(at 0 -4.3434 180)
			(unlocked yes)
			(layer "F.Fab")
			(hide yes)
			(effects
				(font
					(size 1.016 1.016)
					(thickness 0.1524)
				)
			)
		)
		(duplicate_pad_numbers_are_jumpers no)
		(fp_line
			(start 0.508 0)
			(end -0.508 0)
			(stroke
				(width 0.2032)
				(type default)
			)
			(layer "F.SilkS")
		)
		(fp_rect
			(start -0.5842 1.3335)
			(end 0.5842 -1.3335)
			(stroke
				(width 0)
				(type default)
			)
			(fill no)
			(layer "F.CrtYd")
		)
		(fp_rect
			(start -0.5842 1.3335)
			(end 0.5842 -1.3335)
			(stroke
				(width 0)
				(type default)
			)
			(fill no)
			(layer "F.Fab")
		)
		(pad "1" smd custom
			(at 0 -0.762 180)
			(size 0.2159 0.2159)
			(layers "F.Cu" "F.Mask" "F.Paste")
			(net "P12V_HDD16")
			(options
				(clearance outline)
				(anchor circle)
			)
			(primitives
				(gr_poly
					(pts
						(arc
							(start -0.3302 -0.4318)
							(mid -0.402042 -0.402042)
							(end -0.4318 -0.3302)
						)
						(arc
							(start -0.4318 0.3302)
							(mid -0.402042 0.402042)
							(end -0.3302 0.4318)
						)
						(arc
							(start 0.3302 0.4318)
							(mid 0.402042 0.402042)
							(end 0.4318 0.3302)
						)
						(arc
							(start 0.4318 -0.3302)
							(mid 0.402042 -0.402042)
							(end 0.3302 -0.4318)
						)
					)
					(width 0)
					(fill yes)
				)
			)
		)
		(pad "2" smd custom
			(at 0 0.762 180)
			(size 0.2159 0.2159)
			(layers "F.Cu" "F.Mask" "F.Paste")
			(net "GND")
			(options
				(clearance outline)
				(anchor circle)
			)
			(primitives
				(gr_poly
					(pts
						(arc
							(start -0.3302 -0.4318)
							(mid -0.402042 -0.402042)
							(end -0.4318 -0.3302)
						)
						(arc
							(start -0.4318 0.3302)
							(mid -0.402042 0.402042)
							(end -0.3302 0.4318)
						)
						(arc
							(start 0.3302 0.4318)
							(mid 0.402042 0.402042)
							(end 0.4318 0.3302)
						)
						(arc
							(start 0.4318 -0.3302)
							(mid 0.402042 -0.402042)
							(end 0.3302 -0.4318)
						)
					)
					(width 0)
					(fill yes)
				)
			)
		)
	)
	(footprint ""
		(layer "F.Cu")
		(at 272.542 -316.30493 180)
		(property "Reference" "VIA57"
			(at 0 0 180)
			(layer "F.SilkS")
			(hide yes)
			(effects
				(font
					(size 1.27 1.27)
				)
			)
		)
		(property "Value" "100OHM-8L-1D6MM-L18L16-GP"
			(at -3.7211 -4.5085 180)
			(unlocked yes)
			(layer "F.Fab")
			(hide yes)
			(effects
				(font
					(size 1.016 1.016)
					(thickness 0.1524)
				)
			)
		)
		(property "Device Type" "VIA-PCIE-4P-394076"
			(at -3.7211 -6.0325 180)
			(unlocked yes)
			(layer "F.Fab")
			(hide yes)
			(effects
				(font
					(size 1.016 1.016)
					(thickness 0.1524)
				)
			)
		)
		(duplicate_pad_numbers_are_jumpers no)
		(fp_rect
			(start -1.9685 0.381)
			(end 1.9685 -0.381)
			(stroke
				(width 0)
				(type default)
			)
			(fill no)
			(layer "F.CrtYd")
		)
		(fp_rect
			(start -1.9685 0.381)
			(end 1.9685 -0.381)
			(stroke
				(width 0)
				(type default)
			)
			(fill no)
			(layer "F.Fab")
		)
		(pad "1" thru_hole circle
			(at -1.5875 0 180)
			(size 0.508 0.508)
			(drill 0.254)
			(layers "*.Cu" "*.Mask")
			(remove_unused_layers no)
			(net "GND")
			(clearance 0.127)
			(thermal_gap 0.127)
		)
		(pad "2" thru_hole circle
			(at -0.5715 0 180)
			(size 0.508 0.508)
			(drill 0.254)
			(layers "*.Cu" "*.Mask")
			(remove_unused_layers no)
			(net "PHY_SCC_A_TO_DRV_A_24_DP")
			(clearance 0.127)
			(thermal_gap 0.127)
		)
		(pad "3" thru_hole circle
			(at 0.5715 0 180)
			(size 0.508 0.508)
			(drill 0.254)
			(layers "*.Cu" "*.Mask")
			(remove_unused_layers no)
			(net "PHY_SCC_A_TO_DRV_A_24_DN")
			(clearance 0.127)
			(thermal_gap 0.127)
		)
		(pad "4" thru_hole circle
			(at 1.5875 0 180)
			(size 0.508 0.508)
			(drill 0.254)
			(layers "*.Cu" "*.Mask")
			(remove_unused_layers no)
			(net "GND")
			(clearance 0.127)
			(thermal_gap 0.127)
		)
	)
	(footprint ""
		(layer "F.Cu")
		(at 479.036126 -71.287894)
		(property "Reference" "C500"
			(at 0 0 0)
			(layer "F.SilkS")
			(hide yes)
			(effects
				(font
					(size 1.27 1.27)
				)
			)
		)
		(property "Value" "SC4D7U25V5KX-1-GP"
			(at -0.0762 -6.1214 0)
			(unlocked yes)
			(layer "F.Fab")
			(hide yes)
			(effects
				(font
					(size 1.016 1.016)
					(thickness 0.1524)
				)
			)
		)
		(property "Device Type" "C805H58"
			(at -0.0762 -8.1534 0)
			(unlocked yes)
			(layer "F.Fab")
			(hide yes)
			(effects
				(font
					(size 1.016 1.016)
					(thickness 0.1524)
				)
			)
		)
		(duplicate_pad_numbers_are_jumpers no)
		(fp_line
			(start 0.635 0)
			(end -0.635 0)
			(stroke
				(width 0.508)
				(type default)
			)
			(layer "F.SilkS")
		)
		(fp_rect
			(start -0.9652 1.778)
			(end 0.9652 -1.778)
			(stroke
				(width 0)
				(type default)
			)
			(fill no)
			(layer "F.CrtYd")
		)
		(fp_poly
			(pts
				(xy -0.9652 -1.778) (xy 0.9652 -1.778) (xy 0.9652 1.778) (xy -0.9652 1.778)
			)
			(stroke
				(width 0)
				(type default)
			)
			(fill no)
			(layer "F.Fab")
		)
		(pad "1" smd rect
			(at 0 -0.9652)
			(size 1.397 1.143)
			(layers "F.Cu" "F.Mask" "F.Paste")
			(net "P12V_HDD35")
		)
		(pad "2" smd rect
			(at 0 0.9652)
			(size 1.397 1.143)
			(layers "F.Cu" "F.Mask" "F.Paste")
			(net "GND")
		)
	)
	(footprint ""
		(layer "F.Cu")
		(at 35.260788 -253.3015 -90)
		(property "Reference" "R1210"
			(at 0 0 270)
			(layer "F.SilkS")
			(hide yes)
			(effects
				(font
					(size 1.27 1.27)
				)
			)
		)
		(property "Value" "10KR2F-2-GP"
			(at 0.064008 -3.993896 270)
			(unlocked yes)
			(layer "F.Fab")
			(hide yes)
			(effects
				(font
					(size 1.016 1.016)
					(thickness 0.1524)
				)
			)
		)
		(property "Device Type" "R402H16"
			(at 0.064008 -5.517896 270)
			(unlocked yes)
			(layer "F.Fab")
			(hide yes)
			(effects
				(font
					(size 1.016 1.016)
					(thickness 0.1524)
				)
			)
		)
		(duplicate_pad_numbers_are_jumpers no)
		(fp_line
			(start -0.508 -0.9398)
			(end -0.508 0.9398)
			(stroke
				(width 0.1524)
				(type default)
			)
			(layer "F.SilkS")
		)
		(fp_line
			(start 0.508 -0.9398)
			(end -0.508 -0.9398)
			(stroke
				(width 0.1524)
				(type default)
			)
			(layer "F.SilkS")
		)
		(fp_rect
			(start -0.508 0.9398)
			(end 0.508 -0.9398)
			(stroke
				(width 0)
				(type default)
			)
			(fill no)
			(layer "F.CrtYd")
		)
		(fp_rect
			(start -0.508 0.9398)
			(end 0.508 -0.9398)
			(stroke
				(width 0)
				(type default)
			)
			(fill no)
			(layer "F.Fab")
		)
		(pad "1" smd custom
			(at 0 -0.4445 270)
			(size 0.1397 0.1397)
			(layers "F.Cu" "F.Mask" "F.Paste")
			(net "P5V_A_1")
			(options
				(clearance outline)
				(anchor circle)
			)
			(primitives
				(gr_poly
					(pts
						(arc
							(start -0.1778 -0.2794)
							(mid -0.249642 -0.249642)
							(end -0.2794 -0.1778)
						)
						(arc
							(start -0.2794 0.1778)
							(mid -0.249642 0.249642)
							(end -0.1778 0.2794)
						)
						(arc
							(start 0.1778 0.2794)
							(mid 0.249642 0.249642)
							(end 0.2794 0.1778)
						)
						(arc
							(start 0.2794 -0.1778)
							(mid 0.249642 -0.249642)
							(end 0.1778 -0.2794)
						)
					)
					(width 0)
					(fill yes)
				)
			)
		)
		(pad "2" smd custom
			(at 0 0.4445 270)
			(size 0.1397 0.1397)
			(layers "F.Cu" "F.Mask" "F.Paste")
			(net "P5V_A_1_PGOOD")
			(options
				(clearance outline)
				(anchor circle)
			)
			(primitives
				(gr_poly
					(pts
						(arc
							(start -0.1778 -0.2794)
							(mid -0.249642 -0.249642)
							(end -0.2794 -0.1778)
						)
						(arc
							(start -0.2794 0.1778)
							(mid -0.249642 0.249642)
							(end -0.1778 0.2794)
						)
						(arc
							(start 0.1778 0.2794)
							(mid 0.249642 0.249642)
							(end 0.2794 0.1778)
						)
						(arc
							(start 0.2794 -0.1778)
							(mid 0.249642 -0.249642)
							(end 0.1778 -0.2794)
						)
					)
					(width 0)
					(fill yes)
				)
			)
		)
	)
	(footprint ""
		(layer "F.Cu")
		(at 359.681526 -134.075678 90)
		(property "Reference" "R1098"
			(at 0 0 90)
			(layer "F.SilkS")
			(hide yes)
			(effects
				(font
					(size 1.27 1.27)
				)
			)
		)
		(property "Value" "49K9R2F-L-GP"
			(at 0.064008 -3.993896 90)
			(unlocked yes)
			(layer "F.Fab")
			(hide yes)
			(effects
				(font
					(size 1.016 1.016)
					(thickness 0.1524)
				)
			)
		)
		(property "Device Type" "R402H16"
			(at 0.064008 -5.517896 90)
			(unlocked yes)
			(layer "F.Fab")
			(hide yes)
			(effects
				(font
					(size 1.016 1.016)
					(thickness 0.1524)
				)
			)
		)
		(duplicate_pad_numbers_are_jumpers no)
		(fp_line
			(start 0.508 -0.9398)
			(end -0.508 -0.9398)
			(stroke
				(width 0.1524)
				(type default)
			)
			(layer "F.SilkS")
		)
		(fp_line
			(start -0.508 -0.9398)
			(end -0.508 0.9398)
			(stroke
				(width 0.1524)
				(type default)
			)
			(layer "F.SilkS")
		)
		(fp_rect
			(start -0.508 0.9398)
			(end 0.508 -0.9398)
			(stroke
				(width 0)
				(type default)
			)
			(fill no)
			(layer "F.CrtYd")
		)
		(fp_rect
			(start -0.508 0.9398)
			(end 0.508 -0.9398)
			(stroke
				(width 0)
				(type default)
			)
			(fill no)
			(layer "F.Fab")
		)
		(pad "1" smd custom
			(at 0 -0.4445 90)
			(size 0.1397 0.1397)
			(layers "F.Cu" "F.Mask" "F.Paste")
			(net "P12V_B")
			(options
				(clearance outline)
				(anchor circle)
			)
			(primitives
				(gr_poly
					(pts
						(arc
							(start -0.1778 -0.2794)
							(mid -0.249642 -0.249642)
							(end -0.2794 -0.1778)
						)
						(arc
							(start -0.2794 0.1778)
							(mid -0.249642 0.249642)
							(end -0.1778 0.2794)
						)
						(arc
							(start 0.1778 0.2794)
							(mid 0.249642 0.249642)
							(end 0.2794 0.1778)
						)
						(arc
							(start 0.2794 -0.1778)
							(mid 0.249642 -0.249642)
							(end 0.1778 -0.2794)
						)
					)
					(width 0)
					(fill yes)
				)
			)
		)
		(pad "2" smd custom
			(at 0 0.4445 90)
			(size 0.1397 0.1397)
			(layers "F.Cu" "F.Mask" "F.Paste")
			(net "MB1_CM_UV_R")
			(options
				(clearance outline)
				(anchor circle)
			)
			(primitives
				(gr_poly
					(pts
						(arc
							(start -0.1778 -0.2794)
							(mid -0.249642 -0.249642)
							(end -0.2794 -0.1778)
						)
						(arc
							(start -0.2794 0.1778)
							(mid -0.249642 0.249642)
							(end -0.1778 0.2794)
						)
						(arc
							(start 0.1778 0.2794)
							(mid 0.249642 0.249642)
							(end 0.2794 0.1778)
						)
						(arc
							(start 0.2794 -0.1778)
							(mid 0.249642 -0.249642)
							(end 0.1778 -0.2794)
						)
					)
					(width 0)
					(fill yes)
				)
			)
		)
	)
	(footprint ""
		(layer "F.Cu")
		(at 441.964826 -127.254)
		(property "Reference" "R342"
			(at 0 0 0)
			(layer "F.SilkS")
			(hide yes)
			(effects
				(font
					(size 1.27 1.27)
				)
			)
		)
		(property "Value" "91R3F-1-GP"
			(at -0.0254 -2.5146 0)
			(unlocked yes)
			(layer "F.Fab")
			(hide yes)
			(effects
				(font
					(size 1.016 1.016)
					(thickness 0.1524)
				)
			)
		)
		(property "Device Type" "R603H22"
			(at -0.0254 -4.0386 0)
			(unlocked yes)
			(layer "F.Fab")
			(hide yes)
			(effects
				(font
					(size 1.016 1.016)
					(thickness 0.1524)
				)
			)
		)
		(duplicate_pad_numbers_are_jumpers no)
		(fp_line
			(start -0.4826 0)
			(end -0.2032 0)
			(stroke
				(width 0.2032)
				(type default)
			)
			(layer "F.SilkS")
		)
		(fp_line
			(start 0.2032 0)
			(end 0.4826 0)
			(stroke
				(width 0.2032)
				(type default)
			)
			(layer "F.SilkS")
		)
		(fp_rect
			(start -0.5842 1.3335)
			(end 0.5842 -1.3335)
			(stroke
				(width 0)
				(type default)
			)
			(fill no)
			(layer "F.CrtYd")
		)
		(fp_rect
			(start -0.5842 1.3335)
			(end 0.5842 -1.3335)
			(stroke
				(width 0)
				(type default)
			)
			(fill no)
			(layer "F.Fab")
		)
		(pad "1" smd custom
			(at 0 -0.762)
			(size 0.2159 0.2159)
			(layers "F.Cu" "F.Mask" "F.Paste")
			(net "P5V_A_4")
			(options
				(clearance outline)
				(anchor circle)
			)
			(primitives
				(gr_poly
					(pts
						(arc
							(start -0.3302 -0.4318)
							(mid -0.402042 -0.402042)
							(end -0.4318 -0.3302)
						)
						(arc
							(start -0.4318 0.3302)
							(mid -0.402042 0.402042)
							(end -0.3302 0.4318)
						)
						(arc
							(start 0.3302 0.4318)
							(mid 0.402042 0.402042)
							(end 0.4318 0.3302)
						)
						(arc
							(start 0.4318 -0.3302)
							(mid 0.402042 -0.402042)
							(end 0.3302 -0.4318)
						)
					)
					(width 0)
					(fill yes)
				)
			)
		)
		(pad "2" smd custom
			(at 0 0.762)
			(size 0.2159 0.2159)
			(layers "F.Cu" "F.Mask" "F.Paste")
			(net "DRV_ACT_22")
			(options
				(clearance outline)
				(anchor circle)
			)
			(primitives
				(gr_poly
					(pts
						(arc
							(start -0.3302 -0.4318)
							(mid -0.402042 -0.402042)
							(end -0.4318 -0.3302)
						)
						(arc
							(start -0.4318 0.3302)
							(mid -0.402042 0.402042)
							(end -0.3302 0.4318)
						)
						(arc
							(start 0.3302 0.4318)
							(mid 0.402042 0.402042)
							(end 0.4318 0.3302)
						)
						(arc
							(start 0.4318 -0.3302)
							(mid 0.402042 -0.402042)
							(end 0.3302 -0.4318)
						)
					)
					(width 0)
					(fill yes)
				)
			)
		)
	)
	(footprint ""
		(layer "F.Cu")
		(at 145.106898 -179.683918 90)
		(property "Reference" "R499"
			(at 0 0 90)
			(layer "F.SilkS")
			(hide yes)
			(effects
				(font
					(size 1.27 1.27)
				)
			)
		)
		(property "Value" "2R6F-GP"
			(at -0.0508 -4.8514 90)
			(unlocked yes)
			(layer "F.Fab")
			(hide yes)
			(effects
				(font
					(size 1.016 1.016)
					(thickness 0.1524)
				)
			)
		)
		(property "Device Type" "R1206H26"
			(at 0 -6.3754 90)
			(unlocked yes)
			(layer "F.Fab")
			(hide yes)
			(effects
				(font
					(size 1.016 1.016)
					(thickness 0.1524)
				)
			)
		)
		(duplicate_pad_numbers_are_jumpers no)
		(fp_line
			(start 1.016 -2.2352)
			(end 1.016 2.2352)
			(stroke
				(width 0.1524)
				(type default)
			)
			(layer "F.SilkS")
		)
		(fp_line
			(start -1.016 -2.2352)
			(end 1.016 -2.2352)
			(stroke
				(width 0.1524)
				(type default)
			)
			(layer "F.SilkS")
		)
		(fp_line
			(start 1.016 2.2352)
			(end -1.016 2.2352)
			(stroke
				(width 0.1524)
				(type default)
			)
			(layer "F.SilkS")
		)
		(fp_line
			(start -1.016 2.2352)
			(end -1.016 -2.2352)
			(stroke
				(width 0.1524)
				(type default)
			)
			(layer "F.SilkS")
		)
		(fp_rect
			(start -1.0922 2.3114)
			(end 1.0922 -2.3114)
			(stroke
				(width 0)
				(type default)
			)
			(fill no)
			(layer "F.CrtYd")
		)
		(fp_poly
			(pts
				(xy -1.0922 -2.3114) (xy 1.0922 -2.3114) (xy 1.0922 2.3114) (xy -1.0922 2.3114)
			)
			(stroke
				(width 0)
				(type default)
			)
			(fill no)
			(layer "F.Fab")
		)
		(pad "1" smd rect
			(at 0 -1.397 90)
			(size 1.651 1.27)
			(layers "F.Cu" "F.Mask" "F.Paste")
			(net "P12V_HDD16")
		)
		(pad "2" smd rect
			(at 0 1.397 90)
			(size 1.651 1.27)
			(layers "F.Cu" "F.Mask" "F.Paste")
			(net "12V_PRE_16")
		)
	)
	(footprint ""
		(layer "F.Cu")
		(at 101.156516 -188.831982)
		(property "Reference" "Q230"
			(at 0 0 0)
			(layer "F.SilkS")
			(hide yes)
			(effects
				(font
					(size 1.27 1.27)
				)
			)
		)
		(property "Value" "2N7002K-2-GP"
			(at 0.127 -8.9662 0)
			(unlocked yes)
			(layer "F.Fab")
			(hide yes)
			(effects
				(font
					(size 1.016 1.016)
					(thickness 0.1524)
				)
			)
		)
		(property "Device Type" "SOT23DGS2D4H44"
			(at 0.127 -10.4902 0)
			(unlocked yes)
			(layer "F.Fab")
			(hide yes)
			(effects
				(font
					(size 1.016 1.016)
					(thickness 0.1524)
				)
			)
		)
		(duplicate_pad_numbers_are_jumpers no)
		(fp_line
			(start -1.651 -1.778)
			(end -1.651 1.778)
			(stroke
				(width 0.1524)
				(type default)
			)
			(layer "F.SilkS")
		)
		(fp_line
			(start -1.651 1.778)
			(end 1.651 1.778)
			(stroke
				(width 0.1524)
				(type default)
			)
			(layer "F.SilkS")
		)
		(fp_line
			(start 1.651 -1.778)
			(end -1.651 -1.778)
			(stroke
				(width 0.1524)
				(type default)
			)
			(layer "F.SilkS")
		)
		(fp_line
			(start 1.651 1.778)
			(end 1.651 -1.778)
			(stroke
				(width 0.1524)
				(type default)
			)
			(layer "F.SilkS")
		)
		(fp_poly
			(pts
				(xy -1.778 1.8796) (xy -1.778 -1.8796) (xy 1.778 -1.8796) (xy 1.778 1.8796)
			)
			(stroke
				(width 0)
				(type default)
			)
			(fill no)
			(layer "F.CrtYd")
		)
		(fp_poly
			(pts
				(xy -1.778 1.8796) (xy -1.778 -1.8796) (xy 1.778 -1.8796) (xy 1.778 1.8796)
			)
			(stroke
				(width 0)
				(type default)
			)
			(fill no)
			(layer "F.Fab")
		)
		(pad "D" smd custom
			(at 0 -0.9525)
			(size 0.1905 0.1905)
			(layers "F.Cu" "F.Mask" "F.Paste")
			(net "FLT_HDD3_N")
			(options
				(clearance outline)
				(anchor circle)
			)
			(primitives
				(gr_poly
					(pts
						(arc
							(start -0.1778 0.5715)
							(mid -0.321484 0.511984)
							(end -0.381 0.3683)
						)
						(arc
							(start -0.381 -0.3683)
							(mid -0.321484 -0.511984)
							(end -0.1778 -0.5715)
						)
						(arc
							(start 0.1778 -0.5715)
							(mid 0.321484 -0.511984)
							(end 0.381 -0.3683)
						)
						(arc
							(start 0.381 0.3683)
							(mid 0.321484 0.511984)
							(end 0.1778 0.5715)
						)
					)
					(width 0)
					(fill yes)
				)
			)
		)
		(pad "G" smd custom
			(at -0.98425 0.9525)
			(size 0.1905 0.1905)
			(layers "F.Cu" "F.Mask" "F.Paste")
			(net "DRIVE_A_3_FLT_LED")
			(options
				(clearance outline)
				(anchor circle)
			)
			(primitives
				(gr_poly
					(pts
						(arc
							(start -0.1778 0.5715)
							(mid -0.321484 0.511984)
							(end -0.381 0.3683)
						)
						(arc
							(start -0.381 -0.3683)
							(mid -0.321484 -0.511984)
							(end -0.1778 -0.5715)
						)
						(arc
							(start 0.1778 -0.5715)
							(mid 0.321484 -0.511984)
							(end 0.381 -0.3683)
						)
						(arc
							(start 0.381 0.3683)
							(mid 0.321484 0.511984)
							(end 0.1778 0.5715)
						)
					)
					(width 0)
					(fill yes)
				)
			)
		)
		(pad "S" smd custom
			(at 0.98425 0.9525)
			(size 0.1905 0.1905)
			(layers "F.Cu" "F.Mask" "F.Paste")
			(net "GND")
			(options
				(clearance outline)
				(anchor circle)
			)
			(primitives
				(gr_poly
					(pts
						(arc
							(start -0.1778 0.5715)
							(mid -0.321484 0.511984)
							(end -0.381 0.3683)
						)
						(arc
							(start -0.381 -0.3683)
							(mid -0.321484 -0.511984)
							(end -0.1778 -0.5715)
						)
						(arc
							(start 0.1778 -0.5715)
							(mid 0.321484 -0.511984)
							(end 0.381 -0.3683)
						)
						(arc
							(start 0.381 0.3683)
							(mid 0.321484 0.511984)
							(end 0.1778 0.5715)
						)
					)
					(width 0)
					(fill yes)
				)
			)
		)
	)
	(footprint ""
		(layer "F.Cu")
		(at 98.754184 -187.425584)
		(property "Reference" "R465"
			(at 0 0 0)
			(layer "F.SilkS")
			(hide yes)
			(effects
				(font
					(size 1.27 1.27)
				)
			)
		)
		(property "Value" "4K7R2J-2-GP"
			(at 0.064008 -3.993896 0)
			(unlocked yes)
			(layer "F.Fab")
			(hide yes)
			(effects
				(font
					(size 1.016 1.016)
					(thickness 0.1524)
				)
			)
		)
		(property "Device Type" "R402H16"
			(at 0.064008 -5.517896 0)
			(unlocked yes)
			(layer "F.Fab")
			(hide yes)
			(effects
				(font
					(size 1.016 1.016)
					(thickness 0.1524)
				)
			)
		)
		(duplicate_pad_numbers_are_jumpers no)
		(fp_line
			(start -0.508 -0.9398)
			(end -0.508 0.9398)
			(stroke
				(width 0.1524)
				(type default)
			)
			(layer "F.SilkS")
		)
		(fp_line
			(start 0.508 -0.9398)
			(end -0.508 -0.9398)
			(stroke
				(width 0.1524)
				(type default)
			)
			(layer "F.SilkS")
		)
		(fp_rect
			(start -0.508 0.9398)
			(end 0.508 -0.9398)
			(stroke
				(width 0)
				(type default)
			)
			(fill no)
			(layer "F.CrtYd")
		)
		(fp_rect
			(start -0.508 0.9398)
			(end 0.508 -0.9398)
			(stroke
				(width 0)
				(type default)
			)
			(fill no)
			(layer "F.Fab")
		)
		(pad "1" smd custom
			(at 0 -0.4445)
			(size 0.1397 0.1397)
			(layers "F.Cu" "F.Mask" "F.Paste")
			(net "DRIVE_A_3_FLT_LED")
			(options
				(clearance outline)
				(anchor circle)
			)
			(primitives
				(gr_poly
					(pts
						(arc
							(start -0.1778 -0.2794)
							(mid -0.249642 -0.249642)
							(end -0.2794 -0.1778)
						)
						(arc
							(start -0.2794 0.1778)
							(mid -0.249642 0.249642)
							(end -0.1778 0.2794)
						)
						(arc
							(start 0.1778 0.2794)
							(mid 0.249642 0.249642)
							(end 0.2794 0.1778)
						)
						(arc
							(start 0.2794 -0.1778)
							(mid 0.249642 -0.249642)
							(end 0.1778 -0.2794)
						)
					)
					(width 0)
					(fill yes)
				)
			)
		)
		(pad "2" smd custom
			(at 0 0.4445)
			(size 0.1397 0.1397)
			(layers "F.Cu" "F.Mask" "F.Paste")
			(net "GND")
			(options
				(clearance outline)
				(anchor circle)
			)
			(primitives
				(gr_poly
					(pts
						(arc
							(start -0.1778 -0.2794)
							(mid -0.249642 -0.249642)
							(end -0.2794 -0.1778)
						)
						(arc
							(start -0.2794 0.1778)
							(mid -0.249642 0.249642)
							(end -0.1778 0.2794)
						)
						(arc
							(start 0.1778 0.2794)
							(mid 0.249642 0.249642)
							(end 0.2794 0.1778)
						)
						(arc
							(start 0.2794 -0.1778)
							(mid 0.249642 -0.249642)
							(end 0.1778 -0.2794)
						)
					)
					(width 0)
					(fill yes)
				)
			)
		)
	)
	(footprint ""
		(layer "F.Cu")
		(at 27.178 -245.8466 90)
		(property "Reference" "C597"
			(at 0 0 90)
			(layer "F.SilkS")
			(hide yes)
			(effects
				(font
					(size 1.27 1.27)
				)
			)
		)
		(property "Value" "SC10U16V5KX-7-GP-U"
			(at -0.0762 -6.1214 90)
			(unlocked yes)
			(layer "F.Fab")
			(hide yes)
			(effects
				(font
					(size 1.016 1.016)
					(thickness 0.1524)
				)
			)
		)
		(property "Device Type" "C805H58"
			(at -0.0762 -8.1534 90)
			(unlocked yes)
			(layer "F.Fab")
			(hide yes)
			(effects
				(font
					(size 1.016 1.016)
					(thickness 0.1524)
				)
			)
		)
		(duplicate_pad_numbers_are_jumpers no)
		(fp_line
			(start 0.635 0)
			(end -0.635 0)
			(stroke
				(width 0.508)
				(type default)
			)
			(layer "F.SilkS")
		)
		(fp_rect
			(start -0.9652 1.778)
			(end 0.9652 -1.778)
			(stroke
				(width 0)
				(type default)
			)
			(fill no)
			(layer "F.CrtYd")
		)
		(fp_poly
			(pts
				(xy -0.9652 -1.778) (xy 0.9652 -1.778) (xy 0.9652 1.778) (xy -0.9652 1.778)
			)
			(stroke
				(width 0)
				(type default)
			)
			(fill no)
			(layer "F.Fab")
		)
		(pad "1" smd rect
			(at 0 -0.9652 90)
			(size 1.397 1.143)
			(layers "F.Cu" "F.Mask" "F.Paste")
			(net "P12V_A_VIN_U20")
		)
		(pad "2" smd rect
			(at 0 0.9652 90)
			(size 1.397 1.143)
			(layers "F.Cu" "F.Mask" "F.Paste")
			(net "GND")
		)
	)
	(footprint ""
		(layer "F.Cu")
		(at 406.164034 -245.335806 -90)
		(property "Reference" "R493"
			(at 0 0 270)
			(layer "F.SilkS")
			(hide yes)
			(effects
				(font
					(size 1.27 1.27)
				)
			)
		)
		(property "Value" "4K7R2J-2-GP"
			(at 0.064008 -3.993896 270)
			(unlocked yes)
			(layer "F.Fab")
			(hide yes)
			(effects
				(font
					(size 1.016 1.016)
					(thickness 0.1524)
				)
			)
		)
		(property "Device Type" "R402H16"
			(at 0.064008 -5.517896 270)
			(unlocked yes)
			(layer "F.Fab")
			(hide yes)
			(effects
				(font
					(size 1.016 1.016)
					(thickness 0.1524)
				)
			)
		)
		(duplicate_pad_numbers_are_jumpers no)
		(fp_line
			(start -0.508 -0.9398)
			(end -0.508 0.9398)
			(stroke
				(width 0.1524)
				(type default)
			)
			(layer "F.SilkS")
		)
		(fp_line
			(start 0.508 -0.9398)
			(end -0.508 -0.9398)
			(stroke
				(width 0.1524)
				(type default)
			)
			(layer "F.SilkS")
		)
		(fp_rect
			(start -0.508 0.9398)
			(end 0.508 -0.9398)
			(stroke
				(width 0)
				(type default)
			)
			(fill no)
			(layer "F.CrtYd")
		)
		(fp_rect
			(start -0.508 0.9398)
			(end 0.508 -0.9398)
			(stroke
				(width 0)
				(type default)
			)
			(fill no)
			(layer "F.Fab")
		)
		(pad "1" smd custom
			(at 0 -0.4445 270)
			(size 0.1397 0.1397)
			(layers "F.Cu" "F.Mask" "F.Paste")
			(net "DRIVE_A_9_FLT_LED")
			(options
				(clearance outline)
				(anchor circle)
			)
			(primitives
				(gr_poly
					(pts
						(arc
							(start -0.1778 -0.2794)
							(mid -0.249642 -0.249642)
							(end -0.2794 -0.1778)
						)
						(arc
							(start -0.2794 0.1778)
							(mid -0.249642 0.249642)
							(end -0.1778 0.2794)
						)
						(arc
							(start 0.1778 0.2794)
							(mid 0.249642 0.249642)
							(end 0.2794 0.1778)
						)
						(arc
							(start 0.2794 -0.1778)
							(mid 0.249642 -0.249642)
							(end 0.1778 -0.2794)
						)
					)
					(width 0)
					(fill yes)
				)
			)
		)
		(pad "2" smd custom
			(at 0 0.4445 270)
			(size 0.1397 0.1397)
			(layers "F.Cu" "F.Mask" "F.Paste")
			(net "GND")
			(options
				(clearance outline)
				(anchor circle)
			)
			(primitives
				(gr_poly
					(pts
						(arc
							(start -0.1778 -0.2794)
							(mid -0.249642 -0.249642)
							(end -0.2794 -0.1778)
						)
						(arc
							(start -0.2794 0.1778)
							(mid -0.249642 0.249642)
							(end -0.1778 0.2794)
						)
						(arc
							(start 0.1778 0.2794)
							(mid 0.249642 0.249642)
							(end 0.2794 0.1778)
						)
						(arc
							(start 0.2794 -0.1778)
							(mid 0.249642 -0.249642)
							(end 0.1778 -0.2794)
						)
					)
					(width 0)
					(fill yes)
				)
			)
		)
	)
	(footprint ""
		(layer "F.Cu")
		(at 380.98095 -180.064918 -90)
		(property "Reference" "R594"
			(at 0 0 270)
			(layer "F.SilkS")
			(hide yes)
			(effects
				(font
					(size 1.27 1.27)
				)
			)
		)
		(property "Value" "220R3F-1-GP"
			(at -0.0254 -2.5146 270)
			(unlocked yes)
			(layer "F.Fab")
			(hide yes)
			(effects
				(font
					(size 1.016 1.016)
					(thickness 0.1524)
				)
			)
		)
		(property "Device Type" "R603H22"
			(at -0.0254 -4.0386 270)
			(unlocked yes)
			(layer "F.Fab")
			(hide yes)
			(effects
				(font
					(size 1.016 1.016)
					(thickness 0.1524)
				)
			)
		)
		(duplicate_pad_numbers_are_jumpers no)
		(fp_line
			(start -0.4826 0)
			(end -0.2032 0)
			(stroke
				(width 0.2032)
				(type default)
			)
			(layer "F.SilkS")
		)
		(fp_line
			(start 0.2032 0)
			(end 0.4826 0)
			(stroke
				(width 0.2032)
				(type default)
			)
			(layer "F.SilkS")
		)
		(fp_rect
			(start -0.5842 1.3335)
			(end 0.5842 -1.3335)
			(stroke
				(width 0)
				(type default)
			)
			(fill no)
			(layer "F.CrtYd")
		)
		(fp_rect
			(start -0.5842 1.3335)
			(end 0.5842 -1.3335)
			(stroke
				(width 0)
				(type default)
			)
			(fill no)
			(layer "F.Fab")
		)
		(pad "1" smd custom
			(at 0 -0.762 270)
			(size 0.2159 0.2159)
			(layers "F.Cu" "F.Mask" "F.Paste")
			(net "HDD_PRSNT_20")
			(options
				(clearance outline)
				(anchor circle)
			)
			(primitives
				(gr_poly
					(pts
						(arc
							(start -0.3302 -0.4318)
							(mid -0.402042 -0.402042)
							(end -0.4318 -0.3302)
						)
						(arc
							(start -0.4318 0.3302)
							(mid -0.402042 0.402042)
							(end -0.3302 0.4318)
						)
						(arc
							(start 0.3302 0.4318)
							(mid 0.402042 0.402042)
							(end 0.4318 0.3302)
						)
						(arc
							(start 0.4318 -0.3302)
							(mid 0.402042 -0.402042)
							(end 0.3302 -0.4318)
						)
					)
					(width 0)
					(fill yes)
				)
			)
		)
		(pad "2" smd custom
			(at 0 0.762 270)
			(size 0.2159 0.2159)
			(layers "F.Cu" "F.Mask" "F.Paste")
			(net "DRIVE_A_20_INS")
			(options
				(clearance outline)
				(anchor circle)
			)
			(primitives
				(gr_poly
					(pts
						(arc
							(start -0.3302 -0.4318)
							(mid -0.402042 -0.402042)
							(end -0.4318 -0.3302)
						)
						(arc
							(start -0.4318 0.3302)
							(mid -0.402042 0.402042)
							(end -0.3302 0.4318)
						)
						(arc
							(start 0.3302 0.4318)
							(mid 0.402042 0.402042)
							(end 0.4318 0.3302)
						)
						(arc
							(start 0.4318 -0.3302)
							(mid 0.402042 -0.402042)
							(end 0.3302 -0.4318)
						)
					)
					(width 0)
					(fill yes)
				)
			)
		)
	)
	(footprint ""
		(layer "F.Cu")
		(at 437.75884 -130.34391 -90)
		(property "Reference" "R546"
			(at 0 0 270)
			(layer "F.SilkS")
			(hide yes)
			(effects
				(font
					(size 1.27 1.27)
				)
			)
		)
		(property "Value" "4K7R2J-2-GP"
			(at 0.064008 -3.993896 270)
			(unlocked yes)
			(layer "F.Fab")
			(hide yes)
			(effects
				(font
					(size 1.016 1.016)
					(thickness 0.1524)
				)
			)
		)
		(property "Device Type" "R402H16"
			(at 0.064008 -5.517896 270)
			(unlocked yes)
			(layer "F.Fab")
			(hide yes)
			(effects
				(font
					(size 1.016 1.016)
					(thickness 0.1524)
				)
			)
		)
		(duplicate_pad_numbers_are_jumpers no)
		(fp_line
			(start -0.508 -0.9398)
			(end -0.508 0.9398)
			(stroke
				(width 0.1524)
				(type default)
			)
			(layer "F.SilkS")
		)
		(fp_line
			(start 0.508 -0.9398)
			(end -0.508 -0.9398)
			(stroke
				(width 0.1524)
				(type default)
			)
			(layer "F.SilkS")
		)
		(fp_rect
			(start -0.508 0.9398)
			(end 0.508 -0.9398)
			(stroke
				(width 0)
				(type default)
			)
			(fill no)
			(layer "F.CrtYd")
		)
		(fp_rect
			(start -0.508 0.9398)
			(end 0.508 -0.9398)
			(stroke
				(width 0)
				(type default)
			)
			(fill no)
			(layer "F.Fab")
		)
		(pad "1" smd custom
			(at 0 -0.4445 270)
			(size 0.1397 0.1397)
			(layers "F.Cu" "F.Mask" "F.Paste")
			(net "DRIVE_A_22_FLT_LED")
			(options
				(clearance outline)
				(anchor circle)
			)
			(primitives
				(gr_poly
					(pts
						(arc
							(start -0.1778 -0.2794)
							(mid -0.249642 -0.249642)
							(end -0.2794 -0.1778)
						)
						(arc
							(start -0.2794 0.1778)
							(mid -0.249642 0.249642)
							(end -0.1778 0.2794)
						)
						(arc
							(start 0.1778 0.2794)
							(mid 0.249642 0.249642)
							(end 0.2794 0.1778)
						)
						(arc
							(start 0.2794 -0.1778)
							(mid 0.249642 -0.249642)
							(end 0.1778 -0.2794)
						)
					)
					(width 0)
					(fill yes)
				)
			)
		)
		(pad "2" smd custom
			(at 0 0.4445 270)
			(size 0.1397 0.1397)
			(layers "F.Cu" "F.Mask" "F.Paste")
			(net "GND")
			(options
				(clearance outline)
				(anchor circle)
			)
			(primitives
				(gr_poly
					(pts
						(arc
							(start -0.1778 -0.2794)
							(mid -0.249642 -0.249642)
							(end -0.2794 -0.1778)
						)
						(arc
							(start -0.2794 0.1778)
							(mid -0.249642 0.249642)
							(end -0.1778 0.2794)
						)
						(arc
							(start 0.1778 0.2794)
							(mid 0.249642 0.249642)
							(end 0.2794 0.1778)
						)
						(arc
							(start 0.2794 -0.1778)
							(mid 0.249642 -0.249642)
							(end 0.1778 -0.2794)
						)
					)
					(width 0)
					(fill yes)
				)
			)
		)
	)
	(footprint ""
		(layer "F.Cu")
		(at 164.814504 -301.245778 90)
		(property "Reference" "R572"
			(at 0 0 90)
			(layer "F.SilkS")
			(hide yes)
			(effects
				(font
					(size 1.27 1.27)
				)
			)
		)
		(property "Value" "4K7R2J-2-GP"
			(at 0.064008 -3.993896 90)
			(unlocked yes)
			(layer "F.Fab")
			(hide yes)
			(effects
				(font
					(size 1.016 1.016)
					(thickness 0.1524)
				)
			)
		)
		(property "Device Type" "R402H16"
			(at 0.064008 -5.517896 90)
			(unlocked yes)
			(layer "F.Fab")
			(hide yes)
			(effects
				(font
					(size 1.016 1.016)
					(thickness 0.1524)
				)
			)
		)
		(duplicate_pad_numbers_are_jumpers no)
		(fp_line
			(start 0.508 -0.9398)
			(end -0.508 -0.9398)
			(stroke
				(width 0.1524)
				(type default)
			)
			(layer "F.SilkS")
		)
		(fp_line
			(start -0.508 -0.9398)
			(end -0.508 0.9398)
			(stroke
				(width 0.1524)
				(type default)
			)
			(layer "F.SilkS")
		)
		(fp_rect
			(start -0.508 0.9398)
			(end 0.508 -0.9398)
			(stroke
				(width 0)
				(type default)
			)
			(fill no)
			(layer "F.CrtYd")
		)
		(fp_rect
			(start -0.508 0.9398)
			(end 0.508 -0.9398)
			(stroke
				(width 0)
				(type default)
			)
			(fill no)
			(layer "F.Fab")
		)
		(pad "1" smd custom
			(at 0 -0.4445 90)
			(size 0.1397 0.1397)
			(layers "F.Cu" "F.Mask" "F.Paste")
			(net "DRIVE_B_29_FLT_LED")
			(options
				(clearance outline)
				(anchor circle)
			)
			(primitives
				(gr_poly
					(pts
						(arc
							(start -0.1778 -0.2794)
							(mid -0.249642 -0.249642)
							(end -0.2794 -0.1778)
						)
						(arc
							(start -0.2794 0.1778)
							(mid -0.249642 0.249642)
							(end -0.1778 0.2794)
						)
						(arc
							(start 0.1778 0.2794)
							(mid 0.249642 0.249642)
							(end 0.2794 0.1778)
						)
						(arc
							(start 0.2794 -0.1778)
							(mid 0.249642 -0.249642)
							(end 0.1778 -0.2794)
						)
					)
					(width 0)
					(fill yes)
				)
			)
		)
		(pad "2" smd custom
			(at 0 0.4445 90)
			(size 0.1397 0.1397)
			(layers "F.Cu" "F.Mask" "F.Paste")
			(net "GND")
			(options
				(clearance outline)
				(anchor circle)
			)
			(primitives
				(gr_poly
					(pts
						(arc
							(start -0.1778 -0.2794)
							(mid -0.249642 -0.249642)
							(end -0.2794 -0.1778)
						)
						(arc
							(start -0.2794 0.1778)
							(mid -0.249642 0.249642)
							(end -0.1778 0.2794)
						)
						(arc
							(start 0.1778 0.2794)
							(mid 0.249642 0.249642)
							(end 0.2794 0.1778)
						)
						(arc
							(start 0.2794 -0.1778)
							(mid 0.249642 -0.249642)
							(end 0.1778 -0.2794)
						)
					)
					(width 0)
					(fill yes)
				)
			)
		)
	)
	(footprint ""
		(layer "F.Cu")
		(at 26.051002 -250.37415 -90)
		(property "Reference" "R1219"
			(at 0 0 270)
			(layer "F.SilkS")
			(hide yes)
			(effects
				(font
					(size 1.27 1.27)
				)
			)
		)
		(property "Value" "309KR2F-GP"
			(at 0.064008 -3.993896 270)
			(unlocked yes)
			(layer "F.Fab")
			(hide yes)
			(effects
				(font
					(size 1.016 1.016)
					(thickness 0.1524)
				)
			)
		)
		(property "Device Type" "R402H16"
			(at 0.064008 -5.517896 270)
			(unlocked yes)
			(layer "F.Fab")
			(hide yes)
			(effects
				(font
					(size 1.016 1.016)
					(thickness 0.1524)
				)
			)
		)
		(duplicate_pad_numbers_are_jumpers no)
		(fp_line
			(start -0.508 -0.9398)
			(end -0.508 0.9398)
			(stroke
				(width 0.1524)
				(type default)
			)
			(layer "F.SilkS")
		)
		(fp_line
			(start 0.508 -0.9398)
			(end -0.508 -0.9398)
			(stroke
				(width 0.1524)
				(type default)
			)
			(layer "F.SilkS")
		)
		(fp_rect
			(start -0.508 0.9398)
			(end 0.508 -0.9398)
			(stroke
				(width 0)
				(type default)
			)
			(fill no)
			(layer "F.CrtYd")
		)
		(fp_rect
			(start -0.508 0.9398)
			(end 0.508 -0.9398)
			(stroke
				(width 0)
				(type default)
			)
			(fill no)
			(layer "F.Fab")
		)
		(pad "1" smd custom
			(at 0 -0.4445 270)
			(size 0.1397 0.1397)
			(layers "F.Cu" "F.Mask" "F.Paste")
			(net "P5V_A_RF")
			(options
				(clearance outline)
				(anchor circle)
			)
			(primitives
				(gr_poly
					(pts
						(arc
							(start -0.1778 -0.2794)
							(mid -0.249642 -0.249642)
							(end -0.2794 -0.1778)
						)
						(arc
							(start -0.2794 0.1778)
							(mid -0.249642 0.249642)
							(end -0.1778 0.2794)
						)
						(arc
							(start 0.1778 0.2794)
							(mid 0.249642 0.249642)
							(end 0.2794 0.1778)
						)
						(arc
							(start 0.2794 -0.1778)
							(mid 0.249642 -0.249642)
							(end 0.1778 -0.2794)
						)
					)
					(width 0)
					(fill yes)
				)
			)
		)
		(pad "2" smd custom
			(at 0 0.4445 270)
			(size 0.1397 0.1397)
			(layers "F.Cu" "F.Mask" "F.Paste")
			(net "P5V_A_VREG")
			(options
				(clearance outline)
				(anchor circle)
			)
			(primitives
				(gr_poly
					(pts
						(arc
							(start -0.1778 -0.2794)
							(mid -0.249642 -0.249642)
							(end -0.2794 -0.1778)
						)
						(arc
							(start -0.2794 0.1778)
							(mid -0.249642 0.249642)
							(end -0.1778 0.2794)
						)
						(arc
							(start 0.1778 0.2794)
							(mid 0.249642 0.249642)
							(end 0.2794 0.1778)
						)
						(arc
							(start 0.2794 -0.1778)
							(mid 0.249642 -0.249642)
							(end 0.1778 -0.2794)
						)
					)
					(width 0)
					(fill yes)
				)
			)
		)
	)
	(footprint ""
		(layer "F.Cu")
		(at 252.271276 -248.87936)
		(property "Reference" "R58"
			(at 0 0 0)
			(layer "F.SilkS")
			(hide yes)
			(effects
				(font
					(size 1.27 1.27)
				)
			)
		)
		(property "Value" "0R2J-2-GP"
			(at 0.064008 -3.993896 0)
			(unlocked yes)
			(layer "F.Fab")
			(hide yes)
			(effects
				(font
					(size 1.016 1.016)
					(thickness 0.1524)
				)
			)
		)
		(property "Device Type" "R402H16"
			(at 0.064008 -5.517896 0)
			(unlocked yes)
			(layer "F.Fab")
			(hide yes)
			(effects
				(font
					(size 1.016 1.016)
					(thickness 0.1524)
				)
			)
		)
		(duplicate_pad_numbers_are_jumpers no)
		(fp_line
			(start -0.508 -0.9398)
			(end -0.508 0.9398)
			(stroke
				(width 0.1524)
				(type default)
			)
			(layer "F.SilkS")
		)
		(fp_line
			(start 0.508 -0.9398)
			(end -0.508 -0.9398)
			(stroke
				(width 0.1524)
				(type default)
			)
			(layer "F.SilkS")
		)
		(fp_rect
			(start -0.508 0.9398)
			(end 0.508 -0.9398)
			(stroke
				(width 0)
				(type default)
			)
			(fill no)
			(layer "F.CrtYd")
		)
		(fp_rect
			(start -0.508 0.9398)
			(end 0.508 -0.9398)
			(stroke
				(width 0)
				(type default)
			)
			(fill no)
			(layer "F.Fab")
		)
		(pad "1" smd custom
			(at 0 -0.4445)
			(size 0.1397 0.1397)
			(layers "F.Cu" "F.Mask" "F.Paste")
			(net "IO_EXP6_INT_N")
			(options
				(clearance outline)
				(anchor circle)
			)
			(primitives
				(gr_poly
					(pts
						(arc
							(start -0.1778 -0.2794)
							(mid -0.249642 -0.249642)
							(end -0.2794 -0.1778)
						)
						(arc
							(start -0.2794 0.1778)
							(mid -0.249642 0.249642)
							(end -0.1778 0.2794)
						)
						(arc
							(start 0.1778 0.2794)
							(mid 0.249642 0.249642)
							(end 0.2794 0.1778)
						)
						(arc
							(start 0.2794 -0.1778)
							(mid 0.249642 -0.249642)
							(end 0.1778 -0.2794)
						)
					)
					(width 0)
					(fill yes)
				)
			)
		)
		(pad "2" smd custom
			(at 0 0.4445)
			(size 0.1397 0.1397)
			(layers "F.Cu" "F.Mask" "F.Paste")
			(net "DRIVE_INSERT_ALERT_A_N")
			(options
				(clearance outline)
				(anchor circle)
			)
			(primitives
				(gr_poly
					(pts
						(arc
							(start -0.1778 -0.2794)
							(mid -0.249642 -0.249642)
							(end -0.2794 -0.1778)
						)
						(arc
							(start -0.2794 0.1778)
							(mid -0.249642 0.249642)
							(end -0.1778 0.2794)
						)
						(arc
							(start 0.1778 0.2794)
							(mid 0.249642 0.249642)
							(end 0.2794 0.1778)
						)
						(arc
							(start 0.2794 -0.1778)
							(mid 0.249642 -0.249642)
							(end 0.1778 -0.2794)
						)
					)
					(width 0)
					(fill yes)
				)
			)
		)
	)
	(footprint ""
		(layer "F.Cu")
		(at 479.384614 -274.219416 -90)
		(property "Reference" "C181"
			(at 0 0 270)
			(layer "F.SilkS")
			(hide yes)
			(effects
				(font
					(size 1.27 1.27)
				)
			)
		)
		(property "Value" "SCD01U16V1KX-GP"
			(at -2.8321 -1.7399 270)
			(unlocked yes)
			(layer "F.Fab")
			(hide yes)
			(effects
				(font
					(size 1.016 1.016)
					(thickness 0.1524)
				)
			)
		)
		(property "Device Type" "C0201H13"
			(at -2.8321 -3.2639 270)
			(unlocked yes)
			(layer "F.Fab")
			(hide yes)
			(effects
				(font
					(size 1.016 1.016)
					(thickness 0.1524)
				)
			)
		)
		(duplicate_pad_numbers_are_jumpers no)
		(fp_rect
			(start -0.2794 0.6477)
			(end 0.2794 -0.6477)
			(stroke
				(width 0)
				(type default)
			)
			(fill no)
			(layer "F.CrtYd")
		)
		(fp_rect
			(start -0.2794 0.6477)
			(end 0.2794 -0.6477)
			(stroke
				(width 0)
				(type default)
			)
			(fill no)
			(layer "F.Fab")
		)
		(pad "1" smd custom
			(at 0 -0.2794 270)
			(size 0.0762 0.0762)
			(layers "F.Cu" "F.Mask" "F.Paste")
			(net "SAS_HDD_RX_N11")
			(options
				(clearance outline)
				(anchor circle)
			)
			(primitives
				(gr_poly
					(pts
						(arc
							(start 0.1524 -0.127)
							(mid 0.137521 -0.162921)
							(end 0.1016 -0.1778)
						)
						(arc
							(start -0.1016 -0.1778)
							(mid -0.137521 -0.162921)
							(end -0.1524 -0.127)
						)
						(arc
							(start -0.1524 0.127)
							(mid -0.137521 0.162921)
							(end -0.1016 0.1778)
						)
						(arc
							(start 0.1016 0.1778)
							(mid 0.137521 0.162921)
							(end 0.1524 0.127)
						)
					)
					(width 0)
					(fill yes)
				)
			)
		)
		(pad "2" smd custom
			(at 0 0.2794 270)
			(size 0.0762 0.0762)
			(layers "F.Cu" "F.Mask" "F.Paste")
			(net "PHY_SCC_A_TO_DRV_A_11_DN")
			(options
				(clearance outline)
				(anchor circle)
			)
			(primitives
				(gr_poly
					(pts
						(arc
							(start 0.1524 -0.127)
							(mid 0.137521 -0.162921)
							(end 0.1016 -0.1778)
						)
						(arc
							(start -0.1016 -0.1778)
							(mid -0.137521 -0.162921)
							(end -0.1524 -0.127)
						)
						(arc
							(start -0.1524 0.127)
							(mid -0.137521 0.162921)
							(end -0.1016 0.1778)
						)
						(arc
							(start 0.1016 0.1778)
							(mid 0.137521 0.162921)
							(end 0.1524 0.127)
						)
					)
					(width 0)
					(fill yes)
				)
			)
		)
	)
	(footprint ""
		(layer "F.Cu")
		(at 130.433318 -145.397474)
		(property "Reference" "D42"
			(at 0 0 0)
			(layer "F.SilkS")
			(hide yes)
			(effects
				(font
					(size 1.27 1.27)
				)
			)
		)
		(property "Value" "MMPZ5228BPT-GP"
			(at 0 -6.7818 0)
			(unlocked yes)
			(layer "F.Fab")
			(hide yes)
			(effects
				(font
					(size 1.016 1.016)
					(thickness 0.1524)
				)
			)
		)
		(property "Device Type" "SOD323AKH40"
			(at 0 -8.6868 0)
			(unlocked yes)
			(layer "F.Fab")
			(hide yes)
			(effects
				(font
					(size 1.016 1.016)
					(thickness 0.1524)
				)
			)
		)
		(duplicate_pad_numbers_are_jumpers no)
		(fp_line
			(start -0.889 -1.9304)
			(end 0.889 -1.9304)
			(stroke
				(width 0.1524)
				(type default)
			)
			(layer "F.SilkS")
		)
		(fp_line
			(start -0.889 2.159)
			(end -0.889 -1.9304)
			(stroke
				(width 0.1524)
				(type default)
			)
			(layer "F.SilkS")
		)
		(fp_line
			(start 0.762 2.0574)
			(end -0.762 2.0574)
			(stroke
				(width 0.508)
				(type default)
			)
			(layer "F.SilkS")
		)
		(fp_line
			(start 0.889 -1.9304)
			(end 0.889 2.159)
			(stroke
				(width 0.1524)
				(type default)
			)
			(layer "F.SilkS")
		)
		(fp_line
			(start 0.889 2.159)
			(end -0.889 2.159)
			(stroke
				(width 0.1524)
				(type default)
			)
			(layer "F.SilkS")
		)
		(fp_rect
			(start -1.016 2.3114)
			(end 1.016 -2.0066)
			(stroke
				(width 0)
				(type default)
			)
			(fill no)
			(layer "F.CrtYd")
		)
		(fp_poly
			(pts
				(xy -1.016 -2.0066) (xy 1.016 -2.0066) (xy 1.016 2.3114) (xy -1.016 2.3114)
			)
			(stroke
				(width 0)
				(type default)
			)
			(fill no)
			(layer "F.Fab")
		)
		(pad "A" smd rect
			(at 0 -1.143)
			(size 0.5588 1.016)
			(layers "F.Cu" "F.Mask" "F.Paste")
			(net "GND")
		)
		(pad "K" smd rect
			(at 0 1.143)
			(size 0.5588 1.016)
			(layers "F.Cu" "F.Mask" "F.Paste")
			(net "VCCP_A")
		)
	)
	(footprint ""
		(layer "F.Cu")
		(at 255.389634 -3.617722 90)
		(property "Reference" "TP213"
			(at 0 0 90)
			(layer "F.SilkS")
			(hide yes)
			(effects
				(font
					(size 1.27 1.27)
				)
			)
		)
		(property "Value" "TPAD32-GP"
			(at -0.0508 -1.6764 90)
			(unlocked yes)
			(layer "F.Fab")
			(hide yes)
			(effects
				(font
					(size 1.016 1.016)
					(thickness 0.1524)
				)
			)
		)
		(property "Device Type" "TPAD32"
			(at -0.0508 -3.2004 90)
			(unlocked yes)
			(layer "F.Fab")
			(hide yes)
			(effects
				(font
					(size 1.016 1.016)
					(thickness 0.1524)
				)
			)
		)
		(duplicate_pad_numbers_are_jumpers no)
		(fp_poly
			(pts
				(arc
					(start 0 0.4064)
					(mid 0 -0.4064)
					(end 0 0.4064)
				)
			)
			(stroke
				(width 0)
				(type default)
			)
			(fill no)
			(layer "F.CrtYd")
		)
		(fp_poly
			(pts
				(arc
					(start 0 0.7112)
					(mid 0 -0.7112)
					(end 0 0.7112)
				)
			)
			(stroke
				(width 0)
				(type default)
			)
			(fill no)
			(layer "F.Fab")
		)
		(pad "1" smd circle
			(at 0 0 90)
			(size 0.8128 0.8128)
			(layers "F.Cu" "F.Mask" "F.Paste")
			(net "TP_COMP_A_NCSI_RCLK")
		)
	)
	(footprint ""
		(layer "F.Cu")
		(at 343.235534 -294.424862 180)
		(property "Reference" "R280"
			(at 0 0 180)
			(layer "F.SilkS")
			(hide yes)
			(effects
				(font
					(size 1.27 1.27)
				)
			)
		)
		(property "Value" "130R3F-GP"
			(at -0.0254 -2.5146 180)
			(unlocked yes)
			(layer "F.Fab")
			(hide yes)
			(effects
				(font
					(size 1.016 1.016)
					(thickness 0.1524)
				)
			)
		)
		(property "Device Type" "R603H22"
			(at -0.0254 -4.0386 180)
			(unlocked yes)
			(layer "F.Fab")
			(hide yes)
			(effects
				(font
					(size 1.016 1.016)
					(thickness 0.1524)
				)
			)
		)
		(duplicate_pad_numbers_are_jumpers no)
		(fp_line
			(start 0.2032 0)
			(end 0.4826 0)
			(stroke
				(width 0.2032)
				(type default)
			)
			(layer "F.SilkS")
		)
		(fp_line
			(start -0.4826 0)
			(end -0.2032 0)
			(stroke
				(width 0.2032)
				(type default)
			)
			(layer "F.SilkS")
		)
		(fp_rect
			(start -0.5842 1.3335)
			(end 0.5842 -1.3335)
			(stroke
				(width 0)
				(type default)
			)
			(fill no)
			(layer "F.CrtYd")
		)
		(fp_rect
			(start -0.5842 1.3335)
			(end 0.5842 -1.3335)
			(stroke
				(width 0)
				(type default)
			)
			(fill no)
			(layer "F.Fab")
		)
		(pad "1" smd custom
			(at 0 -0.762 180)
			(size 0.2159 0.2159)
			(layers "F.Cu" "F.Mask" "F.Paste")
			(net "P5V_B")
			(options
				(clearance outline)
				(anchor circle)
			)
			(primitives
				(gr_poly
					(pts
						(arc
							(start -0.3302 -0.4318)
							(mid -0.402042 -0.402042)
							(end -0.4318 -0.3302)
						)
						(arc
							(start -0.4318 0.3302)
							(mid -0.402042 0.402042)
							(end -0.3302 0.4318)
						)
						(arc
							(start 0.3302 0.4318)
							(mid 0.402042 0.402042)
							(end 0.4318 0.3302)
						)
						(arc
							(start 0.4318 -0.3302)
							(mid 0.402042 -0.402042)
							(end 0.3302 -0.4318)
						)
					)
					(width 0)
					(fill yes)
				)
			)
		)
		(pad "2" smd custom
			(at 0 0.762 180)
			(size 0.2159 0.2159)
			(layers "F.Cu" "F.Mask" "F.Paste")
			(net "FLT_HDD31")
			(options
				(clearance outline)
				(anchor circle)
			)
			(primitives
				(gr_poly
					(pts
						(arc
							(start -0.3302 -0.4318)
							(mid -0.402042 -0.402042)
							(end -0.4318 -0.3302)
						)
						(arc
							(start -0.4318 0.3302)
							(mid -0.402042 0.402042)
							(end -0.3302 0.4318)
						)
						(arc
							(start 0.3302 0.4318)
							(mid 0.402042 0.402042)
							(end 0.4318 0.3302)
						)
						(arc
							(start 0.4318 -0.3302)
							(mid 0.402042 -0.402042)
							(end 0.3302 -0.4318)
						)
					)
					(width 0)
					(fill yes)
				)
			)
		)
	)
	(footprint ""
		(layer "F.Cu")
		(at 24.240998 -304.462942 180)
		(property "Reference" "C515"
			(at 0 0 180)
			(layer "F.SilkS")
			(hide yes)
			(effects
				(font
					(size 1.27 1.27)
				)
			)
		)
		(property "Value" "SC1U25V3KX-GP"
			(at 0 -2.8194 180)
			(unlocked yes)
			(layer "F.Fab")
			(hide yes)
			(effects
				(font
					(size 1.016 1.016)
					(thickness 0.1524)
				)
			)
		)
		(property "Device Type" "C603H36"
			(at 0 -4.3434 180)
			(unlocked yes)
			(layer "F.Fab")
			(hide yes)
			(effects
				(font
					(size 1.016 1.016)
					(thickness 0.1524)
				)
			)
		)
		(duplicate_pad_numbers_are_jumpers no)
		(fp_line
			(start 0.508 0)
			(end -0.508 0)
			(stroke
				(width 0.2032)
				(type default)
			)
			(layer "F.SilkS")
		)
		(fp_rect
			(start -0.5842 1.3335)
			(end 0.5842 -1.3335)
			(stroke
				(width 0)
				(type default)
			)
			(fill no)
			(layer "F.CrtYd")
		)
		(fp_rect
			(start -0.5842 1.3335)
			(end 0.5842 -1.3335)
			(stroke
				(width 0)
				(type default)
			)
			(fill no)
			(layer "F.Fab")
		)
		(pad "1" smd custom
			(at 0 -0.762 180)
			(size 0.2159 0.2159)
			(layers "F.Cu" "F.Mask" "F.Paste")
			(net "P12V_HDD0")
			(options
				(clearance outline)
				(anchor circle)
			)
			(primitives
				(gr_poly
					(pts
						(arc
							(start -0.3302 -0.4318)
							(mid -0.402042 -0.402042)
							(end -0.4318 -0.3302)
						)
						(arc
							(start -0.4318 0.3302)
							(mid -0.402042 0.402042)
							(end -0.3302 0.4318)
						)
						(arc
							(start 0.3302 0.4318)
							(mid 0.402042 0.402042)
							(end 0.4318 0.3302)
						)
						(arc
							(start 0.4318 -0.3302)
							(mid 0.402042 -0.402042)
							(end 0.3302 -0.4318)
						)
					)
					(width 0)
					(fill yes)
				)
			)
		)
		(pad "2" smd custom
			(at 0 0.762 180)
			(size 0.2159 0.2159)
			(layers "F.Cu" "F.Mask" "F.Paste")
			(net "GND")
			(options
				(clearance outline)
				(anchor circle)
			)
			(primitives
				(gr_poly
					(pts
						(arc
							(start -0.3302 -0.4318)
							(mid -0.402042 -0.402042)
							(end -0.4318 -0.3302)
						)
						(arc
							(start -0.4318 0.3302)
							(mid -0.402042 0.402042)
							(end -0.3302 0.4318)
						)
						(arc
							(start 0.3302 0.4318)
							(mid 0.402042 0.402042)
							(end 0.4318 0.3302)
						)
						(arc
							(start 0.4318 -0.3302)
							(mid 0.402042 -0.402042)
							(end 0.3302 -0.4318)
						)
					)
					(width 0)
					(fill yes)
				)
			)
		)
	)
	(footprint ""
		(layer "F.Cu")
		(at 280.080466 22.062948 90)
		(property "Reference" "R1134"
			(at 0 0 90)
			(layer "F.SilkS")
			(hide yes)
			(effects
				(font
					(size 1.27 1.27)
				)
			)
		)
		(property "Value" "2K2R2F-GP"
			(at 0.064008 -3.993896 90)
			(unlocked yes)
			(layer "F.Fab")
			(hide yes)
			(effects
				(font
					(size 1.016 1.016)
					(thickness 0.1524)
				)
			)
		)
		(property "Device Type" "R402H16"
			(at 0.064008 -5.517896 90)
			(unlocked yes)
			(layer "F.Fab")
			(hide yes)
			(effects
				(font
					(size 1.016 1.016)
					(thickness 0.1524)
				)
			)
		)
		(duplicate_pad_numbers_are_jumpers no)
		(fp_line
			(start 0.508 -0.9398)
			(end -0.508 -0.9398)
			(stroke
				(width 0.1524)
				(type default)
			)
			(layer "F.SilkS")
		)
		(fp_line
			(start -0.508 -0.9398)
			(end -0.508 0.9398)
			(stroke
				(width 0.1524)
				(type default)
			)
			(layer "F.SilkS")
		)
		(fp_rect
			(start -0.508 0.9398)
			(end 0.508 -0.9398)
			(stroke
				(width 0)
				(type default)
			)
			(fill no)
			(layer "F.CrtYd")
		)
		(fp_rect
			(start -0.508 0.9398)
			(end 0.508 -0.9398)
			(stroke
				(width 0)
				(type default)
			)
			(fill no)
			(layer "F.Fab")
		)
		(pad "1" smd custom
			(at 0 -0.4445 90)
			(size 0.1397 0.1397)
			(layers "F.Cu" "F.Mask" "F.Paste")
			(net "P12V_IN")
			(options
				(clearance outline)
				(anchor circle)
			)
			(primitives
				(gr_poly
					(pts
						(arc
							(start -0.1778 -0.2794)
							(mid -0.249642 -0.249642)
							(end -0.2794 -0.1778)
						)
						(arc
							(start -0.2794 0.1778)
							(mid -0.249642 0.249642)
							(end -0.1778 0.2794)
						)
						(arc
							(start 0.1778 0.2794)
							(mid 0.249642 0.249642)
							(end 0.2794 0.1778)
						)
						(arc
							(start 0.2794 -0.1778)
							(mid 0.249642 -0.249642)
							(end 0.1778 -0.2794)
						)
					)
					(width 0)
					(fill yes)
				)
			)
		)
		(pad "2" smd custom
			(at 0 0.4445 90)
			(size 0.1397 0.1397)
			(layers "F.Cu" "F.Mask" "F.Paste")
			(net "DPB_PWR_BTN_A")
			(options
				(clearance outline)
				(anchor circle)
			)
			(primitives
				(gr_poly
					(pts
						(arc
							(start -0.1778 -0.2794)
							(mid -0.249642 -0.249642)
							(end -0.2794 -0.1778)
						)
						(arc
							(start -0.2794 0.1778)
							(mid -0.249642 0.249642)
							(end -0.1778 0.2794)
						)
						(arc
							(start 0.1778 0.2794)
							(mid 0.249642 0.249642)
							(end 0.2794 0.1778)
						)
						(arc
							(start 0.2794 -0.1778)
							(mid 0.249642 -0.249642)
							(end 0.1778 -0.2794)
						)
					)
					(width 0)
					(fill yes)
				)
			)
		)
	)
	(footprint ""
		(layer "F.Cu")
		(at 412.937452 -65.039494 -90)
		(property "Reference" "R893"
			(at 0 0 270)
			(layer "F.SilkS")
			(hide yes)
			(effects
				(font
					(size 1.27 1.27)
				)
			)
		)
		(property "Value" "220R3F-1-GP"
			(at -0.0254 -2.5146 270)
			(unlocked yes)
			(layer "F.Fab")
			(hide yes)
			(effects
				(font
					(size 1.016 1.016)
					(thickness 0.1524)
				)
			)
		)
		(property "Device Type" "R603H22"
			(at -0.0254 -4.0386 270)
			(unlocked yes)
			(layer "F.Fab")
			(hide yes)
			(effects
				(font
					(size 1.016 1.016)
					(thickness 0.1524)
				)
			)
		)
		(duplicate_pad_numbers_are_jumpers no)
		(fp_line
			(start -0.4826 0)
			(end -0.2032 0)
			(stroke
				(width 0.2032)
				(type default)
			)
			(layer "F.SilkS")
		)
		(fp_line
			(start 0.2032 0)
			(end 0.4826 0)
			(stroke
				(width 0.2032)
				(type default)
			)
			(layer "F.SilkS")
		)
		(fp_rect
			(start -0.5842 1.3335)
			(end 0.5842 -1.3335)
			(stroke
				(width 0)
				(type default)
			)
			(fill no)
			(layer "F.CrtYd")
		)
		(fp_rect
			(start -0.5842 1.3335)
			(end 0.5842 -1.3335)
			(stroke
				(width 0)
				(type default)
			)
			(fill no)
			(layer "F.Fab")
		)
		(pad "1" smd custom
			(at 0 -0.762 270)
			(size 0.2159 0.2159)
			(layers "F.Cu" "F.Mask" "F.Paste")
			(net "HDD_PRSNT_33")
			(options
				(clearance outline)
				(anchor circle)
			)
			(primitives
				(gr_poly
					(pts
						(arc
							(start -0.3302 -0.4318)
							(mid -0.402042 -0.402042)
							(end -0.4318 -0.3302)
						)
						(arc
							(start -0.4318 0.3302)
							(mid -0.402042 0.402042)
							(end -0.3302 0.4318)
						)
						(arc
							(start 0.3302 0.4318)
							(mid 0.402042 0.402042)
							(end 0.4318 0.3302)
						)
						(arc
							(start 0.4318 -0.3302)
							(mid 0.402042 -0.402042)
							(end 0.3302 -0.4318)
						)
					)
					(width 0)
					(fill yes)
				)
			)
		)
		(pad "2" smd custom
			(at 0 0.762 270)
			(size 0.2159 0.2159)
			(layers "F.Cu" "F.Mask" "F.Paste")
			(net "DRIVE_A_33_INS")
			(options
				(clearance outline)
				(anchor circle)
			)
			(primitives
				(gr_poly
					(pts
						(arc
							(start -0.3302 -0.4318)
							(mid -0.402042 -0.402042)
							(end -0.4318 -0.3302)
						)
						(arc
							(start -0.4318 0.3302)
							(mid -0.402042 0.402042)
							(end -0.3302 0.4318)
						)
						(arc
							(start 0.3302 0.4318)
							(mid 0.402042 0.402042)
							(end 0.4318 0.3302)
						)
						(arc
							(start 0.4318 -0.3302)
							(mid 0.402042 -0.402042)
							(end 0.3302 -0.4318)
						)
					)
					(width 0)
					(fill yes)
				)
			)
		)
	)
	(footprint ""
		(layer "F.Cu")
		(at 419.389052 -47.749968 -90)
		(property "Reference" "VIA31"
			(at 0 0 270)
			(layer "F.SilkS")
			(hide yes)
			(effects
				(font
					(size 1.27 1.27)
				)
			)
		)
		(property "Value" "100OHM-8L-1D6MM-L18L16-GP"
			(at -3.7211 -4.5085 270)
			(unlocked yes)
			(layer "F.Fab")
			(hide yes)
			(effects
				(font
					(size 1.016 1.016)
					(thickness 0.1524)
				)
			)
		)
		(property "Device Type" "VIA-PCIE-4P-394076"
			(at -3.7211 -6.0325 270)
			(unlocked yes)
			(layer "F.Fab")
			(hide yes)
			(effects
				(font
					(size 1.016 1.016)
					(thickness 0.1524)
				)
			)
		)
		(duplicate_pad_numbers_are_jumpers no)
		(fp_rect
			(start -1.9685 0.381)
			(end 1.9685 -0.381)
			(stroke
				(width 0)
				(type default)
			)
			(fill no)
			(layer "F.CrtYd")
		)
		(fp_rect
			(start -1.9685 0.381)
			(end 1.9685 -0.381)
			(stroke
				(width 0)
				(type default)
			)
			(fill no)
			(layer "F.Fab")
		)
		(pad "1" thru_hole circle
			(at -1.5875 0 270)
			(size 0.508 0.508)
			(drill 0.254)
			(layers "*.Cu" "*.Mask")
			(remove_unused_layers no)
			(net "GND")
			(clearance 0.127)
			(thermal_gap 0.127)
		)
		(pad "2" thru_hole circle
			(at -0.5715 0 270)
			(size 0.508 0.508)
			(drill 0.254)
			(layers "*.Cu" "*.Mask")
			(remove_unused_layers no)
			(net "PHY_DRV_A_TO_SCC_A_33_DP")
			(clearance 0.127)
			(thermal_gap 0.127)
		)
		(pad "3" thru_hole circle
			(at 0.5715 0 270)
			(size 0.508 0.508)
			(drill 0.254)
			(layers "*.Cu" "*.Mask")
			(remove_unused_layers no)
			(net "PHY_DRV_A_TO_SCC_A_33_DN")
			(clearance 0.127)
			(thermal_gap 0.127)
		)
		(pad "4" thru_hole circle
			(at 1.5875 0 270)
			(size 0.508 0.508)
			(drill 0.254)
			(layers "*.Cu" "*.Mask")
			(remove_unused_layers no)
			(net "GND")
			(clearance 0.127)
			(thermal_gap 0.127)
		)
	)
	(footprint ""
		(layer "F.Cu")
		(at 35.543998 -68.747894)
		(property "Reference" "TP122"
			(at 0 0 0)
			(layer "F.SilkS")
			(hide yes)
			(effects
				(font
					(size 1.27 1.27)
				)
			)
		)
		(property "Value" "TPAD32-GP"
			(at -0.0508 -1.6764 0)
			(unlocked yes)
			(layer "F.Fab")
			(hide yes)
			(effects
				(font
					(size 1.016 1.016)
					(thickness 0.1524)
				)
			)
		)
		(property "Device Type" "TPAD32"
			(at -0.0508 -3.2004 0)
			(unlocked yes)
			(layer "F.Fab")
			(hide yes)
			(effects
				(font
					(size 1.016 1.016)
					(thickness 0.1524)
				)
			)
		)
		(duplicate_pad_numbers_are_jumpers no)
		(fp_poly
			(pts
				(arc
					(start 0.4064 0)
					(mid -0.4064 0)
					(end 0.4064 0)
				)
			)
			(stroke
				(width 0)
				(type default)
			)
			(fill no)
			(layer "F.CrtYd")
		)
		(fp_poly
			(pts
				(arc
					(start 0.7112 0)
					(mid -0.7112 0)
					(end 0.7112 0)
				)
			)
			(stroke
				(width 0)
				(type default)
			)
			(fill no)
			(layer "F.Fab")
		)
		(pad "1" smd circle
			(at 0 0)
			(size 0.8128 0.8128)
			(layers "F.Cu" "F.Mask" "F.Paste")
			(net "ACT_HDD_24")
		)
	)
	(footprint ""
		(layer "F.Cu")
		(at 223.421194 -349.439484 -90)
		(property "Reference" "R21"
			(at 0 0 270)
			(layer "F.SilkS")
			(hide yes)
			(effects
				(font
					(size 1.27 1.27)
				)
			)
		)
		(property "Value" "0R2J-2-GP"
			(at 0.064008 -3.993896 270)
			(unlocked yes)
			(layer "F.Fab")
			(hide yes)
			(effects
				(font
					(size 1.016 1.016)
					(thickness 0.1524)
				)
			)
		)
		(property "Device Type" "R402H16"
			(at 0.064008 -5.517896 270)
			(unlocked yes)
			(layer "F.Fab")
			(hide yes)
			(effects
				(font
					(size 1.016 1.016)
					(thickness 0.1524)
				)
			)
		)
		(duplicate_pad_numbers_are_jumpers no)
		(fp_line
			(start -0.508 -0.9398)
			(end -0.508 0.9398)
			(stroke
				(width 0.1524)
				(type default)
			)
			(layer "F.SilkS")
		)
		(fp_line
			(start 0.508 -0.9398)
			(end -0.508 -0.9398)
			(stroke
				(width 0.1524)
				(type default)
			)
			(layer "F.SilkS")
		)
		(fp_rect
			(start -0.508 0.9398)
			(end 0.508 -0.9398)
			(stroke
				(width 0)
				(type default)
			)
			(fill no)
			(layer "F.CrtYd")
		)
		(fp_rect
			(start -0.508 0.9398)
			(end 0.508 -0.9398)
			(stroke
				(width 0)
				(type default)
			)
			(fill no)
			(layer "F.Fab")
		)
		(pad "1" smd custom
			(at 0 -0.4445 270)
			(size 0.1397 0.1397)
			(layers "F.Cu" "F.Mask" "F.Paste")
			(net "VOL_SEN_SCL")
			(options
				(clearance outline)
				(anchor circle)
			)
			(primitives
				(gr_poly
					(pts
						(arc
							(start -0.1778 -0.2794)
							(mid -0.249642 -0.249642)
							(end -0.2794 -0.1778)
						)
						(arc
							(start -0.2794 0.1778)
							(mid -0.249642 0.249642)
							(end -0.1778 0.2794)
						)
						(arc
							(start 0.1778 0.2794)
							(mid 0.249642 0.249642)
							(end 0.2794 0.1778)
						)
						(arc
							(start 0.2794 -0.1778)
							(mid 0.249642 -0.249642)
							(end 0.1778 -0.2794)
						)
					)
					(width 0)
					(fill yes)
				)
			)
		)
		(pad "2" smd custom
			(at 0 0.4445 270)
			(size 0.1397 0.1397)
			(layers "F.Cu" "F.Mask" "F.Paste")
			(net "I2C_DPB_A_SCL_BUF")
			(options
				(clearance outline)
				(anchor circle)
			)
			(primitives
				(gr_poly
					(pts
						(arc
							(start -0.1778 -0.2794)
							(mid -0.249642 -0.249642)
							(end -0.2794 -0.1778)
						)
						(arc
							(start -0.2794 0.1778)
							(mid -0.249642 0.249642)
							(end -0.1778 0.2794)
						)
						(arc
							(start 0.1778 0.2794)
							(mid 0.249642 0.249642)
							(end 0.2794 0.1778)
						)
						(arc
							(start 0.2794 -0.1778)
							(mid 0.249642 -0.249642)
							(end 0.1778 -0.2794)
						)
					)
					(width 0)
					(fill yes)
				)
			)
		)
	)
	(footprint ""
		(layer "F.Cu")
		(at 394.56995 -164.062918 -90)
		(property "Reference" "R597"
			(at 0 0 270)
			(layer "F.SilkS")
			(hide yes)
			(effects
				(font
					(size 1.27 1.27)
				)
			)
		)
		(property "Value" "4K7R2J-2-GP"
			(at 0.064008 -3.993896 270)
			(unlocked yes)
			(layer "F.Fab")
			(hide yes)
			(effects
				(font
					(size 1.016 1.016)
					(thickness 0.1524)
				)
			)
		)
		(property "Device Type" "R402H16"
			(at 0.064008 -5.517896 270)
			(unlocked yes)
			(layer "F.Fab")
			(hide yes)
			(effects
				(font
					(size 1.016 1.016)
					(thickness 0.1524)
				)
			)
		)
		(duplicate_pad_numbers_are_jumpers no)
		(fp_line
			(start -0.508 -0.9398)
			(end -0.508 0.9398)
			(stroke
				(width 0.1524)
				(type default)
			)
			(layer "F.SilkS")
		)
		(fp_line
			(start 0.508 -0.9398)
			(end -0.508 -0.9398)
			(stroke
				(width 0.1524)
				(type default)
			)
			(layer "F.SilkS")
		)
		(fp_rect
			(start -0.508 0.9398)
			(end 0.508 -0.9398)
			(stroke
				(width 0)
				(type default)
			)
			(fill no)
			(layer "F.CrtYd")
		)
		(fp_rect
			(start -0.508 0.9398)
			(end 0.508 -0.9398)
			(stroke
				(width 0)
				(type default)
			)
			(fill no)
			(layer "F.Fab")
		)
		(pad "1" smd custom
			(at 0 -0.4445 270)
			(size 0.1397 0.1397)
			(layers "F.Cu" "F.Mask" "F.Paste")
			(net "P12V_A")
			(options
				(clearance outline)
				(anchor circle)
			)
			(primitives
				(gr_poly
					(pts
						(arc
							(start -0.1778 -0.2794)
							(mid -0.249642 -0.249642)
							(end -0.2794 -0.1778)
						)
						(arc
							(start -0.2794 0.1778)
							(mid -0.249642 0.249642)
							(end -0.1778 0.2794)
						)
						(arc
							(start 0.1778 0.2794)
							(mid 0.249642 0.249642)
							(end 0.2794 0.1778)
						)
						(arc
							(start 0.2794 -0.1778)
							(mid 0.249642 -0.249642)
							(end 0.1778 -0.2794)
						)
					)
					(width 0)
					(fill yes)
				)
			)
		)
		(pad "2" smd custom
			(at 0 0.4445 270)
			(size 0.1397 0.1397)
			(layers "F.Cu" "F.Mask" "F.Paste")
			(net "SW_HDD_P20")
			(options
				(clearance outline)
				(anchor circle)
			)
			(primitives
				(gr_poly
					(pts
						(arc
							(start -0.1778 -0.2794)
							(mid -0.249642 -0.249642)
							(end -0.2794 -0.1778)
						)
						(arc
							(start -0.2794 0.1778)
							(mid -0.249642 0.249642)
							(end -0.1778 0.2794)
						)
						(arc
							(start 0.1778 0.2794)
							(mid 0.249642 0.249642)
							(end 0.2794 0.1778)
						)
						(arc
							(start 0.2794 -0.1778)
							(mid 0.249642 -0.249642)
							(end 0.1778 -0.2794)
						)
					)
					(width 0)
					(fill yes)
				)
			)
		)
	)
	(footprint ""
		(layer "F.Cu")
		(at 394.56995 -188.954918 180)
		(property "Reference" "C305"
			(at 0 0 180)
			(layer "F.SilkS")
			(hide yes)
			(effects
				(font
					(size 1.27 1.27)
				)
			)
		)
		(property "Value" "SC4D7U25V5KX-1-GP"
			(at -0.0762 -6.1214 180)
			(unlocked yes)
			(layer "F.Fab")
			(hide yes)
			(effects
				(font
					(size 1.016 1.016)
					(thickness 0.1524)
				)
			)
		)
		(property "Device Type" "C805H58"
			(at -0.0762 -8.1534 180)
			(unlocked yes)
			(layer "F.Fab")
			(hide yes)
			(effects
				(font
					(size 1.016 1.016)
					(thickness 0.1524)
				)
			)
		)
		(duplicate_pad_numbers_are_jumpers no)
		(fp_line
			(start 0.635 0)
			(end -0.635 0)
			(stroke
				(width 0.508)
				(type default)
			)
			(layer "F.SilkS")
		)
		(fp_rect
			(start -0.9652 1.778)
			(end 0.9652 -1.778)
			(stroke
				(width 0)
				(type default)
			)
			(fill no)
			(layer "F.CrtYd")
		)
		(fp_poly
			(pts
				(xy -0.9652 -1.778) (xy 0.9652 -1.778) (xy 0.9652 1.778) (xy -0.9652 1.778)
			)
			(stroke
				(width 0)
				(type default)
			)
			(fill no)
			(layer "F.Fab")
		)
		(pad "1" smd rect
			(at 0 -0.9652 180)
			(size 1.397 1.143)
			(layers "F.Cu" "F.Mask" "F.Paste")
			(net "P12V_HDD20")
		)
		(pad "2" smd rect
			(at 0 0.9652 180)
			(size 1.397 1.143)
			(layers "F.Cu" "F.Mask" "F.Paste")
			(net "GND")
		)
	)
	(footprint ""
		(layer "F.Cu")
		(at 365.052102 -73.954894 180)
		(property "Reference" "C448"
			(at 0 0 180)
			(layer "F.SilkS")
			(hide yes)
			(effects
				(font
					(size 1.27 1.27)
				)
			)
		)
		(property "Value" "SC4D7U25V5KX-1-GP"
			(at -0.0762 -6.1214 180)
			(unlocked yes)
			(layer "F.Fab")
			(hide yes)
			(effects
				(font
					(size 1.016 1.016)
					(thickness 0.1524)
				)
			)
		)
		(property "Device Type" "C805H58"
			(at -0.0762 -8.1534 180)
			(unlocked yes)
			(layer "F.Fab")
			(hide yes)
			(effects
				(font
					(size 1.016 1.016)
					(thickness 0.1524)
				)
			)
		)
		(duplicate_pad_numbers_are_jumpers no)
		(fp_line
			(start 0.635 0)
			(end -0.635 0)
			(stroke
				(width 0.508)
				(type default)
			)
			(layer "F.SilkS")
		)
		(fp_rect
			(start -0.9652 1.778)
			(end 0.9652 -1.778)
			(stroke
				(width 0)
				(type default)
			)
			(fill no)
			(layer "F.CrtYd")
		)
		(fp_poly
			(pts
				(xy -0.9652 -1.778) (xy 0.9652 -1.778) (xy 0.9652 1.778) (xy -0.9652 1.778)
			)
			(stroke
				(width 0)
				(type default)
			)
			(fill no)
			(layer "F.Fab")
		)
		(pad "1" smd rect
			(at 0 -0.9652 180)
			(size 1.397 1.143)
			(layers "F.Cu" "F.Mask" "F.Paste")
			(net "P12V_HDD31")
		)
		(pad "2" smd rect
			(at 0 0.9652 180)
			(size 1.397 1.143)
			(layers "F.Cu" "F.Mask" "F.Paste")
			(net "GND")
		)
	)
	(footprint ""
		(layer "F.Cu")
		(at 46.265846 -179.683918 -90)
		(property "Reference" "C213"
			(at 0 0 270)
			(layer "F.SilkS")
			(hide yes)
			(effects
				(font
					(size 1.27 1.27)
				)
			)
		)
		(property "Value" "SC4D7U25V5KX-1-GP"
			(at -0.0762 -6.1214 270)
			(unlocked yes)
			(layer "F.Fab")
			(hide yes)
			(effects
				(font
					(size 1.016 1.016)
					(thickness 0.1524)
				)
			)
		)
		(property "Device Type" "C805H58"
			(at -0.0762 -8.1534 270)
			(unlocked yes)
			(layer "F.Fab")
			(hide yes)
			(effects
				(font
					(size 1.016 1.016)
					(thickness 0.1524)
				)
			)
		)
		(duplicate_pad_numbers_are_jumpers no)
		(fp_line
			(start 0.635 0)
			(end -0.635 0)
			(stroke
				(width 0.508)
				(type default)
			)
			(layer "F.SilkS")
		)
		(fp_rect
			(start -0.9652 1.778)
			(end 0.9652 -1.778)
			(stroke
				(width 0)
				(type default)
			)
			(fill no)
			(layer "F.CrtYd")
		)
		(fp_poly
			(pts
				(xy -0.9652 -1.778) (xy 0.9652 -1.778) (xy 0.9652 1.778) (xy -0.9652 1.778)
			)
			(stroke
				(width 0)
				(type default)
			)
			(fill no)
			(layer "F.Fab")
		)
		(pad "1" smd rect
			(at 0 -0.9652 270)
			(size 1.397 1.143)
			(layers "F.Cu" "F.Mask" "F.Paste")
			(net "P12V_HDD13")
		)
		(pad "2" smd rect
			(at 0 0.9652 270)
			(size 1.397 1.143)
			(layers "F.Cu" "F.Mask" "F.Paste")
			(net "GND")
		)
	)
	(footprint ""
		(layer "F.Cu")
		(at 343.038684 -245.28907 -90)
		(property "Reference" "R481"
			(at 0 0 270)
			(layer "F.SilkS")
			(hide yes)
			(effects
				(font
					(size 1.27 1.27)
				)
			)
		)
		(property "Value" "4K7R2J-2-GP"
			(at 0.064008 -3.993896 270)
			(unlocked yes)
			(layer "F.Fab")
			(hide yes)
			(effects
				(font
					(size 1.016 1.016)
					(thickness 0.1524)
				)
			)
		)
		(property "Device Type" "R402H16"
			(at 0.064008 -5.517896 270)
			(unlocked yes)
			(layer "F.Fab")
			(hide yes)
			(effects
				(font
					(size 1.016 1.016)
					(thickness 0.1524)
				)
			)
		)
		(duplicate_pad_numbers_are_jumpers no)
		(fp_line
			(start -0.508 -0.9398)
			(end -0.508 0.9398)
			(stroke
				(width 0.1524)
				(type default)
			)
			(layer "F.SilkS")
		)
		(fp_line
			(start 0.508 -0.9398)
			(end -0.508 -0.9398)
			(stroke
				(width 0.1524)
				(type default)
			)
			(layer "F.SilkS")
		)
		(fp_rect
			(start -0.508 0.9398)
			(end 0.508 -0.9398)
			(stroke
				(width 0)
				(type default)
			)
			(fill no)
			(layer "F.CrtYd")
		)
		(fp_rect
			(start -0.508 0.9398)
			(end 0.508 -0.9398)
			(stroke
				(width 0)
				(type default)
			)
			(fill no)
			(layer "F.Fab")
		)
		(pad "1" smd custom
			(at 0 -0.4445 270)
			(size 0.1397 0.1397)
			(layers "F.Cu" "F.Mask" "F.Paste")
			(net "DRIVE_A_7_FLT_LED")
			(options
				(clearance outline)
				(anchor circle)
			)
			(primitives
				(gr_poly
					(pts
						(arc
							(start -0.1778 -0.2794)
							(mid -0.249642 -0.249642)
							(end -0.2794 -0.1778)
						)
						(arc
							(start -0.2794 0.1778)
							(mid -0.249642 0.249642)
							(end -0.1778 0.2794)
						)
						(arc
							(start 0.1778 0.2794)
							(mid 0.249642 0.249642)
							(end 0.2794 0.1778)
						)
						(arc
							(start 0.2794 -0.1778)
							(mid 0.249642 -0.249642)
							(end 0.1778 -0.2794)
						)
					)
					(width 0)
					(fill yes)
				)
			)
		)
		(pad "2" smd custom
			(at 0 0.4445 270)
			(size 0.1397 0.1397)
			(layers "F.Cu" "F.Mask" "F.Paste")
			(net "GND")
			(options
				(clearance outline)
				(anchor circle)
			)
			(primitives
				(gr_poly
					(pts
						(arc
							(start -0.1778 -0.2794)
							(mid -0.249642 -0.249642)
							(end -0.2794 -0.1778)
						)
						(arc
							(start -0.2794 0.1778)
							(mid -0.249642 0.249642)
							(end -0.1778 0.2794)
						)
						(arc
							(start 0.1778 0.2794)
							(mid 0.249642 0.249642)
							(end 0.2794 0.1778)
						)
						(arc
							(start 0.2794 -0.1778)
							(mid 0.249642 -0.249642)
							(end 0.1778 -0.2794)
						)
					)
					(width 0)
					(fill yes)
				)
			)
		)
	)
	(footprint ""
		(layer "F.Cu")
		(at 47.866046 -285.412942 90)
		(property "Reference" "C62"
			(at 0 0 90)
			(layer "F.SilkS")
			(hide yes)
			(effects
				(font
					(size 1.27 1.27)
				)
			)
		)
		(property "Value" "SCD033U25V2KX-GP"
			(at 1.1811 -2.7051 90)
			(unlocked yes)
			(layer "F.Fab")
			(hide yes)
			(effects
				(font
					(size 1.016 1.016)
					(thickness 0.1524)
				)
			)
		)
		(property "Device Type" "C402H22"
			(at 1.1811 -4.2291 90)
			(unlocked yes)
			(layer "F.Fab")
			(hide yes)
			(effects
				(font
					(size 1.016 1.016)
					(thickness 0.1524)
				)
			)
		)
		(duplicate_pad_numbers_are_jumpers no)
		(fp_rect
			(start -0.4318 0.9525)
			(end 0.4318 -0.9525)
			(stroke
				(width 0)
				(type default)
			)
			(fill no)
			(layer "F.CrtYd")
		)
		(fp_rect
			(start -0.4318 0.9525)
			(end 0.4318 -0.9525)
			(stroke
				(width 0)
				(type default)
			)
			(fill no)
			(layer "F.Fab")
		)
		(pad "1" smd custom
			(at 0 -0.4445 90)
			(size 0.1524 0.1524)
			(layers "F.Cu" "F.Mask" "F.Paste")
			(net "P12V_A")
			(options
				(clearance outline)
				(anchor circle)
			)
			(primitives
				(gr_poly
					(pts
						(arc
							(start 0.3048 -0.2032)
							(mid 0.275042 -0.275042)
							(end 0.2032 -0.3048)
						)
						(arc
							(start -0.2032 -0.3048)
							(mid -0.275042 -0.275042)
							(end -0.3048 -0.2032)
						)
						(arc
							(start -0.3048 0.2032)
							(mid -0.275042 0.275042)
							(end -0.2032 0.3048)
						)
						(arc
							(start 0.2032 0.3048)
							(mid 0.275042 0.275042)
							(end 0.3048 0.2032)
						)
					)
					(width 0)
					(fill yes)
				)
			)
		)
		(pad "2" smd custom
			(at 0 0.4445 90)
			(size 0.1524 0.1524)
			(layers "F.Cu" "F.Mask" "F.Paste")
			(net "SW_HDD_N1")
			(options
				(clearance outline)
				(anchor circle)
			)
			(primitives
				(gr_poly
					(pts
						(arc
							(start 0.3048 -0.2032)
							(mid 0.275042 -0.275042)
							(end 0.2032 -0.3048)
						)
						(arc
							(start -0.2032 -0.3048)
							(mid -0.275042 -0.275042)
							(end -0.3048 -0.2032)
						)
						(arc
							(start -0.3048 0.2032)
							(mid -0.275042 0.275042)
							(end -0.2032 0.3048)
						)
						(arc
							(start 0.2032 0.3048)
							(mid 0.275042 0.275042)
							(end 0.3048 0.2032)
						)
					)
					(width 0)
					(fill yes)
				)
			)
		)
	)
	(footprint ""
		(layer "F.Cu")
		(at 470.021158 -293.887144)
		(property "Reference" "Q300"
			(at 0 0 0)
			(layer "F.SilkS")
			(hide yes)
			(effects
				(font
					(size 1.27 1.27)
				)
			)
		)
		(property "Value" "2N7002K-2-GP"
			(at 0.127 -8.9662 0)
			(unlocked yes)
			(layer "F.Fab")
			(hide yes)
			(effects
				(font
					(size 1.016 1.016)
					(thickness 0.1524)
				)
			)
		)
		(property "Device Type" "SOT23DGS2D4H44"
			(at 0.127 -10.4902 0)
			(unlocked yes)
			(layer "F.Fab")
			(hide yes)
			(effects
				(font
					(size 1.016 1.016)
					(thickness 0.1524)
				)
			)
		)
		(duplicate_pad_numbers_are_jumpers no)
		(fp_line
			(start -1.651 -1.778)
			(end -1.651 1.778)
			(stroke
				(width 0.1524)
				(type default)
			)
			(layer "F.SilkS")
		)
		(fp_line
			(start -1.651 1.778)
			(end 1.651 1.778)
			(stroke
				(width 0.1524)
				(type default)
			)
			(layer "F.SilkS")
		)
		(fp_line
			(start 1.651 -1.778)
			(end -1.651 -1.778)
			(stroke
				(width 0.1524)
				(type default)
			)
			(layer "F.SilkS")
		)
		(fp_line
			(start 1.651 1.778)
			(end 1.651 -1.778)
			(stroke
				(width 0.1524)
				(type default)
			)
			(layer "F.SilkS")
		)
		(fp_poly
			(pts
				(xy -1.778 1.8796) (xy -1.778 -1.8796) (xy 1.778 -1.8796) (xy 1.778 1.8796)
			)
			(stroke
				(width 0)
				(type default)
			)
			(fill no)
			(layer "F.CrtYd")
		)
		(fp_poly
			(pts
				(xy -1.778 1.8796) (xy -1.778 -1.8796) (xy 1.778 -1.8796) (xy 1.778 1.8796)
			)
			(stroke
				(width 0)
				(type default)
			)
			(fill no)
			(layer "F.Fab")
		)
		(pad "D" smd custom
			(at 0 -0.9525)
			(size 0.1905 0.1905)
			(layers "F.Cu" "F.Mask" "F.Paste")
			(net "FLT_HDD35_N")
			(options
				(clearance outline)
				(anchor circle)
			)
			(primitives
				(gr_poly
					(pts
						(arc
							(start -0.1778 0.5715)
							(mid -0.321484 0.511984)
							(end -0.381 0.3683)
						)
						(arc
							(start -0.381 -0.3683)
							(mid -0.321484 -0.511984)
							(end -0.1778 -0.5715)
						)
						(arc
							(start 0.1778 -0.5715)
							(mid 0.321484 -0.511984)
							(end 0.381 -0.3683)
						)
						(arc
							(start 0.381 0.3683)
							(mid 0.321484 0.511984)
							(end 0.1778 0.5715)
						)
					)
					(width 0)
					(fill yes)
				)
			)
		)
		(pad "G" smd custom
			(at -0.98425 0.9525)
			(size 0.1905 0.1905)
			(layers "F.Cu" "F.Mask" "F.Paste")
			(net "DRIVE_B_35_FLT_LED")
			(options
				(clearance outline)
				(anchor circle)
			)
			(primitives
				(gr_poly
					(pts
						(arc
							(start -0.1778 0.5715)
							(mid -0.321484 0.511984)
							(end -0.381 0.3683)
						)
						(arc
							(start -0.381 -0.3683)
							(mid -0.321484 -0.511984)
							(end -0.1778 -0.5715)
						)
						(arc
							(start 0.1778 -0.5715)
							(mid 0.321484 -0.511984)
							(end 0.381 -0.3683)
						)
						(arc
							(start 0.381 0.3683)
							(mid 0.321484 0.511984)
							(end 0.1778 0.5715)
						)
					)
					(width 0)
					(fill yes)
				)
			)
		)
		(pad "S" smd custom
			(at 0.98425 0.9525)
			(size 0.1905 0.1905)
			(layers "F.Cu" "F.Mask" "F.Paste")
			(net "GND")
			(options
				(clearance outline)
				(anchor circle)
			)
			(primitives
				(gr_poly
					(pts
						(arc
							(start -0.1778 0.5715)
							(mid -0.321484 0.511984)
							(end -0.381 0.3683)
						)
						(arc
							(start -0.381 -0.3683)
							(mid -0.321484 -0.511984)
							(end -0.1778 -0.5715)
						)
						(arc
							(start 0.1778 -0.5715)
							(mid 0.321484 -0.511984)
							(end 0.381 -0.3683)
						)
						(arc
							(start 0.381 0.3683)
							(mid 0.321484 0.511984)
							(end 0.1778 0.5715)
						)
					)
					(width 0)
					(fill yes)
				)
			)
		)
	)
	(footprint ""
		(layer "F.Cu")
		(at 177.8 -291.000942 -90)
		(property "Reference" "C106"
			(at 0 0 270)
			(layer "F.SilkS")
			(hide yes)
			(effects
				(font
					(size 1.27 1.27)
				)
			)
		)
		(property "Value" "SC10U16V6KX-2GP"
			(at -0.0762 -5.1308 270)
			(unlocked yes)
			(layer "F.Fab")
			(hide yes)
			(effects
				(font
					(size 1.016 1.016)
					(thickness 0.1524)
				)
			)
		)
		(property "Device Type" "C1206H71"
			(at -0.127 -6.6548 270)
			(unlocked yes)
			(layer "F.Fab")
			(hide yes)
			(effects
				(font
					(size 1.016 1.016)
					(thickness 0.1524)
				)
			)
		)
		(duplicate_pad_numbers_are_jumpers no)
		(fp_line
			(start -1.016 2.2352)
			(end -1.016 0.8382)
			(stroke
				(width 0.1524)
				(type default)
			)
			(layer "F.SilkS")
		)
		(fp_line
			(start 1.016 2.2352)
			(end -1.016 2.2352)
			(stroke
				(width 0.1524)
				(type default)
			)
			(layer "F.SilkS")
		)
		(fp_line
			(start 1.016 0.8382)
			(end 1.016 2.2352)
			(stroke
				(width 0.1524)
				(type default)
			)
			(layer "F.SilkS")
		)
		(fp_line
			(start -1.016 -0.8382)
			(end -1.016 -2.2352)
			(stroke
				(width 0.1524)
				(type default)
			)
			(layer "F.SilkS")
		)
		(fp_line
			(start -1.016 -2.2352)
			(end 1.016 -2.2352)
			(stroke
				(width 0.1524)
				(type default)
			)
			(layer "F.SilkS")
		)
		(fp_line
			(start 1.016 -2.2352)
			(end 1.016 -0.8382)
			(stroke
				(width 0.1524)
				(type default)
			)
			(layer "F.SilkS")
		)
		(fp_rect
			(start -1.0922 2.3114)
			(end 1.0922 -2.3114)
			(stroke
				(width 0)
				(type default)
			)
			(fill no)
			(layer "F.CrtYd")
		)
		(fp_poly
			(pts
				(xy 1.0922 -2.3114) (xy 1.0922 2.3114) (xy -1.0922 2.3114) (xy -1.0922 -2.3114)
			)
			(stroke
				(width 0)
				(type default)
			)
			(fill no)
			(layer "F.Fab")
		)
		(pad "1" smd rect
			(at 0 -1.397 270)
			(size 1.651 1.27)
			(layers "F.Cu" "F.Mask" "F.Paste")
			(net "P5V_HDD5")
		)
		(pad "2" smd rect
			(at 0 1.397 270)
			(size 1.651 1.27)
			(layers "F.Cu" "F.Mask" "F.Paste")
			(net "GND")
		)
	)
	(footprint ""
		(layer "F.Cu")
		(at 332.359 -65.826894 180)
		(property "Reference" "C431"
			(at 0 0 180)
			(layer "F.SilkS")
			(hide yes)
			(effects
				(font
					(size 1.27 1.27)
				)
			)
		)
		(property "Value" "SC10U16V6KX-2GP"
			(at -0.0762 -5.1308 180)
			(unlocked yes)
			(layer "F.Fab")
			(hide yes)
			(effects
				(font
					(size 1.016 1.016)
					(thickness 0.1524)
				)
			)
		)
		(property "Device Type" "C1206H71"
			(at -0.127 -6.6548 180)
			(unlocked yes)
			(layer "F.Fab")
			(hide yes)
			(effects
				(font
					(size 1.016 1.016)
					(thickness 0.1524)
				)
			)
		)
		(duplicate_pad_numbers_are_jumpers no)
		(fp_line
			(start 1.016 2.2352)
			(end -1.016 2.2352)
			(stroke
				(width 0.1524)
				(type default)
			)
			(layer "F.SilkS")
		)
		(fp_line
			(start 1.016 0.8382)
			(end 1.016 2.2352)
			(stroke
				(width 0.1524)
				(type default)
			)
			(layer "F.SilkS")
		)
		(fp_line
			(start 1.016 -2.2352)
			(end 1.016 -0.8382)
			(stroke
				(width 0.1524)
				(type default)
			)
			(layer "F.SilkS")
		)
		(fp_line
			(start -1.016 2.2352)
			(end -1.016 0.8382)
			(stroke
				(width 0.1524)
				(type default)
			)
			(layer "F.SilkS")
		)
		(fp_line
			(start -1.016 -0.8382)
			(end -1.016 -2.2352)
			(stroke
				(width 0.1524)
				(type default)
			)
			(layer "F.SilkS")
		)
		(fp_line
			(start -1.016 -2.2352)
			(end 1.016 -2.2352)
			(stroke
				(width 0.1524)
				(type default)
			)
			(layer "F.SilkS")
		)
		(fp_rect
			(start -1.0922 2.3114)
			(end 1.0922 -2.3114)
			(stroke
				(width 0)
				(type default)
			)
			(fill no)
			(layer "F.CrtYd")
		)
		(fp_poly
			(pts
				(xy 1.0922 -2.3114) (xy 1.0922 2.3114) (xy -1.0922 2.3114) (xy -1.0922 -2.3114)
			)
			(stroke
				(width 0)
				(type default)
			)
			(fill no)
			(layer "F.Fab")
		)
		(pad "1" smd rect
			(at 0 -1.397 180)
			(size 1.651 1.27)
			(layers "F.Cu" "F.Mask" "F.Paste")
			(net "P5V_HDD30")
		)
		(pad "2" smd rect
			(at 0 1.397 180)
			(size 1.651 1.27)
			(layers "F.Cu" "F.Mask" "F.Paste")
			(net "GND")
		)
	)
	(footprint ""
		(layer "F.Cu")
		(at 321.634612 -273.660616 -90)
		(property "Reference" "C117"
			(at 0 0 270)
			(layer "F.SilkS")
			(hide yes)
			(effects
				(font
					(size 1.27 1.27)
				)
			)
		)
		(property "Value" "SCD01U16V1KX-GP"
			(at -2.8321 -1.7399 270)
			(unlocked yes)
			(layer "F.Fab")
			(hide yes)
			(effects
				(font
					(size 1.016 1.016)
					(thickness 0.1524)
				)
			)
		)
		(property "Device Type" "C0201H13"
			(at -2.8321 -3.2639 270)
			(unlocked yes)
			(layer "F.Fab")
			(hide yes)
			(effects
				(font
					(size 1.016 1.016)
					(thickness 0.1524)
				)
			)
		)
		(duplicate_pad_numbers_are_jumpers no)
		(fp_rect
			(start -0.2794 0.6477)
			(end 0.2794 -0.6477)
			(stroke
				(width 0)
				(type default)
			)
			(fill no)
			(layer "F.CrtYd")
		)
		(fp_rect
			(start -0.2794 0.6477)
			(end 0.2794 -0.6477)
			(stroke
				(width 0)
				(type default)
			)
			(fill no)
			(layer "F.Fab")
		)
		(pad "1" smd custom
			(at 0 -0.2794 270)
			(size 0.0762 0.0762)
			(layers "F.Cu" "F.Mask" "F.Paste")
			(net "SAS_HDD_RX_P6")
			(options
				(clearance outline)
				(anchor circle)
			)
			(primitives
				(gr_poly
					(pts
						(arc
							(start 0.1524 -0.127)
							(mid 0.137521 -0.162921)
							(end 0.1016 -0.1778)
						)
						(arc
							(start -0.1016 -0.1778)
							(mid -0.137521 -0.162921)
							(end -0.1524 -0.127)
						)
						(arc
							(start -0.1524 0.127)
							(mid -0.137521 0.162921)
							(end -0.1016 0.1778)
						)
						(arc
							(start 0.1016 0.1778)
							(mid 0.137521 0.162921)
							(end 0.1524 0.127)
						)
					)
					(width 0)
					(fill yes)
				)
			)
		)
		(pad "2" smd custom
			(at 0 0.2794 270)
			(size 0.0762 0.0762)
			(layers "F.Cu" "F.Mask" "F.Paste")
			(net "PHY_SCC_A_TO_DRV_A_6_DP")
			(options
				(clearance outline)
				(anchor circle)
			)
			(primitives
				(gr_poly
					(pts
						(arc
							(start 0.1524 -0.127)
							(mid 0.137521 -0.162921)
							(end 0.1016 -0.1778)
						)
						(arc
							(start -0.1016 -0.1778)
							(mid -0.137521 -0.162921)
							(end -0.1524 -0.127)
						)
						(arc
							(start -0.1524 0.127)
							(mid -0.137521 0.162921)
							(end -0.1016 0.1778)
						)
						(arc
							(start 0.1016 0.1778)
							(mid 0.137521 0.162921)
							(end 0.1524 0.127)
						)
					)
					(width 0)
					(fill yes)
				)
			)
		)
	)
	(footprint ""
		(layer "F.Cu")
		(at 267.5128 -230.3018)
		(property "Reference" "R98"
			(at 0 0 0)
			(layer "F.SilkS")
			(hide yes)
			(effects
				(font
					(size 1.27 1.27)
				)
			)
		)
		(property "Value" "4K7R2F-GP"
			(at 0.064008 -3.993896 0)
			(unlocked yes)
			(layer "F.Fab")
			(hide yes)
			(effects
				(font
					(size 1.016 1.016)
					(thickness 0.1524)
				)
			)
		)
		(property "Device Type" "R402H16"
			(at 0.064008 -5.517896 0)
			(unlocked yes)
			(layer "F.Fab")
			(hide yes)
			(effects
				(font
					(size 1.016 1.016)
					(thickness 0.1524)
				)
			)
		)
		(duplicate_pad_numbers_are_jumpers no)
		(fp_line
			(start -0.508 -0.9398)
			(end -0.508 0.9398)
			(stroke
				(width 0.1524)
				(type default)
			)
			(layer "F.SilkS")
		)
		(fp_line
			(start 0.508 -0.9398)
			(end -0.508 -0.9398)
			(stroke
				(width 0.1524)
				(type default)
			)
			(layer "F.SilkS")
		)
		(fp_rect
			(start -0.508 0.9398)
			(end 0.508 -0.9398)
			(stroke
				(width 0)
				(type default)
			)
			(fill no)
			(layer "F.CrtYd")
		)
		(fp_rect
			(start -0.508 0.9398)
			(end 0.508 -0.9398)
			(stroke
				(width 0)
				(type default)
			)
			(fill no)
			(layer "F.Fab")
		)
		(pad "1" smd custom
			(at 0 -0.4445)
			(size 0.1397 0.1397)
			(layers "F.Cu" "F.Mask" "F.Paste")
			(net "IO_EXP3_A2")
			(options
				(clearance outline)
				(anchor circle)
			)
			(primitives
				(gr_poly
					(pts
						(arc
							(start -0.1778 -0.2794)
							(mid -0.249642 -0.249642)
							(end -0.2794 -0.1778)
						)
						(arc
							(start -0.2794 0.1778)
							(mid -0.249642 0.249642)
							(end -0.1778 0.2794)
						)
						(arc
							(start 0.1778 0.2794)
							(mid 0.249642 0.249642)
							(end 0.2794 0.1778)
						)
						(arc
							(start 0.2794 -0.1778)
							(mid 0.249642 -0.249642)
							(end 0.1778 -0.2794)
						)
					)
					(width 0)
					(fill yes)
				)
			)
		)
		(pad "2" smd custom
			(at 0 0.4445)
			(size 0.1397 0.1397)
			(layers "F.Cu" "F.Mask" "F.Paste")
			(net "GND")
			(options
				(clearance outline)
				(anchor circle)
			)
			(primitives
				(gr_poly
					(pts
						(arc
							(start -0.1778 -0.2794)
							(mid -0.249642 -0.249642)
							(end -0.2794 -0.1778)
						)
						(arc
							(start -0.2794 0.1778)
							(mid -0.249642 0.249642)
							(end -0.1778 0.2794)
						)
						(arc
							(start 0.1778 0.2794)
							(mid 0.249642 0.249642)
							(end 0.2794 0.1778)
						)
						(arc
							(start 0.2794 -0.1778)
							(mid 0.249642 -0.249642)
							(end 0.1778 -0.2794)
						)
					)
					(width 0)
					(fill yes)
				)
			)
		)
	)
	(footprint ""
		(layer "F.Cu")
		(at 146.249898 -176.000918 -90)
		(property "Reference" "C249"
			(at 0 0 270)
			(layer "F.SilkS")
			(hide yes)
			(effects
				(font
					(size 1.27 1.27)
				)
			)
		)
		(property "Value" "SC10U16V6KX-2GP"
			(at -0.0762 -5.1308 270)
			(unlocked yes)
			(layer "F.Fab")
			(hide yes)
			(effects
				(font
					(size 1.016 1.016)
					(thickness 0.1524)
				)
			)
		)
		(property "Device Type" "C1206H71"
			(at -0.127 -6.6548 270)
			(unlocked yes)
			(layer "F.Fab")
			(hide yes)
			(effects
				(font
					(size 1.016 1.016)
					(thickness 0.1524)
				)
			)
		)
		(duplicate_pad_numbers_are_jumpers no)
		(fp_line
			(start -1.016 2.2352)
			(end -1.016 0.8382)
			(stroke
				(width 0.1524)
				(type default)
			)
			(layer "F.SilkS")
		)
		(fp_line
			(start 1.016 2.2352)
			(end -1.016 2.2352)
			(stroke
				(width 0.1524)
				(type default)
			)
			(layer "F.SilkS")
		)
		(fp_line
			(start 1.016 0.8382)
			(end 1.016 2.2352)
			(stroke
				(width 0.1524)
				(type default)
			)
			(layer "F.SilkS")
		)
		(fp_line
			(start -1.016 -0.8382)
			(end -1.016 -2.2352)
			(stroke
				(width 0.1524)
				(type default)
			)
			(layer "F.SilkS")
		)
		(fp_line
			(start -1.016 -2.2352)
			(end 1.016 -2.2352)
			(stroke
				(width 0.1524)
				(type default)
			)
			(layer "F.SilkS")
		)
		(fp_line
			(start 1.016 -2.2352)
			(end 1.016 -0.8382)
			(stroke
				(width 0.1524)
				(type default)
			)
			(layer "F.SilkS")
		)
		(fp_rect
			(start -1.0922 2.3114)
			(end 1.0922 -2.3114)
			(stroke
				(width 0)
				(type default)
			)
			(fill no)
			(layer "F.CrtYd")
		)
		(fp_poly
			(pts
				(xy 1.0922 -2.3114) (xy 1.0922 2.3114) (xy -1.0922 2.3114) (xy -1.0922 -2.3114)
			)
			(stroke
				(width 0)
				(type default)
			)
			(fill no)
			(layer "F.Fab")
		)
		(pad "1" smd rect
			(at 0 -1.397 270)
			(size 1.651 1.27)
			(layers "F.Cu" "F.Mask" "F.Paste")
			(net "P5V_HDD16")
		)
		(pad "2" smd rect
			(at 0 1.397 270)
			(size 1.651 1.27)
			(layers "F.Cu" "F.Mask" "F.Paste")
			(net "GND")
		)
	)
	(footprint ""
		(layer "F.Cu")
		(at 15.223998 -162.157918 180)
		(property "Reference" "R422"
			(at 0 0 180)
			(layer "F.SilkS")
			(hide yes)
			(effects
				(font
					(size 1.27 1.27)
				)
			)
		)
		(property "Value" "200KR2F-L-GP"
			(at 0.064008 -3.993896 180)
			(unlocked yes)
			(layer "F.Fab")
			(hide yes)
			(effects
				(font
					(size 1.016 1.016)
					(thickness 0.1524)
				)
			)
		)
		(property "Device Type" "R402H16"
			(at 0.064008 -5.517896 180)
			(unlocked yes)
			(layer "F.Fab")
			(hide yes)
			(effects
				(font
					(size 1.016 1.016)
					(thickness 0.1524)
				)
			)
		)
		(duplicate_pad_numbers_are_jumpers no)
		(fp_line
			(start 0.508 -0.9398)
			(end -0.508 -0.9398)
			(stroke
				(width 0.1524)
				(type default)
			)
			(layer "F.SilkS")
		)
		(fp_line
			(start -0.508 -0.9398)
			(end -0.508 0.9398)
			(stroke
				(width 0.1524)
				(type default)
			)
			(layer "F.SilkS")
		)
		(fp_rect
			(start -0.508 0.9398)
			(end 0.508 -0.9398)
			(stroke
				(width 0)
				(type default)
			)
			(fill no)
			(layer "F.CrtYd")
		)
		(fp_rect
			(start -0.508 0.9398)
			(end 0.508 -0.9398)
			(stroke
				(width 0)
				(type default)
			)
			(fill no)
			(layer "F.Fab")
		)
		(pad "1" smd custom
			(at 0 -0.4445 180)
			(size 0.1397 0.1397)
			(layers "F.Cu" "F.Mask" "F.Paste")
			(net "SW_HDD_R12")
			(options
				(clearance outline)
				(anchor circle)
			)
			(primitives
				(gr_poly
					(pts
						(arc
							(start -0.1778 -0.2794)
							(mid -0.249642 -0.249642)
							(end -0.2794 -0.1778)
						)
						(arc
							(start -0.2794 0.1778)
							(mid -0.249642 0.249642)
							(end -0.1778 0.2794)
						)
						(arc
							(start 0.1778 0.2794)
							(mid 0.249642 0.249642)
							(end 0.2794 0.1778)
						)
						(arc
							(start 0.2794 -0.1778)
							(mid 0.249642 -0.249642)
							(end 0.1778 -0.2794)
						)
					)
					(width 0)
					(fill yes)
				)
			)
		)
		(pad "2" smd custom
			(at 0 0.4445 180)
			(size 0.1397 0.1397)
			(layers "F.Cu" "F.Mask" "F.Paste")
			(net "SW_HDD_N12")
			(options
				(clearance outline)
				(anchor circle)
			)
			(primitives
				(gr_poly
					(pts
						(arc
							(start -0.1778 -0.2794)
							(mid -0.249642 -0.249642)
							(end -0.2794 -0.1778)
						)
						(arc
							(start -0.2794 0.1778)
							(mid -0.249642 0.249642)
							(end -0.1778 0.2794)
						)
						(arc
							(start 0.1778 0.2794)
							(mid 0.249642 0.249642)
							(end 0.2794 0.1778)
						)
						(arc
							(start 0.2794 -0.1778)
							(mid 0.249642 -0.249642)
							(end 0.1778 -0.2794)
						)
					)
					(width 0)
					(fill yes)
				)
			)
		)
	)
	(footprint ""
		(layer "F.Cu")
		(at 433.359052 -171.809918 -90)
		(property "Reference" "R628"
			(at 0 0 270)
			(layer "F.SilkS")
			(hide yes)
			(effects
				(font
					(size 1.27 1.27)
				)
			)
		)
		(property "Value" "300KR2F-GP"
			(at 0.064008 -3.993896 270)
			(unlocked yes)
			(layer "F.Fab")
			(hide yes)
			(effects
				(font
					(size 1.016 1.016)
					(thickness 0.1524)
				)
			)
		)
		(property "Device Type" "R402H16"
			(at 0.064008 -5.517896 270)
			(unlocked yes)
			(layer "F.Fab")
			(hide yes)
			(effects
				(font
					(size 1.016 1.016)
					(thickness 0.1524)
				)
			)
		)
		(duplicate_pad_numbers_are_jumpers no)
		(fp_line
			(start -0.508 -0.9398)
			(end -0.508 0.9398)
			(stroke
				(width 0.1524)
				(type default)
			)
			(layer "F.SilkS")
		)
		(fp_line
			(start 0.508 -0.9398)
			(end -0.508 -0.9398)
			(stroke
				(width 0.1524)
				(type default)
			)
			(layer "F.SilkS")
		)
		(fp_rect
			(start -0.508 0.9398)
			(end 0.508 -0.9398)
			(stroke
				(width 0)
				(type default)
			)
			(fill no)
			(layer "F.CrtYd")
		)
		(fp_rect
			(start -0.508 0.9398)
			(end 0.508 -0.9398)
			(stroke
				(width 0)
				(type default)
			)
			(fill no)
			(layer "F.Fab")
		)
		(pad "1" smd custom
			(at 0 -0.4445 270)
			(size 0.1397 0.1397)
			(layers "F.Cu" "F.Mask" "F.Paste")
			(net "SW_HDD_N21")
			(options
				(clearance outline)
				(anchor circle)
			)
			(primitives
				(gr_poly
					(pts
						(arc
							(start -0.1778 -0.2794)
							(mid -0.249642 -0.249642)
							(end -0.2794 -0.1778)
						)
						(arc
							(start -0.2794 0.1778)
							(mid -0.249642 0.249642)
							(end -0.1778 0.2794)
						)
						(arc
							(start 0.1778 0.2794)
							(mid 0.249642 0.249642)
							(end 0.2794 0.1778)
						)
						(arc
							(start 0.2794 -0.1778)
							(mid 0.249642 -0.249642)
							(end 0.1778 -0.2794)
						)
					)
					(width 0)
					(fill yes)
				)
			)
		)
		(pad "2" smd custom
			(at 0 0.4445 270)
			(size 0.1397 0.1397)
			(layers "F.Cu" "F.Mask" "F.Paste")
			(net "P12V_A")
			(options
				(clearance outline)
				(anchor circle)
			)
			(primitives
				(gr_poly
					(pts
						(arc
							(start -0.1778 -0.2794)
							(mid -0.249642 -0.249642)
							(end -0.2794 -0.1778)
						)
						(arc
							(start -0.2794 0.1778)
							(mid -0.249642 0.249642)
							(end -0.1778 0.2794)
						)
						(arc
							(start 0.1778 0.2794)
							(mid 0.249642 0.249642)
							(end 0.2794 0.1778)
						)
						(arc
							(start 0.2794 -0.1778)
							(mid 0.249642 -0.249642)
							(end 0.1778 -0.2794)
						)
					)
					(width 0)
					(fill yes)
				)
			)
		)
	)
	(footprint ""
		(layer "F.Cu")
		(at 427.898052 -42.585894 180)
		(property "Reference" "R897"
			(at 0 0 180)
			(layer "F.SilkS")
			(hide yes)
			(effects
				(font
					(size 1.27 1.27)
				)
			)
		)
		(property "Value" "1KR2F-3-GP"
			(at 0.064008 -3.993896 180)
			(unlocked yes)
			(layer "F.Fab")
			(hide yes)
			(effects
				(font
					(size 1.016 1.016)
					(thickness 0.1524)
				)
			)
		)
		(property "Device Type" "R402H16"
			(at 0.064008 -5.517896 180)
			(unlocked yes)
			(layer "F.Fab")
			(hide yes)
			(effects
				(font
					(size 1.016 1.016)
					(thickness 0.1524)
				)
			)
		)
		(duplicate_pad_numbers_are_jumpers no)
		(fp_line
			(start 0.508 -0.9398)
			(end -0.508 -0.9398)
			(stroke
				(width 0.1524)
				(type default)
			)
			(layer "F.SilkS")
		)
		(fp_line
			(start -0.508 -0.9398)
			(end -0.508 0.9398)
			(stroke
				(width 0.1524)
				(type default)
			)
			(layer "F.SilkS")
		)
		(fp_rect
			(start -0.508 0.9398)
			(end 0.508 -0.9398)
			(stroke
				(width 0)
				(type default)
			)
			(fill no)
			(layer "F.CrtYd")
		)
		(fp_rect
			(start -0.508 0.9398)
			(end 0.508 -0.9398)
			(stroke
				(width 0)
				(type default)
			)
			(fill no)
			(layer "F.Fab")
		)
		(pad "1" smd custom
			(at 0 -0.4445 180)
			(size 0.1397 0.1397)
			(layers "F.Cu" "F.Mask" "F.Paste")
			(net "P3V3_STBY_A")
			(options
				(clearance outline)
				(anchor circle)
			)
			(primitives
				(gr_poly
					(pts
						(arc
							(start -0.1778 -0.2794)
							(mid -0.249642 -0.249642)
							(end -0.2794 -0.1778)
						)
						(arc
							(start -0.2794 0.1778)
							(mid -0.249642 0.249642)
							(end -0.1778 0.2794)
						)
						(arc
							(start 0.1778 0.2794)
							(mid 0.249642 0.249642)
							(end 0.2794 0.1778)
						)
						(arc
							(start 0.2794 -0.1778)
							(mid 0.249642 -0.249642)
							(end 0.1778 -0.2794)
						)
					)
					(width 0)
					(fill yes)
				)
			)
		)
		(pad "2" smd custom
			(at 0 0.4445 180)
			(size 0.1397 0.1397)
			(layers "F.Cu" "F.Mask" "F.Paste")
			(net "SW_PWR_R_HDD33")
			(options
				(clearance outline)
				(anchor circle)
			)
			(primitives
				(gr_poly
					(pts
						(arc
							(start -0.1778 -0.2794)
							(mid -0.249642 -0.249642)
							(end -0.2794 -0.1778)
						)
						(arc
							(start -0.2794 0.1778)
							(mid -0.249642 0.249642)
							(end -0.1778 0.2794)
						)
						(arc
							(start 0.1778 0.2794)
							(mid 0.249642 0.249642)
							(end 0.2794 0.1778)
						)
						(arc
							(start 0.2794 -0.1778)
							(mid 0.249642 -0.249642)
							(end 0.1778 -0.2794)
						)
					)
					(width 0)
					(fill yes)
				)
			)
		)
	)
	(footprint ""
		(layer "F.Cu")
		(at 366.6998 -132.7404)
		(property "Reference" "C563"
			(at 0 0 0)
			(layer "F.SilkS")
			(hide yes)
			(effects
				(font
					(size 1.27 1.27)
				)
			)
		)
		(property "Value" "SC1U16V3KX-5GP"
			(at 0 -2.8194 0)
			(unlocked yes)
			(layer "F.Fab")
			(hide yes)
			(effects
				(font
					(size 1.016 1.016)
					(thickness 0.1524)
				)
			)
		)
		(property "Device Type" "C603H36"
			(at 0 -4.3434 0)
			(unlocked yes)
			(layer "F.Fab")
			(hide yes)
			(effects
				(font
					(size 1.016 1.016)
					(thickness 0.1524)
				)
			)
		)
		(duplicate_pad_numbers_are_jumpers no)
		(fp_line
			(start 0.508 0)
			(end -0.508 0)
			(stroke
				(width 0.2032)
				(type default)
			)
			(layer "F.SilkS")
		)
		(fp_rect
			(start -0.5842 1.3335)
			(end 0.5842 -1.3335)
			(stroke
				(width 0)
				(type default)
			)
			(fill no)
			(layer "F.CrtYd")
		)
		(fp_rect
			(start -0.5842 1.3335)
			(end 0.5842 -1.3335)
			(stroke
				(width 0)
				(type default)
			)
			(fill no)
			(layer "F.Fab")
		)
		(pad "1" smd custom
			(at 0 -0.762)
			(size 0.2159 0.2159)
			(layers "F.Cu" "F.Mask" "F.Paste")
			(net "MB1_VCAP_R")
			(options
				(clearance outline)
				(anchor circle)
			)
			(primitives
				(gr_poly
					(pts
						(arc
							(start -0.3302 -0.4318)
							(mid -0.402042 -0.402042)
							(end -0.4318 -0.3302)
						)
						(arc
							(start -0.4318 0.3302)
							(mid -0.402042 0.402042)
							(end -0.3302 0.4318)
						)
						(arc
							(start 0.3302 0.4318)
							(mid 0.402042 0.402042)
							(end 0.4318 0.3302)
						)
						(arc
							(start 0.4318 -0.3302)
							(mid 0.402042 -0.402042)
							(end 0.3302 -0.4318)
						)
					)
					(width 0)
					(fill yes)
				)
			)
		)
		(pad "2" smd custom
			(at 0 0.762)
			(size 0.2159 0.2159)
			(layers "F.Cu" "F.Mask" "F.Paste")
			(net "AGND_CURRENT_MONOB")
			(options
				(clearance outline)
				(anchor circle)
			)
			(primitives
				(gr_poly
					(pts
						(arc
							(start -0.3302 -0.4318)
							(mid -0.402042 -0.402042)
							(end -0.4318 -0.3302)
						)
						(arc
							(start -0.4318 0.3302)
							(mid -0.402042 0.402042)
							(end -0.3302 0.4318)
						)
						(arc
							(start 0.3302 0.4318)
							(mid 0.402042 0.402042)
							(end 0.4318 0.3302)
						)
						(arc
							(start 0.4318 -0.3302)
							(mid 0.402042 -0.402042)
							(end 0.3302 -0.4318)
						)
					)
					(width 0)
					(fill yes)
				)
			)
		)
	)
	(footprint ""
		(layer "F.Cu")
		(at 431.581052 -275.735542 180)
		(property "Reference" "R351"
			(at 0 0 180)
			(layer "F.SilkS")
			(hide yes)
			(effects
				(font
					(size 1.27 1.27)
				)
			)
		)
		(property "Value" "4K7R2J-2-GP"
			(at 0.064008 -3.993896 180)
			(unlocked yes)
			(layer "F.Fab")
			(hide yes)
			(effects
				(font
					(size 1.016 1.016)
					(thickness 0.1524)
				)
			)
		)
		(property "Device Type" "R402H16"
			(at 0.064008 -5.517896 180)
			(unlocked yes)
			(layer "F.Fab")
			(hide yes)
			(effects
				(font
					(size 1.016 1.016)
					(thickness 0.1524)
				)
			)
		)
		(duplicate_pad_numbers_are_jumpers no)
		(fp_line
			(start 0.508 -0.9398)
			(end -0.508 -0.9398)
			(stroke
				(width 0.1524)
				(type default)
			)
			(layer "F.SilkS")
		)
		(fp_line
			(start -0.508 -0.9398)
			(end -0.508 0.9398)
			(stroke
				(width 0.1524)
				(type default)
			)
			(layer "F.SilkS")
		)
		(fp_rect
			(start -0.508 0.9398)
			(end 0.508 -0.9398)
			(stroke
				(width 0)
				(type default)
			)
			(fill no)
			(layer "F.CrtYd")
		)
		(fp_rect
			(start -0.508 0.9398)
			(end 0.508 -0.9398)
			(stroke
				(width 0)
				(type default)
			)
			(fill no)
			(layer "F.Fab")
		)
		(pad "1" smd custom
			(at 0 -0.4445 180)
			(size 0.1397 0.1397)
			(layers "F.Cu" "F.Mask" "F.Paste")
			(net "P12V_A")
			(options
				(clearance outline)
				(anchor circle)
			)
			(primitives
				(gr_poly
					(pts
						(arc
							(start -0.1778 -0.2794)
							(mid -0.249642 -0.249642)
							(end -0.2794 -0.1778)
						)
						(arc
							(start -0.2794 0.1778)
							(mid -0.249642 0.249642)
							(end -0.1778 0.2794)
						)
						(arc
							(start 0.1778 0.2794)
							(mid 0.249642 0.249642)
							(end 0.2794 0.1778)
						)
						(arc
							(start 0.2794 -0.1778)
							(mid 0.249642 -0.249642)
							(end 0.1778 -0.2794)
						)
					)
					(width 0)
					(fill yes)
				)
			)
		)
		(pad "2" smd custom
			(at 0 0.4445 180)
			(size 0.1397 0.1397)
			(layers "F.Cu" "F.Mask" "F.Paste")
			(net "SW_HDD_R9")
			(options
				(clearance outline)
				(anchor circle)
			)
			(primitives
				(gr_poly
					(pts
						(arc
							(start -0.1778 -0.2794)
							(mid -0.249642 -0.249642)
							(end -0.2794 -0.1778)
						)
						(arc
							(start -0.2794 0.1778)
							(mid -0.249642 0.249642)
							(end -0.1778 0.2794)
						)
						(arc
							(start 0.1778 0.2794)
							(mid 0.249642 0.249642)
							(end 0.2794 0.1778)
						)
						(arc
							(start 0.2794 -0.1778)
							(mid 0.249642 -0.249642)
							(end 0.1778 -0.2794)
						)
					)
					(width 0)
					(fill yes)
				)
			)
		)
	)
	(footprint ""
		(layer "F.Cu")
		(at 82.006948 -294.683942 90)
		(property "Reference" "R179"
			(at 0 0 90)
			(layer "F.SilkS")
			(hide yes)
			(effects
				(font
					(size 1.27 1.27)
				)
			)
		)
		(property "Value" "2R6F-GP"
			(at -0.0508 -4.8514 90)
			(unlocked yes)
			(layer "F.Fab")
			(hide yes)
			(effects
				(font
					(size 1.016 1.016)
					(thickness 0.1524)
				)
			)
		)
		(property "Device Type" "R1206H26"
			(at 0 -6.3754 90)
			(unlocked yes)
			(layer "F.Fab")
			(hide yes)
			(effects
				(font
					(size 1.016 1.016)
					(thickness 0.1524)
				)
			)
		)
		(duplicate_pad_numbers_are_jumpers no)
		(fp_line
			(start 1.016 -2.2352)
			(end 1.016 2.2352)
			(stroke
				(width 0.1524)
				(type default)
			)
			(layer "F.SilkS")
		)
		(fp_line
			(start -1.016 -2.2352)
			(end 1.016 -2.2352)
			(stroke
				(width 0.1524)
				(type default)
			)
			(layer "F.SilkS")
		)
		(fp_line
			(start 1.016 2.2352)
			(end -1.016 2.2352)
			(stroke
				(width 0.1524)
				(type default)
			)
			(layer "F.SilkS")
		)
		(fp_line
			(start -1.016 2.2352)
			(end -1.016 -2.2352)
			(stroke
				(width 0.1524)
				(type default)
			)
			(layer "F.SilkS")
		)
		(fp_rect
			(start -1.0922 2.3114)
			(end 1.0922 -2.3114)
			(stroke
				(width 0)
				(type default)
			)
			(fill no)
			(layer "F.CrtYd")
		)
		(fp_poly
			(pts
				(xy -1.0922 -2.3114) (xy 1.0922 -2.3114) (xy 1.0922 2.3114) (xy -1.0922 2.3114)
			)
			(stroke
				(width 0)
				(type default)
			)
			(fill no)
			(layer "F.Fab")
		)
		(pad "1" smd rect
			(at 0 -1.397 90)
			(size 1.651 1.27)
			(layers "F.Cu" "F.Mask" "F.Paste")
			(net "P12V_HDD2")
		)
		(pad "2" smd rect
			(at 0 1.397 90)
			(size 1.651 1.27)
			(layers "F.Cu" "F.Mask" "F.Paste")
			(net "12V_PRE_2")
		)
	)
	(footprint ""
		(layer "F.Cu")
		(at 260.8326 -284.4292 180)
		(property "Reference" "R105"
			(at 0 0 180)
			(layer "F.SilkS")
			(hide yes)
			(effects
				(font
					(size 1.27 1.27)
				)
			)
		)
		(property "Value" "0R2J-2-GP"
			(at 0.064008 -3.993896 180)
			(unlocked yes)
			(layer "F.Fab")
			(hide yes)
			(effects
				(font
					(size 1.016 1.016)
					(thickness 0.1524)
				)
			)
		)
		(property "Device Type" "R402H16"
			(at 0.064008 -5.517896 180)
			(unlocked yes)
			(layer "F.Fab")
			(hide yes)
			(effects
				(font
					(size 1.016 1.016)
					(thickness 0.1524)
				)
			)
		)
		(duplicate_pad_numbers_are_jumpers no)
		(fp_line
			(start 0.508 -0.9398)
			(end -0.508 -0.9398)
			(stroke
				(width 0.1524)
				(type default)
			)
			(layer "F.SilkS")
		)
		(fp_line
			(start -0.508 -0.9398)
			(end -0.508 0.9398)
			(stroke
				(width 0.1524)
				(type default)
			)
			(layer "F.SilkS")
		)
		(fp_rect
			(start -0.508 0.9398)
			(end 0.508 -0.9398)
			(stroke
				(width 0)
				(type default)
			)
			(fill no)
			(layer "F.CrtYd")
		)
		(fp_rect
			(start -0.508 0.9398)
			(end 0.508 -0.9398)
			(stroke
				(width 0)
				(type default)
			)
			(fill no)
			(layer "F.Fab")
		)
		(pad "1" smd custom
			(at 0 -0.4445 180)
			(size 0.1397 0.1397)
			(layers "F.Cu" "F.Mask" "F.Paste")
			(net "IO_EXP0_LED_SCL")
			(options
				(clearance outline)
				(anchor circle)
			)
			(primitives
				(gr_poly
					(pts
						(arc
							(start -0.1778 -0.2794)
							(mid -0.249642 -0.249642)
							(end -0.2794 -0.1778)
						)
						(arc
							(start -0.2794 0.1778)
							(mid -0.249642 0.249642)
							(end -0.1778 0.2794)
						)
						(arc
							(start 0.1778 0.2794)
							(mid 0.249642 0.249642)
							(end 0.2794 0.1778)
						)
						(arc
							(start 0.2794 -0.1778)
							(mid 0.249642 -0.249642)
							(end 0.1778 -0.2794)
						)
					)
					(width 0)
					(fill yes)
				)
			)
		)
		(pad "2" smd custom
			(at 0 0.4445 180)
			(size 0.1397 0.1397)
			(layers "F.Cu" "F.Mask" "F.Paste")
			(net "I2C_DRIVE_A_FLT_LED_SCL")
			(options
				(clearance outline)
				(anchor circle)
			)
			(primitives
				(gr_poly
					(pts
						(arc
							(start -0.1778 -0.2794)
							(mid -0.249642 -0.249642)
							(end -0.2794 -0.1778)
						)
						(arc
							(start -0.2794 0.1778)
							(mid -0.249642 0.249642)
							(end -0.1778 0.2794)
						)
						(arc
							(start 0.1778 0.2794)
							(mid 0.249642 0.249642)
							(end 0.2794 0.1778)
						)
						(arc
							(start 0.2794 -0.1778)
							(mid 0.249642 -0.249642)
							(end 0.1778 -0.2794)
						)
					)
					(width 0)
					(fill yes)
				)
			)
		)
	)
	(footprint ""
		(layer "F.Cu")
		(at 101.708458 -181.362858 90)
		(property "Reference" "R462"
			(at 0 0 90)
			(layer "F.SilkS")
			(hide yes)
			(effects
				(font
					(size 1.27 1.27)
				)
			)
		)
		(property "Value" "4K7R2J-2-GP"
			(at 0.064008 -3.993896 90)
			(unlocked yes)
			(layer "F.Fab")
			(hide yes)
			(effects
				(font
					(size 1.016 1.016)
					(thickness 0.1524)
				)
			)
		)
		(property "Device Type" "R402H16"
			(at 0.064008 -5.517896 90)
			(unlocked yes)
			(layer "F.Fab")
			(hide yes)
			(effects
				(font
					(size 1.016 1.016)
					(thickness 0.1524)
				)
			)
		)
		(duplicate_pad_numbers_are_jumpers no)
		(fp_line
			(start 0.508 -0.9398)
			(end -0.508 -0.9398)
			(stroke
				(width 0.1524)
				(type default)
			)
			(layer "F.SilkS")
		)
		(fp_line
			(start -0.508 -0.9398)
			(end -0.508 0.9398)
			(stroke
				(width 0.1524)
				(type default)
			)
			(layer "F.SilkS")
		)
		(fp_rect
			(start -0.508 0.9398)
			(end 0.508 -0.9398)
			(stroke
				(width 0)
				(type default)
			)
			(fill no)
			(layer "F.CrtYd")
		)
		(fp_rect
			(start -0.508 0.9398)
			(end 0.508 -0.9398)
			(stroke
				(width 0)
				(type default)
			)
			(fill no)
			(layer "F.Fab")
		)
		(pad "1" smd custom
			(at 0 -0.4445 90)
			(size 0.1397 0.1397)
			(layers "F.Cu" "F.Mask" "F.Paste")
			(net "DRIVE_A_3_ACT")
			(options
				(clearance outline)
				(anchor circle)
			)
			(primitives
				(gr_poly
					(pts
						(arc
							(start -0.1778 -0.2794)
							(mid -0.249642 -0.249642)
							(end -0.2794 -0.1778)
						)
						(arc
							(start -0.2794 0.1778)
							(mid -0.249642 0.249642)
							(end -0.1778 0.2794)
						)
						(arc
							(start 0.1778 0.2794)
							(mid 0.249642 0.249642)
							(end 0.2794 0.1778)
						)
						(arc
							(start 0.2794 -0.1778)
							(mid 0.249642 -0.249642)
							(end 0.1778 -0.2794)
						)
					)
					(width 0)
					(fill yes)
				)
			)
		)
		(pad "2" smd custom
			(at 0 0.4445 90)
			(size 0.1397 0.1397)
			(layers "F.Cu" "F.Mask" "F.Paste")
			(net "GND")
			(options
				(clearance outline)
				(anchor circle)
			)
			(primitives
				(gr_poly
					(pts
						(arc
							(start -0.1778 -0.2794)
							(mid -0.249642 -0.249642)
							(end -0.2794 -0.1778)
						)
						(arc
							(start -0.2794 0.1778)
							(mid -0.249642 0.249642)
							(end -0.1778 0.2794)
						)
						(arc
							(start 0.1778 0.2794)
							(mid 0.249642 0.249642)
							(end 0.2794 0.1778)
						)
						(arc
							(start 0.2794 -0.1778)
							(mid 0.249642 -0.249642)
							(end 0.1778 -0.2794)
						)
					)
					(width 0)
					(fill yes)
				)
			)
		)
	)
	(footprint ""
		(layer "F.Cu")
		(at 241.3762 -382.1938 180)
		(property "Reference" "R1152"
			(at 0 0 180)
			(layer "F.SilkS")
			(hide yes)
			(effects
				(font
					(size 1.27 1.27)
				)
			)
		)
		(property "Value" "100KR2F-L1-GP"
			(at 0.064008 -3.993896 180)
			(unlocked yes)
			(layer "F.Fab")
			(hide yes)
			(effects
				(font
					(size 1.016 1.016)
					(thickness 0.1524)
				)
			)
		)
		(property "Device Type" "R402H16"
			(at 0.064008 -5.517896 180)
			(unlocked yes)
			(layer "F.Fab")
			(hide yes)
			(effects
				(font
					(size 1.016 1.016)
					(thickness 0.1524)
				)
			)
		)
		(duplicate_pad_numbers_are_jumpers no)
		(fp_line
			(start 0.508 -0.9398)
			(end -0.508 -0.9398)
			(stroke
				(width 0.1524)
				(type default)
			)
			(layer "F.SilkS")
		)
		(fp_line
			(start -0.508 -0.9398)
			(end -0.508 0.9398)
			(stroke
				(width 0.1524)
				(type default)
			)
			(layer "F.SilkS")
		)
		(fp_rect
			(start -0.508 0.9398)
			(end 0.508 -0.9398)
			(stroke
				(width 0)
				(type default)
			)
			(fill no)
			(layer "F.CrtYd")
		)
		(fp_rect
			(start -0.508 0.9398)
			(end 0.508 -0.9398)
			(stroke
				(width 0)
				(type default)
			)
			(fill no)
			(layer "F.Fab")
		)
		(pad "1" smd custom
			(at 0 -0.4445 180)
			(size 0.1397 0.1397)
			(layers "F.Cu" "F.Mask" "F.Paste")
			(net "P12V_A")
			(options
				(clearance outline)
				(anchor circle)
			)
			(primitives
				(gr_poly
					(pts
						(arc
							(start -0.1778 -0.2794)
							(mid -0.249642 -0.249642)
							(end -0.2794 -0.1778)
						)
						(arc
							(start -0.2794 0.1778)
							(mid -0.249642 0.249642)
							(end -0.1778 0.2794)
						)
						(arc
							(start 0.1778 0.2794)
							(mid 0.249642 0.249642)
							(end 0.2794 0.1778)
						)
						(arc
							(start 0.2794 -0.1778)
							(mid 0.249642 -0.249642)
							(end 0.1778 -0.2794)
						)
					)
					(width 0)
					(fill yes)
				)
			)
		)
		(pad "2" smd custom
			(at 0 0.4445 180)
			(size 0.1397 0.1397)
			(layers "F.Cu" "F.Mask" "F.Paste")
			(net "MB3_P12V_PWGIN_R")
			(options
				(clearance outline)
				(anchor circle)
			)
			(primitives
				(gr_poly
					(pts
						(arc
							(start -0.1778 -0.2794)
							(mid -0.249642 -0.249642)
							(end -0.2794 -0.1778)
						)
						(arc
							(start -0.2794 0.1778)
							(mid -0.249642 0.249642)
							(end -0.1778 0.2794)
						)
						(arc
							(start 0.1778 0.2794)
							(mid 0.249642 0.249642)
							(end 0.2794 0.1778)
						)
						(arc
							(start 0.2794 -0.1778)
							(mid 0.249642 -0.249642)
							(end 0.1778 -0.2794)
						)
					)
					(width 0)
					(fill yes)
				)
			)
		)
	)
	(footprint ""
		(layer "F.Cu")
		(at 428.221902 -184.420002 -90)
		(property "Reference" "R614"
			(at 0 0 270)
			(layer "F.SilkS")
			(hide yes)
			(effects
				(font
					(size 1.27 1.27)
				)
			)
		)
		(property "Value" "2R6F-GP"
			(at -0.0508 -4.8514 270)
			(unlocked yes)
			(layer "F.Fab")
			(hide yes)
			(effects
				(font
					(size 1.016 1.016)
					(thickness 0.1524)
				)
			)
		)
		(property "Device Type" "R1206H26"
			(at 0 -6.3754 270)
			(unlocked yes)
			(layer "F.Fab")
			(hide yes)
			(effects
				(font
					(size 1.016 1.016)
					(thickness 0.1524)
				)
			)
		)
		(duplicate_pad_numbers_are_jumpers no)
		(fp_line
			(start -1.016 2.2352)
			(end -1.016 -2.2352)
			(stroke
				(width 0.1524)
				(type default)
			)
			(layer "F.SilkS")
		)
		(fp_line
			(start 1.016 2.2352)
			(end -1.016 2.2352)
			(stroke
				(width 0.1524)
				(type default)
			)
			(layer "F.SilkS")
		)
		(fp_line
			(start -1.016 -2.2352)
			(end 1.016 -2.2352)
			(stroke
				(width 0.1524)
				(type default)
			)
			(layer "F.SilkS")
		)
		(fp_line
			(start 1.016 -2.2352)
			(end 1.016 2.2352)
			(stroke
				(width 0.1524)
				(type default)
			)
			(layer "F.SilkS")
		)
		(fp_rect
			(start -1.0922 2.3114)
			(end 1.0922 -2.3114)
			(stroke
				(width 0)
				(type default)
			)
			(fill no)
			(layer "F.CrtYd")
		)
		(fp_poly
			(pts
				(xy -1.0922 -2.3114) (xy 1.0922 -2.3114) (xy 1.0922 2.3114) (xy -1.0922 2.3114)
			)
			(stroke
				(width 0)
				(type default)
			)
			(fill no)
			(layer "F.Fab")
		)
		(pad "1" smd rect
			(at 0 -1.397 270)
			(size 1.651 1.27)
			(layers "F.Cu" "F.Mask" "F.Paste")
			(net "P12V_HDD21")
		)
		(pad "2" smd rect
			(at 0 1.397 270)
			(size 1.651 1.27)
			(layers "F.Cu" "F.Mask" "F.Paste")
			(net "12V_PRE_21")
		)
	)
	(footprint ""
		(layer "F.Cu")
		(at 464.9089 -56.809894 -90)
		(property "Reference" "R925"
			(at 0 0 270)
			(layer "F.SilkS")
			(hide yes)
			(effects
				(font
					(size 1.27 1.27)
				)
			)
		)
		(property "Value" "300KR2F-GP"
			(at 0.064008 -3.993896 270)
			(unlocked yes)
			(layer "F.Fab")
			(hide yes)
			(effects
				(font
					(size 1.016 1.016)
					(thickness 0.1524)
				)
			)
		)
		(property "Device Type" "R402H16"
			(at 0.064008 -5.517896 270)
			(unlocked yes)
			(layer "F.Fab")
			(hide yes)
			(effects
				(font
					(size 1.016 1.016)
					(thickness 0.1524)
				)
			)
		)
		(duplicate_pad_numbers_are_jumpers no)
		(fp_line
			(start -0.508 -0.9398)
			(end -0.508 0.9398)
			(stroke
				(width 0.1524)
				(type default)
			)
			(layer "F.SilkS")
		)
		(fp_line
			(start 0.508 -0.9398)
			(end -0.508 -0.9398)
			(stroke
				(width 0.1524)
				(type default)
			)
			(layer "F.SilkS")
		)
		(fp_rect
			(start -0.508 0.9398)
			(end 0.508 -0.9398)
			(stroke
				(width 0)
				(type default)
			)
			(fill no)
			(layer "F.CrtYd")
		)
		(fp_rect
			(start -0.508 0.9398)
			(end 0.508 -0.9398)
			(stroke
				(width 0)
				(type default)
			)
			(fill no)
			(layer "F.Fab")
		)
		(pad "1" smd custom
			(at 0 -0.4445 270)
			(size 0.1397 0.1397)
			(layers "F.Cu" "F.Mask" "F.Paste")
			(net "SW_HDD_N34")
			(options
				(clearance outline)
				(anchor circle)
			)
			(primitives
				(gr_poly
					(pts
						(arc
							(start -0.1778 -0.2794)
							(mid -0.249642 -0.249642)
							(end -0.2794 -0.1778)
						)
						(arc
							(start -0.2794 0.1778)
							(mid -0.249642 0.249642)
							(end -0.1778 0.2794)
						)
						(arc
							(start 0.1778 0.2794)
							(mid 0.249642 0.249642)
							(end 0.2794 0.1778)
						)
						(arc
							(start 0.2794 -0.1778)
							(mid 0.249642 -0.249642)
							(end 0.1778 -0.2794)
						)
					)
					(width 0)
					(fill yes)
				)
			)
		)
		(pad "2" smd custom
			(at 0 0.4445 270)
			(size 0.1397 0.1397)
			(layers "F.Cu" "F.Mask" "F.Paste")
			(net "P12V_A")
			(options
				(clearance outline)
				(anchor circle)
			)
			(primitives
				(gr_poly
					(pts
						(arc
							(start -0.1778 -0.2794)
							(mid -0.249642 -0.249642)
							(end -0.2794 -0.1778)
						)
						(arc
							(start -0.2794 0.1778)
							(mid -0.249642 0.249642)
							(end -0.1778 0.2794)
						)
						(arc
							(start 0.1778 0.2794)
							(mid 0.249642 0.249642)
							(end 0.2794 0.1778)
						)
						(arc
							(start 0.2794 -0.1778)
							(mid 0.249642 -0.249642)
							(end 0.1778 -0.2794)
						)
					)
					(width 0)
					(fill yes)
				)
			)
		)
	)
	(footprint ""
		(layer "F.Cu")
		(at 437.671718 -294.424862 180)
		(property "Reference" "R320"
			(at 0 0 180)
			(layer "F.SilkS")
			(hide yes)
			(effects
				(font
					(size 1.27 1.27)
				)
			)
		)
		(property "Value" "130R3F-GP"
			(at -0.0254 -2.5146 180)
			(unlocked yes)
			(layer "F.Fab")
			(hide yes)
			(effects
				(font
					(size 1.016 1.016)
					(thickness 0.1524)
				)
			)
		)
		(property "Device Type" "R603H22"
			(at -0.0254 -4.0386 180)
			(unlocked yes)
			(layer "F.Fab")
			(hide yes)
			(effects
				(font
					(size 1.016 1.016)
					(thickness 0.1524)
				)
			)
		)
		(duplicate_pad_numbers_are_jumpers no)
		(fp_line
			(start 0.2032 0)
			(end 0.4826 0)
			(stroke
				(width 0.2032)
				(type default)
			)
			(layer "F.SilkS")
		)
		(fp_line
			(start -0.4826 0)
			(end -0.2032 0)
			(stroke
				(width 0.2032)
				(type default)
			)
			(layer "F.SilkS")
		)
		(fp_rect
			(start -0.5842 1.3335)
			(end 0.5842 -1.3335)
			(stroke
				(width 0)
				(type default)
			)
			(fill no)
			(layer "F.CrtYd")
		)
		(fp_rect
			(start -0.5842 1.3335)
			(end 0.5842 -1.3335)
			(stroke
				(width 0)
				(type default)
			)
			(fill no)
			(layer "F.Fab")
		)
		(pad "1" smd custom
			(at 0 -0.762 180)
			(size 0.2159 0.2159)
			(layers "F.Cu" "F.Mask" "F.Paste")
			(net "P5V_B")
			(options
				(clearance outline)
				(anchor circle)
			)
			(primitives
				(gr_poly
					(pts
						(arc
							(start -0.3302 -0.4318)
							(mid -0.402042 -0.402042)
							(end -0.4318 -0.3302)
						)
						(arc
							(start -0.4318 0.3302)
							(mid -0.402042 0.402042)
							(end -0.3302 0.4318)
						)
						(arc
							(start 0.3302 0.4318)
							(mid 0.402042 0.402042)
							(end 0.4318 0.3302)
						)
						(arc
							(start 0.4318 -0.3302)
							(mid 0.402042 -0.402042)
							(end 0.3302 -0.4318)
						)
					)
					(width 0)
					(fill yes)
				)
			)
		)
		(pad "2" smd custom
			(at 0 0.762 180)
			(size 0.2159 0.2159)
			(layers "F.Cu" "F.Mask" "F.Paste")
			(net "FLT_HDD34")
			(options
				(clearance outline)
				(anchor circle)
			)
			(primitives
				(gr_poly
					(pts
						(arc
							(start -0.3302 -0.4318)
							(mid -0.402042 -0.402042)
							(end -0.4318 -0.3302)
						)
						(arc
							(start -0.4318 0.3302)
							(mid -0.402042 0.402042)
							(end -0.3302 0.4318)
						)
						(arc
							(start 0.3302 0.4318)
							(mid 0.402042 0.402042)
							(end 0.4318 0.3302)
						)
						(arc
							(start 0.4318 -0.3302)
							(mid 0.402042 -0.402042)
							(end 0.3302 -0.4318)
						)
					)
					(width 0)
					(fill yes)
				)
			)
		)
	)
	(footprint ""
		(layer "F.Cu")
		(at 241.4016 -242.6716 180)
		(property "Reference" "R83"
			(at 0 0 180)
			(layer "F.SilkS")
			(hide yes)
			(effects
				(font
					(size 1.27 1.27)
				)
			)
		)
		(property "Value" "0R2J-2-GP"
			(at 0.064008 -3.993896 180)
			(unlocked yes)
			(layer "F.Fab")
			(hide yes)
			(effects
				(font
					(size 1.016 1.016)
					(thickness 0.1524)
				)
			)
		)
		(property "Device Type" "R402H16"
			(at 0.064008 -5.517896 180)
			(unlocked yes)
			(layer "F.Fab")
			(hide yes)
			(effects
				(font
					(size 1.016 1.016)
					(thickness 0.1524)
				)
			)
		)
		(duplicate_pad_numbers_are_jumpers no)
		(fp_line
			(start 0.508 -0.9398)
			(end -0.508 -0.9398)
			(stroke
				(width 0.1524)
				(type default)
			)
			(layer "F.SilkS")
		)
		(fp_line
			(start -0.508 -0.9398)
			(end -0.508 0.9398)
			(stroke
				(width 0.1524)
				(type default)
			)
			(layer "F.SilkS")
		)
		(fp_rect
			(start -0.508 0.9398)
			(end 0.508 -0.9398)
			(stroke
				(width 0)
				(type default)
			)
			(fill no)
			(layer "F.CrtYd")
		)
		(fp_rect
			(start -0.508 0.9398)
			(end 0.508 -0.9398)
			(stroke
				(width 0)
				(type default)
			)
			(fill no)
			(layer "F.Fab")
		)
		(pad "1" smd custom
			(at 0 -0.4445 180)
			(size 0.1397 0.1397)
			(layers "F.Cu" "F.Mask" "F.Paste")
			(net "IO_EXP2_SDA")
			(options
				(clearance outline)
				(anchor circle)
			)
			(primitives
				(gr_poly
					(pts
						(arc
							(start -0.1778 -0.2794)
							(mid -0.249642 -0.249642)
							(end -0.2794 -0.1778)
						)
						(arc
							(start -0.2794 0.1778)
							(mid -0.249642 0.249642)
							(end -0.1778 0.2794)
						)
						(arc
							(start 0.1778 0.2794)
							(mid 0.249642 0.249642)
							(end 0.2794 0.1778)
						)
						(arc
							(start 0.2794 -0.1778)
							(mid 0.249642 -0.249642)
							(end 0.1778 -0.2794)
						)
					)
					(width 0)
					(fill yes)
				)
			)
		)
		(pad "2" smd custom
			(at 0 0.4445 180)
			(size 0.1397 0.1397)
			(layers "F.Cu" "F.Mask" "F.Paste")
			(net "I2C_DRIVE_A_PWR_SDA")
			(options
				(clearance outline)
				(anchor circle)
			)
			(primitives
				(gr_poly
					(pts
						(arc
							(start -0.1778 -0.2794)
							(mid -0.249642 -0.249642)
							(end -0.2794 -0.1778)
						)
						(arc
							(start -0.2794 0.1778)
							(mid -0.249642 0.249642)
							(end -0.1778 0.2794)
						)
						(arc
							(start 0.1778 0.2794)
							(mid 0.249642 0.249642)
							(end 0.2794 0.1778)
						)
						(arc
							(start 0.2794 -0.1778)
							(mid 0.249642 -0.249642)
							(end 0.1778 -0.2794)
						)
					)
					(width 0)
					(fill yes)
				)
			)
		)
	)
	(footprint ""
		(layer "F.Cu")
		(at 219.907866 -15.20698 -90)
		(property "Reference" "TC4"
			(at 0 0 270)
			(layer "F.SilkS")
			(hide yes)
			(effects
				(font
					(size 1.27 1.27)
				)
			)
		)
		(property "Value" "ST100U16VDM-3-GP"
			(at 0 -9.6012 270)
			(unlocked yes)
			(layer "F.Fab")
			(hide yes)
			(effects
				(font
					(size 1.016 1.016)
					(thickness 0.1524)
				)
			)
		)
		(property "Device Type" "CT7343H79"
			(at 0 -11.1252 270)
			(unlocked yes)
			(layer "F.Fab")
			(hide yes)
			(effects
				(font
					(size 1.016 1.016)
					(thickness 0.1524)
				)
			)
		)
		(duplicate_pad_numbers_are_jumpers no)
		(fp_line
			(start -2.286 4.8768)
			(end -2.286 2.032)
			(stroke
				(width 0.1524)
				(type default)
			)
			(layer "F.SilkS")
		)
		(fp_line
			(start 2.286 4.8768)
			(end -2.286 4.8768)
			(stroke
				(width 0.1524)
				(type default)
			)
			(layer "F.SilkS")
		)
		(fp_line
			(start 2.286 2.032)
			(end 2.286 4.8768)
			(stroke
				(width 0.1524)
				(type default)
			)
			(layer "F.SilkS")
		)
		(fp_line
			(start 2.286 -2.032)
			(end 2.286 -4.8768)
			(stroke
				(width 0.1524)
				(type default)
			)
			(layer "F.SilkS")
		)
		(fp_line
			(start 2.1082 -4.699)
			(end -2.1082 -4.699)
			(stroke
				(width 0.508)
				(type default)
			)
			(layer "F.SilkS")
		)
		(fp_line
			(start -2.286 -4.8768)
			(end -2.286 -2.032)
			(stroke
				(width 0.1524)
				(type default)
			)
			(layer "F.SilkS")
		)
		(fp_line
			(start 2.286 -4.8768)
			(end -2.286 -4.8768)
			(stroke
				(width 0.1524)
				(type default)
			)
			(layer "F.SilkS")
		)
		(fp_rect
			(start -2.1463 3.6449)
			(end 2.1463 -3.6449)
			(stroke
				(width 0)
				(type default)
			)
			(fill no)
			(layer "F.CrtYd")
		)
		(fp_poly
			(pts
				(xy -2.54 4.953) (xy -2.54 4.2926) (xy -3.81 4.2926) (xy -3.81 -4.2926) (xy -2.54 -4.2926) (xy -2.54 -4.953)
				(xy 2.54 -4.953) (xy 2.54 -4.2926) (xy 3.81 -4.2926) (xy 3.81 -1.6256) (xy 2.1463 -1.6256) (xy 2.1463 -3.6449)
				(xy -2.1463 -3.6449) (xy -2.1463 3.6449) (xy 2.1463 3.6449) (xy 2.1463 -1.6129) (xy 3.81 -1.6129)
				(xy 3.81 4.2926) (xy 2.54 4.2926) (xy 2.54 4.953)
			)
			(stroke
				(width 0)
				(type default)
			)
			(fill no)
			(layer "F.CrtYd")
		)
		(fp_rect
			(start -2.54 4.953)
			(end 2.54 -4.953)
			(stroke
				(width 0)
				(type default)
			)
			(fill no)
			(layer "F.Fab")
		)
		(fp_rect
			(start -3.81 4.2926)
			(end -2.54 -4.2926)
			(stroke
				(width 0)
				(type default)
			)
			(fill no)
			(layer "F.Fab")
		)
		(fp_rect
			(start 2.54 4.2926)
			(end 3.81 -4.2926)
			(stroke
				(width 0)
				(type default)
			)
			(fill no)
			(layer "F.Fab")
		)
		(pad "1" smd rect
			(at 0 -3.1496 270)
			(size 2.413 2.286)
			(layers "F.Cu" "F.Mask" "F.Paste")
			(net "P12V_A_COMP")
		)
		(pad "2" smd rect
			(at 0 3.1496 270)
			(size 2.413 2.286)
			(layers "F.Cu" "F.Mask" "F.Paste")
			(net "GND")
		)
		(zone
			(layer "F.Cu")
			(hatch none 0.5)
			(connect_pads
				(clearance 0)
			)
			(min_thickness 0.25)
			(keepout
				(tracks allowed)
				(vias not_allowed)
				(pads allowed)
				(copperpour not_allowed)
				(footprints allowed)
			)
			(placement
				(enabled no)
				(sheetname "")
			)
			(fill
				(thermal_gap 0.5)
				(thermal_bridge_width 0.5)
				(island_removal_mode 0)
			)
			(polygon
				(pts
					(xy 215.310466 -16.71828) (xy 215.310466 -13.69568) (xy 218.206066 -13.69568) (xy 218.536266 -13.69568)
					(xy 218.536266 -16.71828) (xy 218.206066 -16.71828)
				)
			)
		)
		(zone
			(layer "F.Cu")
			(hatch none 0.5)
			(connect_pads
				(clearance 0)
			)
			(min_thickness 0.25)
			(keepout
				(tracks allowed)
				(vias not_allowed)
				(pads allowed)
				(copperpour not_allowed)
				(footprints allowed)
			)
			(placement
				(enabled no)
				(sheetname "")
			)
			(fill
				(thermal_gap 0.5)
				(thermal_bridge_width 0.5)
				(island_removal_mode 0)
			)
			(polygon
				(pts
					(xy 221.596966 -13.69568) (xy 224.505266 -13.69568) (xy 224.505266 -16.71828) (xy 221.609666 -16.71828)
					(xy 221.279466 -16.71828) (xy 221.279466 -13.69568)
				)
			)
		)
	)
	(footprint ""
		(layer "F.Cu")
		(at 46.392846 -174.857918)
		(property "Reference" "Q80"
			(at 0 0 0)
			(layer "F.SilkS")
			(hide yes)
			(effects
				(font
					(size 1.27 1.27)
				)
			)
		)
		(property "Value" "AO4407AL-GP"
			(at -3.707384 -1.5367 0)
			(unlocked yes)
			(layer "F.Fab")
			(hide yes)
			(effects
				(font
					(size 1.016 1.016)
					(thickness 0.1524)
				)
			)
		)
		(property "Device Type" "SOIC8H69"
			(at -3.707384 -3.0607 0)
			(unlocked yes)
			(layer "F.Fab")
			(hide yes)
			(effects
				(font
					(size 1.016 1.016)
					(thickness 0.1524)
				)
			)
		)
		(duplicate_pad_numbers_are_jumpers no)
		(fp_line
			(start -2.7432 -1.4224)
			(end -2.7432 1.4224)
			(stroke
				(width 0.1524)
				(type default)
			)
			(layer "F.SilkS")
		)
		(fp_line
			(start -2.7432 1.4224)
			(end -2.6416 1.4224)
			(stroke
				(width 0.1524)
				(type default)
			)
			(layer "F.SilkS")
		)
		(fp_line
			(start -2.7432 1.4224)
			(end 2.1336 1.4224)
			(stroke
				(width 0.1524)
				(type default)
			)
			(layer "F.SilkS")
		)
		(fp_line
			(start -2.7178 -0.508)
			(end -2.1844 -0.0508)
			(stroke
				(width 0.1524)
				(type default)
			)
			(layer "F.SilkS")
		)
		(fp_line
			(start -2.6289 3.4417)
			(end -2.6289 1.4732)
			(stroke
				(width 0.381)
				(type default)
			)
			(layer "F.SilkS")
		)
		(fp_line
			(start -2.1844 -0.0508)
			(end -2.7178 0.508)
			(stroke
				(width 0.1524)
				(type default)
			)
			(layer "F.SilkS")
		)
		(fp_line
			(start 2.1336 -1.4224)
			(end -2.7432 -1.4224)
			(stroke
				(width 0.1524)
				(type default)
			)
			(layer "F.SilkS")
		)
		(fp_line
			(start 2.1336 1.4224)
			(end 2.1336 -1.4224)
			(stroke
				(width 0.1524)
				(type default)
			)
			(layer "F.SilkS")
		)
		(fp_poly
			(pts
				(xy -2.2098 -1.4224) (xy -2.2098 1.4224) (xy 2.2098 1.4224) (xy 2.2098 -1.4224)
			)
			(stroke
				(width 0)
				(type default)
			)
			(fill yes)
			(layer "F.SilkS")
		)
		(fp_rect
			(start -2.450084 2.999994)
			(end 2.450084 -2.999994)
			(stroke
				(width 0)
				(type default)
			)
			(fill no)
			(layer "F.CrtYd")
		)
		(fp_poly
			(pts
				(xy -2.8194 3.6322) (xy -2.8194 -3.6322) (xy 2.8194 -3.6322) (xy 2.8194 1.18364) (xy 2.450084 1.18364)
				(xy 2.450084 -2.999994) (xy -2.450084 -2.999994) (xy -2.450084 2.999994) (xy 2.450084 2.999994)
				(xy 2.450084 1.18618) (xy 2.8194 1.18618) (xy 2.8194 3.6322)
			)
			(stroke
				(width 0)
				(type default)
			)
			(fill no)
			(layer "F.CrtYd")
		)
		(fp_rect
			(start -2.8194 3.6322)
			(end 2.8194 -3.6322)
			(stroke
				(width 0)
				(type default)
			)
			(fill no)
			(layer "F.Fab")
		)
		(pad "1" smd rect
			(at -1.905 2.54)
			(size 0.635 1.651)
			(layers "F.Cu" "F.Mask" "F.Paste")
			(net "P12V_A")
		)
		(pad "2" smd rect
			(at -0.635 2.54)
			(size 0.635 1.651)
			(layers "F.Cu" "F.Mask" "F.Paste")
			(net "P12V_A")
		)
		(pad "3" smd rect
			(at 0.635 2.54)
			(size 0.635 1.651)
			(layers "F.Cu" "F.Mask" "F.Paste")
			(net "P12V_A")
		)
		(pad "4" smd rect
			(at 1.905 2.54)
			(size 0.635 1.651)
			(layers "F.Cu" "F.Mask" "F.Paste")
			(net "SW_HDD_N13")
		)
		(pad "5" smd rect
			(at 1.905 -2.54)
			(size 0.635 1.651)
			(layers "F.Cu" "F.Mask" "F.Paste")
			(net "P12V_HDD13")
		)
		(pad "6" smd rect
			(at 0.635 -2.54)
			(size 0.635 1.651)
			(layers "F.Cu" "F.Mask" "F.Paste")
			(net "P12V_HDD13")
		)
		(pad "7" smd rect
			(at -0.635 -2.54)
			(size 0.635 1.651)
			(layers "F.Cu" "F.Mask" "F.Paste")
			(net "P12V_HDD13")
		)
		(pad "8" smd rect
			(at -1.905 -2.54)
			(size 0.635 1.651)
			(layers "F.Cu" "F.Mask" "F.Paste")
			(net "P12V_HDD13")
		)
	)
	(footprint ""
		(layer "F.Cu")
		(at 287.147 -278.384)
		(property "Reference" "U12"
			(at 0 0 0)
			(layer "F.SilkS")
			(hide yes)
			(effects
				(font
					(size 1.27 1.27)
				)
			)
		)
		(property "Value" "TCA9555PWR-GP"
			(at 0 -6.9342 0)
			(unlocked yes)
			(layer "F.Fab")
			(hide yes)
			(effects
				(font
					(size 1.016 1.016)
					(thickness 0.1524)
				)
			)
		)
		(property "Device Type" "TSOIC24H48"
			(at 0 -8.5852 0)
			(unlocked yes)
			(layer "F.Fab")
			(hide yes)
			(effects
				(font
					(size 1.016 1.016)
					(thickness 0.1524)
				)
			)
		)
		(duplicate_pad_numbers_are_jumpers no)
		(fp_line
			(start -4.2291 -1.397)
			(end 3.81 -1.397)
			(stroke
				(width 0.1524)
				(type default)
			)
			(layer "F.SilkS")
		)
		(fp_line
			(start -4.2291 -0.8001)
			(end -3.429 0)
			(stroke
				(width 0.1524)
				(type default)
			)
			(layer "F.SilkS")
		)
		(fp_line
			(start -4.2291 3.937)
			(end -4.2291 -1.397)
			(stroke
				(width 0.1524)
				(type default)
			)
			(layer "F.SilkS")
		)
		(fp_line
			(start -4.22656 3.81)
			(end -4.2291 1.397)
			(stroke
				(width 0.508)
				(type default)
			)
			(layer "F.SilkS")
		)
		(fp_line
			(start -3.429 0)
			(end -4.2291 0.8001)
			(stroke
				(width 0.1524)
				(type default)
			)
			(layer "F.SilkS")
		)
		(fp_line
			(start 3.81 -1.397)
			(end 3.81 1.397)
			(stroke
				(width 0.1524)
				(type default)
			)
			(layer "F.SilkS")
		)
		(fp_line
			(start 3.81 1.397)
			(end -4.2291 1.397)
			(stroke
				(width 0.1524)
				(type default)
			)
			(layer "F.SilkS")
		)
		(fp_poly
			(pts
				(xy -3.90652 -1.8542) (xy 3.90652 -1.8542) (xy 3.90652 1.8542) (xy -3.90652 1.8542)
			)
			(stroke
				(width 0)
				(type default)
			)
			(fill yes)
			(layer "F.SilkS")
		)
		(fp_poly
			(pts
				(xy -4.2164 3.81) (xy 4.2164 3.81) (xy 4.22656 -3.81) (xy -4.2164 -3.81)
			)
			(stroke
				(width 0)
				(type default)
			)
			(fill no)
			(layer "F.CrtYd")
		)
		(fp_poly
			(pts
				(xy -4.22656 -3.81) (xy 4.22656 -3.81) (xy 4.22656 3.81) (xy -4.22656 3.81)
			)
			(stroke
				(width 0)
				(type default)
			)
			(fill no)
			(layer "F.Fab")
		)
		(pad "1" smd rect
			(at -3.57632 2.8194)
			(size 0.3556 1.524)
			(layers "F.Cu" "F.Mask" "F.Paste")
			(net "IO_EXP2_HDD_FAULT_INT_N")
		)
		(pad "2" smd rect
			(at -2.92608 2.8194)
			(size 0.3556 1.524)
			(layers "F.Cu" "F.Mask" "F.Paste")
			(net "IO_EXP2_HDD_FAULT_A1")
		)
		(pad "3" smd rect
			(at -2.27584 2.8194)
			(size 0.3556 1.524)
			(layers "F.Cu" "F.Mask" "F.Paste")
			(net "IO_EXP2_HDD_FAULT_A2")
		)
		(pad "4" smd rect
			(at -1.6256 2.8194)
			(size 0.3556 1.524)
			(layers "F.Cu" "F.Mask" "F.Paste")
			(net "DRIVE_A_24_FLT_LED")
		)
		(pad "5" smd rect
			(at -0.97536 2.8194)
			(size 0.3556 1.524)
			(layers "F.Cu" "F.Mask" "F.Paste")
			(net "DRIVE_A_25_FLT_LED")
		)
		(pad "6" smd rect
			(at -0.32512 2.8194)
			(size 0.3556 1.524)
			(layers "F.Cu" "F.Mask" "F.Paste")
			(net "DRIVE_A_26_FLT_LED")
		)
		(pad "7" smd rect
			(at 0.32512 2.8194)
			(size 0.3556 1.524)
			(layers "F.Cu" "F.Mask" "F.Paste")
			(net "DRIVE_A_27_FLT_LED")
		)
		(pad "8" smd rect
			(at 0.97536 2.8194)
			(size 0.3556 1.524)
			(layers "F.Cu" "F.Mask" "F.Paste")
			(net "DRIVE_A_28_FLT_LED")
		)
		(pad "9" smd rect
			(at 1.6256 2.8194)
			(size 0.3556 1.524)
			(layers "F.Cu" "F.Mask" "F.Paste")
			(net "DRIVE_A_29_FLT_LED")
		)
		(pad "10" smd rect
			(at 2.27584 2.8194)
			(size 0.3556 1.524)
			(layers "F.Cu" "F.Mask" "F.Paste")
			(net "DRIVE_A_30_FLT_LED")
		)
		(pad "11" smd rect
			(at 2.92608 2.8194)
			(size 0.3556 1.524)
			(layers "F.Cu" "F.Mask" "F.Paste")
			(net "DRIVE_A_31_FLT_LED")
		)
		(pad "12" smd rect
			(at 3.57632 2.8194)
			(size 0.3556 1.524)
			(layers "F.Cu" "F.Mask" "F.Paste")
			(net "GND")
		)
		(pad "13" smd rect
			(at 3.57632 -2.8194)
			(size 0.3556 1.524)
			(layers "F.Cu" "F.Mask" "F.Paste")
			(net "DRIVE_A_32_FLT_LED")
		)
		(pad "14" smd rect
			(at 2.92608 -2.8194)
			(size 0.3556 1.524)
			(layers "F.Cu" "F.Mask" "F.Paste")
			(net "DRIVE_A_33_FLT_LED")
		)
		(pad "15" smd rect
			(at 2.27584 -2.8194)
			(size 0.3556 1.524)
			(layers "F.Cu" "F.Mask" "F.Paste")
			(net "DRIVE_A_34_FLT_LED")
		)
		(pad "16" smd rect
			(at 1.6256 -2.8194)
			(size 0.3556 1.524)
			(layers "F.Cu" "F.Mask" "F.Paste")
			(net "DRIVE_A_35_FLT_LED")
		)
		(pad "17" smd rect
			(at 0.97536 -2.8194)
			(size 0.3556 1.524)
			(layers "F.Cu" "F.Mask" "F.Paste")
			(net "Net_275")
		)
		(pad "18" smd rect
			(at 0.32512 -2.8194)
			(size 0.3556 1.524)
			(layers "F.Cu" "F.Mask" "F.Paste")
			(net "Net_274")
		)
		(pad "19" smd rect
			(at -0.32512 -2.8194)
			(size 0.3556 1.524)
			(layers "F.Cu" "F.Mask" "F.Paste")
			(net "Net_273")
		)
		(pad "20" smd rect
			(at -0.97536 -2.8194)
			(size 0.3556 1.524)
			(layers "F.Cu" "F.Mask" "F.Paste")
			(net "Net_272")
		)
		(pad "21" smd rect
			(at -1.6256 -2.8194)
			(size 0.3556 1.524)
			(layers "F.Cu" "F.Mask" "F.Paste")
			(net "IO_EXP2_HDD_FAULT_A0")
		)
		(pad "22" smd rect
			(at -2.27584 -2.8194)
			(size 0.3556 1.524)
			(layers "F.Cu" "F.Mask" "F.Paste")
			(net "IO_EXP2_LED_SCL")
		)
		(pad "23" smd rect
			(at -2.92608 -2.8194)
			(size 0.3556 1.524)
			(layers "F.Cu" "F.Mask" "F.Paste")
			(net "IO_EXP2_LED_SDA")
		)
		(pad "24" smd rect
			(at -3.57632 -2.8194)
			(size 0.3556 1.524)
			(layers "F.Cu" "F.Mask" "F.Paste")
			(net "P3V3_STBY_A")
		)
	)
	(footprint ""
		(layer "F.Cu")
		(at 50.456846 -294.683942 90)
		(property "Reference" "R154"
			(at 0 0 90)
			(layer "F.SilkS")
			(hide yes)
			(effects
				(font
					(size 1.27 1.27)
				)
			)
		)
		(property "Value" "2R6F-GP"
			(at -0.0508 -4.8514 90)
			(unlocked yes)
			(layer "F.Fab")
			(hide yes)
			(effects
				(font
					(size 1.016 1.016)
					(thickness 0.1524)
				)
			)
		)
		(property "Device Type" "R1206H26"
			(at 0 -6.3754 90)
			(unlocked yes)
			(layer "F.Fab")
			(hide yes)
			(effects
				(font
					(size 1.016 1.016)
					(thickness 0.1524)
				)
			)
		)
		(duplicate_pad_numbers_are_jumpers no)
		(fp_line
			(start 1.016 -2.2352)
			(end 1.016 2.2352)
			(stroke
				(width 0.1524)
				(type default)
			)
			(layer "F.SilkS")
		)
		(fp_line
			(start -1.016 -2.2352)
			(end 1.016 -2.2352)
			(stroke
				(width 0.1524)
				(type default)
			)
			(layer "F.SilkS")
		)
		(fp_line
			(start 1.016 2.2352)
			(end -1.016 2.2352)
			(stroke
				(width 0.1524)
				(type default)
			)
			(layer "F.SilkS")
		)
		(fp_line
			(start -1.016 2.2352)
			(end -1.016 -2.2352)
			(stroke
				(width 0.1524)
				(type default)
			)
			(layer "F.SilkS")
		)
		(fp_rect
			(start -1.0922 2.3114)
			(end 1.0922 -2.3114)
			(stroke
				(width 0)
				(type default)
			)
			(fill no)
			(layer "F.CrtYd")
		)
		(fp_poly
			(pts
				(xy -1.0922 -2.3114) (xy 1.0922 -2.3114) (xy 1.0922 2.3114) (xy -1.0922 2.3114)
			)
			(stroke
				(width 0)
				(type default)
			)
			(fill no)
			(layer "F.Fab")
		)
		(pad "1" smd rect
			(at 0 -1.397 90)
			(size 1.651 1.27)
			(layers "F.Cu" "F.Mask" "F.Paste")
			(net "P12V_HDD1")
		)
		(pad "2" smd rect
			(at 0 1.397 90)
			(size 1.651 1.27)
			(layers "F.Cu" "F.Mask" "F.Paste")
			(net "12V_PRE_1")
		)
	)
	(footprint ""
		(layer "F.Cu")
		(at 272.542 -307.304948 180)
		(property "Reference" "VIA61"
			(at 0 0 180)
			(layer "F.SilkS")
			(hide yes)
			(effects
				(font
					(size 1.27 1.27)
				)
			)
		)
		(property "Value" "100OHM-8L-1D6MM-L18L16-GP"
			(at -3.7211 -4.5085 180)
			(unlocked yes)
			(layer "F.Fab")
			(hide yes)
			(effects
				(font
					(size 1.016 1.016)
					(thickness 0.1524)
				)
			)
		)
		(property "Device Type" "VIA-PCIE-4P-394076"
			(at -3.7211 -6.0325 180)
			(unlocked yes)
			(layer "F.Fab")
			(hide yes)
			(effects
				(font
					(size 1.016 1.016)
					(thickness 0.1524)
				)
			)
		)
		(duplicate_pad_numbers_are_jumpers no)
		(fp_rect
			(start -1.9685 0.381)
			(end 1.9685 -0.381)
			(stroke
				(width 0)
				(type default)
			)
			(fill no)
			(layer "F.CrtYd")
		)
		(fp_rect
			(start -1.9685 0.381)
			(end 1.9685 -0.381)
			(stroke
				(width 0)
				(type default)
			)
			(fill no)
			(layer "F.Fab")
		)
		(pad "1" thru_hole circle
			(at -1.5875 0 180)
			(size 0.508 0.508)
			(drill 0.254)
			(layers "*.Cu" "*.Mask")
			(remove_unused_layers no)
			(net "GND")
			(clearance 0.127)
			(thermal_gap 0.127)
		)
		(pad "2" thru_hole circle
			(at -0.5715 0 180)
			(size 0.508 0.508)
			(drill 0.254)
			(layers "*.Cu" "*.Mask")
			(remove_unused_layers no)
			(net "PHY_SCC_A_TO_DRV_A_29_DP")
			(clearance 0.127)
			(thermal_gap 0.127)
		)
		(pad "3" thru_hole circle
			(at 0.5715 0 180)
			(size 0.508 0.508)
			(drill 0.254)
			(layers "*.Cu" "*.Mask")
			(remove_unused_layers no)
			(net "PHY_SCC_A_TO_DRV_A_29_DN")
			(clearance 0.127)
			(thermal_gap 0.127)
		)
		(pad "4" thru_hole circle
			(at 1.5875 0 180)
			(size 0.508 0.508)
			(drill 0.254)
			(layers "*.Cu" "*.Mask")
			(remove_unused_layers no)
			(net "GND")
			(clearance 0.127)
			(thermal_gap 0.127)
		)
	)
	(footprint ""
		(layer "F.Cu")
		(at 245.110254 -389.617204 -90)
		(property "Reference" "C585"
			(at 0 0 270)
			(layer "F.SilkS")
			(hide yes)
			(effects
				(font
					(size 1.27 1.27)
				)
			)
		)
		(property "Value" "SC1U25V3KX-GP"
			(at 0 -2.8194 270)
			(unlocked yes)
			(layer "F.Fab")
			(hide yes)
			(effects
				(font
					(size 1.016 1.016)
					(thickness 0.1524)
				)
			)
		)
		(property "Device Type" "C603H36"
			(at 0 -4.3434 270)
			(unlocked yes)
			(layer "F.Fab")
			(hide yes)
			(effects
				(font
					(size 1.016 1.016)
					(thickness 0.1524)
				)
			)
		)
		(duplicate_pad_numbers_are_jumpers no)
		(fp_line
			(start 0.508 0)
			(end -0.508 0)
			(stroke
				(width 0.2032)
				(type default)
			)
			(layer "F.SilkS")
		)
		(fp_rect
			(start -0.5842 1.3335)
			(end 0.5842 -1.3335)
			(stroke
				(width 0)
				(type default)
			)
			(fill no)
			(layer "F.CrtYd")
		)
		(fp_rect
			(start -0.5842 1.3335)
			(end 0.5842 -1.3335)
			(stroke
				(width 0)
				(type default)
			)
			(fill no)
			(layer "F.Fab")
		)
		(pad "1" smd custom
			(at 0 -0.762 270)
			(size 0.2159 0.2159)
			(layers "F.Cu" "F.Mask" "F.Paste")
			(net "AGND_CURRENT_DPB")
			(options
				(clearance outline)
				(anchor circle)
			)
			(primitives
				(gr_poly
					(pts
						(arc
							(start -0.3302 -0.4318)
							(mid -0.402042 -0.402042)
							(end -0.4318 -0.3302)
						)
						(arc
							(start -0.4318 0.3302)
							(mid -0.402042 0.402042)
							(end -0.3302 0.4318)
						)
						(arc
							(start 0.3302 0.4318)
							(mid 0.402042 0.402042)
							(end 0.4318 0.3302)
						)
						(arc
							(start 0.4318 -0.3302)
							(mid 0.402042 -0.402042)
							(end 0.3302 -0.4318)
						)
					)
					(width 0)
					(fill yes)
				)
			)
		)
		(pad "2" smd custom
			(at 0 0.762 270)
			(size 0.2159 0.2159)
			(layers "F.Cu" "F.Mask" "F.Paste")
			(net "MB3_P12V_HS")
			(options
				(clearance outline)
				(anchor circle)
			)
			(primitives
				(gr_poly
					(pts
						(arc
							(start -0.3302 -0.4318)
							(mid -0.402042 -0.402042)
							(end -0.4318 -0.3302)
						)
						(arc
							(start -0.4318 0.3302)
							(mid -0.402042 0.402042)
							(end -0.3302 0.4318)
						)
						(arc
							(start 0.3302 0.4318)
							(mid 0.402042 0.402042)
							(end 0.4318 0.3302)
						)
						(arc
							(start 0.4318 -0.3302)
							(mid 0.402042 -0.402042)
							(end 0.3302 -0.4318)
						)
					)
					(width 0)
					(fill yes)
				)
			)
		)
	)
	(footprint ""
		(layer "F.Cu")
		(at 450.9389 -277.750016 -90)
		(property "Reference" "VIA21"
			(at 0 0 270)
			(layer "F.SilkS")
			(hide yes)
			(effects
				(font
					(size 1.27 1.27)
				)
			)
		)
		(property "Value" "100OHM-8L-1D6MM-L18L16-GP"
			(at -3.7211 -4.5085 270)
			(unlocked yes)
			(layer "F.Fab")
			(hide yes)
			(effects
				(font
					(size 1.016 1.016)
					(thickness 0.1524)
				)
			)
		)
		(property "Device Type" "VIA-PCIE-4P-394076"
			(at -3.7211 -6.0325 270)
			(unlocked yes)
			(layer "F.Fab")
			(hide yes)
			(effects
				(font
					(size 1.016 1.016)
					(thickness 0.1524)
				)
			)
		)
		(duplicate_pad_numbers_are_jumpers no)
		(fp_rect
			(start -1.9685 0.381)
			(end 1.9685 -0.381)
			(stroke
				(width 0)
				(type default)
			)
			(fill no)
			(layer "F.CrtYd")
		)
		(fp_rect
			(start -1.9685 0.381)
			(end 1.9685 -0.381)
			(stroke
				(width 0)
				(type default)
			)
			(fill no)
			(layer "F.Fab")
		)
		(pad "1" thru_hole circle
			(at -1.5875 0 270)
			(size 0.508 0.508)
			(drill 0.254)
			(layers "*.Cu" "*.Mask")
			(remove_unused_layers no)
			(net "GND")
			(clearance 0.127)
			(thermal_gap 0.127)
		)
		(pad "2" thru_hole circle
			(at -0.5715 0 270)
			(size 0.508 0.508)
			(drill 0.254)
			(layers "*.Cu" "*.Mask")
			(remove_unused_layers no)
			(net "PHY_DRV_A_TO_SCC_A_10_DP")
			(clearance 0.127)
			(thermal_gap 0.127)
		)
		(pad "3" thru_hole circle
			(at 0.5715 0 270)
			(size 0.508 0.508)
			(drill 0.254)
			(layers "*.Cu" "*.Mask")
			(remove_unused_layers no)
			(net "PHY_DRV_A_TO_SCC_A_10_DN")
			(clearance 0.127)
			(thermal_gap 0.127)
		)
		(pad "4" thru_hole circle
			(at 1.5875 0 270)
			(size 0.508 0.508)
			(drill 0.254)
			(layers "*.Cu" "*.Mask")
			(remove_unused_layers no)
			(net "GND")
			(clearance 0.127)
			(thermal_gap 0.127)
		)
	)
	(footprint ""
		(layer "F.Cu")
		(at 141.042898 -284.523942 90)
		(property "Reference" "C101"
			(at 0 0 90)
			(layer "F.SilkS")
			(hide yes)
			(effects
				(font
					(size 1.27 1.27)
				)
			)
		)
		(property "Value" "SCD033U25V2KX-GP"
			(at 1.1811 -2.7051 90)
			(unlocked yes)
			(layer "F.Fab")
			(hide yes)
			(effects
				(font
					(size 1.016 1.016)
					(thickness 0.1524)
				)
			)
		)
		(property "Device Type" "C402H22"
			(at 1.1811 -4.2291 90)
			(unlocked yes)
			(layer "F.Fab")
			(hide yes)
			(effects
				(font
					(size 1.016 1.016)
					(thickness 0.1524)
				)
			)
		)
		(duplicate_pad_numbers_are_jumpers no)
		(fp_rect
			(start -0.4318 0.9525)
			(end 0.4318 -0.9525)
			(stroke
				(width 0)
				(type default)
			)
			(fill no)
			(layer "F.CrtYd")
		)
		(fp_rect
			(start -0.4318 0.9525)
			(end 0.4318 -0.9525)
			(stroke
				(width 0)
				(type default)
			)
			(fill no)
			(layer "F.Fab")
		)
		(pad "1" smd custom
			(at 0 -0.4445 90)
			(size 0.1524 0.1524)
			(layers "F.Cu" "F.Mask" "F.Paste")
			(net "P12V_A")
			(options
				(clearance outline)
				(anchor circle)
			)
			(primitives
				(gr_poly
					(pts
						(arc
							(start 0.3048 -0.2032)
							(mid 0.275042 -0.275042)
							(end 0.2032 -0.3048)
						)
						(arc
							(start -0.2032 -0.3048)
							(mid -0.275042 -0.275042)
							(end -0.3048 -0.2032)
						)
						(arc
							(start -0.3048 0.2032)
							(mid -0.275042 0.275042)
							(end -0.2032 0.3048)
						)
						(arc
							(start 0.2032 0.3048)
							(mid 0.275042 0.275042)
							(end 0.3048 0.2032)
						)
					)
					(width 0)
					(fill yes)
				)
			)
		)
		(pad "2" smd custom
			(at 0 0.4445 90)
			(size 0.1524 0.1524)
			(layers "F.Cu" "F.Mask" "F.Paste")
			(net "SW_HDD_N4")
			(options
				(clearance outline)
				(anchor circle)
			)
			(primitives
				(gr_poly
					(pts
						(arc
							(start 0.3048 -0.2032)
							(mid 0.275042 -0.275042)
							(end 0.2032 -0.3048)
						)
						(arc
							(start -0.2032 -0.3048)
							(mid -0.275042 -0.275042)
							(end -0.3048 -0.2032)
						)
						(arc
							(start -0.3048 0.2032)
							(mid -0.275042 0.275042)
							(end -0.2032 0.3048)
						)
						(arc
							(start 0.2032 0.3048)
							(mid 0.275042 0.275042)
							(end 0.3048 0.2032)
						)
					)
					(width 0)
					(fill yes)
				)
			)
		)
	)
	(footprint ""
		(layer "F.Cu")
		(at 441.349892 -94.400116)
		(property "Reference" "FLED23"
			(at 0 0 0)
			(layer "F.SilkS")
			(hide yes)
			(effects
				(font
					(size 1.27 1.27)
				)
			)
		)
		(property "Value" "LED-BY-19-GP"
			(at -2.132076 1.414018 0)
			(unlocked yes)
			(layer "F.Fab")
			(hide yes)
			(effects
				(font
					(size 1.016 1.016)
					(thickness 0.1524)
				)
			)
		)
		(property "Device Type" "LED-1615-4PH26"
			(at -2.132076 -0.109982 0)
			(unlocked yes)
			(layer "F.Fab")
			(hide yes)
			(effects
				(font
					(size 1.016 1.016)
					(thickness 0.1524)
				)
			)
		)
		(duplicate_pad_numbers_are_jumpers no)
		(fp_line
			(start -1.2954 0.254)
			(end -1.2954 1.6002)
			(stroke
				(width 0.508)
				(type default)
			)
			(layer "F.SilkS")
		)
		(fp_line
			(start -1.2954 1.6002)
			(end 1.2954 1.6002)
			(stroke
				(width 0.508)
				(type default)
			)
			(layer "F.SilkS")
		)
		(fp_line
			(start -1.1176 -1.4224)
			(end 1.1176 -1.4224)
			(stroke
				(width 0.1524)
				(type default)
			)
			(layer "F.SilkS")
		)
		(fp_line
			(start -1.1176 1.4224)
			(end -1.1176 -1.4224)
			(stroke
				(width 0.1524)
				(type default)
			)
			(layer "F.SilkS")
		)
		(fp_line
			(start 1.1176 -1.4224)
			(end 1.1176 1.4224)
			(stroke
				(width 0.1524)
				(type default)
			)
			(layer "F.SilkS")
		)
		(fp_line
			(start 1.1176 1.4224)
			(end -1.1176 1.4224)
			(stroke
				(width 0.1524)
				(type default)
			)
			(layer "F.SilkS")
		)
		(fp_line
			(start 1.2954 1.6002)
			(end 1.2954 0.254)
			(stroke
				(width 0.508)
				(type default)
			)
			(layer "F.SilkS")
		)
		(fp_rect
			(start -0.7493 0.8001)
			(end 0.7493 -0.8001)
			(stroke
				(width 0)
				(type default)
			)
			(fill no)
			(layer "F.CrtYd")
		)
		(fp_poly
			(pts
				(xy -1.3716 1.6764) (xy -1.3716 -1.6764) (xy 1.3716 -1.6764) (xy 1.3716 0.0635) (xy 0.7493 0.0635)
				(xy 0.7493 -0.8001) (xy -0.7493 -0.8001) (xy -0.7493 0.8001) (xy 0.7493 0.8001) (xy 0.7493 0.0762)
				(xy 1.3716 0.0762) (xy 1.3716 1.6764)
			)
			(stroke
				(width 0)
				(type default)
			)
			(fill no)
			(layer "F.CrtYd")
		)
		(fp_rect
			(start -1.3716 1.6764)
			(end 1.3716 -1.6764)
			(stroke
				(width 0)
				(type default)
			)
			(fill no)
			(layer "F.Fab")
		)
		(pad "1" smd rect
			(at 0.50038 -0.73025)
			(size 0.7112 0.8636)
			(layers "F.Cu" "F.Mask" "F.Paste")
			(net "DRV_ACT_22")
		)
		(pad "2" smd rect
			(at -0.50038 -0.73025)
			(size 0.7112 0.8636)
			(layers "F.Cu" "F.Mask" "F.Paste")
			(net "FLT_HDD22")
		)
		(pad "3" smd rect
			(at 0.50038 0.73025)
			(size 0.7112 0.8636)
			(layers "F.Cu" "F.Mask" "F.Paste")
			(net "DRV_ACT_22_N")
		)
		(pad "4" smd rect
			(at -0.50038 0.73025)
			(size 0.7112 0.8636)
			(layers "F.Cu" "F.Mask" "F.Paste")
			(net "FLT_HDD22_N")
		)
	)
	(footprint ""
		(layer "F.Cu")
		(at 341.965534 -294.424862 180)
		(property "Reference" "R287"
			(at 0 0 180)
			(layer "F.SilkS")
			(hide yes)
			(effects
				(font
					(size 1.27 1.27)
				)
			)
		)
		(property "Value" "91R3F-1-GP"
			(at -0.0254 -2.5146 180)
			(unlocked yes)
			(layer "F.Fab")
			(hide yes)
			(effects
				(font
					(size 1.016 1.016)
					(thickness 0.1524)
				)
			)
		)
		(property "Device Type" "R603H22"
			(at -0.0254 -4.0386 180)
			(unlocked yes)
			(layer "F.Fab")
			(hide yes)
			(effects
				(font
					(size 1.016 1.016)
					(thickness 0.1524)
				)
			)
		)
		(duplicate_pad_numbers_are_jumpers no)
		(fp_line
			(start 0.2032 0)
			(end 0.4826 0)
			(stroke
				(width 0.2032)
				(type default)
			)
			(layer "F.SilkS")
		)
		(fp_line
			(start -0.4826 0)
			(end -0.2032 0)
			(stroke
				(width 0.2032)
				(type default)
			)
			(layer "F.SilkS")
		)
		(fp_rect
			(start -0.5842 1.3335)
			(end 0.5842 -1.3335)
			(stroke
				(width 0)
				(type default)
			)
			(fill no)
			(layer "F.CrtYd")
		)
		(fp_rect
			(start -0.5842 1.3335)
			(end 0.5842 -1.3335)
			(stroke
				(width 0)
				(type default)
			)
			(fill no)
			(layer "F.Fab")
		)
		(pad "1" smd custom
			(at 0 -0.762 180)
			(size 0.2159 0.2159)
			(layers "F.Cu" "F.Mask" "F.Paste")
			(net "P5V_B")
			(options
				(clearance outline)
				(anchor circle)
			)
			(primitives
				(gr_poly
					(pts
						(arc
							(start -0.3302 -0.4318)
							(mid -0.402042 -0.402042)
							(end -0.4318 -0.3302)
						)
						(arc
							(start -0.4318 0.3302)
							(mid -0.402042 0.402042)
							(end -0.3302 0.4318)
						)
						(arc
							(start 0.3302 0.4318)
							(mid 0.402042 0.402042)
							(end 0.4318 0.3302)
						)
						(arc
							(start 0.4318 -0.3302)
							(mid 0.402042 -0.402042)
							(end 0.3302 -0.4318)
						)
					)
					(width 0)
					(fill yes)
				)
			)
		)
		(pad "2" smd custom
			(at 0 0.762 180)
			(size 0.2159 0.2159)
			(layers "F.Cu" "F.Mask" "F.Paste")
			(net "DRV_ACT_31")
			(options
				(clearance outline)
				(anchor circle)
			)
			(primitives
				(gr_poly
					(pts
						(arc
							(start -0.3302 -0.4318)
							(mid -0.402042 -0.402042)
							(end -0.4318 -0.3302)
						)
						(arc
							(start -0.4318 0.3302)
							(mid -0.402042 0.402042)
							(end -0.3302 0.4318)
						)
						(arc
							(start 0.3302 0.4318)
							(mid 0.402042 0.402042)
							(end 0.4318 0.3302)
						)
						(arc
							(start 0.4318 -0.3302)
							(mid 0.402042 -0.402042)
							(end 0.3302 -0.4318)
						)
					)
					(width 0)
					(fill yes)
				)
			)
		)
	)
	(footprint ""
		(layer "F.Cu")
		(at 353.184714 -44.219368 -90)
		(property "Reference" "C441"
			(at 0 0 270)
			(layer "F.SilkS")
			(hide yes)
			(effects
				(font
					(size 1.27 1.27)
				)
			)
		)
		(property "Value" "SCD01U16V1KX-GP"
			(at -2.8321 -1.7399 270)
			(unlocked yes)
			(layer "F.Fab")
			(hide yes)
			(effects
				(font
					(size 1.016 1.016)
					(thickness 0.1524)
				)
			)
		)
		(property "Device Type" "C0201H13"
			(at -2.8321 -3.2639 270)
			(unlocked yes)
			(layer "F.Fab")
			(hide yes)
			(effects
				(font
					(size 1.016 1.016)
					(thickness 0.1524)
				)
			)
		)
		(duplicate_pad_numbers_are_jumpers no)
		(fp_rect
			(start -0.2794 0.6477)
			(end 0.2794 -0.6477)
			(stroke
				(width 0)
				(type default)
			)
			(fill no)
			(layer "F.CrtYd")
		)
		(fp_rect
			(start -0.2794 0.6477)
			(end 0.2794 -0.6477)
			(stroke
				(width 0)
				(type default)
			)
			(fill no)
			(layer "F.Fab")
		)
		(pad "1" smd custom
			(at 0 -0.2794 270)
			(size 0.0762 0.0762)
			(layers "F.Cu" "F.Mask" "F.Paste")
			(net "SAS_HDD_RX_N31")
			(options
				(clearance outline)
				(anchor circle)
			)
			(primitives
				(gr_poly
					(pts
						(arc
							(start 0.1524 -0.127)
							(mid 0.137521 -0.162921)
							(end 0.1016 -0.1778)
						)
						(arc
							(start -0.1016 -0.1778)
							(mid -0.137521 -0.162921)
							(end -0.1524 -0.127)
						)
						(arc
							(start -0.1524 0.127)
							(mid -0.137521 0.162921)
							(end -0.1016 0.1778)
						)
						(arc
							(start 0.1016 0.1778)
							(mid 0.137521 0.162921)
							(end 0.1524 0.127)
						)
					)
					(width 0)
					(fill yes)
				)
			)
		)
		(pad "2" smd custom
			(at 0 0.2794 270)
			(size 0.0762 0.0762)
			(layers "F.Cu" "F.Mask" "F.Paste")
			(net "PHY_SCC_A_TO_DRV_A_31_DN")
			(options
				(clearance outline)
				(anchor circle)
			)
			(primitives
				(gr_poly
					(pts
						(arc
							(start 0.1524 -0.127)
							(mid 0.137521 -0.162921)
							(end 0.1016 -0.1778)
						)
						(arc
							(start -0.1016 -0.1778)
							(mid -0.137521 -0.162921)
							(end -0.1524 -0.127)
						)
						(arc
							(start -0.1524 0.127)
							(mid -0.137521 0.162921)
							(end -0.1016 0.1778)
						)
						(arc
							(start 0.1016 0.1778)
							(mid 0.137521 0.162921)
							(end 0.1524 0.127)
						)
					)
					(width 0)
					(fill yes)
				)
			)
		)
	)
	(footprint ""
		(layer "F.Cu")
		(at 464.8073 -287.825942 90)
		(property "Reference" "C179"
			(at 0 0 90)
			(layer "F.SilkS")
			(hide yes)
			(effects
				(font
					(size 1.27 1.27)
				)
			)
		)
		(property "Value" "SCD033U25V2KX-GP"
			(at 1.1811 -2.7051 90)
			(unlocked yes)
			(layer "F.Fab")
			(hide yes)
			(effects
				(font
					(size 1.016 1.016)
					(thickness 0.1524)
				)
			)
		)
		(property "Device Type" "C402H22"
			(at 1.1811 -4.2291 90)
			(unlocked yes)
			(layer "F.Fab")
			(hide yes)
			(effects
				(font
					(size 1.016 1.016)
					(thickness 0.1524)
				)
			)
		)
		(duplicate_pad_numbers_are_jumpers no)
		(fp_rect
			(start -0.4318 0.9525)
			(end 0.4318 -0.9525)
			(stroke
				(width 0)
				(type default)
			)
			(fill no)
			(layer "F.CrtYd")
		)
		(fp_rect
			(start -0.4318 0.9525)
			(end 0.4318 -0.9525)
			(stroke
				(width 0)
				(type default)
			)
			(fill no)
			(layer "F.Fab")
		)
		(pad "1" smd custom
			(at 0 -0.4445 90)
			(size 0.1524 0.1524)
			(layers "F.Cu" "F.Mask" "F.Paste")
			(net "P12V_A")
			(options
				(clearance outline)
				(anchor circle)
			)
			(primitives
				(gr_poly
					(pts
						(arc
							(start 0.3048 -0.2032)
							(mid 0.275042 -0.275042)
							(end 0.2032 -0.3048)
						)
						(arc
							(start -0.2032 -0.3048)
							(mid -0.275042 -0.275042)
							(end -0.3048 -0.2032)
						)
						(arc
							(start -0.3048 0.2032)
							(mid -0.275042 0.275042)
							(end -0.2032 0.3048)
						)
						(arc
							(start 0.2032 0.3048)
							(mid 0.275042 0.275042)
							(end 0.3048 0.2032)
						)
					)
					(width 0)
					(fill yes)
				)
			)
		)
		(pad "2" smd custom
			(at 0 0.4445 90)
			(size 0.1524 0.1524)
			(layers "F.Cu" "F.Mask" "F.Paste")
			(net "SW_HDD_N10")
			(options
				(clearance outline)
				(anchor circle)
			)
			(primitives
				(gr_poly
					(pts
						(arc
							(start 0.3048 -0.2032)
							(mid 0.275042 -0.275042)
							(end 0.2032 -0.3048)
						)
						(arc
							(start -0.2032 -0.3048)
							(mid -0.275042 -0.275042)
							(end -0.3048 -0.2032)
						)
						(arc
							(start -0.3048 0.2032)
							(mid -0.275042 0.275042)
							(end -0.2032 0.3048)
						)
						(arc
							(start 0.2032 0.3048)
							(mid 0.275042 0.275042)
							(end 0.3048 0.2032)
						)
					)
					(width 0)
					(fill yes)
				)
			)
		)
	)
	(footprint ""
		(layer "F.Cu")
		(at 237.47984 -240.14303)
		(property "Reference" "Q16"
			(at 0 0 0)
			(layer "F.SilkS")
			(hide yes)
			(effects
				(font
					(size 1.27 1.27)
				)
			)
		)
		(property "Value" "SSM3K324R-GP"
			(at 0.127 -8.9662 0)
			(unlocked yes)
			(layer "F.Fab")
			(hide yes)
			(effects
				(font
					(size 1.016 1.016)
					(thickness 0.1524)
				)
			)
		)
		(property "Device Type" "SOT23DGS2D4H35"
			(at 0.127 -10.4902 0)
			(unlocked yes)
			(layer "F.Fab")
			(hide yes)
			(effects
				(font
					(size 1.016 1.016)
					(thickness 0.1524)
				)
			)
		)
		(duplicate_pad_numbers_are_jumpers no)
		(fp_line
			(start -1.651 -1.778)
			(end -1.651 1.778)
			(stroke
				(width 0.1524)
				(type default)
			)
			(layer "F.SilkS")
		)
		(fp_line
			(start -1.651 1.778)
			(end 1.651 1.778)
			(stroke
				(width 0.1524)
				(type default)
			)
			(layer "F.SilkS")
		)
		(fp_line
			(start 1.651 -1.778)
			(end -1.651 -1.778)
			(stroke
				(width 0.1524)
				(type default)
			)
			(layer "F.SilkS")
		)
		(fp_line
			(start 1.651 1.778)
			(end 1.651 -1.778)
			(stroke
				(width 0.1524)
				(type default)
			)
			(layer "F.SilkS")
		)
		(fp_poly
			(pts
				(xy -1.778 1.8796) (xy -1.778 -1.8796) (xy 1.778 -1.8796) (xy 1.778 1.8796)
			)
			(stroke
				(width 0)
				(type default)
			)
			(fill no)
			(layer "F.CrtYd")
		)
		(fp_poly
			(pts
				(xy -1.778 1.8796) (xy -1.778 -1.8796) (xy 1.778 -1.8796) (xy 1.778 1.8796)
			)
			(stroke
				(width 0)
				(type default)
			)
			(fill no)
			(layer "F.Fab")
		)
		(pad "D" smd custom
			(at 0 -0.9525)
			(size 0.1905 0.1905)
			(layers "F.Cu" "F.Mask" "F.Paste")
			(net "P3V3_STBY_A")
			(options
				(clearance outline)
				(anchor circle)
			)
			(primitives
				(gr_poly
					(pts
						(arc
							(start -0.1778 0.5715)
							(mid -0.321484 0.511984)
							(end -0.381 0.3683)
						)
						(arc
							(start -0.381 -0.3683)
							(mid -0.321484 -0.511984)
							(end -0.1778 -0.5715)
						)
						(arc
							(start 0.1778 -0.5715)
							(mid 0.321484 -0.511984)
							(end 0.381 -0.3683)
						)
						(arc
							(start 0.381 0.3683)
							(mid 0.321484 0.511984)
							(end 0.1778 0.5715)
						)
					)
					(width 0)
					(fill yes)
				)
			)
		)
		(pad "G" smd custom
			(at -0.98425 0.9525)
			(size 0.1905 0.1905)
			(layers "F.Cu" "F.Mask" "F.Paste")
			(net "SCC_FULL_PWR_EN_5V")
			(options
				(clearance outline)
				(anchor circle)
			)
			(primitives
				(gr_poly
					(pts
						(arc
							(start -0.1778 0.5715)
							(mid -0.321484 0.511984)
							(end -0.381 0.3683)
						)
						(arc
							(start -0.381 -0.3683)
							(mid -0.321484 -0.511984)
							(end -0.1778 -0.5715)
						)
						(arc
							(start 0.1778 -0.5715)
							(mid 0.321484 -0.511984)
							(end 0.381 -0.3683)
						)
						(arc
							(start 0.381 0.3683)
							(mid 0.321484 0.511984)
							(end 0.1778 0.5715)
						)
					)
					(width 0)
					(fill yes)
				)
			)
		)
		(pad "S" smd custom
			(at 0.98425 0.9525)
			(size 0.1905 0.1905)
			(layers "F.Cu" "F.Mask" "F.Paste")
			(net "GPIO_VCC_U8")
			(options
				(clearance outline)
				(anchor circle)
			)
			(primitives
				(gr_poly
					(pts
						(arc
							(start -0.1778 0.5715)
							(mid -0.321484 0.511984)
							(end -0.381 0.3683)
						)
						(arc
							(start -0.381 -0.3683)
							(mid -0.321484 -0.511984)
							(end -0.1778 -0.5715)
						)
						(arc
							(start 0.1778 -0.5715)
							(mid 0.321484 -0.511984)
							(end 0.381 -0.3683)
						)
						(arc
							(start 0.381 0.3683)
							(mid 0.321484 0.511984)
							(end 0.1778 0.5715)
						)
					)
					(width 0)
					(fill yes)
				)
			)
		)
	)
	(footprint ""
		(layer "F.Cu")
		(at 140.915898 -64.683894 -90)
		(property "Reference" "C408"
			(at 0 0 270)
			(layer "F.SilkS")
			(hide yes)
			(effects
				(font
					(size 1.27 1.27)
				)
			)
		)
		(property "Value" "SC4D7U25V5KX-1-GP"
			(at -0.0762 -6.1214 270)
			(unlocked yes)
			(layer "F.Fab")
			(hide yes)
			(effects
				(font
					(size 1.016 1.016)
					(thickness 0.1524)
				)
			)
		)
		(property "Device Type" "C805H58"
			(at -0.0762 -8.1534 270)
			(unlocked yes)
			(layer "F.Fab")
			(hide yes)
			(effects
				(font
					(size 1.016 1.016)
					(thickness 0.1524)
				)
			)
		)
		(duplicate_pad_numbers_are_jumpers no)
		(fp_line
			(start 0.635 0)
			(end -0.635 0)
			(stroke
				(width 0.508)
				(type default)
			)
			(layer "F.SilkS")
		)
		(fp_rect
			(start -0.9652 1.778)
			(end 0.9652 -1.778)
			(stroke
				(width 0)
				(type default)
			)
			(fill no)
			(layer "F.CrtYd")
		)
		(fp_poly
			(pts
				(xy -0.9652 -1.778) (xy 0.9652 -1.778) (xy 0.9652 1.778) (xy -0.9652 1.778)
			)
			(stroke
				(width 0)
				(type default)
			)
			(fill no)
			(layer "F.Fab")
		)
		(pad "1" smd rect
			(at 0 -0.9652 270)
			(size 1.397 1.143)
			(layers "F.Cu" "F.Mask" "F.Paste")
			(net "P12V_HDD28")
		)
		(pad "2" smd rect
			(at 0 0.9652 270)
			(size 1.397 1.143)
			(layers "F.Cu" "F.Mask" "F.Paste")
			(net "GND")
		)
	)
	(footprint ""
		(layer "F.Cu")
		(at 230.7844 -384.2004 -90)
		(property "Reference" "R1145"
			(at 0 0 270)
			(layer "F.SilkS")
			(hide yes)
			(effects
				(font
					(size 1.27 1.27)
				)
			)
		)
		(property "Value" "0R2J-2-GP"
			(at 0.064008 -3.993896 270)
			(unlocked yes)
			(layer "F.Fab")
			(hide yes)
			(effects
				(font
					(size 1.016 1.016)
					(thickness 0.1524)
				)
			)
		)
		(property "Device Type" "R402H16"
			(at 0.064008 -5.517896 270)
			(unlocked yes)
			(layer "F.Fab")
			(hide yes)
			(effects
				(font
					(size 1.016 1.016)
					(thickness 0.1524)
				)
			)
		)
		(duplicate_pad_numbers_are_jumpers no)
		(fp_line
			(start -0.508 -0.9398)
			(end -0.508 0.9398)
			(stroke
				(width 0.1524)
				(type default)
			)
			(layer "F.SilkS")
		)
		(fp_line
			(start 0.508 -0.9398)
			(end -0.508 -0.9398)
			(stroke
				(width 0.1524)
				(type default)
			)
			(layer "F.SilkS")
		)
		(fp_rect
			(start -0.508 0.9398)
			(end 0.508 -0.9398)
			(stroke
				(width 0)
				(type default)
			)
			(fill no)
			(layer "F.CrtYd")
		)
		(fp_rect
			(start -0.508 0.9398)
			(end 0.508 -0.9398)
			(stroke
				(width 0)
				(type default)
			)
			(fill no)
			(layer "F.Fab")
		)
		(pad "1" smd custom
			(at 0 -0.4445 270)
			(size 0.1397 0.1397)
			(layers "F.Cu" "F.Mask" "F.Paste")
			(net "MB3_SDA_R")
			(options
				(clearance outline)
				(anchor circle)
			)
			(primitives
				(gr_poly
					(pts
						(arc
							(start -0.1778 -0.2794)
							(mid -0.249642 -0.249642)
							(end -0.2794 -0.1778)
						)
						(arc
							(start -0.2794 0.1778)
							(mid -0.249642 0.249642)
							(end -0.1778 0.2794)
						)
						(arc
							(start 0.1778 0.2794)
							(mid 0.249642 0.249642)
							(end 0.2794 0.1778)
						)
						(arc
							(start 0.2794 -0.1778)
							(mid 0.249642 -0.249642)
							(end 0.1778 -0.2794)
						)
					)
					(width 0)
					(fill yes)
				)
			)
		)
		(pad "2" smd custom
			(at 0 0.4445 270)
			(size 0.1397 0.1397)
			(layers "F.Cu" "F.Mask" "F.Paste")
			(net "I2C_DPB_A_SDA_BUF")
			(options
				(clearance outline)
				(anchor circle)
			)
			(primitives
				(gr_poly
					(pts
						(arc
							(start -0.1778 -0.2794)
							(mid -0.249642 -0.249642)
							(end -0.2794 -0.1778)
						)
						(arc
							(start -0.2794 0.1778)
							(mid -0.249642 0.249642)
							(end -0.1778 0.2794)
						)
						(arc
							(start 0.1778 0.2794)
							(mid 0.249642 0.249642)
							(end 0.2794 0.1778)
						)
						(arc
							(start 0.2794 -0.1778)
							(mid 0.249642 -0.249642)
							(end 0.1778 -0.2794)
						)
					)
					(width 0)
					(fill yes)
				)
			)
		)
	)
	(footprint ""
		(layer "F.Cu")
		(at 78.298548 -162.183318 180)
		(property "Reference" "R468"
			(at 0 0 180)
			(layer "F.SilkS")
			(hide yes)
			(effects
				(font
					(size 1.27 1.27)
				)
			)
		)
		(property "Value" "200KR2F-L-GP"
			(at 0.064008 -3.993896 180)
			(unlocked yes)
			(layer "F.Fab")
			(hide yes)
			(effects
				(font
					(size 1.016 1.016)
					(thickness 0.1524)
				)
			)
		)
		(property "Device Type" "R402H16"
			(at 0.064008 -5.517896 180)
			(unlocked yes)
			(layer "F.Fab")
			(hide yes)
			(effects
				(font
					(size 1.016 1.016)
					(thickness 0.1524)
				)
			)
		)
		(duplicate_pad_numbers_are_jumpers no)
		(fp_line
			(start 0.508 -0.9398)
			(end -0.508 -0.9398)
			(stroke
				(width 0.1524)
				(type default)
			)
			(layer "F.SilkS")
		)
		(fp_line
			(start -0.508 -0.9398)
			(end -0.508 0.9398)
			(stroke
				(width 0.1524)
				(type default)
			)
			(layer "F.SilkS")
		)
		(fp_rect
			(start -0.508 0.9398)
			(end 0.508 -0.9398)
			(stroke
				(width 0)
				(type default)
			)
			(fill no)
			(layer "F.CrtYd")
		)
		(fp_rect
			(start -0.508 0.9398)
			(end 0.508 -0.9398)
			(stroke
				(width 0)
				(type default)
			)
			(fill no)
			(layer "F.Fab")
		)
		(pad "1" smd custom
			(at 0 -0.4445 180)
			(size 0.1397 0.1397)
			(layers "F.Cu" "F.Mask" "F.Paste")
			(net "SW_HDD_R14")
			(options
				(clearance outline)
				(anchor circle)
			)
			(primitives
				(gr_poly
					(pts
						(arc
							(start -0.1778 -0.2794)
							(mid -0.249642 -0.249642)
							(end -0.2794 -0.1778)
						)
						(arc
							(start -0.2794 0.1778)
							(mid -0.249642 0.249642)
							(end -0.1778 0.2794)
						)
						(arc
							(start 0.1778 0.2794)
							(mid 0.249642 0.249642)
							(end 0.2794 0.1778)
						)
						(arc
							(start 0.2794 -0.1778)
							(mid 0.249642 -0.249642)
							(end 0.1778 -0.2794)
						)
					)
					(width 0)
					(fill yes)
				)
			)
		)
		(pad "2" smd custom
			(at 0 0.4445 180)
			(size 0.1397 0.1397)
			(layers "F.Cu" "F.Mask" "F.Paste")
			(net "SW_HDD_N14")
			(options
				(clearance outline)
				(anchor circle)
			)
			(primitives
				(gr_poly
					(pts
						(arc
							(start -0.1778 -0.2794)
							(mid -0.249642 -0.249642)
							(end -0.2794 -0.1778)
						)
						(arc
							(start -0.2794 0.1778)
							(mid -0.249642 0.249642)
							(end -0.1778 0.2794)
						)
						(arc
							(start 0.1778 0.2794)
							(mid 0.249642 0.249642)
							(end 0.2794 0.1778)
						)
						(arc
							(start 0.2794 -0.1778)
							(mid 0.249642 -0.249642)
							(end 0.1778 -0.2794)
						)
					)
					(width 0)
					(fill yes)
				)
			)
		)
	)
	(footprint ""
		(layer "F.Cu")
		(at 319.9892 -158.939992 90)
		(property "Reference" "VIA7"
			(at 0 0 90)
			(layer "F.SilkS")
			(hide yes)
			(effects
				(font
					(size 1.27 1.27)
				)
			)
		)
		(property "Value" "100OHM-8L-1D6MM-L18L16-GP"
			(at -3.7211 -4.5085 90)
			(unlocked yes)
			(layer "F.Fab")
			(hide yes)
			(effects
				(font
					(size 1.016 1.016)
					(thickness 0.1524)
				)
			)
		)
		(property "Device Type" "VIA-PCIE-4P-394076"
			(at -3.7211 -6.0325 90)
			(unlocked yes)
			(layer "F.Fab")
			(hide yes)
			(effects
				(font
					(size 1.016 1.016)
					(thickness 0.1524)
				)
			)
		)
		(duplicate_pad_numbers_are_jumpers no)
		(fp_rect
			(start -1.9685 0.381)
			(end 1.9685 -0.381)
			(stroke
				(width 0)
				(type default)
			)
			(fill no)
			(layer "F.CrtYd")
		)
		(fp_rect
			(start -1.9685 0.381)
			(end 1.9685 -0.381)
			(stroke
				(width 0)
				(type default)
			)
			(fill no)
			(layer "F.Fab")
		)
		(pad "1" thru_hole circle
			(at -1.5875 0 90)
			(size 0.508 0.508)
			(drill 0.254)
			(layers "*.Cu" "*.Mask")
			(remove_unused_layers no)
			(net "GND")
			(clearance 0.127)
			(thermal_gap 0.127)
		)
		(pad "2" thru_hole circle
			(at -0.5715 0 90)
			(size 0.508 0.508)
			(drill 0.254)
			(layers "*.Cu" "*.Mask")
			(remove_unused_layers no)
			(net "PHY_SCC_A_TO_DRV_A_18_DP")
			(clearance 0.127)
			(thermal_gap 0.127)
		)
		(pad "3" thru_hole circle
			(at 0.5715 0 90)
			(size 0.508 0.508)
			(drill 0.254)
			(layers "*.Cu" "*.Mask")
			(remove_unused_layers no)
			(net "PHY_SCC_A_TO_DRV_A_18_DN")
			(clearance 0.127)
			(thermal_gap 0.127)
		)
		(pad "4" thru_hole circle
			(at 1.5875 0 90)
			(size 0.508 0.508)
			(drill 0.254)
			(layers "*.Cu" "*.Mask")
			(remove_unused_layers no)
			(net "GND")
			(clearance 0.127)
			(thermal_gap 0.127)
		)
	)
	(footprint ""
		(layer "F.Cu")
		(at 259.3848 -280.0604)
		(property "Reference" "C33"
			(at 0 0 0)
			(layer "F.SilkS")
			(hide yes)
			(effects
				(font
					(size 1.27 1.27)
				)
			)
		)
		(property "Value" "SCD1U16V2KX-3GP"
			(at 1.1811 -2.7051 0)
			(unlocked yes)
			(layer "F.Fab")
			(hide yes)
			(effects
				(font
					(size 1.016 1.016)
					(thickness 0.1524)
				)
			)
		)
		(property "Device Type" "C402H22"
			(at 1.1811 -4.2291 0)
			(unlocked yes)
			(layer "F.Fab")
			(hide yes)
			(effects
				(font
					(size 1.016 1.016)
					(thickness 0.1524)
				)
			)
		)
		(duplicate_pad_numbers_are_jumpers no)
		(fp_rect
			(start -0.4318 0.9525)
			(end 0.4318 -0.9525)
			(stroke
				(width 0)
				(type default)
			)
			(fill no)
			(layer "F.CrtYd")
		)
		(fp_rect
			(start -0.4318 0.9525)
			(end 0.4318 -0.9525)
			(stroke
				(width 0)
				(type default)
			)
			(fill no)
			(layer "F.Fab")
		)
		(pad "1" smd custom
			(at 0 -0.4445)
			(size 0.1524 0.1524)
			(layers "F.Cu" "F.Mask" "F.Paste")
			(net "P3V3_STBY_A")
			(options
				(clearance outline)
				(anchor circle)
			)
			(primitives
				(gr_poly
					(pts
						(arc
							(start 0.3048 -0.2032)
							(mid 0.275042 -0.275042)
							(end 0.2032 -0.3048)
						)
						(arc
							(start -0.2032 -0.3048)
							(mid -0.275042 -0.275042)
							(end -0.3048 -0.2032)
						)
						(arc
							(start -0.3048 0.2032)
							(mid -0.275042 0.275042)
							(end -0.2032 0.3048)
						)
						(arc
							(start 0.2032 0.3048)
							(mid 0.275042 0.275042)
							(end 0.3048 0.2032)
						)
					)
					(width 0)
					(fill yes)
				)
			)
		)
		(pad "2" smd custom
			(at 0 0.4445)
			(size 0.1524 0.1524)
			(layers "F.Cu" "F.Mask" "F.Paste")
			(net "GND")
			(options
				(clearance outline)
				(anchor circle)
			)
			(primitives
				(gr_poly
					(pts
						(arc
							(start 0.3048 -0.2032)
							(mid 0.275042 -0.275042)
							(end 0.2032 -0.3048)
						)
						(arc
							(start -0.2032 -0.3048)
							(mid -0.275042 -0.275042)
							(end -0.3048 -0.2032)
						)
						(arc
							(start -0.3048 0.2032)
							(mid -0.275042 0.275042)
							(end -0.2032 0.3048)
						)
						(arc
							(start 0.2032 0.3048)
							(mid 0.275042 0.275042)
							(end 0.3048 0.2032)
						)
					)
					(width 0)
					(fill yes)
				)
			)
		)
	)
	(footprint ""
		(layer "F.Cu")
		(at 343.611962 -242.809776 180)
		(property "Reference" "Q234"
			(at 0 0 180)
			(layer "F.SilkS")
			(hide yes)
			(effects
				(font
					(size 1.27 1.27)
				)
			)
		)
		(property "Value" "2N7002K-2-GP"
			(at 0.127 -8.9662 180)
			(unlocked yes)
			(layer "F.Fab")
			(hide yes)
			(effects
				(font
					(size 1.016 1.016)
					(thickness 0.1524)
				)
			)
		)
		(property "Device Type" "SOT23DGS2D4H44"
			(at 0.127 -10.4902 180)
			(unlocked yes)
			(layer "F.Fab")
			(hide yes)
			(effects
				(font
					(size 1.016 1.016)
					(thickness 0.1524)
				)
			)
		)
		(duplicate_pad_numbers_are_jumpers no)
		(fp_line
			(start 1.651 1.778)
			(end 1.651 -1.778)
			(stroke
				(width 0.1524)
				(type default)
			)
			(layer "F.SilkS")
		)
		(fp_line
			(start 1.651 -1.778)
			(end -1.651 -1.778)
			(stroke
				(width 0.1524)
				(type default)
			)
			(layer "F.SilkS")
		)
		(fp_line
			(start -1.651 1.778)
			(end 1.651 1.778)
			(stroke
				(width 0.1524)
				(type default)
			)
			(layer "F.SilkS")
		)
		(fp_line
			(start -1.651 -1.778)
			(end -1.651 1.778)
			(stroke
				(width 0.1524)
				(type default)
			)
			(layer "F.SilkS")
		)
		(fp_poly
			(pts
				(xy -1.778 1.8796) (xy -1.778 -1.8796) (xy 1.778 -1.8796) (xy 1.778 1.8796)
			)
			(stroke
				(width 0)
				(type default)
			)
			(fill no)
			(layer "F.CrtYd")
		)
		(fp_poly
			(pts
				(xy -1.778 1.8796) (xy -1.778 -1.8796) (xy 1.778 -1.8796) (xy 1.778 1.8796)
			)
			(stroke
				(width 0)
				(type default)
			)
			(fill no)
			(layer "F.Fab")
		)
		(pad "D" smd custom
			(at 0 -0.9525 180)
			(size 0.1905 0.1905)
			(layers "F.Cu" "F.Mask" "F.Paste")
			(net "FLT_HDD7_N")
			(options
				(clearance outline)
				(anchor circle)
			)
			(primitives
				(gr_poly
					(pts
						(arc
							(start -0.1778 0.5715)
							(mid -0.321484 0.511984)
							(end -0.381 0.3683)
						)
						(arc
							(start -0.381 -0.3683)
							(mid -0.321484 -0.511984)
							(end -0.1778 -0.5715)
						)
						(arc
							(start 0.1778 -0.5715)
							(mid 0.321484 -0.511984)
							(end 0.381 -0.3683)
						)
						(arc
							(start 0.381 0.3683)
							(mid 0.321484 0.511984)
							(end 0.1778 0.5715)
						)
					)
					(width 0)
					(fill yes)
				)
			)
		)
		(pad "G" smd custom
			(at -0.98425 0.9525 180)
			(size 0.1905 0.1905)
			(layers "F.Cu" "F.Mask" "F.Paste")
			(net "DRIVE_A_7_FLT_LED")
			(options
				(clearance outline)
				(anchor circle)
			)
			(primitives
				(gr_poly
					(pts
						(arc
							(start -0.1778 0.5715)
							(mid -0.321484 0.511984)
							(end -0.381 0.3683)
						)
						(arc
							(start -0.381 -0.3683)
							(mid -0.321484 -0.511984)
							(end -0.1778 -0.5715)
						)
						(arc
							(start 0.1778 -0.5715)
							(mid 0.321484 -0.511984)
							(end 0.381 -0.3683)
						)
						(arc
							(start 0.381 0.3683)
							(mid 0.321484 0.511984)
							(end 0.1778 0.5715)
						)
					)
					(width 0)
					(fill yes)
				)
			)
		)
		(pad "S" smd custom
			(at 0.98425 0.9525 180)
			(size 0.1905 0.1905)
			(layers "F.Cu" "F.Mask" "F.Paste")
			(net "GND")
			(options
				(clearance outline)
				(anchor circle)
			)
			(primitives
				(gr_poly
					(pts
						(arc
							(start -0.1778 0.5715)
							(mid -0.321484 0.511984)
							(end -0.381 0.3683)
						)
						(arc
							(start -0.381 -0.3683)
							(mid -0.321484 -0.511984)
							(end -0.1778 -0.5715)
						)
						(arc
							(start 0.1778 -0.5715)
							(mid 0.321484 -0.511984)
							(end 0.381 -0.3683)
						)
						(arc
							(start 0.381 0.3683)
							(mid 0.321484 0.511984)
							(end 0.1778 0.5715)
						)
					)
					(width 0)
					(fill yes)
				)
			)
		)
	)
	(footprint ""
		(layer "F.Cu")
		(at 477.2406 -163.068 180)
		(property "Reference" "R659"
			(at 0 0 180)
			(layer "F.SilkS")
			(hide yes)
			(effects
				(font
					(size 1.27 1.27)
				)
			)
		)
		(property "Value" "10KR2F-2-GP"
			(at 0.064008 -3.993896 180)
			(unlocked yes)
			(layer "F.Fab")
			(hide yes)
			(effects
				(font
					(size 1.016 1.016)
					(thickness 0.1524)
				)
			)
		)
		(property "Device Type" "R402H16"
			(at 0.064008 -5.517896 180)
			(unlocked yes)
			(layer "F.Fab")
			(hide yes)
			(effects
				(font
					(size 1.016 1.016)
					(thickness 0.1524)
				)
			)
		)
		(duplicate_pad_numbers_are_jumpers no)
		(fp_line
			(start 0.508 -0.9398)
			(end -0.508 -0.9398)
			(stroke
				(width 0.1524)
				(type default)
			)
			(layer "F.SilkS")
		)
		(fp_line
			(start -0.508 -0.9398)
			(end -0.508 0.9398)
			(stroke
				(width 0.1524)
				(type default)
			)
			(layer "F.SilkS")
		)
		(fp_rect
			(start -0.508 0.9398)
			(end 0.508 -0.9398)
			(stroke
				(width 0)
				(type default)
			)
			(fill no)
			(layer "F.CrtYd")
		)
		(fp_rect
			(start -0.508 0.9398)
			(end 0.508 -0.9398)
			(stroke
				(width 0)
				(type default)
			)
			(fill no)
			(layer "F.Fab")
		)
		(pad "1" smd custom
			(at 0 -0.4445 180)
			(size 0.1397 0.1397)
			(layers "F.Cu" "F.Mask" "F.Paste")
			(net "P3V3_STBY_A")
			(options
				(clearance outline)
				(anchor circle)
			)
			(primitives
				(gr_poly
					(pts
						(arc
							(start -0.1778 -0.2794)
							(mid -0.249642 -0.249642)
							(end -0.2794 -0.1778)
						)
						(arc
							(start -0.2794 0.1778)
							(mid -0.249642 0.249642)
							(end -0.1778 0.2794)
						)
						(arc
							(start 0.1778 0.2794)
							(mid 0.249642 0.249642)
							(end 0.2794 0.1778)
						)
						(arc
							(start 0.2794 -0.1778)
							(mid 0.249642 -0.249642)
							(end 0.1778 -0.2794)
						)
					)
					(width 0)
					(fill yes)
				)
			)
		)
		(pad "2" smd custom
			(at 0 0.4445 180)
			(size 0.1397 0.1397)
			(layers "F.Cu" "F.Mask" "F.Paste")
			(net "HDD_PRSNT_23")
			(options
				(clearance outline)
				(anchor circle)
			)
			(primitives
				(gr_poly
					(pts
						(arc
							(start -0.1778 -0.2794)
							(mid -0.249642 -0.249642)
							(end -0.2794 -0.1778)
						)
						(arc
							(start -0.2794 0.1778)
							(mid -0.249642 0.249642)
							(end -0.1778 0.2794)
						)
						(arc
							(start 0.1778 0.2794)
							(mid 0.249642 0.249642)
							(end 0.2794 0.1778)
						)
						(arc
							(start 0.2794 -0.1778)
							(mid 0.249642 -0.249642)
							(end 0.1778 -0.2794)
						)
					)
					(width 0)
					(fill yes)
				)
			)
		)
	)
	(footprint ""
		(layer "F.Cu")
		(at 202.300078 -183.805576)
		(property "Reference" ""
			(at 0 0 0)
			(layer "F.SilkS")
			(hide yes)
			(effects
				(font
					(size 1.27 1.27)
				)
			)
		)
		(property "Value" "*"
			(at -8.398764 -8.057642 0)
			(unlocked yes)
			(layer "F.Fab")
			(hide yes)
			(effects
				(font
					(size 1.016 1.016)
					(thickness 0.1524)
				)
			)
		)
		(duplicate_pad_numbers_are_jumpers no)
		(fp_poly
			(pts
				(arc
					(start 7.3152 0)
					(mid 0 7.3152)
					(end -7.3152 0)
				)
				(arc
					(start -7.3152 -5.9944)
					(mid 0 -13.3096)
					(end 7.3152 -5.9944)
				)
			)
			(stroke
				(width 0)
				(type default)
			)
			(fill no)
			(layer "B.CrtYd")
		)
		(fp_poly
			(pts
				(arc
					(start 7.3152 0)
					(mid 0 7.3152)
					(end -7.3152 0)
				)
				(arc
					(start -7.3152 -5.9944)
					(mid 0 -13.3096)
					(end 7.3152 -5.9944)
				)
			)
			(stroke
				(width 0)
				(type default)
			)
			(fill no)
			(layer "F.CrtYd")
		)
		(fp_poly
			(pts
				(arc
					(start 7.3152 0)
					(mid 0 7.3152)
					(end -7.3152 0)
				)
				(arc
					(start -7.3152 -5.9944)
					(mid 0 -13.3096)
					(end 7.3152 -5.9944)
				)
			)
			(stroke
				(width 0)
				(type default)
			)
			(fill no)
			(layer "B.Fab")
		)
		(fp_poly
			(pts
				(arc
					(start 7.3152 0)
					(mid 0 7.3152)
					(end -7.3152 0)
				)
				(arc
					(start -7.3152 -5.9944)
					(mid 0 -13.3096)
					(end 7.3152 -5.9944)
				)
			)
			(stroke
				(width 0)
				(type default)
			)
			(fill no)
			(layer "F.Fab")
		)
		(pad "1" thru_hole oval
			(at 0 0)
			(size 14.0208 20.0152)
			(drill 0.0254
				(offset 0 -2.9972)
			)
			(layers "*.Cu" "*.Mask")
			(remove_unused_layers no)
			(net "Net_67")
			(clearance -1.002284)
			(thermal_gap 0.1524)
			(padstack
				(mode front_inner_back)
				(layer "Inner"
					(shape custom)
					(size 2.928012 2.928012)
					(options
						(anchor circle)
					)
					(primitives
						(gr_poly
							(pts
								(arc
									(start 4.571746 -2.084324)
									(mid 0.000333 7.430372)
									(end -4.571492 -2.084324)
								)
								(arc
									(start -4.571492 -2.084324)
									(mid -3.570296 -3.611977)
									(end -2.875026 -5.30098)
								)
								(arc
									(start -2.875026 -5.30098)
									(mid 0.000217 -7.43089)
									(end 2.87528 -5.30098)
								)
								(arc
									(start 2.87528 -5.30098)
									(mid 3.570511 -3.611956)
									(end 4.571746 -2.084324)
								)
							)
							(width 0)
							(fill yes)
						)
					)
					(clearance 0.1524)
				)
				(layer "B.Cu"
					(shape oval)
					(size 14.0208 20.0152)
					(offset 0 -2.9972)
					(clearance -1.002284)
				)
			)
		)
		(zone
			(layers "F.Cu" "B.Cu" "In1.Cu" "In2.Cu" "In3.Cu" "In4.Cu" "In5.Cu" "In6.Cu"
				"In7.Cu" "In8.Cu" "In9.Cu" "In10.Cu"
			)
			(hatch none 0.5)
			(connect_pads
				(clearance 0)
			)
			(min_thickness 0.25)
			(keepout
				(tracks not_allowed)
				(vias allowed)
				(pads allowed)
				(copperpour not_allowed)
				(footprints allowed)
			)
			(placement
				(enabled no)
				(sheetname "")
			)
			(fill
				(thermal_gap 0.5)
				(thermal_bridge_width 0.5)
				(island_removal_mode 0)
			)
			(polygon
				(pts
					(arc
						(start 195.289678 -189.799976)
						(mid 202.300078 -196.810376)
						(end 209.310478 -189.799976)
					)
					(arc
						(start 209.310478 -183.805576)
						(mid 202.300078 -176.795176)
						(end 195.289678 -183.805576)
					)
				)
			)
		)
	)
	(footprint ""
		(layer "F.Cu")
		(at 80.24495 -127.254)
		(property "Reference" "R289"
			(at 0 0 0)
			(layer "F.SilkS")
			(hide yes)
			(effects
				(font
					(size 1.27 1.27)
				)
			)
		)
		(property "Value" "130R3F-GP"
			(at -0.0254 -2.5146 0)
			(unlocked yes)
			(layer "F.Fab")
			(hide yes)
			(effects
				(font
					(size 1.016 1.016)
					(thickness 0.1524)
				)
			)
		)
		(property "Device Type" "R603H22"
			(at -0.0254 -4.0386 0)
			(unlocked yes)
			(layer "F.Fab")
			(hide yes)
			(effects
				(font
					(size 1.016 1.016)
					(thickness 0.1524)
				)
			)
		)
		(duplicate_pad_numbers_are_jumpers no)
		(fp_line
			(start -0.4826 0)
			(end -0.2032 0)
			(stroke
				(width 0.2032)
				(type default)
			)
			(layer "F.SilkS")
		)
		(fp_line
			(start 0.2032 0)
			(end 0.4826 0)
			(stroke
				(width 0.2032)
				(type default)
			)
			(layer "F.SilkS")
		)
		(fp_rect
			(start -0.5842 1.3335)
			(end 0.5842 -1.3335)
			(stroke
				(width 0)
				(type default)
			)
			(fill no)
			(layer "F.CrtYd")
		)
		(fp_rect
			(start -0.5842 1.3335)
			(end 0.5842 -1.3335)
			(stroke
				(width 0)
				(type default)
			)
			(fill no)
			(layer "F.Fab")
		)
		(pad "1" smd custom
			(at 0 -0.762)
			(size 0.2159 0.2159)
			(layers "F.Cu" "F.Mask" "F.Paste")
			(net "P5V_A_1")
			(options
				(clearance outline)
				(anchor circle)
			)
			(primitives
				(gr_poly
					(pts
						(arc
							(start -0.3302 -0.4318)
							(mid -0.402042 -0.402042)
							(end -0.4318 -0.3302)
						)
						(arc
							(start -0.4318 0.3302)
							(mid -0.402042 0.402042)
							(end -0.3302 0.4318)
						)
						(arc
							(start 0.3302 0.4318)
							(mid 0.402042 0.402042)
							(end 0.4318 0.3302)
						)
						(arc
							(start 0.4318 -0.3302)
							(mid 0.402042 -0.402042)
							(end 0.3302 -0.4318)
						)
					)
					(width 0)
					(fill yes)
				)
			)
		)
		(pad "2" smd custom
			(at 0 0.762)
			(size 0.2159 0.2159)
			(layers "F.Cu" "F.Mask" "F.Paste")
			(net "FLT_HDD14")
			(options
				(clearance outline)
				(anchor circle)
			)
			(primitives
				(gr_poly
					(pts
						(arc
							(start -0.3302 -0.4318)
							(mid -0.402042 -0.402042)
							(end -0.4318 -0.3302)
						)
						(arc
							(start -0.4318 0.3302)
							(mid -0.402042 0.402042)
							(end -0.3302 0.4318)
						)
						(arc
							(start 0.3302 0.4318)
							(mid 0.402042 0.402042)
							(end 0.4318 0.3302)
						)
						(arc
							(start 0.4318 -0.3302)
							(mid 0.402042 -0.402042)
							(end 0.3302 -0.4318)
						)
					)
					(width 0)
					(fill yes)
				)
			)
		)
	)
	(footprint ""
		(layer "F.Cu")
		(at 113.175542 -280.879804)
		(property "Reference" "R213"
			(at 0 0 0)
			(layer "F.SilkS")
			(hide yes)
			(effects
				(font
					(size 1.27 1.27)
				)
			)
		)
		(property "Value" "4K7R2J-2-GP"
			(at 0.064008 -3.993896 0)
			(unlocked yes)
			(layer "F.Fab")
			(hide yes)
			(effects
				(font
					(size 1.016 1.016)
					(thickness 0.1524)
				)
			)
		)
		(property "Device Type" "R402H16"
			(at 0.064008 -5.517896 0)
			(unlocked yes)
			(layer "F.Fab")
			(hide yes)
			(effects
				(font
					(size 1.016 1.016)
					(thickness 0.1524)
				)
			)
		)
		(duplicate_pad_numbers_are_jumpers no)
		(fp_line
			(start -0.508 -0.9398)
			(end -0.508 0.9398)
			(stroke
				(width 0.1524)
				(type default)
			)
			(layer "F.SilkS")
		)
		(fp_line
			(start 0.508 -0.9398)
			(end -0.508 -0.9398)
			(stroke
				(width 0.1524)
				(type default)
			)
			(layer "F.SilkS")
		)
		(fp_rect
			(start -0.508 0.9398)
			(end 0.508 -0.9398)
			(stroke
				(width 0)
				(type default)
			)
			(fill no)
			(layer "F.CrtYd")
		)
		(fp_rect
			(start -0.508 0.9398)
			(end 0.508 -0.9398)
			(stroke
				(width 0)
				(type default)
			)
			(fill no)
			(layer "F.Fab")
		)
		(pad "1" smd custom
			(at 0 -0.4445)
			(size 0.1397 0.1397)
			(layers "F.Cu" "F.Mask" "F.Paste")
			(net "P12V_A")
			(options
				(clearance outline)
				(anchor circle)
			)
			(primitives
				(gr_poly
					(pts
						(arc
							(start -0.1778 -0.2794)
							(mid -0.249642 -0.249642)
							(end -0.2794 -0.1778)
						)
						(arc
							(start -0.2794 0.1778)
							(mid -0.249642 0.249642)
							(end -0.1778 0.2794)
						)
						(arc
							(start 0.1778 0.2794)
							(mid 0.249642 0.249642)
							(end 0.2794 0.1778)
						)
						(arc
							(start 0.2794 -0.1778)
							(mid 0.249642 -0.249642)
							(end 0.1778 -0.2794)
						)
					)
					(width 0)
					(fill yes)
				)
			)
		)
		(pad "2" smd custom
			(at 0 0.4445)
			(size 0.1397 0.1397)
			(layers "F.Cu" "F.Mask" "F.Paste")
			(net "SW_HDD_R3")
			(options
				(clearance outline)
				(anchor circle)
			)
			(primitives
				(gr_poly
					(pts
						(arc
							(start -0.1778 -0.2794)
							(mid -0.249642 -0.249642)
							(end -0.2794 -0.1778)
						)
						(arc
							(start -0.2794 0.1778)
							(mid -0.249642 0.249642)
							(end -0.1778 0.2794)
						)
						(arc
							(start 0.1778 0.2794)
							(mid 0.249642 0.249642)
							(end 0.2794 0.1778)
						)
						(arc
							(start 0.2794 -0.1778)
							(mid 0.249642 -0.249642)
							(end 0.1778 -0.2794)
						)
					)
					(width 0)
					(fill yes)
				)
			)
		)
	)
	(footprint ""
		(layer "F.Cu")
		(at 229.849934 6.500114)
		(property "Reference" ""
			(at 0 0 0)
			(layer "F.SilkS")
			(hide yes)
			(effects
				(font
					(size 1.27 1.27)
				)
			)
		)
		(property "Value" "*"
			(at -4.9911 1.5494 0)
			(unlocked yes)
			(layer "F.Fab")
			(hide yes)
			(effects
				(font
					(size 1.016 1.016)
					(thickness 0.1524)
				)
			)
		)
		(duplicate_pad_numbers_are_jumpers no)
		(fp_poly
			(pts
				(arc
					(start 4.064 0)
					(mid -4.064 0)
					(end 4.064 0)
				)
			)
			(stroke
				(width 0)
				(type default)
			)
			(fill no)
			(layer "B.CrtYd")
		)
		(fp_poly
			(pts
				(arc
					(start 4.064 0)
					(mid -4.064 0)
					(end 4.064 0)
				)
			)
			(stroke
				(width 0)
				(type default)
			)
			(fill no)
			(layer "F.CrtYd")
		)
		(fp_poly
			(pts
				(arc
					(start 4.064 0)
					(mid -4.064 0)
					(end 4.064 0)
				)
			)
			(stroke
				(width 0)
				(type default)
			)
			(fill no)
			(layer "B.Fab")
		)
		(fp_poly
			(pts
				(arc
					(start 4.064 0)
					(mid -4.064 0)
					(end 4.064 0)
				)
			)
			(stroke
				(width 0)
				(type default)
			)
			(fill no)
			(layer "F.Fab")
		)
		(pad "1" thru_hole circle
			(at 0 0)
			(size 7.5184 7.5184)
			(drill oval 6.223 4.2164)
			(layers "*.Cu" "*.Mask")
			(remove_unused_layers no)
			(net "Net_34")
			(clearance -1.143)
			(thermal_gap 0.1524)
			(padstack
				(mode front_inner_back)
				(layer "Inner"
					(shape oval)
					(size 4.9276 6.9342)
					(clearance 0.1524)
				)
				(layer "B.Cu"
					(shape circle)
					(size 7.5184 7.5184)
					(clearance -1.143)
				)
			)
		)
		(zone
			(layers "F.Cu" "B.Cu" "In1.Cu" "In2.Cu" "In3.Cu" "In4.Cu" "In5.Cu" "In6.Cu"
				"In7.Cu" "In8.Cu" "In9.Cu" "In10.Cu"
			)
			(hatch none 0.5)
			(connect_pads
				(clearance 0)
			)
			(min_thickness 0.25)
			(keepout
				(tracks not_allowed)
				(vias allowed)
				(pads allowed)
				(copperpour not_allowed)
				(footprints allowed)
			)
			(placement
				(enabled no)
				(sheetname "")
			)
			(fill
				(thermal_gap 0.5)
				(thermal_bridge_width 0.5)
				(island_removal_mode 0)
			)
			(polygon
				(pts
					(arc
						(start 233.609134 6.500114)
						(mid 226.090734 6.500114)
						(end 233.609134 6.500114)
					)
				)
			)
		)
	)
	(footprint ""
		(layer "F.Cu")
		(at 158.663386 -274.219416 90)
		(property "Reference" "C90"
			(at 0 0 90)
			(layer "F.SilkS")
			(hide yes)
			(effects
				(font
					(size 1.27 1.27)
				)
			)
		)
		(property "Value" "SCD01U16V1KX-GP"
			(at -2.8321 -1.7399 90)
			(unlocked yes)
			(layer "F.Fab")
			(hide yes)
			(effects
				(font
					(size 1.016 1.016)
					(thickness 0.1524)
				)
			)
		)
		(property "Device Type" "C0201H13"
			(at -2.8321 -3.2639 90)
			(unlocked yes)
			(layer "F.Fab")
			(hide yes)
			(effects
				(font
					(size 1.016 1.016)
					(thickness 0.1524)
				)
			)
		)
		(duplicate_pad_numbers_are_jumpers no)
		(fp_rect
			(start -0.2794 0.6477)
			(end 0.2794 -0.6477)
			(stroke
				(width 0)
				(type default)
			)
			(fill no)
			(layer "F.CrtYd")
		)
		(fp_rect
			(start -0.2794 0.6477)
			(end 0.2794 -0.6477)
			(stroke
				(width 0)
				(type default)
			)
			(fill no)
			(layer "F.Fab")
		)
		(pad "1" smd custom
			(at 0 -0.2794 90)
			(size 0.0762 0.0762)
			(layers "F.Cu" "F.Mask" "F.Paste")
			(net "SAS_HDD_RX_N4")
			(options
				(clearance outline)
				(anchor circle)
			)
			(primitives
				(gr_poly
					(pts
						(arc
							(start 0.1524 -0.127)
							(mid 0.137521 -0.162921)
							(end 0.1016 -0.1778)
						)
						(arc
							(start -0.1016 -0.1778)
							(mid -0.137521 -0.162921)
							(end -0.1524 -0.127)
						)
						(arc
							(start -0.1524 0.127)
							(mid -0.137521 0.162921)
							(end -0.1016 0.1778)
						)
						(arc
							(start 0.1016 0.1778)
							(mid 0.137521 0.162921)
							(end 0.1524 0.127)
						)
					)
					(width 0)
					(fill yes)
				)
			)
		)
		(pad "2" smd custom
			(at 0 0.2794 90)
			(size 0.0762 0.0762)
			(layers "F.Cu" "F.Mask" "F.Paste")
			(net "PHY_SCC_A_TO_DRV_A_4_DN")
			(options
				(clearance outline)
				(anchor circle)
			)
			(primitives
				(gr_poly
					(pts
						(arc
							(start 0.1524 -0.127)
							(mid 0.137521 -0.162921)
							(end 0.1016 -0.1778)
						)
						(arc
							(start -0.1016 -0.1778)
							(mid -0.137521 -0.162921)
							(end -0.1524 -0.127)
						)
						(arc
							(start -0.1524 0.127)
							(mid -0.137521 0.162921)
							(end -0.1016 0.1778)
						)
						(arc
							(start 0.1016 0.1778)
							(mid 0.137521 0.162921)
							(end 0.1524 0.127)
						)
					)
					(width 0)
					(fill yes)
				)
			)
		)
	)
	(footprint ""
		(layer "F.Cu")
		(at 443.8396 -298.704)
		(property "Reference" "TP52"
			(at 0 0 0)
			(layer "F.SilkS")
			(hide yes)
			(effects
				(font
					(size 1.27 1.27)
				)
			)
		)
		(property "Value" "TPAD32-GP"
			(at -0.0508 -1.6764 0)
			(unlocked yes)
			(layer "F.Fab")
			(hide yes)
			(effects
				(font
					(size 1.016 1.016)
					(thickness 0.1524)
				)
			)
		)
		(property "Device Type" "TPAD32"
			(at -0.0508 -3.2004 0)
			(unlocked yes)
			(layer "F.Fab")
			(hide yes)
			(effects
				(font
					(size 1.016 1.016)
					(thickness 0.1524)
				)
			)
		)
		(duplicate_pad_numbers_are_jumpers no)
		(fp_poly
			(pts
				(arc
					(start 0.4064 0)
					(mid -0.4064 0)
					(end 0.4064 0)
				)
			)
			(stroke
				(width 0)
				(type default)
			)
			(fill no)
			(layer "F.CrtYd")
		)
		(fp_poly
			(pts
				(arc
					(start 0.7112 0)
					(mid -0.7112 0)
					(end 0.7112 0)
				)
			)
			(stroke
				(width 0)
				(type default)
			)
			(fill no)
			(layer "F.Fab")
		)
		(pad "1" smd circle
			(at 0 0)
			(size 0.8128 0.8128)
			(layers "F.Cu" "F.Mask" "F.Paste")
			(net "ACT_HDD_10")
		)
	)
	(footprint ""
		(layer "F.Cu")
		(at 272.542 -359.504996 180)
		(property "Reference" "VIA33"
			(at 0 0 180)
			(layer "F.SilkS")
			(hide yes)
			(effects
				(font
					(size 1.27 1.27)
				)
			)
		)
		(property "Value" "100OHM-8L-1D6MM-L18L16-GP"
			(at -3.7211 -4.5085 180)
			(unlocked yes)
			(layer "F.Fab")
			(hide yes)
			(effects
				(font
					(size 1.016 1.016)
					(thickness 0.1524)
				)
			)
		)
		(property "Device Type" "VIA-PCIE-4P-394076"
			(at -3.7211 -6.0325 180)
			(unlocked yes)
			(layer "F.Fab")
			(hide yes)
			(effects
				(font
					(size 1.016 1.016)
					(thickness 0.1524)
				)
			)
		)
		(duplicate_pad_numbers_are_jumpers no)
		(fp_rect
			(start -1.9685 0.381)
			(end 1.9685 -0.381)
			(stroke
				(width 0)
				(type default)
			)
			(fill no)
			(layer "F.CrtYd")
		)
		(fp_rect
			(start -1.9685 0.381)
			(end 1.9685 -0.381)
			(stroke
				(width 0)
				(type default)
			)
			(fill no)
			(layer "F.Fab")
		)
		(pad "1" thru_hole circle
			(at -1.5875 0 180)
			(size 0.508 0.508)
			(drill 0.254)
			(layers "*.Cu" "*.Mask")
			(remove_unused_layers no)
			(net "GND")
			(clearance 0.127)
			(thermal_gap 0.127)
		)
		(pad "2" thru_hole circle
			(at -0.5715 0 180)
			(size 0.508 0.508)
			(drill 0.254)
			(layers "*.Cu" "*.Mask")
			(remove_unused_layers no)
			(net "PHY_SCC_A_TO_DRV_A_0_DP")
			(clearance 0.127)
			(thermal_gap 0.127)
		)
		(pad "3" thru_hole circle
			(at 0.5715 0 180)
			(size 0.508 0.508)
			(drill 0.254)
			(layers "*.Cu" "*.Mask")
			(remove_unused_layers no)
			(net "PHY_SCC_A_TO_DRV_A_0_DN")
			(clearance 0.127)
			(thermal_gap 0.127)
		)
		(pad "4" thru_hole circle
			(at 1.5875 0 180)
			(size 0.508 0.508)
			(drill 0.254)
			(layers "*.Cu" "*.Mask")
			(remove_unused_layers no)
			(net "GND")
			(clearance 0.127)
			(thermal_gap 0.127)
		)
	)
	(footprint ""
		(layer "F.Cu")
		(at 319.151 -292.143942 -90)
		(property "Reference" "R270"
			(at 0 0 270)
			(layer "F.SilkS")
			(hide yes)
			(effects
				(font
					(size 1.27 1.27)
				)
			)
		)
		(property "Value" "10KR2F-2-GP"
			(at 0.064008 -3.993896 270)
			(unlocked yes)
			(layer "F.Fab")
			(hide yes)
			(effects
				(font
					(size 1.016 1.016)
					(thickness 0.1524)
				)
			)
		)
		(property "Device Type" "R402H16"
			(at 0.064008 -5.517896 270)
			(unlocked yes)
			(layer "F.Fab")
			(hide yes)
			(effects
				(font
					(size 1.016 1.016)
					(thickness 0.1524)
				)
			)
		)
		(duplicate_pad_numbers_are_jumpers no)
		(fp_line
			(start -0.508 -0.9398)
			(end -0.508 0.9398)
			(stroke
				(width 0.1524)
				(type default)
			)
			(layer "F.SilkS")
		)
		(fp_line
			(start 0.508 -0.9398)
			(end -0.508 -0.9398)
			(stroke
				(width 0.1524)
				(type default)
			)
			(layer "F.SilkS")
		)
		(fp_rect
			(start -0.508 0.9398)
			(end 0.508 -0.9398)
			(stroke
				(width 0)
				(type default)
			)
			(fill no)
			(layer "F.CrtYd")
		)
		(fp_rect
			(start -0.508 0.9398)
			(end 0.508 -0.9398)
			(stroke
				(width 0)
				(type default)
			)
			(fill no)
			(layer "F.Fab")
		)
		(pad "1" smd custom
			(at 0 -0.4445 270)
			(size 0.1397 0.1397)
			(layers "F.Cu" "F.Mask" "F.Paste")
			(net "P3V3_STBY_A")
			(options
				(clearance outline)
				(anchor circle)
			)
			(primitives
				(gr_poly
					(pts
						(arc
							(start -0.1778 -0.2794)
							(mid -0.249642 -0.249642)
							(end -0.2794 -0.1778)
						)
						(arc
							(start -0.2794 0.1778)
							(mid -0.249642 0.249642)
							(end -0.1778 0.2794)
						)
						(arc
							(start 0.1778 0.2794)
							(mid 0.249642 0.249642)
							(end 0.2794 0.1778)
						)
						(arc
							(start 0.2794 -0.1778)
							(mid 0.249642 -0.249642)
							(end 0.1778 -0.2794)
						)
					)
					(width 0)
					(fill yes)
				)
			)
		)
		(pad "2" smd custom
			(at 0 0.4445 270)
			(size 0.1397 0.1397)
			(layers "F.Cu" "F.Mask" "F.Paste")
			(net "HDD_PRSNT_6")
			(options
				(clearance outline)
				(anchor circle)
			)
			(primitives
				(gr_poly
					(pts
						(arc
							(start -0.1778 -0.2794)
							(mid -0.249642 -0.249642)
							(end -0.2794 -0.1778)
						)
						(arc
							(start -0.2794 0.1778)
							(mid -0.249642 0.249642)
							(end -0.1778 0.2794)
						)
						(arc
							(start 0.1778 0.2794)
							(mid 0.249642 0.249642)
							(end 0.2794 0.1778)
						)
						(arc
							(start 0.2794 -0.1778)
							(mid 0.249642 -0.249642)
							(end 0.1778 -0.2794)
						)
					)
					(width 0)
					(fill yes)
				)
			)
		)
	)
	(footprint ""
		(layer "F.Cu")
		(at 463.5119 -47.792894 90)
		(property "Reference" "D34"
			(at 0 0 90)
			(layer "F.SilkS")
			(hide yes)
			(effects
				(font
					(size 1.27 1.27)
				)
			)
		)
		(property "Value" "RB551V30-GP"
			(at 0 -6.7818 90)
			(unlocked yes)
			(layer "F.Fab")
			(hide yes)
			(effects
				(font
					(size 1.016 1.016)
					(thickness 0.1524)
				)
			)
		)
		(property "Device Type" "SOD323AKH38"
			(at 0 -8.6868 90)
			(unlocked yes)
			(layer "F.Fab")
			(hide yes)
			(effects
				(font
					(size 1.016 1.016)
					(thickness 0.1524)
				)
			)
		)
		(duplicate_pad_numbers_are_jumpers no)
		(fp_line
			(start 0.889 -1.9304)
			(end 0.889 2.159)
			(stroke
				(width 0.1524)
				(type default)
			)
			(layer "F.SilkS")
		)
		(fp_line
			(start -0.889 -1.9304)
			(end 0.889 -1.9304)
			(stroke
				(width 0.1524)
				(type default)
			)
			(layer "F.SilkS")
		)
		(fp_line
			(start 0.762 2.0574)
			(end -0.762 2.0574)
			(stroke
				(width 0.508)
				(type default)
			)
			(layer "F.SilkS")
		)
		(fp_line
			(start 0.889 2.159)
			(end -0.889 2.159)
			(stroke
				(width 0.1524)
				(type default)
			)
			(layer "F.SilkS")
		)
		(fp_line
			(start -0.889 2.159)
			(end -0.889 -1.9304)
			(stroke
				(width 0.1524)
				(type default)
			)
			(layer "F.SilkS")
		)
		(fp_rect
			(start -1.016 2.3114)
			(end 1.016 -2.0066)
			(stroke
				(width 0)
				(type default)
			)
			(fill no)
			(layer "F.CrtYd")
		)
		(fp_poly
			(pts
				(xy -1.016 -2.0066) (xy 1.016 -2.0066) (xy 1.016 2.3114) (xy -1.016 2.3114)
			)
			(stroke
				(width 0)
				(type default)
			)
			(fill no)
			(layer "F.Fab")
		)
		(pad "A" smd rect
			(at 0 -1.143 90)
			(size 0.5588 1.016)
			(layers "F.Cu" "F.Mask" "F.Paste")
			(net "SW_HDD_R34")
		)
		(pad "K" smd rect
			(at 0 1.143 90)
			(size 0.5588 1.016)
			(layers "F.Cu" "F.Mask" "F.Paste")
			(net "SW_HDD_N34")
		)
	)
	(footprint ""
		(layer "F.Cu")
		(at 244.475 -254.889)
		(property "Reference" "U5"
			(at 0 0 0)
			(layer "F.SilkS")
			(hide yes)
			(effects
				(font
					(size 1.27 1.27)
				)
			)
		)
		(property "Value" "TCA9555PWR-GP"
			(at 0 -6.9342 0)
			(unlocked yes)
			(layer "F.Fab")
			(hide yes)
			(effects
				(font
					(size 1.016 1.016)
					(thickness 0.1524)
				)
			)
		)
		(property "Device Type" "TSOIC24H48"
			(at 0 -8.5852 0)
			(unlocked yes)
			(layer "F.Fab")
			(hide yes)
			(effects
				(font
					(size 1.016 1.016)
					(thickness 0.1524)
				)
			)
		)
		(duplicate_pad_numbers_are_jumpers no)
		(fp_line
			(start -4.2291 -1.397)
			(end 3.81 -1.397)
			(stroke
				(width 0.1524)
				(type default)
			)
			(layer "F.SilkS")
		)
		(fp_line
			(start -4.2291 -0.8001)
			(end -3.429 0)
			(stroke
				(width 0.1524)
				(type default)
			)
			(layer "F.SilkS")
		)
		(fp_line
			(start -4.2291 3.937)
			(end -4.2291 -1.397)
			(stroke
				(width 0.1524)
				(type default)
			)
			(layer "F.SilkS")
		)
		(fp_line
			(start -4.22656 3.81)
			(end -4.2291 1.397)
			(stroke
				(width 0.508)
				(type default)
			)
			(layer "F.SilkS")
		)
		(fp_line
			(start -3.429 0)
			(end -4.2291 0.8001)
			(stroke
				(width 0.1524)
				(type default)
			)
			(layer "F.SilkS")
		)
		(fp_line
			(start 3.81 -1.397)
			(end 3.81 1.397)
			(stroke
				(width 0.1524)
				(type default)
			)
			(layer "F.SilkS")
		)
		(fp_line
			(start 3.81 1.397)
			(end -4.2291 1.397)
			(stroke
				(width 0.1524)
				(type default)
			)
			(layer "F.SilkS")
		)
		(fp_poly
			(pts
				(xy -3.90652 -1.8542) (xy 3.90652 -1.8542) (xy 3.90652 1.8542) (xy -3.90652 1.8542)
			)
			(stroke
				(width 0)
				(type default)
			)
			(fill yes)
			(layer "F.SilkS")
		)
		(fp_poly
			(pts
				(xy -4.2164 3.81) (xy 4.2164 3.81) (xy 4.22656 -3.81) (xy -4.2164 -3.81)
			)
			(stroke
				(width 0)
				(type default)
			)
			(fill no)
			(layer "F.CrtYd")
		)
		(fp_poly
			(pts
				(xy -4.22656 -3.81) (xy 4.22656 -3.81) (xy 4.22656 3.81) (xy -4.22656 3.81)
			)
			(stroke
				(width 0)
				(type default)
			)
			(fill no)
			(layer "F.Fab")
		)
		(pad "1" smd rect
			(at -3.57632 2.8194)
			(size 0.3556 1.524)
			(layers "F.Cu" "F.Mask" "F.Paste")
			(net "IO_EXP5_INT_N")
		)
		(pad "2" smd rect
			(at -2.92608 2.8194)
			(size 0.3556 1.524)
			(layers "F.Cu" "F.Mask" "F.Paste")
			(net "IO_EXP5_A1")
		)
		(pad "3" smd rect
			(at -2.27584 2.8194)
			(size 0.3556 1.524)
			(layers "F.Cu" "F.Mask" "F.Paste")
			(net "IO_EXP5_A2")
		)
		(pad "4" smd rect
			(at -1.6256 2.8194)
			(size 0.3556 1.524)
			(layers "F.Cu" "F.Mask" "F.Paste")
			(net "DRIVE_A_16_INS")
		)
		(pad "5" smd rect
			(at -0.97536 2.8194)
			(size 0.3556 1.524)
			(layers "F.Cu" "F.Mask" "F.Paste")
			(net "DRIVE_A_17_INS")
		)
		(pad "6" smd rect
			(at -0.32512 2.8194)
			(size 0.3556 1.524)
			(layers "F.Cu" "F.Mask" "F.Paste")
			(net "DRIVE_A_18_INS")
		)
		(pad "7" smd rect
			(at 0.32512 2.8194)
			(size 0.3556 1.524)
			(layers "F.Cu" "F.Mask" "F.Paste")
			(net "DRIVE_A_19_INS")
		)
		(pad "8" smd rect
			(at 0.97536 2.8194)
			(size 0.3556 1.524)
			(layers "F.Cu" "F.Mask" "F.Paste")
			(net "DRIVE_A_20_INS")
		)
		(pad "9" smd rect
			(at 1.6256 2.8194)
			(size 0.3556 1.524)
			(layers "F.Cu" "F.Mask" "F.Paste")
			(net "DRIVE_A_21_INS")
		)
		(pad "10" smd rect
			(at 2.27584 2.8194)
			(size 0.3556 1.524)
			(layers "F.Cu" "F.Mask" "F.Paste")
			(net "DRIVE_A_22_INS")
		)
		(pad "11" smd rect
			(at 2.92608 2.8194)
			(size 0.3556 1.524)
			(layers "F.Cu" "F.Mask" "F.Paste")
			(net "DRIVE_A_23_INS")
		)
		(pad "12" smd rect
			(at 3.57632 2.8194)
			(size 0.3556 1.524)
			(layers "F.Cu" "F.Mask" "F.Paste")
			(net "GND")
		)
		(pad "13" smd rect
			(at 3.57632 -2.8194)
			(size 0.3556 1.524)
			(layers "F.Cu" "F.Mask" "F.Paste")
			(net "DRIVE_A_24_INS")
		)
		(pad "14" smd rect
			(at 2.92608 -2.8194)
			(size 0.3556 1.524)
			(layers "F.Cu" "F.Mask" "F.Paste")
			(net "DRIVE_A_25_INS")
		)
		(pad "15" smd rect
			(at 2.27584 -2.8194)
			(size 0.3556 1.524)
			(layers "F.Cu" "F.Mask" "F.Paste")
			(net "DRIVE_A_26_INS")
		)
		(pad "16" smd rect
			(at 1.6256 -2.8194)
			(size 0.3556 1.524)
			(layers "F.Cu" "F.Mask" "F.Paste")
			(net "DRIVE_A_27_INS")
		)
		(pad "17" smd rect
			(at 0.97536 -2.8194)
			(size 0.3556 1.524)
			(layers "F.Cu" "F.Mask" "F.Paste")
			(net "DRIVE_A_28_INS")
		)
		(pad "18" smd rect
			(at 0.32512 -2.8194)
			(size 0.3556 1.524)
			(layers "F.Cu" "F.Mask" "F.Paste")
			(net "DRIVE_A_29_INS")
		)
		(pad "19" smd rect
			(at -0.32512 -2.8194)
			(size 0.3556 1.524)
			(layers "F.Cu" "F.Mask" "F.Paste")
			(net "DRIVE_A_30_INS")
		)
		(pad "20" smd rect
			(at -0.97536 -2.8194)
			(size 0.3556 1.524)
			(layers "F.Cu" "F.Mask" "F.Paste")
			(net "DRIVE_A_31_INS")
		)
		(pad "21" smd rect
			(at -1.6256 -2.8194)
			(size 0.3556 1.524)
			(layers "F.Cu" "F.Mask" "F.Paste")
			(net "IO_EXP5_A0")
		)
		(pad "22" smd rect
			(at -2.27584 -2.8194)
			(size 0.3556 1.524)
			(layers "F.Cu" "F.Mask" "F.Paste")
			(net "IO_EXP5_SCL")
		)
		(pad "23" smd rect
			(at -2.92608 -2.8194)
			(size 0.3556 1.524)
			(layers "F.Cu" "F.Mask" "F.Paste")
			(net "IO_EXP5_SDA")
		)
		(pad "24" smd rect
			(at -3.57632 -2.8194)
			(size 0.3556 1.524)
			(layers "F.Cu" "F.Mask" "F.Paste")
			(net "P3V3_STBY_A")
		)
	)
	(footprint ""
		(layer "F.Cu")
		(at 219.89542 -11.017504 90)
		(property "Reference" "C44"
			(at 0 0 90)
			(layer "F.SilkS")
			(hide yes)
			(effects
				(font
					(size 1.27 1.27)
				)
			)
		)
		(property "Value" "SC10U16V5KX-7-GP-U"
			(at -0.0762 -6.1214 90)
			(unlocked yes)
			(layer "F.Fab")
			(hide yes)
			(effects
				(font
					(size 1.016 1.016)
					(thickness 0.1524)
				)
			)
		)
		(property "Device Type" "C805H58"
			(at -0.0762 -8.1534 90)
			(unlocked yes)
			(layer "F.Fab")
			(hide yes)
			(effects
				(font
					(size 1.016 1.016)
					(thickness 0.1524)
				)
			)
		)
		(duplicate_pad_numbers_are_jumpers no)
		(fp_line
			(start 0.635 0)
			(end -0.635 0)
			(stroke
				(width 0.508)
				(type default)
			)
			(layer "F.SilkS")
		)
		(fp_rect
			(start -0.9652 1.778)
			(end 0.9652 -1.778)
			(stroke
				(width 0)
				(type default)
			)
			(fill no)
			(layer "F.CrtYd")
		)
		(fp_poly
			(pts
				(xy -0.9652 -1.778) (xy 0.9652 -1.778) (xy 0.9652 1.778) (xy -0.9652 1.778)
			)
			(stroke
				(width 0)
				(type default)
			)
			(fill no)
			(layer "F.Fab")
		)
		(pad "1" smd rect
			(at 0 -0.9652 90)
			(size 1.397 1.143)
			(layers "F.Cu" "F.Mask" "F.Paste")
			(net "P5V_A_2")
		)
		(pad "2" smd rect
			(at 0 0.9652 90)
			(size 1.397 1.143)
			(layers "F.Cu" "F.Mask" "F.Paste")
			(net "GND")
		)
	)
	(footprint ""
		(layer "F.Cu")
		(at 18.500598 -45.633894)
		(property "Reference" "R699"
			(at 0 0 0)
			(layer "F.SilkS")
			(hide yes)
			(effects
				(font
					(size 1.27 1.27)
				)
			)
		)
		(property "Value" "0R2J-2-GP"
			(at 0.064008 -3.993896 0)
			(unlocked yes)
			(layer "F.Fab")
			(hide yes)
			(effects
				(font
					(size 1.016 1.016)
					(thickness 0.1524)
				)
			)
		)
		(property "Device Type" "R402H16"
			(at 0.064008 -5.517896 0)
			(unlocked yes)
			(layer "F.Fab")
			(hide yes)
			(effects
				(font
					(size 1.016 1.016)
					(thickness 0.1524)
				)
			)
		)
		(duplicate_pad_numbers_are_jumpers no)
		(fp_line
			(start -0.508 -0.9398)
			(end -0.508 0.9398)
			(stroke
				(width 0.1524)
				(type default)
			)
			(layer "F.SilkS")
		)
		(fp_line
			(start 0.508 -0.9398)
			(end -0.508 -0.9398)
			(stroke
				(width 0.1524)
				(type default)
			)
			(layer "F.SilkS")
		)
		(fp_rect
			(start -0.508 0.9398)
			(end 0.508 -0.9398)
			(stroke
				(width 0)
				(type default)
			)
			(fill no)
			(layer "F.CrtYd")
		)
		(fp_rect
			(start -0.508 0.9398)
			(end 0.508 -0.9398)
			(stroke
				(width 0)
				(type default)
			)
			(fill no)
			(layer "F.Fab")
		)
		(pad "1" smd custom
			(at 0 -0.4445)
			(size 0.1397 0.1397)
			(layers "F.Cu" "F.Mask" "F.Paste")
			(net "SW_HDD_G24")
			(options
				(clearance outline)
				(anchor circle)
			)
			(primitives
				(gr_poly
					(pts
						(arc
							(start -0.1778 -0.2794)
							(mid -0.249642 -0.249642)
							(end -0.2794 -0.1778)
						)
						(arc
							(start -0.2794 0.1778)
							(mid -0.249642 0.249642)
							(end -0.1778 0.2794)
						)
						(arc
							(start 0.1778 0.2794)
							(mid 0.249642 0.249642)
							(end 0.2794 0.1778)
						)
						(arc
							(start 0.2794 -0.1778)
							(mid 0.249642 -0.249642)
							(end 0.1778 -0.2794)
						)
					)
					(width 0)
					(fill yes)
				)
			)
		)
		(pad "2" smd custom
			(at 0 0.4445)
			(size 0.1397 0.1397)
			(layers "F.Cu" "F.Mask" "F.Paste")
			(net "SW_HDD_R24")
			(options
				(clearance outline)
				(anchor circle)
			)
			(primitives
				(gr_poly
					(pts
						(arc
							(start -0.1778 -0.2794)
							(mid -0.249642 -0.249642)
							(end -0.2794 -0.1778)
						)
						(arc
							(start -0.2794 0.1778)
							(mid -0.249642 0.249642)
							(end -0.1778 0.2794)
						)
						(arc
							(start 0.1778 0.2794)
							(mid 0.249642 0.249642)
							(end 0.2794 0.1778)
						)
						(arc
							(start 0.2794 -0.1778)
							(mid 0.249642 -0.249642)
							(end 0.1778 -0.2794)
						)
					)
					(width 0)
					(fill yes)
				)
			)
		)
	)
	(footprint ""
		(layer "F.Cu")
		(at 374.5738 -145.8214)
		(property "Reference" "R1085"
			(at 0 0 0)
			(layer "F.SilkS")
			(hide yes)
			(effects
				(font
					(size 1.27 1.27)
				)
			)
		)
		(property "Value" "10KR2F-2-GP"
			(at 0.064008 -3.993896 0)
			(unlocked yes)
			(layer "F.Fab")
			(hide yes)
			(effects
				(font
					(size 1.016 1.016)
					(thickness 0.1524)
				)
			)
		)
		(property "Device Type" "R402H16"
			(at 0.064008 -5.517896 0)
			(unlocked yes)
			(layer "F.Fab")
			(hide yes)
			(effects
				(font
					(size 1.016 1.016)
					(thickness 0.1524)
				)
			)
		)
		(duplicate_pad_numbers_are_jumpers no)
		(fp_line
			(start -0.508 -0.9398)
			(end -0.508 0.9398)
			(stroke
				(width 0.1524)
				(type default)
			)
			(layer "F.SilkS")
		)
		(fp_line
			(start 0.508 -0.9398)
			(end -0.508 -0.9398)
			(stroke
				(width 0.1524)
				(type default)
			)
			(layer "F.SilkS")
		)
		(fp_rect
			(start -0.508 0.9398)
			(end 0.508 -0.9398)
			(stroke
				(width 0)
				(type default)
			)
			(fill no)
			(layer "F.CrtYd")
		)
		(fp_rect
			(start -0.508 0.9398)
			(end 0.508 -0.9398)
			(stroke
				(width 0)
				(type default)
			)
			(fill no)
			(layer "F.Fab")
		)
		(pad "1" smd custom
			(at 0 -0.4445)
			(size 0.1397 0.1397)
			(layers "F.Cu" "F.Mask" "F.Paste")
			(net "P12V_B_COMP")
			(options
				(clearance outline)
				(anchor circle)
			)
			(primitives
				(gr_poly
					(pts
						(arc
							(start -0.1778 -0.2794)
							(mid -0.249642 -0.249642)
							(end -0.2794 -0.1778)
						)
						(arc
							(start -0.2794 0.1778)
							(mid -0.249642 0.249642)
							(end -0.1778 0.2794)
						)
						(arc
							(start 0.1778 0.2794)
							(mid 0.249642 0.249642)
							(end 0.2794 0.1778)
						)
						(arc
							(start 0.2794 -0.1778)
							(mid 0.249642 -0.249642)
							(end 0.1778 -0.2794)
						)
					)
					(width 0)
					(fill yes)
				)
			)
		)
		(pad "2" smd custom
			(at 0 0.4445)
			(size 0.1397 0.1397)
			(layers "F.Cu" "F.Mask" "F.Paste")
			(net "COMP_B_PGOOD")
			(options
				(clearance outline)
				(anchor circle)
			)
			(primitives
				(gr_poly
					(pts
						(arc
							(start -0.1778 -0.2794)
							(mid -0.249642 -0.249642)
							(end -0.2794 -0.1778)
						)
						(arc
							(start -0.2794 0.1778)
							(mid -0.249642 0.249642)
							(end -0.1778 0.2794)
						)
						(arc
							(start 0.1778 0.2794)
							(mid 0.249642 0.249642)
							(end 0.2794 0.1778)
						)
						(arc
							(start 0.2794 -0.1778)
							(mid 0.249642 -0.249642)
							(end 0.1778 -0.2794)
						)
					)
					(width 0)
					(fill yes)
				)
			)
		)
	)
	(footprint ""
		(layer "F.Cu")
		(at 223.182942 -205.639162 180)
		(property "Reference" "R412"
			(at 0 0 180)
			(layer "F.SilkS")
			(hide yes)
			(effects
				(font
					(size 1.27 1.27)
				)
			)
		)
		(property "Value" "1KR2F-3-GP"
			(at 0.064008 -3.993896 180)
			(unlocked yes)
			(layer "F.Fab")
			(hide yes)
			(effects
				(font
					(size 1.016 1.016)
					(thickness 0.1524)
				)
			)
		)
		(property "Device Type" "R402H16"
			(at 0.064008 -5.517896 180)
			(unlocked yes)
			(layer "F.Fab")
			(hide yes)
			(effects
				(font
					(size 1.016 1.016)
					(thickness 0.1524)
				)
			)
		)
		(duplicate_pad_numbers_are_jumpers no)
		(fp_line
			(start 0.508 -0.9398)
			(end -0.508 -0.9398)
			(stroke
				(width 0.1524)
				(type default)
			)
			(layer "F.SilkS")
		)
		(fp_line
			(start -0.508 -0.9398)
			(end -0.508 0.9398)
			(stroke
				(width 0.1524)
				(type default)
			)
			(layer "F.SilkS")
		)
		(fp_rect
			(start -0.508 0.9398)
			(end 0.508 -0.9398)
			(stroke
				(width 0)
				(type default)
			)
			(fill no)
			(layer "F.CrtYd")
		)
		(fp_rect
			(start -0.508 0.9398)
			(end 0.508 -0.9398)
			(stroke
				(width 0)
				(type default)
			)
			(fill no)
			(layer "F.Fab")
		)
		(pad "1" smd custom
			(at 0 -0.4445 180)
			(size 0.1397 0.1397)
			(layers "F.Cu" "F.Mask" "F.Paste")
			(net "P3V3_STBY_A")
			(options
				(clearance outline)
				(anchor circle)
			)
			(primitives
				(gr_poly
					(pts
						(arc
							(start -0.1778 -0.2794)
							(mid -0.249642 -0.249642)
							(end -0.2794 -0.1778)
						)
						(arc
							(start -0.2794 0.1778)
							(mid -0.249642 0.249642)
							(end -0.1778 0.2794)
						)
						(arc
							(start 0.1778 0.2794)
							(mid 0.249642 0.249642)
							(end 0.2794 0.1778)
						)
						(arc
							(start 0.2794 -0.1778)
							(mid 0.249642 -0.249642)
							(end 0.1778 -0.2794)
						)
					)
					(width 0)
					(fill yes)
				)
			)
		)
		(pad "2" smd custom
			(at 0 0.4445 180)
			(size 0.1397 0.1397)
			(layers "F.Cu" "F.Mask" "F.Paste")
			(net "I2C_SCC_A_SCL_BUF")
			(options
				(clearance outline)
				(anchor circle)
			)
			(primitives
				(gr_poly
					(pts
						(arc
							(start -0.1778 -0.2794)
							(mid -0.249642 -0.249642)
							(end -0.2794 -0.1778)
						)
						(arc
							(start -0.2794 0.1778)
							(mid -0.249642 0.249642)
							(end -0.1778 0.2794)
						)
						(arc
							(start 0.1778 0.2794)
							(mid 0.249642 0.249642)
							(end 0.2794 0.1778)
						)
						(arc
							(start 0.2794 -0.1778)
							(mid 0.249642 -0.249642)
							(end 0.1778 -0.2794)
						)
					)
					(width 0)
					(fill yes)
				)
			)
		)
	)
	(footprint ""
		(layer "F.Cu")
		(at 177.8 -61.000894 -90)
		(property "Reference" "C418"
			(at 0 0 270)
			(layer "F.SilkS")
			(hide yes)
			(effects
				(font
					(size 1.27 1.27)
				)
			)
		)
		(property "Value" "SC10U16V6KX-2GP"
			(at -0.0762 -5.1308 270)
			(unlocked yes)
			(layer "F.Fab")
			(hide yes)
			(effects
				(font
					(size 1.016 1.016)
					(thickness 0.1524)
				)
			)
		)
		(property "Device Type" "C1206H71"
			(at -0.127 -6.6548 270)
			(unlocked yes)
			(layer "F.Fab")
			(hide yes)
			(effects
				(font
					(size 1.016 1.016)
					(thickness 0.1524)
				)
			)
		)
		(duplicate_pad_numbers_are_jumpers no)
		(fp_line
			(start -1.016 2.2352)
			(end -1.016 0.8382)
			(stroke
				(width 0.1524)
				(type default)
			)
			(layer "F.SilkS")
		)
		(fp_line
			(start 1.016 2.2352)
			(end -1.016 2.2352)
			(stroke
				(width 0.1524)
				(type default)
			)
			(layer "F.SilkS")
		)
		(fp_line
			(start 1.016 0.8382)
			(end 1.016 2.2352)
			(stroke
				(width 0.1524)
				(type default)
			)
			(layer "F.SilkS")
		)
		(fp_line
			(start -1.016 -0.8382)
			(end -1.016 -2.2352)
			(stroke
				(width 0.1524)
				(type default)
			)
			(layer "F.SilkS")
		)
		(fp_line
			(start -1.016 -2.2352)
			(end 1.016 -2.2352)
			(stroke
				(width 0.1524)
				(type default)
			)
			(layer "F.SilkS")
		)
		(fp_line
			(start 1.016 -2.2352)
			(end 1.016 -0.8382)
			(stroke
				(width 0.1524)
				(type default)
			)
			(layer "F.SilkS")
		)
		(fp_rect
			(start -1.0922 2.3114)
			(end 1.0922 -2.3114)
			(stroke
				(width 0)
				(type default)
			)
			(fill no)
			(layer "F.CrtYd")
		)
		(fp_poly
			(pts
				(xy 1.0922 -2.3114) (xy 1.0922 2.3114) (xy -1.0922 2.3114) (xy -1.0922 -2.3114)
			)
			(stroke
				(width 0)
				(type default)
			)
			(fill no)
			(layer "F.Fab")
		)
		(pad "1" smd rect
			(at 0 -1.397 270)
			(size 1.651 1.27)
			(layers "F.Cu" "F.Mask" "F.Paste")
			(net "P5V_HDD29")
		)
		(pad "2" smd rect
			(at 0 1.397 270)
			(size 1.651 1.27)
			(layers "F.Cu" "F.Mask" "F.Paste")
			(net "GND")
		)
	)
	(footprint ""
		(layer "F.Cu")
		(at 241.935 -231.14 180)
		(property "Reference" "R88"
			(at 0 0 180)
			(layer "F.SilkS")
			(hide yes)
			(effects
				(font
					(size 1.27 1.27)
				)
			)
		)
		(property "Value" "4K7R2F-GP"
			(at 0.064008 -3.993896 180)
			(unlocked yes)
			(layer "F.Fab")
			(hide yes)
			(effects
				(font
					(size 1.016 1.016)
					(thickness 0.1524)
				)
			)
		)
		(property "Device Type" "R402H16"
			(at 0.064008 -5.517896 180)
			(unlocked yes)
			(layer "F.Fab")
			(hide yes)
			(effects
				(font
					(size 1.016 1.016)
					(thickness 0.1524)
				)
			)
		)
		(duplicate_pad_numbers_are_jumpers no)
		(fp_line
			(start 0.508 -0.9398)
			(end -0.508 -0.9398)
			(stroke
				(width 0.1524)
				(type default)
			)
			(layer "F.SilkS")
		)
		(fp_line
			(start -0.508 -0.9398)
			(end -0.508 0.9398)
			(stroke
				(width 0.1524)
				(type default)
			)
			(layer "F.SilkS")
		)
		(fp_rect
			(start -0.508 0.9398)
			(end 0.508 -0.9398)
			(stroke
				(width 0)
				(type default)
			)
			(fill no)
			(layer "F.CrtYd")
		)
		(fp_rect
			(start -0.508 0.9398)
			(end 0.508 -0.9398)
			(stroke
				(width 0)
				(type default)
			)
			(fill no)
			(layer "F.Fab")
		)
		(pad "1" smd custom
			(at 0 -0.4445 180)
			(size 0.1397 0.1397)
			(layers "F.Cu" "F.Mask" "F.Paste")
			(net "P3V3_STBY_A")
			(options
				(clearance outline)
				(anchor circle)
			)
			(primitives
				(gr_poly
					(pts
						(arc
							(start -0.1778 -0.2794)
							(mid -0.249642 -0.249642)
							(end -0.2794 -0.1778)
						)
						(arc
							(start -0.2794 0.1778)
							(mid -0.249642 0.249642)
							(end -0.1778 0.2794)
						)
						(arc
							(start 0.1778 0.2794)
							(mid 0.249642 0.249642)
							(end 0.2794 0.1778)
						)
						(arc
							(start 0.2794 -0.1778)
							(mid 0.249642 -0.249642)
							(end 0.1778 -0.2794)
						)
					)
					(width 0)
					(fill yes)
				)
			)
		)
		(pad "2" smd custom
			(at 0 0.4445 180)
			(size 0.1397 0.1397)
			(layers "F.Cu" "F.Mask" "F.Paste")
			(net "IO_EXP2_INT_N")
			(options
				(clearance outline)
				(anchor circle)
			)
			(primitives
				(gr_poly
					(pts
						(arc
							(start -0.1778 -0.2794)
							(mid -0.249642 -0.249642)
							(end -0.2794 -0.1778)
						)
						(arc
							(start -0.2794 0.1778)
							(mid -0.249642 0.249642)
							(end -0.1778 0.2794)
						)
						(arc
							(start 0.1778 0.2794)
							(mid 0.249642 0.249642)
							(end 0.2794 0.1778)
						)
						(arc
							(start 0.2794 -0.1778)
							(mid 0.249642 -0.249642)
							(end 0.1778 -0.2794)
						)
					)
					(width 0)
					(fill yes)
				)
			)
		)
	)
	(footprint ""
		(layer "F.Cu")
		(at 83.149948 -61.000894 -90)
		(property "Reference" "C379"
			(at 0 0 270)
			(layer "F.SilkS")
			(hide yes)
			(effects
				(font
					(size 1.27 1.27)
				)
			)
		)
		(property "Value" "SC10U16V6KX-2GP"
			(at -0.0762 -5.1308 270)
			(unlocked yes)
			(layer "F.Fab")
			(hide yes)
			(effects
				(font
					(size 1.016 1.016)
					(thickness 0.1524)
				)
			)
		)
		(property "Device Type" "C1206H71"
			(at -0.127 -6.6548 270)
			(unlocked yes)
			(layer "F.Fab")
			(hide yes)
			(effects
				(font
					(size 1.016 1.016)
					(thickness 0.1524)
				)
			)
		)
		(duplicate_pad_numbers_are_jumpers no)
		(fp_line
			(start -1.016 2.2352)
			(end -1.016 0.8382)
			(stroke
				(width 0.1524)
				(type default)
			)
			(layer "F.SilkS")
		)
		(fp_line
			(start 1.016 2.2352)
			(end -1.016 2.2352)
			(stroke
				(width 0.1524)
				(type default)
			)
			(layer "F.SilkS")
		)
		(fp_line
			(start 1.016 0.8382)
			(end 1.016 2.2352)
			(stroke
				(width 0.1524)
				(type default)
			)
			(layer "F.SilkS")
		)
		(fp_line
			(start -1.016 -0.8382)
			(end -1.016 -2.2352)
			(stroke
				(width 0.1524)
				(type default)
			)
			(layer "F.SilkS")
		)
		(fp_line
			(start -1.016 -2.2352)
			(end 1.016 -2.2352)
			(stroke
				(width 0.1524)
				(type default)
			)
			(layer "F.SilkS")
		)
		(fp_line
			(start 1.016 -2.2352)
			(end 1.016 -0.8382)
			(stroke
				(width 0.1524)
				(type default)
			)
			(layer "F.SilkS")
		)
		(fp_rect
			(start -1.0922 2.3114)
			(end 1.0922 -2.3114)
			(stroke
				(width 0)
				(type default)
			)
			(fill no)
			(layer "F.CrtYd")
		)
		(fp_poly
			(pts
				(xy 1.0922 -2.3114) (xy 1.0922 2.3114) (xy -1.0922 2.3114) (xy -1.0922 -2.3114)
			)
			(stroke
				(width 0)
				(type default)
			)
			(fill no)
			(layer "F.Fab")
		)
		(pad "1" smd rect
			(at 0 -1.397 270)
			(size 1.651 1.27)
			(layers "F.Cu" "F.Mask" "F.Paste")
			(net "P5V_HDD26")
		)
		(pad "2" smd rect
			(at 0 1.397 270)
			(size 1.651 1.27)
			(layers "F.Cu" "F.Mask" "F.Paste")
			(net "GND")
		)
	)
	(footprint ""
		(layer "F.Cu")
		(at 95.563436 -158.660592 90)
		(property "Reference" "C221"
			(at 0 0 90)
			(layer "F.SilkS")
			(hide yes)
			(effects
				(font
					(size 1.27 1.27)
				)
			)
		)
		(property "Value" "SCD01U16V1KX-GP"
			(at -2.8321 -1.7399 90)
			(unlocked yes)
			(layer "F.Fab")
			(hide yes)
			(effects
				(font
					(size 1.016 1.016)
					(thickness 0.1524)
				)
			)
		)
		(property "Device Type" "C0201H13"
			(at -2.8321 -3.2639 90)
			(unlocked yes)
			(layer "F.Fab")
			(hide yes)
			(effects
				(font
					(size 1.016 1.016)
					(thickness 0.1524)
				)
			)
		)
		(duplicate_pad_numbers_are_jumpers no)
		(fp_rect
			(start -0.2794 0.6477)
			(end 0.2794 -0.6477)
			(stroke
				(width 0)
				(type default)
			)
			(fill no)
			(layer "F.CrtYd")
		)
		(fp_rect
			(start -0.2794 0.6477)
			(end 0.2794 -0.6477)
			(stroke
				(width 0)
				(type default)
			)
			(fill no)
			(layer "F.Fab")
		)
		(pad "1" smd custom
			(at 0 -0.2794 90)
			(size 0.0762 0.0762)
			(layers "F.Cu" "F.Mask" "F.Paste")
			(net "SAS_HDD_RX_P14")
			(options
				(clearance outline)
				(anchor circle)
			)
			(primitives
				(gr_poly
					(pts
						(arc
							(start 0.1524 -0.127)
							(mid 0.137521 -0.162921)
							(end 0.1016 -0.1778)
						)
						(arc
							(start -0.1016 -0.1778)
							(mid -0.137521 -0.162921)
							(end -0.1524 -0.127)
						)
						(arc
							(start -0.1524 0.127)
							(mid -0.137521 0.162921)
							(end -0.1016 0.1778)
						)
						(arc
							(start 0.1016 0.1778)
							(mid 0.137521 0.162921)
							(end 0.1524 0.127)
						)
					)
					(width 0)
					(fill yes)
				)
			)
		)
		(pad "2" smd custom
			(at 0 0.2794 90)
			(size 0.0762 0.0762)
			(layers "F.Cu" "F.Mask" "F.Paste")
			(net "PHY_SCC_A_TO_DRV_A_14_DP")
			(options
				(clearance outline)
				(anchor circle)
			)
			(primitives
				(gr_poly
					(pts
						(arc
							(start 0.1524 -0.127)
							(mid 0.137521 -0.162921)
							(end 0.1016 -0.1778)
						)
						(arc
							(start -0.1016 -0.1778)
							(mid -0.137521 -0.162921)
							(end -0.1524 -0.127)
						)
						(arc
							(start -0.1524 0.127)
							(mid -0.137521 0.162921)
							(end -0.1016 0.1778)
						)
						(arc
							(start 0.1016 0.1778)
							(mid 0.137521 0.162921)
							(end 0.1524 0.127)
						)
					)
					(width 0)
					(fill yes)
				)
			)
		)
	)
	(footprint ""
		(layer "F.Cu")
		(at 356.289102 -277.750016 -90)
		(property "Reference" "VIA18"
			(at 0 0 270)
			(layer "F.SilkS")
			(hide yes)
			(effects
				(font
					(size 1.27 1.27)
				)
			)
		)
		(property "Value" "100OHM-8L-1D6MM-L18L16-GP"
			(at -3.7211 -4.5085 270)
			(unlocked yes)
			(layer "F.Fab")
			(hide yes)
			(effects
				(font
					(size 1.016 1.016)
					(thickness 0.1524)
				)
			)
		)
		(property "Device Type" "VIA-PCIE-4P-394076"
			(at -3.7211 -6.0325 270)
			(unlocked yes)
			(layer "F.Fab")
			(hide yes)
			(effects
				(font
					(size 1.016 1.016)
					(thickness 0.1524)
				)
			)
		)
		(duplicate_pad_numbers_are_jumpers no)
		(fp_rect
			(start -1.9685 0.381)
			(end 1.9685 -0.381)
			(stroke
				(width 0)
				(type default)
			)
			(fill no)
			(layer "F.CrtYd")
		)
		(fp_rect
			(start -1.9685 0.381)
			(end 1.9685 -0.381)
			(stroke
				(width 0)
				(type default)
			)
			(fill no)
			(layer "F.Fab")
		)
		(pad "1" thru_hole circle
			(at -1.5875 0 270)
			(size 0.508 0.508)
			(drill 0.254)
			(layers "*.Cu" "*.Mask")
			(remove_unused_layers no)
			(net "GND")
			(clearance 0.127)
			(thermal_gap 0.127)
		)
		(pad "2" thru_hole circle
			(at -0.5715 0 270)
			(size 0.508 0.508)
			(drill 0.254)
			(layers "*.Cu" "*.Mask")
			(remove_unused_layers no)
			(net "PHY_DRV_A_TO_SCC_A_7_DP")
			(clearance 0.127)
			(thermal_gap 0.127)
		)
		(pad "3" thru_hole circle
			(at 0.5715 0 270)
			(size 0.508 0.508)
			(drill 0.254)
			(layers "*.Cu" "*.Mask")
			(remove_unused_layers no)
			(net "PHY_DRV_A_TO_SCC_A_7_DN")
			(clearance 0.127)
			(thermal_gap 0.127)
		)
		(pad "4" thru_hole circle
			(at 1.5875 0 270)
			(size 0.508 0.508)
			(drill 0.254)
			(layers "*.Cu" "*.Mask")
			(remove_unused_layers no)
			(net "GND")
			(clearance 0.127)
			(thermal_gap 0.127)
		)
	)
	(footprint ""
		(layer "F.Cu")
		(at 143.024098 -283.126942 -90)
		(property "Reference" "C100"
			(at 0 0 270)
			(layer "F.SilkS")
			(hide yes)
			(effects
				(font
					(size 1.27 1.27)
				)
			)
		)
		(property "Value" "SCD033U25V2KX-GP"
			(at 1.1811 -2.7051 270)
			(unlocked yes)
			(layer "F.Fab")
			(hide yes)
			(effects
				(font
					(size 1.016 1.016)
					(thickness 0.1524)
				)
			)
		)
		(property "Device Type" "C402H22"
			(at 1.1811 -4.2291 270)
			(unlocked yes)
			(layer "F.Fab")
			(hide yes)
			(effects
				(font
					(size 1.016 1.016)
					(thickness 0.1524)
				)
			)
		)
		(duplicate_pad_numbers_are_jumpers no)
		(fp_rect
			(start -0.4318 0.9525)
			(end 0.4318 -0.9525)
			(stroke
				(width 0)
				(type default)
			)
			(fill no)
			(layer "F.CrtYd")
		)
		(fp_rect
			(start -0.4318 0.9525)
			(end 0.4318 -0.9525)
			(stroke
				(width 0)
				(type default)
			)
			(fill no)
			(layer "F.Fab")
		)
		(pad "1" smd custom
			(at 0 -0.4445 270)
			(size 0.1524 0.1524)
			(layers "F.Cu" "F.Mask" "F.Paste")
			(net "SW_HDD_P4")
			(options
				(clearance outline)
				(anchor circle)
			)
			(primitives
				(gr_poly
					(pts
						(arc
							(start 0.3048 -0.2032)
							(mid 0.275042 -0.275042)
							(end 0.2032 -0.3048)
						)
						(arc
							(start -0.2032 -0.3048)
							(mid -0.275042 -0.275042)
							(end -0.3048 -0.2032)
						)
						(arc
							(start -0.3048 0.2032)
							(mid -0.275042 0.275042)
							(end -0.2032 0.3048)
						)
						(arc
							(start 0.2032 0.3048)
							(mid 0.275042 0.275042)
							(end 0.3048 0.2032)
						)
					)
					(width 0)
					(fill yes)
				)
			)
		)
		(pad "2" smd custom
			(at 0 0.4445 270)
			(size 0.1524 0.1524)
			(layers "F.Cu" "F.Mask" "F.Paste")
			(net "GND")
			(options
				(clearance outline)
				(anchor circle)
			)
			(primitives
				(gr_poly
					(pts
						(arc
							(start 0.3048 -0.2032)
							(mid 0.275042 -0.275042)
							(end 0.2032 -0.3048)
						)
						(arc
							(start -0.2032 -0.3048)
							(mid -0.275042 -0.275042)
							(end -0.3048 -0.2032)
						)
						(arc
							(start -0.3048 0.2032)
							(mid -0.275042 0.275042)
							(end -0.2032 0.3048)
						)
						(arc
							(start 0.2032 0.3048)
							(mid 0.275042 0.275042)
							(end 0.3048 0.2032)
						)
					)
					(width 0)
					(fill yes)
				)
			)
		)
	)
	(footprint ""
		(layer "F.Cu")
		(at 221.032832 -387.02488 -90)
		(property "Reference" "R130"
			(at 0 0 270)
			(layer "F.SilkS")
			(hide yes)
			(effects
				(font
					(size 1.27 1.27)
				)
			)
		)
		(property "Value" "10KR2F-2-GP"
			(at 0.064008 -3.993896 270)
			(unlocked yes)
			(layer "F.Fab")
			(hide yes)
			(effects
				(font
					(size 1.016 1.016)
					(thickness 0.1524)
				)
			)
		)
		(property "Device Type" "R402H16"
			(at 0.064008 -5.517896 270)
			(unlocked yes)
			(layer "F.Fab")
			(hide yes)
			(effects
				(font
					(size 1.016 1.016)
					(thickness 0.1524)
				)
			)
		)
		(duplicate_pad_numbers_are_jumpers no)
		(fp_line
			(start -0.508 -0.9398)
			(end -0.508 0.9398)
			(stroke
				(width 0.1524)
				(type default)
			)
			(layer "F.SilkS")
		)
		(fp_line
			(start 0.508 -0.9398)
			(end -0.508 -0.9398)
			(stroke
				(width 0.1524)
				(type default)
			)
			(layer "F.SilkS")
		)
		(fp_rect
			(start -0.508 0.9398)
			(end 0.508 -0.9398)
			(stroke
				(width 0)
				(type default)
			)
			(fill no)
			(layer "F.CrtYd")
		)
		(fp_rect
			(start -0.508 0.9398)
			(end 0.508 -0.9398)
			(stroke
				(width 0)
				(type default)
			)
			(fill no)
			(layer "F.Fab")
		)
		(pad "1" smd custom
			(at 0 -0.4445 270)
			(size 0.1397 0.1397)
			(layers "F.Cu" "F.Mask" "F.Paste")
			(net "P12V_A")
			(options
				(clearance outline)
				(anchor circle)
			)
			(primitives
				(gr_poly
					(pts
						(arc
							(start -0.1778 -0.2794)
							(mid -0.249642 -0.249642)
							(end -0.2794 -0.1778)
						)
						(arc
							(start -0.2794 0.1778)
							(mid -0.249642 0.249642)
							(end -0.1778 0.2794)
						)
						(arc
							(start 0.1778 0.2794)
							(mid 0.249642 0.249642)
							(end 0.2794 0.1778)
						)
						(arc
							(start 0.2794 -0.1778)
							(mid 0.249642 -0.249642)
							(end 0.1778 -0.2794)
						)
					)
					(width 0)
					(fill yes)
				)
			)
		)
		(pad "2" smd custom
			(at 0 0.4445 270)
			(size 0.1397 0.1397)
			(layers "F.Cu" "F.Mask" "F.Paste")
			(net "SCC_A_FULL_PWR_EN_12V")
			(options
				(clearance outline)
				(anchor circle)
			)
			(primitives
				(gr_poly
					(pts
						(arc
							(start -0.1778 -0.2794)
							(mid -0.249642 -0.249642)
							(end -0.2794 -0.1778)
						)
						(arc
							(start -0.2794 0.1778)
							(mid -0.249642 0.249642)
							(end -0.1778 0.2794)
						)
						(arc
							(start 0.1778 0.2794)
							(mid 0.249642 0.249642)
							(end 0.2794 0.1778)
						)
						(arc
							(start 0.2794 -0.1778)
							(mid 0.249642 -0.249642)
							(end 0.1778 -0.2794)
						)
					)
					(width 0)
					(fill yes)
				)
			)
		)
	)
	(footprint ""
		(layer "F.Cu")
		(at 64.013334 -158.660592 90)
		(property "Reference" "C208"
			(at 0 0 90)
			(layer "F.SilkS")
			(hide yes)
			(effects
				(font
					(size 1.27 1.27)
				)
			)
		)
		(property "Value" "SCD01U16V1KX-GP"
			(at -2.8321 -1.7399 90)
			(unlocked yes)
			(layer "F.Fab")
			(hide yes)
			(effects
				(font
					(size 1.016 1.016)
					(thickness 0.1524)
				)
			)
		)
		(property "Device Type" "C0201H13"
			(at -2.8321 -3.2639 90)
			(unlocked yes)
			(layer "F.Fab")
			(hide yes)
			(effects
				(font
					(size 1.016 1.016)
					(thickness 0.1524)
				)
			)
		)
		(duplicate_pad_numbers_are_jumpers no)
		(fp_rect
			(start -0.2794 0.6477)
			(end 0.2794 -0.6477)
			(stroke
				(width 0)
				(type default)
			)
			(fill no)
			(layer "F.CrtYd")
		)
		(fp_rect
			(start -0.2794 0.6477)
			(end 0.2794 -0.6477)
			(stroke
				(width 0)
				(type default)
			)
			(fill no)
			(layer "F.Fab")
		)
		(pad "1" smd custom
			(at 0 -0.2794 90)
			(size 0.0762 0.0762)
			(layers "F.Cu" "F.Mask" "F.Paste")
			(net "SAS_HDD_RX_P13")
			(options
				(clearance outline)
				(anchor circle)
			)
			(primitives
				(gr_poly
					(pts
						(arc
							(start 0.1524 -0.127)
							(mid 0.137521 -0.162921)
							(end 0.1016 -0.1778)
						)
						(arc
							(start -0.1016 -0.1778)
							(mid -0.137521 -0.162921)
							(end -0.1524 -0.127)
						)
						(arc
							(start -0.1524 0.127)
							(mid -0.137521 0.162921)
							(end -0.1016 0.1778)
						)
						(arc
							(start 0.1016 0.1778)
							(mid 0.137521 0.162921)
							(end 0.1524 0.127)
						)
					)
					(width 0)
					(fill yes)
				)
			)
		)
		(pad "2" smd custom
			(at 0 0.2794 90)
			(size 0.0762 0.0762)
			(layers "F.Cu" "F.Mask" "F.Paste")
			(net "PHY_SCC_A_TO_DRV_A_13_DP")
			(options
				(clearance outline)
				(anchor circle)
			)
			(primitives
				(gr_poly
					(pts
						(arc
							(start 0.1524 -0.127)
							(mid 0.137521 -0.162921)
							(end 0.1016 -0.1778)
						)
						(arc
							(start -0.1016 -0.1778)
							(mid -0.137521 -0.162921)
							(end -0.1524 -0.127)
						)
						(arc
							(start -0.1524 0.127)
							(mid -0.137521 0.162921)
							(end -0.1016 0.1778)
						)
						(arc
							(start 0.1016 0.1778)
							(mid 0.137521 0.162921)
							(end 0.1524 0.127)
						)
					)
					(width 0)
					(fill yes)
				)
			)
		)
	)
	(footprint ""
		(layer "F.Cu")
		(at 14.842998 -54.523894 90)
		(property "Reference" "C361"
			(at 0 0 90)
			(layer "F.SilkS")
			(hide yes)
			(effects
				(font
					(size 1.27 1.27)
				)
			)
		)
		(property "Value" "SCD033U25V2KX-GP"
			(at 1.1811 -2.7051 90)
			(unlocked yes)
			(layer "F.Fab")
			(hide yes)
			(effects
				(font
					(size 1.016 1.016)
					(thickness 0.1524)
				)
			)
		)
		(property "Device Type" "C402H22"
			(at 1.1811 -4.2291 90)
			(unlocked yes)
			(layer "F.Fab")
			(hide yes)
			(effects
				(font
					(size 1.016 1.016)
					(thickness 0.1524)
				)
			)
		)
		(duplicate_pad_numbers_are_jumpers no)
		(fp_rect
			(start -0.4318 0.9525)
			(end 0.4318 -0.9525)
			(stroke
				(width 0)
				(type default)
			)
			(fill no)
			(layer "F.CrtYd")
		)
		(fp_rect
			(start -0.4318 0.9525)
			(end 0.4318 -0.9525)
			(stroke
				(width 0)
				(type default)
			)
			(fill no)
			(layer "F.Fab")
		)
		(pad "1" smd custom
			(at 0 -0.4445 90)
			(size 0.1524 0.1524)
			(layers "F.Cu" "F.Mask" "F.Paste")
			(net "P12V_A")
			(options
				(clearance outline)
				(anchor circle)
			)
			(primitives
				(gr_poly
					(pts
						(arc
							(start 0.3048 -0.2032)
							(mid 0.275042 -0.275042)
							(end 0.2032 -0.3048)
						)
						(arc
							(start -0.2032 -0.3048)
							(mid -0.275042 -0.275042)
							(end -0.3048 -0.2032)
						)
						(arc
							(start -0.3048 0.2032)
							(mid -0.275042 0.275042)
							(end -0.2032 0.3048)
						)
						(arc
							(start 0.2032 0.3048)
							(mid 0.275042 0.275042)
							(end 0.3048 0.2032)
						)
					)
					(width 0)
					(fill yes)
				)
			)
		)
		(pad "2" smd custom
			(at 0 0.4445 90)
			(size 0.1524 0.1524)
			(layers "F.Cu" "F.Mask" "F.Paste")
			(net "SW_HDD_N24")
			(options
				(clearance outline)
				(anchor circle)
			)
			(primitives
				(gr_poly
					(pts
						(arc
							(start 0.3048 -0.2032)
							(mid 0.275042 -0.275042)
							(end 0.2032 -0.3048)
						)
						(arc
							(start -0.2032 -0.3048)
							(mid -0.275042 -0.275042)
							(end -0.3048 -0.2032)
						)
						(arc
							(start -0.3048 0.2032)
							(mid -0.275042 0.275042)
							(end -0.2032 0.3048)
						)
						(arc
							(start 0.2032 0.3048)
							(mid 0.275042 0.275042)
							(end 0.3048 0.2032)
						)
					)
					(width 0)
					(fill yes)
				)
			)
		)
	)
	(footprint ""
		(layer "F.Cu")
		(at 471.603324 -282.776676 -90)
		(property "Reference" "R398"
			(at 0 0 270)
			(layer "F.SilkS")
			(hide yes)
			(effects
				(font
					(size 1.27 1.27)
				)
			)
		)
		(property "Value" "300KR2F-GP"
			(at 0.064008 -3.993896 270)
			(unlocked yes)
			(layer "F.Fab")
			(hide yes)
			(effects
				(font
					(size 1.016 1.016)
					(thickness 0.1524)
				)
			)
		)
		(property "Device Type" "R402H16"
			(at 0.064008 -5.517896 270)
			(unlocked yes)
			(layer "F.Fab")
			(hide yes)
			(effects
				(font
					(size 1.016 1.016)
					(thickness 0.1524)
				)
			)
		)
		(duplicate_pad_numbers_are_jumpers no)
		(fp_line
			(start -0.508 -0.9398)
			(end -0.508 0.9398)
			(stroke
				(width 0.1524)
				(type default)
			)
			(layer "F.SilkS")
		)
		(fp_line
			(start 0.508 -0.9398)
			(end -0.508 -0.9398)
			(stroke
				(width 0.1524)
				(type default)
			)
			(layer "F.SilkS")
		)
		(fp_rect
			(start -0.508 0.9398)
			(end 0.508 -0.9398)
			(stroke
				(width 0)
				(type default)
			)
			(fill no)
			(layer "F.CrtYd")
		)
		(fp_rect
			(start -0.508 0.9398)
			(end 0.508 -0.9398)
			(stroke
				(width 0)
				(type default)
			)
			(fill no)
			(layer "F.Fab")
		)
		(pad "1" smd custom
			(at 0 -0.4445 270)
			(size 0.1397 0.1397)
			(layers "F.Cu" "F.Mask" "F.Paste")
			(net "SW_HDD_N11")
			(options
				(clearance outline)
				(anchor circle)
			)
			(primitives
				(gr_poly
					(pts
						(arc
							(start -0.1778 -0.2794)
							(mid -0.249642 -0.249642)
							(end -0.2794 -0.1778)
						)
						(arc
							(start -0.2794 0.1778)
							(mid -0.249642 0.249642)
							(end -0.1778 0.2794)
						)
						(arc
							(start 0.1778 0.2794)
							(mid 0.249642 0.249642)
							(end 0.2794 0.1778)
						)
						(arc
							(start 0.2794 -0.1778)
							(mid 0.249642 -0.249642)
							(end 0.1778 -0.2794)
						)
					)
					(width 0)
					(fill yes)
				)
			)
		)
		(pad "2" smd custom
			(at 0 0.4445 270)
			(size 0.1397 0.1397)
			(layers "F.Cu" "F.Mask" "F.Paste")
			(net "P12V_A")
			(options
				(clearance outline)
				(anchor circle)
			)
			(primitives
				(gr_poly
					(pts
						(arc
							(start -0.1778 -0.2794)
							(mid -0.249642 -0.249642)
							(end -0.2794 -0.1778)
						)
						(arc
							(start -0.2794 0.1778)
							(mid -0.249642 0.249642)
							(end -0.1778 0.2794)
						)
						(arc
							(start 0.1778 0.2794)
							(mid 0.249642 0.249642)
							(end 0.2794 0.1778)
						)
						(arc
							(start 0.2794 -0.1778)
							(mid 0.249642 -0.249642)
							(end 0.1778 -0.2794)
						)
					)
					(width 0)
					(fill yes)
				)
			)
		)
	)
	(footprint ""
		(layer "F.Cu")
		(at 331.47 -303.954942 180)
		(property "Reference" "C122"
			(at 0 0 180)
			(layer "F.SilkS")
			(hide yes)
			(effects
				(font
					(size 1.27 1.27)
				)
			)
		)
		(property "Value" "SC4D7U25V5KX-1-GP"
			(at -0.0762 -6.1214 180)
			(unlocked yes)
			(layer "F.Fab")
			(hide yes)
			(effects
				(font
					(size 1.016 1.016)
					(thickness 0.1524)
				)
			)
		)
		(property "Device Type" "C805H58"
			(at -0.0762 -8.1534 180)
			(unlocked yes)
			(layer "F.Fab")
			(hide yes)
			(effects
				(font
					(size 1.016 1.016)
					(thickness 0.1524)
				)
			)
		)
		(duplicate_pad_numbers_are_jumpers no)
		(fp_line
			(start 0.635 0)
			(end -0.635 0)
			(stroke
				(width 0.508)
				(type default)
			)
			(layer "F.SilkS")
		)
		(fp_rect
			(start -0.9652 1.778)
			(end 0.9652 -1.778)
			(stroke
				(width 0)
				(type default)
			)
			(fill no)
			(layer "F.CrtYd")
		)
		(fp_poly
			(pts
				(xy -0.9652 -1.778) (xy 0.9652 -1.778) (xy 0.9652 1.778) (xy -0.9652 1.778)
			)
			(stroke
				(width 0)
				(type default)
			)
			(fill no)
			(layer "F.Fab")
		)
		(pad "1" smd rect
			(at 0 -0.9652 180)
			(size 1.397 1.143)
			(layers "F.Cu" "F.Mask" "F.Paste")
			(net "P12V_HDD6")
		)
		(pad "2" smd rect
			(at 0 0.9652 180)
			(size 1.397 1.143)
			(layers "F.Cu" "F.Mask" "F.Paste")
			(net "GND")
		)
	)
	(footprint ""
		(layer "F.Cu")
		(at 321.634612 -43.660568 -90)
		(property "Reference" "C429"
			(at 0 0 270)
			(layer "F.SilkS")
			(hide yes)
			(effects
				(font
					(size 1.27 1.27)
				)
			)
		)
		(property "Value" "SCD01U16V1KX-GP"
			(at -2.8321 -1.7399 270)
			(unlocked yes)
			(layer "F.Fab")
			(hide yes)
			(effects
				(font
					(size 1.016 1.016)
					(thickness 0.1524)
				)
			)
		)
		(property "Device Type" "C0201H13"
			(at -2.8321 -3.2639 270)
			(unlocked yes)
			(layer "F.Fab")
			(hide yes)
			(effects
				(font
					(size 1.016 1.016)
					(thickness 0.1524)
				)
			)
		)
		(duplicate_pad_numbers_are_jumpers no)
		(fp_rect
			(start -0.2794 0.6477)
			(end 0.2794 -0.6477)
			(stroke
				(width 0)
				(type default)
			)
			(fill no)
			(layer "F.CrtYd")
		)
		(fp_rect
			(start -0.2794 0.6477)
			(end 0.2794 -0.6477)
			(stroke
				(width 0)
				(type default)
			)
			(fill no)
			(layer "F.Fab")
		)
		(pad "1" smd custom
			(at 0 -0.2794 270)
			(size 0.0762 0.0762)
			(layers "F.Cu" "F.Mask" "F.Paste")
			(net "SAS_HDD_RX_P30")
			(options
				(clearance outline)
				(anchor circle)
			)
			(primitives
				(gr_poly
					(pts
						(arc
							(start 0.1524 -0.127)
							(mid 0.137521 -0.162921)
							(end 0.1016 -0.1778)
						)
						(arc
							(start -0.1016 -0.1778)
							(mid -0.137521 -0.162921)
							(end -0.1524 -0.127)
						)
						(arc
							(start -0.1524 0.127)
							(mid -0.137521 0.162921)
							(end -0.1016 0.1778)
						)
						(arc
							(start 0.1016 0.1778)
							(mid 0.137521 0.162921)
							(end 0.1524 0.127)
						)
					)
					(width 0)
					(fill yes)
				)
			)
		)
		(pad "2" smd custom
			(at 0 0.2794 270)
			(size 0.0762 0.0762)
			(layers "F.Cu" "F.Mask" "F.Paste")
			(net "PHY_SCC_A_TO_DRV_A_30_DP")
			(options
				(clearance outline)
				(anchor circle)
			)
			(primitives
				(gr_poly
					(pts
						(arc
							(start 0.1524 -0.127)
							(mid 0.137521 -0.162921)
							(end 0.1016 -0.1778)
						)
						(arc
							(start -0.1016 -0.1778)
							(mid -0.137521 -0.162921)
							(end -0.1524 -0.127)
						)
						(arc
							(start -0.1524 0.127)
							(mid -0.137521 0.162921)
							(end -0.1016 0.1778)
						)
						(arc
							(start 0.1016 0.1778)
							(mid 0.137521 0.162921)
							(end 0.1524 0.127)
						)
					)
					(width 0)
					(fill yes)
				)
			)
		)
	)
	(footprint ""
		(layer "F.Cu")
		(at 351.539302 -273.940016 90)
		(property "Reference" "VIA2"
			(at 0 0 90)
			(layer "F.SilkS")
			(hide yes)
			(effects
				(font
					(size 1.27 1.27)
				)
			)
		)
		(property "Value" "100OHM-8L-1D6MM-L18L16-GP"
			(at -3.7211 -4.5085 90)
			(unlocked yes)
			(layer "F.Fab")
			(hide yes)
			(effects
				(font
					(size 1.016 1.016)
					(thickness 0.1524)
				)
			)
		)
		(property "Device Type" "VIA-PCIE-4P-394076"
			(at -3.7211 -6.0325 90)
			(unlocked yes)
			(layer "F.Fab")
			(hide yes)
			(effects
				(font
					(size 1.016 1.016)
					(thickness 0.1524)
				)
			)
		)
		(duplicate_pad_numbers_are_jumpers no)
		(fp_rect
			(start -1.9685 0.381)
			(end 1.9685 -0.381)
			(stroke
				(width 0)
				(type default)
			)
			(fill no)
			(layer "F.CrtYd")
		)
		(fp_rect
			(start -1.9685 0.381)
			(end 1.9685 -0.381)
			(stroke
				(width 0)
				(type default)
			)
			(fill no)
			(layer "F.Fab")
		)
		(pad "1" thru_hole circle
			(at -1.5875 0 90)
			(size 0.508 0.508)
			(drill 0.254)
			(layers "*.Cu" "*.Mask")
			(remove_unused_layers no)
			(net "GND")
			(clearance 0.127)
			(thermal_gap 0.127)
		)
		(pad "2" thru_hole circle
			(at -0.5715 0 90)
			(size 0.508 0.508)
			(drill 0.254)
			(layers "*.Cu" "*.Mask")
			(remove_unused_layers no)
			(net "PHY_SCC_A_TO_DRV_A_7_DP")
			(clearance 0.127)
			(thermal_gap 0.127)
		)
		(pad "3" thru_hole circle
			(at 0.5715 0 90)
			(size 0.508 0.508)
			(drill 0.254)
			(layers "*.Cu" "*.Mask")
			(remove_unused_layers no)
			(net "PHY_SCC_A_TO_DRV_A_7_DN")
			(clearance 0.127)
			(thermal_gap 0.127)
		)
		(pad "4" thru_hole circle
			(at 1.5875 0 90)
			(size 0.508 0.508)
			(drill 0.254)
			(layers "*.Cu" "*.Mask")
			(remove_unused_layers no)
			(net "GND")
			(clearance 0.127)
			(thermal_gap 0.127)
		)
	)
	(footprint ""
		(layer "F.Cu")
		(at 176.983898 -148.94433)
		(property "Reference" "C551"
			(at 0 0 0)
			(layer "F.SilkS")
			(hide yes)
			(effects
				(font
					(size 1.27 1.27)
				)
			)
		)
		(property "Value" "SCD1U25V2KX-2-GP"
			(at 1.1811 -2.7051 0)
			(unlocked yes)
			(layer "F.Fab")
			(hide yes)
			(effects
				(font
					(size 1.016 1.016)
					(thickness 0.1524)
				)
			)
		)
		(property "Device Type" "C402H22"
			(at 1.1811 -4.2291 0)
			(unlocked yes)
			(layer "F.Fab")
			(hide yes)
			(effects
				(font
					(size 1.016 1.016)
					(thickness 0.1524)
				)
			)
		)
		(duplicate_pad_numbers_are_jumpers no)
		(fp_rect
			(start -0.4318 0.9525)
			(end 0.4318 -0.9525)
			(stroke
				(width 0)
				(type default)
			)
			(fill no)
			(layer "F.CrtYd")
		)
		(fp_rect
			(start -0.4318 0.9525)
			(end 0.4318 -0.9525)
			(stroke
				(width 0)
				(type default)
			)
			(fill no)
			(layer "F.Fab")
		)
		(pad "1" smd custom
			(at 0 -0.4445)
			(size 0.1524 0.1524)
			(layers "F.Cu" "F.Mask" "F.Paste")
			(net "P12V_A")
			(options
				(clearance outline)
				(anchor circle)
			)
			(primitives
				(gr_poly
					(pts
						(arc
							(start 0.3048 -0.2032)
							(mid 0.275042 -0.275042)
							(end 0.2032 -0.3048)
						)
						(arc
							(start -0.2032 -0.3048)
							(mid -0.275042 -0.275042)
							(end -0.3048 -0.2032)
						)
						(arc
							(start -0.3048 0.2032)
							(mid -0.275042 0.275042)
							(end -0.2032 0.3048)
						)
						(arc
							(start 0.2032 0.3048)
							(mid 0.275042 0.275042)
							(end 0.3048 0.2032)
						)
					)
					(width 0)
					(fill yes)
				)
			)
		)
		(pad "2" smd custom
			(at 0 0.4445)
			(size 0.1524 0.1524)
			(layers "F.Cu" "F.Mask" "F.Paste")
			(net "GND")
			(options
				(clearance outline)
				(anchor circle)
			)
			(primitives
				(gr_poly
					(pts
						(arc
							(start 0.3048 -0.2032)
							(mid 0.275042 -0.275042)
							(end 0.2032 -0.3048)
						)
						(arc
							(start -0.2032 -0.3048)
							(mid -0.275042 -0.275042)
							(end -0.3048 -0.2032)
						)
						(arc
							(start -0.3048 0.2032)
							(mid -0.275042 0.275042)
							(end -0.2032 0.3048)
						)
						(arc
							(start 0.2032 0.3048)
							(mid 0.275042 0.275042)
							(end 0.3048 0.2032)
						)
					)
					(width 0)
					(fill yes)
				)
			)
		)
	)
	(footprint ""
		(layer "F.Cu")
		(at 77.942948 -168.482518 -90)
		(property "Reference" "R467"
			(at 0 0 270)
			(layer "F.SilkS")
			(hide yes)
			(effects
				(font
					(size 1.27 1.27)
				)
			)
		)
		(property "Value" "300KR2F-GP"
			(at 0.064008 -3.993896 270)
			(unlocked yes)
			(layer "F.Fab")
			(hide yes)
			(effects
				(font
					(size 1.016 1.016)
					(thickness 0.1524)
				)
			)
		)
		(property "Device Type" "R402H16"
			(at 0.064008 -5.517896 270)
			(unlocked yes)
			(layer "F.Fab")
			(hide yes)
			(effects
				(font
					(size 1.016 1.016)
					(thickness 0.1524)
				)
			)
		)
		(duplicate_pad_numbers_are_jumpers no)
		(fp_line
			(start -0.508 -0.9398)
			(end -0.508 0.9398)
			(stroke
				(width 0.1524)
				(type default)
			)
			(layer "F.SilkS")
		)
		(fp_line
			(start 0.508 -0.9398)
			(end -0.508 -0.9398)
			(stroke
				(width 0.1524)
				(type default)
			)
			(layer "F.SilkS")
		)
		(fp_rect
			(start -0.508 0.9398)
			(end 0.508 -0.9398)
			(stroke
				(width 0)
				(type default)
			)
			(fill no)
			(layer "F.CrtYd")
		)
		(fp_rect
			(start -0.508 0.9398)
			(end 0.508 -0.9398)
			(stroke
				(width 0)
				(type default)
			)
			(fill no)
			(layer "F.Fab")
		)
		(pad "1" smd custom
			(at 0 -0.4445 270)
			(size 0.1397 0.1397)
			(layers "F.Cu" "F.Mask" "F.Paste")
			(net "SW_HDD_N14")
			(options
				(clearance outline)
				(anchor circle)
			)
			(primitives
				(gr_poly
					(pts
						(arc
							(start -0.1778 -0.2794)
							(mid -0.249642 -0.249642)
							(end -0.2794 -0.1778)
						)
						(arc
							(start -0.2794 0.1778)
							(mid -0.249642 0.249642)
							(end -0.1778 0.2794)
						)
						(arc
							(start 0.1778 0.2794)
							(mid 0.249642 0.249642)
							(end 0.2794 0.1778)
						)
						(arc
							(start 0.2794 -0.1778)
							(mid 0.249642 -0.249642)
							(end 0.1778 -0.2794)
						)
					)
					(width 0)
					(fill yes)
				)
			)
		)
		(pad "2" smd custom
			(at 0 0.4445 270)
			(size 0.1397 0.1397)
			(layers "F.Cu" "F.Mask" "F.Paste")
			(net "P12V_A")
			(options
				(clearance outline)
				(anchor circle)
			)
			(primitives
				(gr_poly
					(pts
						(arc
							(start -0.1778 -0.2794)
							(mid -0.249642 -0.249642)
							(end -0.2794 -0.1778)
						)
						(arc
							(start -0.2794 0.1778)
							(mid -0.249642 0.249642)
							(end -0.1778 0.2794)
						)
						(arc
							(start 0.1778 0.2794)
							(mid 0.249642 0.249642)
							(end 0.2794 0.1778)
						)
						(arc
							(start 0.2794 -0.1778)
							(mid 0.249642 -0.249642)
							(end 0.1778 -0.2794)
						)
					)
					(width 0)
					(fill yes)
				)
			)
		)
	)
	(footprint ""
		(layer "F.Cu")
		(at 375.5898 -145.8214)
		(property "Reference" "R1079"
			(at 0 0 0)
			(layer "F.SilkS")
			(hide yes)
			(effects
				(font
					(size 1.27 1.27)
				)
			)
		)
		(property "Value" "10KR2J-3-GP"
			(at 0.064008 -3.993896 0)
			(unlocked yes)
			(layer "F.Fab")
			(hide yes)
			(effects
				(font
					(size 1.016 1.016)
					(thickness 0.1524)
				)
			)
		)
		(property "Device Type" "R402H16"
			(at 0.064008 -5.517896 0)
			(unlocked yes)
			(layer "F.Fab")
			(hide yes)
			(effects
				(font
					(size 1.016 1.016)
					(thickness 0.1524)
				)
			)
		)
		(duplicate_pad_numbers_are_jumpers no)
		(fp_line
			(start -0.508 -0.9398)
			(end -0.508 0.9398)
			(stroke
				(width 0.1524)
				(type default)
			)
			(layer "F.SilkS")
		)
		(fp_line
			(start 0.508 -0.9398)
			(end -0.508 -0.9398)
			(stroke
				(width 0.1524)
				(type default)
			)
			(layer "F.SilkS")
		)
		(fp_rect
			(start -0.508 0.9398)
			(end 0.508 -0.9398)
			(stroke
				(width 0)
				(type default)
			)
			(fill no)
			(layer "F.CrtYd")
		)
		(fp_rect
			(start -0.508 0.9398)
			(end 0.508 -0.9398)
			(stroke
				(width 0)
				(type default)
			)
			(fill no)
			(layer "F.Fab")
		)
		(pad "1" smd custom
			(at 0 -0.4445)
			(size 0.1397 0.1397)
			(layers "F.Cu" "F.Mask" "F.Paste")
			(net "GND")
			(options
				(clearance outline)
				(anchor circle)
			)
			(primitives
				(gr_poly
					(pts
						(arc
							(start -0.1778 -0.2794)
							(mid -0.249642 -0.249642)
							(end -0.2794 -0.1778)
						)
						(arc
							(start -0.2794 0.1778)
							(mid -0.249642 0.249642)
							(end -0.1778 0.2794)
						)
						(arc
							(start 0.1778 0.2794)
							(mid 0.249642 0.249642)
							(end 0.2794 0.1778)
						)
						(arc
							(start 0.2794 -0.1778)
							(mid 0.249642 -0.249642)
							(end 0.1778 -0.2794)
						)
					)
					(width 0)
					(fill yes)
				)
			)
		)
		(pad "2" smd custom
			(at 0 0.4445)
			(size 0.1397 0.1397)
			(layers "F.Cu" "F.Mask" "F.Paste")
			(net "MB1_RETRY_R")
			(options
				(clearance outline)
				(anchor circle)
			)
			(primitives
				(gr_poly
					(pts
						(arc
							(start -0.1778 -0.2794)
							(mid -0.249642 -0.249642)
							(end -0.2794 -0.1778)
						)
						(arc
							(start -0.2794 0.1778)
							(mid -0.249642 0.249642)
							(end -0.1778 0.2794)
						)
						(arc
							(start 0.1778 0.2794)
							(mid 0.249642 0.249642)
							(end 0.2794 0.1778)
						)
						(arc
							(start 0.2794 -0.1778)
							(mid 0.249642 -0.249642)
							(end 0.1778 -0.2794)
						)
					)
					(width 0)
					(fill yes)
				)
			)
		)
	)
	(footprint ""
		(layer "F.Cu")
		(at 156.2354 -131.7244 180)
		(property "Reference" "R1038"
			(at 0 0 180)
			(layer "F.SilkS")
			(hide yes)
			(effects
				(font
					(size 1.27 1.27)
				)
			)
		)
		(property "Value" "100R2D-GP"
			(at 0.064008 -3.993896 180)
			(unlocked yes)
			(layer "F.Fab")
			(hide yes)
			(effects
				(font
					(size 1.016 1.016)
					(thickness 0.1524)
				)
			)
		)
		(property "Device Type" "R402H14"
			(at 0.064008 -5.517896 180)
			(unlocked yes)
			(layer "F.Fab")
			(hide yes)
			(effects
				(font
					(size 1.016 1.016)
					(thickness 0.1524)
				)
			)
		)
		(duplicate_pad_numbers_are_jumpers no)
		(fp_line
			(start 0.508 -0.9398)
			(end -0.508 -0.9398)
			(stroke
				(width 0.1524)
				(type default)
			)
			(layer "F.SilkS")
		)
		(fp_line
			(start -0.508 -0.9398)
			(end -0.508 0.9398)
			(stroke
				(width 0.1524)
				(type default)
			)
			(layer "F.SilkS")
		)
		(fp_rect
			(start -0.508 0.9398)
			(end 0.508 -0.9398)
			(stroke
				(width 0)
				(type default)
			)
			(fill no)
			(layer "F.CrtYd")
		)
		(fp_rect
			(start -0.508 0.9398)
			(end 0.508 -0.9398)
			(stroke
				(width 0)
				(type default)
			)
			(fill no)
			(layer "F.Fab")
		)
		(pad "1" smd custom
			(at 0 -0.4445 180)
			(size 0.1397 0.1397)
			(layers "F.Cu" "F.Mask" "F.Paste")
			(net "GND")
			(options
				(clearance outline)
				(anchor circle)
			)
			(primitives
				(gr_poly
					(pts
						(arc
							(start -0.1778 -0.2794)
							(mid -0.249642 -0.249642)
							(end -0.2794 -0.1778)
						)
						(arc
							(start -0.2794 0.1778)
							(mid -0.249642 0.249642)
							(end -0.1778 0.2794)
						)
						(arc
							(start 0.1778 0.2794)
							(mid 0.249642 0.249642)
							(end 0.2794 0.1778)
						)
						(arc
							(start 0.2794 -0.1778)
							(mid 0.249642 -0.249642)
							(end 0.1778 -0.2794)
						)
					)
					(width 0)
					(fill yes)
				)
			)
		)
		(pad "2" smd custom
			(at 0 0.4445 180)
			(size 0.1397 0.1397)
			(layers "F.Cu" "F.Mask" "F.Paste")
			(net "MB0_TEMP_E")
			(options
				(clearance outline)
				(anchor circle)
			)
			(primitives
				(gr_poly
					(pts
						(arc
							(start -0.1778 -0.2794)
							(mid -0.249642 -0.249642)
							(end -0.2794 -0.1778)
						)
						(arc
							(start -0.2794 0.1778)
							(mid -0.249642 0.249642)
							(end -0.1778 0.2794)
						)
						(arc
							(start 0.1778 0.2794)
							(mid 0.249642 0.249642)
							(end 0.2794 0.1778)
						)
						(arc
							(start 0.2794 -0.1778)
							(mid 0.249642 -0.249642)
							(end 0.1778 -0.2794)
						)
					)
					(width 0)
					(fill yes)
				)
			)
		)
	)
	(footprint ""
		(layer "F.Cu")
		(at 367.7158 -145.8214)
		(property "Reference" "R1084"
			(at 0 0 0)
			(layer "F.SilkS")
			(hide yes)
			(effects
				(font
					(size 1.27 1.27)
				)
			)
		)
		(property "Value" "100KR2F-L1-GP"
			(at 0.064008 -3.993896 0)
			(unlocked yes)
			(layer "F.Fab")
			(hide yes)
			(effects
				(font
					(size 1.016 1.016)
					(thickness 0.1524)
				)
			)
		)
		(property "Device Type" "R402H16"
			(at 0.064008 -5.517896 0)
			(unlocked yes)
			(layer "F.Fab")
			(hide yes)
			(effects
				(font
					(size 1.016 1.016)
					(thickness 0.1524)
				)
			)
		)
		(duplicate_pad_numbers_are_jumpers no)
		(fp_line
			(start -0.508 -0.9398)
			(end -0.508 0.9398)
			(stroke
				(width 0.1524)
				(type default)
			)
			(layer "F.SilkS")
		)
		(fp_line
			(start 0.508 -0.9398)
			(end -0.508 -0.9398)
			(stroke
				(width 0.1524)
				(type default)
			)
			(layer "F.SilkS")
		)
		(fp_rect
			(start -0.508 0.9398)
			(end 0.508 -0.9398)
			(stroke
				(width 0)
				(type default)
			)
			(fill no)
			(layer "F.CrtYd")
		)
		(fp_rect
			(start -0.508 0.9398)
			(end 0.508 -0.9398)
			(stroke
				(width 0)
				(type default)
			)
			(fill no)
			(layer "F.Fab")
		)
		(pad "1" smd custom
			(at 0 -0.4445)
			(size 0.1397 0.1397)
			(layers "F.Cu" "F.Mask" "F.Paste")
			(net "P12V_B_COMP")
			(options
				(clearance outline)
				(anchor circle)
			)
			(primitives
				(gr_poly
					(pts
						(arc
							(start -0.1778 -0.2794)
							(mid -0.249642 -0.249642)
							(end -0.2794 -0.1778)
						)
						(arc
							(start -0.2794 0.1778)
							(mid -0.249642 0.249642)
							(end -0.1778 0.2794)
						)
						(arc
							(start 0.1778 0.2794)
							(mid 0.249642 0.249642)
							(end 0.2794 0.1778)
						)
						(arc
							(start 0.2794 -0.1778)
							(mid 0.249642 -0.249642)
							(end 0.1778 -0.2794)
						)
					)
					(width 0)
					(fill yes)
				)
			)
		)
		(pad "2" smd custom
			(at 0 0.4445)
			(size 0.1397 0.1397)
			(layers "F.Cu" "F.Mask" "F.Paste")
			(net "MB1_P12V_PWGIN_R")
			(options
				(clearance outline)
				(anchor circle)
			)
			(primitives
				(gr_poly
					(pts
						(arc
							(start -0.1778 -0.2794)
							(mid -0.249642 -0.249642)
							(end -0.2794 -0.1778)
						)
						(arc
							(start -0.2794 0.1778)
							(mid -0.249642 0.249642)
							(end -0.1778 0.2794)
						)
						(arc
							(start 0.1778 0.2794)
							(mid 0.249642 0.249642)
							(end 0.2794 0.1778)
						)
						(arc
							(start 0.2794 -0.1778)
							(mid 0.249642 -0.249642)
							(end 0.1778 -0.2794)
						)
					)
					(width 0)
					(fill yes)
				)
			)
		)
	)
	(footprint ""
		(layer "F.Cu")
		(at 469.370918 -47.64405 90)
		(property "Reference" "D35"
			(at 0 0 90)
			(layer "F.SilkS")
			(hide yes)
			(effects
				(font
					(size 1.27 1.27)
				)
			)
		)
		(property "Value" "RB551V30-GP"
			(at 0 -6.7818 90)
			(unlocked yes)
			(layer "F.Fab")
			(hide yes)
			(effects
				(font
					(size 1.016 1.016)
					(thickness 0.1524)
				)
			)
		)
		(property "Device Type" "SOD323AKH38"
			(at 0 -8.6868 90)
			(unlocked yes)
			(layer "F.Fab")
			(hide yes)
			(effects
				(font
					(size 1.016 1.016)
					(thickness 0.1524)
				)
			)
		)
		(duplicate_pad_numbers_are_jumpers no)
		(fp_line
			(start 0.889 -1.9304)
			(end 0.889 2.159)
			(stroke
				(width 0.1524)
				(type default)
			)
			(layer "F.SilkS")
		)
		(fp_line
			(start -0.889 -1.9304)
			(end 0.889 -1.9304)
			(stroke
				(width 0.1524)
				(type default)
			)
			(layer "F.SilkS")
		)
		(fp_line
			(start 0.762 2.0574)
			(end -0.762 2.0574)
			(stroke
				(width 0.508)
				(type default)
			)
			(layer "F.SilkS")
		)
		(fp_line
			(start 0.889 2.159)
			(end -0.889 2.159)
			(stroke
				(width 0.1524)
				(type default)
			)
			(layer "F.SilkS")
		)
		(fp_line
			(start -0.889 2.159)
			(end -0.889 -1.9304)
			(stroke
				(width 0.1524)
				(type default)
			)
			(layer "F.SilkS")
		)
		(fp_rect
			(start -1.016 2.3114)
			(end 1.016 -2.0066)
			(stroke
				(width 0)
				(type default)
			)
			(fill no)
			(layer "F.CrtYd")
		)
		(fp_poly
			(pts
				(xy -1.016 -2.0066) (xy 1.016 -2.0066) (xy 1.016 2.3114) (xy -1.016 2.3114)
			)
			(stroke
				(width 0)
				(type default)
			)
			(fill no)
			(layer "F.Fab")
		)
		(pad "A" smd rect
			(at 0 -1.143 90)
			(size 0.5588 1.016)
			(layers "F.Cu" "F.Mask" "F.Paste")
			(net "SW_HDD_R35")
		)
		(pad "K" smd rect
			(at 0 1.143 90)
			(size 0.5588 1.016)
			(layers "F.Cu" "F.Mask" "F.Paste")
			(net "SW_HDD_N35")
		)
	)
	(footprint ""
		(layer "F.Cu")
		(at 367.287302 -45.735494 180)
		(property "Reference" "R860"
			(at 0 0 180)
			(layer "F.SilkS")
			(hide yes)
			(effects
				(font
					(size 1.27 1.27)
				)
			)
		)
		(property "Value" "0R2J-2-GP"
			(at 0.064008 -3.993896 180)
			(unlocked yes)
			(layer "F.Fab")
			(hide yes)
			(effects
				(font
					(size 1.016 1.016)
					(thickness 0.1524)
				)
			)
		)
		(property "Device Type" "R402H16"
			(at 0.064008 -5.517896 180)
			(unlocked yes)
			(layer "F.Fab")
			(hide yes)
			(effects
				(font
					(size 1.016 1.016)
					(thickness 0.1524)
				)
			)
		)
		(duplicate_pad_numbers_are_jumpers no)
		(fp_line
			(start 0.508 -0.9398)
			(end -0.508 -0.9398)
			(stroke
				(width 0.1524)
				(type default)
			)
			(layer "F.SilkS")
		)
		(fp_line
			(start -0.508 -0.9398)
			(end -0.508 0.9398)
			(stroke
				(width 0.1524)
				(type default)
			)
			(layer "F.SilkS")
		)
		(fp_rect
			(start -0.508 0.9398)
			(end 0.508 -0.9398)
			(stroke
				(width 0)
				(type default)
			)
			(fill no)
			(layer "F.CrtYd")
		)
		(fp_rect
			(start -0.508 0.9398)
			(end 0.508 -0.9398)
			(stroke
				(width 0)
				(type default)
			)
			(fill no)
			(layer "F.Fab")
		)
		(pad "1" smd custom
			(at 0 -0.4445 180)
			(size 0.1397 0.1397)
			(layers "F.Cu" "F.Mask" "F.Paste")
			(net "SW_HDD_G31")
			(options
				(clearance outline)
				(anchor circle)
			)
			(primitives
				(gr_poly
					(pts
						(arc
							(start -0.1778 -0.2794)
							(mid -0.249642 -0.249642)
							(end -0.2794 -0.1778)
						)
						(arc
							(start -0.2794 0.1778)
							(mid -0.249642 0.249642)
							(end -0.1778 0.2794)
						)
						(arc
							(start 0.1778 0.2794)
							(mid 0.249642 0.249642)
							(end 0.2794 0.1778)
						)
						(arc
							(start 0.2794 -0.1778)
							(mid 0.249642 -0.249642)
							(end 0.1778 -0.2794)
						)
					)
					(width 0)
					(fill yes)
				)
			)
		)
		(pad "2" smd custom
			(at 0 0.4445 180)
			(size 0.1397 0.1397)
			(layers "F.Cu" "F.Mask" "F.Paste")
			(net "SW_HDD_R31")
			(options
				(clearance outline)
				(anchor circle)
			)
			(primitives
				(gr_poly
					(pts
						(arc
							(start -0.1778 -0.2794)
							(mid -0.249642 -0.249642)
							(end -0.2794 -0.1778)
						)
						(arc
							(start -0.2794 0.1778)
							(mid -0.249642 0.249642)
							(end -0.1778 0.2794)
						)
						(arc
							(start 0.1778 0.2794)
							(mid 0.249642 0.249642)
							(end 0.2794 0.1778)
						)
						(arc
							(start 0.2794 -0.1778)
							(mid 0.249642 -0.249642)
							(end 0.1778 -0.2794)
						)
					)
					(width 0)
					(fill yes)
				)
			)
		)
	)
	(footprint ""
		(layer "F.Cu")
		(at 459.756764 -69.39026 -90)
		(property "Reference" "R913"
			(at 0 0 270)
			(layer "F.SilkS")
			(hide yes)
			(effects
				(font
					(size 1.27 1.27)
				)
			)
		)
		(property "Value" "2R6F-GP"
			(at -0.0508 -4.8514 270)
			(unlocked yes)
			(layer "F.Fab")
			(hide yes)
			(effects
				(font
					(size 1.016 1.016)
					(thickness 0.1524)
				)
			)
		)
		(property "Device Type" "R1206H26"
			(at 0 -6.3754 270)
			(unlocked yes)
			(layer "F.Fab")
			(hide yes)
			(effects
				(font
					(size 1.016 1.016)
					(thickness 0.1524)
				)
			)
		)
		(duplicate_pad_numbers_are_jumpers no)
		(fp_line
			(start -1.016 2.2352)
			(end -1.016 -2.2352)
			(stroke
				(width 0.1524)
				(type default)
			)
			(layer "F.SilkS")
		)
		(fp_line
			(start 1.016 2.2352)
			(end -1.016 2.2352)
			(stroke
				(width 0.1524)
				(type default)
			)
			(layer "F.SilkS")
		)
		(fp_line
			(start -1.016 -2.2352)
			(end 1.016 -2.2352)
			(stroke
				(width 0.1524)
				(type default)
			)
			(layer "F.SilkS")
		)
		(fp_line
			(start 1.016 -2.2352)
			(end 1.016 2.2352)
			(stroke
				(width 0.1524)
				(type default)
			)
			(layer "F.SilkS")
		)
		(fp_rect
			(start -1.0922 2.3114)
			(end 1.0922 -2.3114)
			(stroke
				(width 0)
				(type default)
			)
			(fill no)
			(layer "F.CrtYd")
		)
		(fp_poly
			(pts
				(xy -1.0922 -2.3114) (xy 1.0922 -2.3114) (xy 1.0922 2.3114) (xy -1.0922 2.3114)
			)
			(stroke
				(width 0)
				(type default)
			)
			(fill no)
			(layer "F.Fab")
		)
		(pad "1" smd rect
			(at 0 -1.397 270)
			(size 1.651 1.27)
			(layers "F.Cu" "F.Mask" "F.Paste")
			(net "P12V_HDD34")
		)
		(pad "2" smd rect
			(at 0 1.397 270)
			(size 1.651 1.27)
			(layers "F.Cu" "F.Mask" "F.Paste")
			(net "12V_PRE_34")
		)
	)
	(footprint ""
		(layer "F.Cu")
		(at 83.149948 -291.000942 -90)
		(property "Reference" "C67"
			(at 0 0 270)
			(layer "F.SilkS")
			(hide yes)
			(effects
				(font
					(size 1.27 1.27)
				)
			)
		)
		(property "Value" "SC10U16V6KX-2GP"
			(at -0.0762 -5.1308 270)
			(unlocked yes)
			(layer "F.Fab")
			(hide yes)
			(effects
				(font
					(size 1.016 1.016)
					(thickness 0.1524)
				)
			)
		)
		(property "Device Type" "C1206H71"
			(at -0.127 -6.6548 270)
			(unlocked yes)
			(layer "F.Fab")
			(hide yes)
			(effects
				(font
					(size 1.016 1.016)
					(thickness 0.1524)
				)
			)
		)
		(duplicate_pad_numbers_are_jumpers no)
		(fp_line
			(start -1.016 2.2352)
			(end -1.016 0.8382)
			(stroke
				(width 0.1524)
				(type default)
			)
			(layer "F.SilkS")
		)
		(fp_line
			(start 1.016 2.2352)
			(end -1.016 2.2352)
			(stroke
				(width 0.1524)
				(type default)
			)
			(layer "F.SilkS")
		)
		(fp_line
			(start 1.016 0.8382)
			(end 1.016 2.2352)
			(stroke
				(width 0.1524)
				(type default)
			)
			(layer "F.SilkS")
		)
		(fp_line
			(start -1.016 -0.8382)
			(end -1.016 -2.2352)
			(stroke
				(width 0.1524)
				(type default)
			)
			(layer "F.SilkS")
		)
		(fp_line
			(start -1.016 -2.2352)
			(end 1.016 -2.2352)
			(stroke
				(width 0.1524)
				(type default)
			)
			(layer "F.SilkS")
		)
		(fp_line
			(start 1.016 -2.2352)
			(end 1.016 -0.8382)
			(stroke
				(width 0.1524)
				(type default)
			)
			(layer "F.SilkS")
		)
		(fp_rect
			(start -1.0922 2.3114)
			(end 1.0922 -2.3114)
			(stroke
				(width 0)
				(type default)
			)
			(fill no)
			(layer "F.CrtYd")
		)
		(fp_poly
			(pts
				(xy 1.0922 -2.3114) (xy 1.0922 2.3114) (xy -1.0922 2.3114) (xy -1.0922 -2.3114)
			)
			(stroke
				(width 0)
				(type default)
			)
			(fill no)
			(layer "F.Fab")
		)
		(pad "1" smd rect
			(at 0 -1.397 270)
			(size 1.651 1.27)
			(layers "F.Cu" "F.Mask" "F.Paste")
			(net "P5V_HDD2")
		)
		(pad "2" smd rect
			(at 0 1.397 270)
			(size 1.651 1.27)
			(layers "F.Cu" "F.Mask" "F.Paste")
			(net "GND")
		)
	)
	(footprint ""
		(layer "F.Cu")
		(at 225.171 -365.125)
		(property "Reference" "R194"
			(at 0 0 0)
			(layer "F.SilkS")
			(hide yes)
			(effects
				(font
					(size 1.27 1.27)
				)
			)
		)
		(property "Value" "4K7R2F-GP"
			(at 0.064008 -3.993896 0)
			(unlocked yes)
			(layer "F.Fab")
			(hide yes)
			(effects
				(font
					(size 1.016 1.016)
					(thickness 0.1524)
				)
			)
		)
		(property "Device Type" "R402H16"
			(at 0.064008 -5.517896 0)
			(unlocked yes)
			(layer "F.Fab")
			(hide yes)
			(effects
				(font
					(size 1.016 1.016)
					(thickness 0.1524)
				)
			)
		)
		(duplicate_pad_numbers_are_jumpers no)
		(fp_line
			(start -0.508 -0.9398)
			(end -0.508 0.9398)
			(stroke
				(width 0.1524)
				(type default)
			)
			(layer "F.SilkS")
		)
		(fp_line
			(start 0.508 -0.9398)
			(end -0.508 -0.9398)
			(stroke
				(width 0.1524)
				(type default)
			)
			(layer "F.SilkS")
		)
		(fp_rect
			(start -0.508 0.9398)
			(end 0.508 -0.9398)
			(stroke
				(width 0)
				(type default)
			)
			(fill no)
			(layer "F.CrtYd")
		)
		(fp_rect
			(start -0.508 0.9398)
			(end 0.508 -0.9398)
			(stroke
				(width 0)
				(type default)
			)
			(fill no)
			(layer "F.Fab")
		)
		(pad "1" smd custom
			(at 0 -0.4445)
			(size 0.1397 0.1397)
			(layers "F.Cu" "F.Mask" "F.Paste")
			(net "IO_EXP3_HDD_FAULT_A2")
			(options
				(clearance outline)
				(anchor circle)
			)
			(primitives
				(gr_poly
					(pts
						(arc
							(start -0.1778 -0.2794)
							(mid -0.249642 -0.249642)
							(end -0.2794 -0.1778)
						)
						(arc
							(start -0.2794 0.1778)
							(mid -0.249642 0.249642)
							(end -0.1778 0.2794)
						)
						(arc
							(start 0.1778 0.2794)
							(mid 0.249642 0.249642)
							(end 0.2794 0.1778)
						)
						(arc
							(start 0.2794 -0.1778)
							(mid 0.249642 -0.249642)
							(end 0.1778 -0.2794)
						)
					)
					(width 0)
					(fill yes)
				)
			)
		)
		(pad "2" smd custom
			(at 0 0.4445)
			(size 0.1397 0.1397)
			(layers "F.Cu" "F.Mask" "F.Paste")
			(net "GND")
			(options
				(clearance outline)
				(anchor circle)
			)
			(primitives
				(gr_poly
					(pts
						(arc
							(start -0.1778 -0.2794)
							(mid -0.249642 -0.249642)
							(end -0.2794 -0.1778)
						)
						(arc
							(start -0.2794 0.1778)
							(mid -0.249642 0.249642)
							(end -0.1778 0.2794)
						)
						(arc
							(start 0.1778 0.2794)
							(mid 0.249642 0.249642)
							(end 0.2794 0.1778)
						)
						(arc
							(start 0.2794 -0.1778)
							(mid 0.249642 -0.249642)
							(end 0.1778 -0.2794)
						)
					)
					(width 0)
					(fill yes)
				)
			)
		)
	)
	(footprint ""
		(layer "F.Cu")
		(at 468.354918 -49.70145)
		(property "Reference" "R949"
			(at 0 0 0)
			(layer "F.SilkS")
			(hide yes)
			(effects
				(font
					(size 1.27 1.27)
				)
			)
		)
		(property "Value" "4K7R2J-2-GP"
			(at 0.064008 -3.993896 0)
			(unlocked yes)
			(layer "F.Fab")
			(hide yes)
			(effects
				(font
					(size 1.016 1.016)
					(thickness 0.1524)
				)
			)
		)
		(property "Device Type" "R402H16"
			(at 0.064008 -5.517896 0)
			(unlocked yes)
			(layer "F.Fab")
			(hide yes)
			(effects
				(font
					(size 1.016 1.016)
					(thickness 0.1524)
				)
			)
		)
		(duplicate_pad_numbers_are_jumpers no)
		(fp_line
			(start -0.508 -0.9398)
			(end -0.508 0.9398)
			(stroke
				(width 0.1524)
				(type default)
			)
			(layer "F.SilkS")
		)
		(fp_line
			(start 0.508 -0.9398)
			(end -0.508 -0.9398)
			(stroke
				(width 0.1524)
				(type default)
			)
			(layer "F.SilkS")
		)
		(fp_rect
			(start -0.508 0.9398)
			(end 0.508 -0.9398)
			(stroke
				(width 0)
				(type default)
			)
			(fill no)
			(layer "F.CrtYd")
		)
		(fp_rect
			(start -0.508 0.9398)
			(end 0.508 -0.9398)
			(stroke
				(width 0)
				(type default)
			)
			(fill no)
			(layer "F.Fab")
		)
		(pad "1" smd custom
			(at 0 -0.4445)
			(size 0.1397 0.1397)
			(layers "F.Cu" "F.Mask" "F.Paste")
			(net "P12V_A")
			(options
				(clearance outline)
				(anchor circle)
			)
			(primitives
				(gr_poly
					(pts
						(arc
							(start -0.1778 -0.2794)
							(mid -0.249642 -0.249642)
							(end -0.2794 -0.1778)
						)
						(arc
							(start -0.2794 0.1778)
							(mid -0.249642 0.249642)
							(end -0.1778 0.2794)
						)
						(arc
							(start 0.1778 0.2794)
							(mid 0.249642 0.249642)
							(end 0.2794 0.1778)
						)
						(arc
							(start 0.2794 -0.1778)
							(mid 0.249642 -0.249642)
							(end 0.1778 -0.2794)
						)
					)
					(width 0)
					(fill yes)
				)
			)
		)
		(pad "2" smd custom
			(at 0 0.4445)
			(size 0.1397 0.1397)
			(layers "F.Cu" "F.Mask" "F.Paste")
			(net "SW_HDD_R35")
			(options
				(clearance outline)
				(anchor circle)
			)
			(primitives
				(gr_poly
					(pts
						(arc
							(start -0.1778 -0.2794)
							(mid -0.249642 -0.249642)
							(end -0.2794 -0.1778)
						)
						(arc
							(start -0.2794 0.1778)
							(mid -0.249642 0.249642)
							(end -0.1778 0.2794)
						)
						(arc
							(start 0.1778 0.2794)
							(mid 0.249642 0.249642)
							(end 0.2794 0.1778)
						)
						(arc
							(start 0.2794 -0.1778)
							(mid 0.249642 -0.249642)
							(end 0.1778 -0.2794)
						)
					)
					(width 0)
					(fill yes)
				)
			)
		)
	)
	(footprint ""
		(layer "F.Cu")
		(at 245.745 -236.982)
		(property "Reference" "U8"
			(at 0 0 0)
			(layer "F.SilkS")
			(hide yes)
			(effects
				(font
					(size 1.27 1.27)
				)
			)
		)
		(property "Value" "TCA9555PWR-GP"
			(at 0 -6.9342 0)
			(unlocked yes)
			(layer "F.Fab")
			(hide yes)
			(effects
				(font
					(size 1.016 1.016)
					(thickness 0.1524)
				)
			)
		)
		(property "Device Type" "TSOIC24H48"
			(at 0 -8.5852 0)
			(unlocked yes)
			(layer "F.Fab")
			(hide yes)
			(effects
				(font
					(size 1.016 1.016)
					(thickness 0.1524)
				)
			)
		)
		(duplicate_pad_numbers_are_jumpers no)
		(fp_line
			(start -4.2291 -1.397)
			(end 3.81 -1.397)
			(stroke
				(width 0.1524)
				(type default)
			)
			(layer "F.SilkS")
		)
		(fp_line
			(start -4.2291 -0.8001)
			(end -3.429 0)
			(stroke
				(width 0.1524)
				(type default)
			)
			(layer "F.SilkS")
		)
		(fp_line
			(start -4.2291 3.937)
			(end -4.2291 -1.397)
			(stroke
				(width 0.1524)
				(type default)
			)
			(layer "F.SilkS")
		)
		(fp_line
			(start -4.22656 3.81)
			(end -4.2291 1.397)
			(stroke
				(width 0.508)
				(type default)
			)
			(layer "F.SilkS")
		)
		(fp_line
			(start -3.429 0)
			(end -4.2291 0.8001)
			(stroke
				(width 0.1524)
				(type default)
			)
			(layer "F.SilkS")
		)
		(fp_line
			(start 3.81 -1.397)
			(end 3.81 1.397)
			(stroke
				(width 0.1524)
				(type default)
			)
			(layer "F.SilkS")
		)
		(fp_line
			(start 3.81 1.397)
			(end -4.2291 1.397)
			(stroke
				(width 0.1524)
				(type default)
			)
			(layer "F.SilkS")
		)
		(fp_poly
			(pts
				(xy -3.90652 -1.8542) (xy 3.90652 -1.8542) (xy 3.90652 1.8542) (xy -3.90652 1.8542)
			)
			(stroke
				(width 0)
				(type default)
			)
			(fill yes)
			(layer "F.SilkS")
		)
		(fp_poly
			(pts
				(xy -4.2164 3.81) (xy 4.2164 3.81) (xy 4.22656 -3.81) (xy -4.2164 -3.81)
			)
			(stroke
				(width 0)
				(type default)
			)
			(fill no)
			(layer "F.CrtYd")
		)
		(fp_poly
			(pts
				(xy -4.22656 -3.81) (xy 4.22656 -3.81) (xy 4.22656 3.81) (xy -4.22656 3.81)
			)
			(stroke
				(width 0)
				(type default)
			)
			(fill no)
			(layer "F.Fab")
		)
		(pad "1" smd rect
			(at -3.57632 2.8194)
			(size 0.3556 1.524)
			(layers "F.Cu" "F.Mask" "F.Paste")
			(net "IO_EXP2_INT_N")
		)
		(pad "2" smd rect
			(at -2.92608 2.8194)
			(size 0.3556 1.524)
			(layers "F.Cu" "F.Mask" "F.Paste")
			(net "IO_EXP2_A1")
		)
		(pad "3" smd rect
			(at -2.27584 2.8194)
			(size 0.3556 1.524)
			(layers "F.Cu" "F.Mask" "F.Paste")
			(net "IO_EXP2_A2")
		)
		(pad "4" smd rect
			(at -1.6256 2.8194)
			(size 0.3556 1.524)
			(layers "F.Cu" "F.Mask" "F.Paste")
			(net "DRIVE_A_16_PWR")
		)
		(pad "5" smd rect
			(at -0.97536 2.8194)
			(size 0.3556 1.524)
			(layers "F.Cu" "F.Mask" "F.Paste")
			(net "DRIVE_A_17_PWR")
		)
		(pad "6" smd rect
			(at -0.32512 2.8194)
			(size 0.3556 1.524)
			(layers "F.Cu" "F.Mask" "F.Paste")
			(net "DRIVE_A_18_PWR")
		)
		(pad "7" smd rect
			(at 0.32512 2.8194)
			(size 0.3556 1.524)
			(layers "F.Cu" "F.Mask" "F.Paste")
			(net "DRIVE_A_19_PWR")
		)
		(pad "8" smd rect
			(at 0.97536 2.8194)
			(size 0.3556 1.524)
			(layers "F.Cu" "F.Mask" "F.Paste")
			(net "DRIVE_A_20_PWR")
		)
		(pad "9" smd rect
			(at 1.6256 2.8194)
			(size 0.3556 1.524)
			(layers "F.Cu" "F.Mask" "F.Paste")
			(net "DRIVE_A_21_PWR")
		)
		(pad "10" smd rect
			(at 2.27584 2.8194)
			(size 0.3556 1.524)
			(layers "F.Cu" "F.Mask" "F.Paste")
			(net "DRIVE_A_22_PWR")
		)
		(pad "11" smd rect
			(at 2.92608 2.8194)
			(size 0.3556 1.524)
			(layers "F.Cu" "F.Mask" "F.Paste")
			(net "DRIVE_A_23_PWR")
		)
		(pad "12" smd rect
			(at 3.57632 2.8194)
			(size 0.3556 1.524)
			(layers "F.Cu" "F.Mask" "F.Paste")
			(net "GND")
		)
		(pad "13" smd rect
			(at 3.57632 -2.8194)
			(size 0.3556 1.524)
			(layers "F.Cu" "F.Mask" "F.Paste")
			(net "DRIVE_A_24_PWR")
		)
		(pad "14" smd rect
			(at 2.92608 -2.8194)
			(size 0.3556 1.524)
			(layers "F.Cu" "F.Mask" "F.Paste")
			(net "DRIVE_A_25_PWR")
		)
		(pad "15" smd rect
			(at 2.27584 -2.8194)
			(size 0.3556 1.524)
			(layers "F.Cu" "F.Mask" "F.Paste")
			(net "DRIVE_A_26_PWR")
		)
		(pad "16" smd rect
			(at 1.6256 -2.8194)
			(size 0.3556 1.524)
			(layers "F.Cu" "F.Mask" "F.Paste")
			(net "DRIVE_A_27_PWR")
		)
		(pad "17" smd rect
			(at 0.97536 -2.8194)
			(size 0.3556 1.524)
			(layers "F.Cu" "F.Mask" "F.Paste")
			(net "DRIVE_A_28_PWR")
		)
		(pad "18" smd rect
			(at 0.32512 -2.8194)
			(size 0.3556 1.524)
			(layers "F.Cu" "F.Mask" "F.Paste")
			(net "DRIVE_A_29_PWR")
		)
		(pad "19" smd rect
			(at -0.32512 -2.8194)
			(size 0.3556 1.524)
			(layers "F.Cu" "F.Mask" "F.Paste")
			(net "DRIVE_A_30_PWR")
		)
		(pad "20" smd rect
			(at -0.97536 -2.8194)
			(size 0.3556 1.524)
			(layers "F.Cu" "F.Mask" "F.Paste")
			(net "DRIVE_A_31_PWR")
		)
		(pad "21" smd rect
			(at -1.6256 -2.8194)
			(size 0.3556 1.524)
			(layers "F.Cu" "F.Mask" "F.Paste")
			(net "IO_EXP2_A0")
		)
		(pad "22" smd rect
			(at -2.27584 -2.8194)
			(size 0.3556 1.524)
			(layers "F.Cu" "F.Mask" "F.Paste")
			(net "IO_EXP2_SCL")
		)
		(pad "23" smd rect
			(at -2.92608 -2.8194)
			(size 0.3556 1.524)
			(layers "F.Cu" "F.Mask" "F.Paste")
			(net "IO_EXP2_SDA")
		)
		(pad "24" smd rect
			(at -3.57632 -2.8194)
			(size 0.3556 1.524)
			(layers "F.Cu" "F.Mask" "F.Paste")
			(net "GPIO_VCC_U8")
		)
	)
	(footprint ""
		(layer "F.Cu")
		(at 46.392846 -289.857942)
		(property "Reference" "Q8"
			(at 0 0 0)
			(layer "F.SilkS")
			(hide yes)
			(effects
				(font
					(size 1.27 1.27)
				)
			)
		)
		(property "Value" "AO4407AL-GP"
			(at -3.707384 -1.5367 0)
			(unlocked yes)
			(layer "F.Fab")
			(hide yes)
			(effects
				(font
					(size 1.016 1.016)
					(thickness 0.1524)
				)
			)
		)
		(property "Device Type" "SOIC8H69"
			(at -3.707384 -3.0607 0)
			(unlocked yes)
			(layer "F.Fab")
			(hide yes)
			(effects
				(font
					(size 1.016 1.016)
					(thickness 0.1524)
				)
			)
		)
		(duplicate_pad_numbers_are_jumpers no)
		(fp_line
			(start -2.7432 -1.4224)
			(end -2.7432 1.4224)
			(stroke
				(width 0.1524)
				(type default)
			)
			(layer "F.SilkS")
		)
		(fp_line
			(start -2.7432 1.4224)
			(end -2.6416 1.4224)
			(stroke
				(width 0.1524)
				(type default)
			)
			(layer "F.SilkS")
		)
		(fp_line
			(start -2.7432 1.4224)
			(end 2.1336 1.4224)
			(stroke
				(width 0.1524)
				(type default)
			)
			(layer "F.SilkS")
		)
		(fp_line
			(start -2.7178 -0.508)
			(end -2.1844 -0.0508)
			(stroke
				(width 0.1524)
				(type default)
			)
			(layer "F.SilkS")
		)
		(fp_line
			(start -2.6289 3.4417)
			(end -2.6289 1.4732)
			(stroke
				(width 0.381)
				(type default)
			)
			(layer "F.SilkS")
		)
		(fp_line
			(start -2.1844 -0.0508)
			(end -2.7178 0.508)
			(stroke
				(width 0.1524)
				(type default)
			)
			(layer "F.SilkS")
		)
		(fp_line
			(start 2.1336 -1.4224)
			(end -2.7432 -1.4224)
			(stroke
				(width 0.1524)
				(type default)
			)
			(layer "F.SilkS")
		)
		(fp_line
			(start 2.1336 1.4224)
			(end 2.1336 -1.4224)
			(stroke
				(width 0.1524)
				(type default)
			)
			(layer "F.SilkS")
		)
		(fp_poly
			(pts
				(xy -2.2098 -1.4224) (xy -2.2098 1.4224) (xy 2.2098 1.4224) (xy 2.2098 -1.4224)
			)
			(stroke
				(width 0)
				(type default)
			)
			(fill yes)
			(layer "F.SilkS")
		)
		(fp_rect
			(start -2.450084 2.999994)
			(end 2.450084 -2.999994)
			(stroke
				(width 0)
				(type default)
			)
			(fill no)
			(layer "F.CrtYd")
		)
		(fp_poly
			(pts
				(xy -2.8194 3.6322) (xy -2.8194 -3.6322) (xy 2.8194 -3.6322) (xy 2.8194 1.18364) (xy 2.450084 1.18364)
				(xy 2.450084 -2.999994) (xy -2.450084 -2.999994) (xy -2.450084 2.999994) (xy 2.450084 2.999994)
				(xy 2.450084 1.18618) (xy 2.8194 1.18618) (xy 2.8194 3.6322)
			)
			(stroke
				(width 0)
				(type default)
			)
			(fill no)
			(layer "F.CrtYd")
		)
		(fp_rect
			(start -2.8194 3.6322)
			(end 2.8194 -3.6322)
			(stroke
				(width 0)
				(type default)
			)
			(fill no)
			(layer "F.Fab")
		)
		(pad "1" smd rect
			(at -1.905 2.54)
			(size 0.635 1.651)
			(layers "F.Cu" "F.Mask" "F.Paste")
			(net "P12V_A")
		)
		(pad "2" smd rect
			(at -0.635 2.54)
			(size 0.635 1.651)
			(layers "F.Cu" "F.Mask" "F.Paste")
			(net "P12V_A")
		)
		(pad "3" smd rect
			(at 0.635 2.54)
			(size 0.635 1.651)
			(layers "F.Cu" "F.Mask" "F.Paste")
			(net "P12V_A")
		)
		(pad "4" smd rect
			(at 1.905 2.54)
			(size 0.635 1.651)
			(layers "F.Cu" "F.Mask" "F.Paste")
			(net "SW_HDD_N1")
		)
		(pad "5" smd rect
			(at 1.905 -2.54)
			(size 0.635 1.651)
			(layers "F.Cu" "F.Mask" "F.Paste")
			(net "P12V_HDD1")
		)
		(pad "6" smd rect
			(at 0.635 -2.54)
			(size 0.635 1.651)
			(layers "F.Cu" "F.Mask" "F.Paste")
			(net "P12V_HDD1")
		)
		(pad "7" smd rect
			(at -0.635 -2.54)
			(size 0.635 1.651)
			(layers "F.Cu" "F.Mask" "F.Paste")
			(net "P12V_HDD1")
		)
		(pad "8" smd rect
			(at -1.905 -2.54)
			(size 0.635 1.651)
			(layers "F.Cu" "F.Mask" "F.Paste")
			(net "P12V_HDD1")
		)
	)
	(footprint ""
		(layer "F.Cu")
		(at 303.4284 -74.7776 180)
		(property "Reference" "R987"
			(at 0 0 180)
			(layer "F.SilkS")
			(hide yes)
			(effects
				(font
					(size 1.27 1.27)
				)
			)
		)
		(property "Value" "100KR2F-L1-GP"
			(at 0.064008 -3.993896 180)
			(unlocked yes)
			(layer "F.Fab")
			(hide yes)
			(effects
				(font
					(size 1.016 1.016)
					(thickness 0.1524)
				)
			)
		)
		(property "Device Type" "R402H16"
			(at 0.064008 -5.517896 180)
			(unlocked yes)
			(layer "F.Fab")
			(hide yes)
			(effects
				(font
					(size 1.016 1.016)
					(thickness 0.1524)
				)
			)
		)
		(duplicate_pad_numbers_are_jumpers no)
		(fp_line
			(start 0.508 -0.9398)
			(end -0.508 -0.9398)
			(stroke
				(width 0.1524)
				(type default)
			)
			(layer "F.SilkS")
		)
		(fp_line
			(start -0.508 -0.9398)
			(end -0.508 0.9398)
			(stroke
				(width 0.1524)
				(type default)
			)
			(layer "F.SilkS")
		)
		(fp_rect
			(start -0.508 0.9398)
			(end 0.508 -0.9398)
			(stroke
				(width 0)
				(type default)
			)
			(fill no)
			(layer "F.CrtYd")
		)
		(fp_rect
			(start -0.508 0.9398)
			(end 0.508 -0.9398)
			(stroke
				(width 0)
				(type default)
			)
			(fill no)
			(layer "F.Fab")
		)
		(pad "1" smd custom
			(at 0 -0.4445 180)
			(size 0.1397 0.1397)
			(layers "F.Cu" "F.Mask" "F.Paste")
			(net "P3V3_STBY_B")
			(options
				(clearance outline)
				(anchor circle)
			)
			(primitives
				(gr_poly
					(pts
						(arc
							(start -0.1778 -0.2794)
							(mid -0.249642 -0.249642)
							(end -0.2794 -0.1778)
						)
						(arc
							(start -0.2794 0.1778)
							(mid -0.249642 0.249642)
							(end -0.1778 0.2794)
						)
						(arc
							(start 0.1778 0.2794)
							(mid 0.249642 0.249642)
							(end 0.2794 0.1778)
						)
						(arc
							(start 0.2794 -0.1778)
							(mid 0.249642 -0.249642)
							(end 0.1778 -0.2794)
						)
					)
					(width 0)
					(fill yes)
				)
			)
		)
		(pad "2" smd custom
			(at 0 0.4445 180)
			(size 0.1397 0.1397)
			(layers "F.Cu" "F.Mask" "F.Paste")
			(net "COMP_B_PRI_INS_N")
			(options
				(clearance outline)
				(anchor circle)
			)
			(primitives
				(gr_poly
					(pts
						(arc
							(start -0.1778 -0.2794)
							(mid -0.249642 -0.249642)
							(end -0.2794 -0.1778)
						)
						(arc
							(start -0.2794 0.1778)
							(mid -0.249642 0.249642)
							(end -0.1778 0.2794)
						)
						(arc
							(start 0.1778 0.2794)
							(mid 0.249642 0.249642)
							(end 0.2794 0.1778)
						)
						(arc
							(start 0.2794 -0.1778)
							(mid 0.249642 -0.249642)
							(end 0.1778 -0.2794)
						)
					)
					(width 0)
					(fill yes)
				)
			)
		)
	)
	(footprint ""
		(layer "F.Cu")
		(at 464.8073 -286.759142 -90)
		(property "Reference" "R375"
			(at 0 0 270)
			(layer "F.SilkS")
			(hide yes)
			(effects
				(font
					(size 1.27 1.27)
				)
			)
		)
		(property "Value" "300KR2F-GP"
			(at 0.064008 -3.993896 270)
			(unlocked yes)
			(layer "F.Fab")
			(hide yes)
			(effects
				(font
					(size 1.016 1.016)
					(thickness 0.1524)
				)
			)
		)
		(property "Device Type" "R402H16"
			(at 0.064008 -5.517896 270)
			(unlocked yes)
			(layer "F.Fab")
			(hide yes)
			(effects
				(font
					(size 1.016 1.016)
					(thickness 0.1524)
				)
			)
		)
		(duplicate_pad_numbers_are_jumpers no)
		(fp_line
			(start -0.508 -0.9398)
			(end -0.508 0.9398)
			(stroke
				(width 0.1524)
				(type default)
			)
			(layer "F.SilkS")
		)
		(fp_line
			(start 0.508 -0.9398)
			(end -0.508 -0.9398)
			(stroke
				(width 0.1524)
				(type default)
			)
			(layer "F.SilkS")
		)
		(fp_rect
			(start -0.508 0.9398)
			(end 0.508 -0.9398)
			(stroke
				(width 0)
				(type default)
			)
			(fill no)
			(layer "F.CrtYd")
		)
		(fp_rect
			(start -0.508 0.9398)
			(end 0.508 -0.9398)
			(stroke
				(width 0)
				(type default)
			)
			(fill no)
			(layer "F.Fab")
		)
		(pad "1" smd custom
			(at 0 -0.4445 270)
			(size 0.1397 0.1397)
			(layers "F.Cu" "F.Mask" "F.Paste")
			(net "SW_HDD_N10")
			(options
				(clearance outline)
				(anchor circle)
			)
			(primitives
				(gr_poly
					(pts
						(arc
							(start -0.1778 -0.2794)
							(mid -0.249642 -0.249642)
							(end -0.2794 -0.1778)
						)
						(arc
							(start -0.2794 0.1778)
							(mid -0.249642 0.249642)
							(end -0.1778 0.2794)
						)
						(arc
							(start 0.1778 0.2794)
							(mid 0.249642 0.249642)
							(end 0.2794 0.1778)
						)
						(arc
							(start 0.2794 -0.1778)
							(mid 0.249642 -0.249642)
							(end 0.1778 -0.2794)
						)
					)
					(width 0)
					(fill yes)
				)
			)
		)
		(pad "2" smd custom
			(at 0 0.4445 270)
			(size 0.1397 0.1397)
			(layers "F.Cu" "F.Mask" "F.Paste")
			(net "P12V_A")
			(options
				(clearance outline)
				(anchor circle)
			)
			(primitives
				(gr_poly
					(pts
						(arc
							(start -0.1778 -0.2794)
							(mid -0.249642 -0.249642)
							(end -0.2794 -0.1778)
						)
						(arc
							(start -0.2794 0.1778)
							(mid -0.249642 0.249642)
							(end -0.1778 0.2794)
						)
						(arc
							(start 0.1778 0.2794)
							(mid 0.249642 0.249642)
							(end 0.2794 0.1778)
						)
						(arc
							(start 0.2794 -0.1778)
							(mid 0.249642 -0.249642)
							(end 0.1778 -0.2794)
						)
					)
					(width 0)
					(fill yes)
				)
			)
		)
	)
	(footprint ""
		(layer "F.Cu")
		(at 381.36195 -176.127918 -90)
		(property "Reference" "C303"
			(at 0 0 270)
			(layer "F.SilkS")
			(hide yes)
			(effects
				(font
					(size 1.27 1.27)
				)
			)
		)
		(property "Value" "SCD01U50V2KX-1GP"
			(at 1.1811 -2.7051 270)
			(unlocked yes)
			(layer "F.Fab")
			(hide yes)
			(effects
				(font
					(size 1.016 1.016)
					(thickness 0.1524)
				)
			)
		)
		(property "Device Type" "C402H22"
			(at 1.1811 -4.2291 270)
			(unlocked yes)
			(layer "F.Fab")
			(hide yes)
			(effects
				(font
					(size 1.016 1.016)
					(thickness 0.1524)
				)
			)
		)
		(duplicate_pad_numbers_are_jumpers no)
		(fp_rect
			(start -0.4318 0.9525)
			(end 0.4318 -0.9525)
			(stroke
				(width 0)
				(type default)
			)
			(fill no)
			(layer "F.CrtYd")
		)
		(fp_rect
			(start -0.4318 0.9525)
			(end 0.4318 -0.9525)
			(stroke
				(width 0)
				(type default)
			)
			(fill no)
			(layer "F.Fab")
		)
		(pad "1" smd custom
			(at 0 -0.4445 270)
			(size 0.1524 0.1524)
			(layers "F.Cu" "F.Mask" "F.Paste")
			(net "HDD_PRSNT_20")
			(options
				(clearance outline)
				(anchor circle)
			)
			(primitives
				(gr_poly
					(pts
						(arc
							(start 0.3048 -0.2032)
							(mid 0.275042 -0.275042)
							(end 0.2032 -0.3048)
						)
						(arc
							(start -0.2032 -0.3048)
							(mid -0.275042 -0.275042)
							(end -0.3048 -0.2032)
						)
						(arc
							(start -0.3048 0.2032)
							(mid -0.275042 0.275042)
							(end -0.2032 0.3048)
						)
						(arc
							(start 0.2032 0.3048)
							(mid 0.275042 0.275042)
							(end 0.3048 0.2032)
						)
					)
					(width 0)
					(fill yes)
				)
			)
		)
		(pad "2" smd custom
			(at 0 0.4445 270)
			(size 0.1524 0.1524)
			(layers "F.Cu" "F.Mask" "F.Paste")
			(net "GND")
			(options
				(clearance outline)
				(anchor circle)
			)
			(primitives
				(gr_poly
					(pts
						(arc
							(start 0.3048 -0.2032)
							(mid 0.275042 -0.275042)
							(end 0.2032 -0.3048)
						)
						(arc
							(start -0.2032 -0.3048)
							(mid -0.275042 -0.275042)
							(end -0.3048 -0.2032)
						)
						(arc
							(start -0.3048 0.2032)
							(mid -0.275042 0.275042)
							(end -0.2032 0.3048)
						)
						(arc
							(start 0.2032 0.3048)
							(mid 0.275042 0.275042)
							(end 0.3048 0.2032)
						)
					)
					(width 0)
					(fill yes)
				)
			)
		)
	)
	(footprint ""
		(layer "F.Cu")
		(at 86.096348 -46.014894 -90)
		(property "Reference" "R736"
			(at 0 0 270)
			(layer "F.SilkS")
			(hide yes)
			(effects
				(font
					(size 1.27 1.27)
				)
			)
		)
		(property "Value" "1KR2F-3-GP"
			(at 0.064008 -3.993896 270)
			(unlocked yes)
			(layer "F.Fab")
			(hide yes)
			(effects
				(font
					(size 1.016 1.016)
					(thickness 0.1524)
				)
			)
		)
		(property "Device Type" "R402H16"
			(at 0.064008 -5.517896 270)
			(unlocked yes)
			(layer "F.Fab")
			(hide yes)
			(effects
				(font
					(size 1.016 1.016)
					(thickness 0.1524)
				)
			)
		)
		(duplicate_pad_numbers_are_jumpers no)
		(fp_line
			(start -0.508 -0.9398)
			(end -0.508 0.9398)
			(stroke
				(width 0.1524)
				(type default)
			)
			(layer "F.SilkS")
		)
		(fp_line
			(start 0.508 -0.9398)
			(end -0.508 -0.9398)
			(stroke
				(width 0.1524)
				(type default)
			)
			(layer "F.SilkS")
		)
		(fp_rect
			(start -0.508 0.9398)
			(end 0.508 -0.9398)
			(stroke
				(width 0)
				(type default)
			)
			(fill no)
			(layer "F.CrtYd")
		)
		(fp_rect
			(start -0.508 0.9398)
			(end 0.508 -0.9398)
			(stroke
				(width 0)
				(type default)
			)
			(fill no)
			(layer "F.Fab")
		)
		(pad "1" smd custom
			(at 0 -0.4445 270)
			(size 0.1397 0.1397)
			(layers "F.Cu" "F.Mask" "F.Paste")
			(net "P3V3_STBY_A")
			(options
				(clearance outline)
				(anchor circle)
			)
			(primitives
				(gr_poly
					(pts
						(arc
							(start -0.1778 -0.2794)
							(mid -0.249642 -0.249642)
							(end -0.2794 -0.1778)
						)
						(arc
							(start -0.2794 0.1778)
							(mid -0.249642 0.249642)
							(end -0.1778 0.2794)
						)
						(arc
							(start 0.1778 0.2794)
							(mid 0.249642 0.249642)
							(end 0.2794 0.1778)
						)
						(arc
							(start 0.2794 -0.1778)
							(mid 0.249642 -0.249642)
							(end 0.1778 -0.2794)
						)
					)
					(width 0)
					(fill yes)
				)
			)
		)
		(pad "2" smd custom
			(at 0 0.4445 270)
			(size 0.1397 0.1397)
			(layers "F.Cu" "F.Mask" "F.Paste")
			(net "SW_PWR_R_HDD26")
			(options
				(clearance outline)
				(anchor circle)
			)
			(primitives
				(gr_poly
					(pts
						(arc
							(start -0.1778 -0.2794)
							(mid -0.249642 -0.249642)
							(end -0.2794 -0.1778)
						)
						(arc
							(start -0.2794 0.1778)
							(mid -0.249642 0.249642)
							(end -0.1778 0.2794)
						)
						(arc
							(start 0.1778 0.2794)
							(mid 0.249642 0.249642)
							(end 0.2794 0.1778)
						)
						(arc
							(start 0.2794 -0.1778)
							(mid 0.249642 -0.249642)
							(end 0.1778 -0.2794)
						)
					)
					(width 0)
					(fill yes)
				)
			)
		)
	)
	(footprint ""
		(layer "F.Cu")
		(at 210.000088 -419.200076)
		(property "Reference" "DPB1"
			(at 0 0 0)
			(layer "F.SilkS")
			(hide yes)
			(effects
				(font
					(size 1.27 1.27)
				)
			)
		)
		(property "Value" "AMP-CONN150-12R-4-GP"
			(at -12.8016 -12.1412 0)
			(unlocked yes)
			(layer "F.Fab")
			(hide yes)
			(effects
				(font
					(size 1.016 1.016)
					(thickness 0.1524)
				)
			)
		)
		(property "Device Type" "PREFIT-150P-258346H582"
			(at -12.8016 -13.6652 0)
			(unlocked yes)
			(layer "F.Fab")
			(hide yes)
			(effects
				(font
					(size 1.016 1.016)
					(thickness 0.1524)
				)
			)
		)
		(duplicate_pad_numbers_are_jumpers no)
		(fp_line
			(start -2.2098 -1.999996)
			(end -2.2098 17.5514)
			(stroke
				(width 0.1524)
				(type default)
			)
			(layer "F.SilkS")
		)
		(fp_line
			(start -2.2098 17.5514)
			(end 24.1046 17.5514)
			(stroke
				(width 0.1524)
				(type default)
			)
			(layer "F.SilkS")
		)
		(fp_line
			(start 24.1046 -1.999996)
			(end -2.2098 -1.999996)
			(stroke
				(width 0.1524)
				(type default)
			)
			(layer "F.SilkS")
		)
		(fp_line
			(start 24.1046 17.5514)
			(end 24.1046 -1.999996)
			(stroke
				(width 0.1524)
				(type default)
			)
			(layer "F.SilkS")
		)
		(fp_poly
			(pts
				(xy -2.2098 17.5514) (xy -2.2098 -1.999996) (xy -0.635 -1.999996) (xy -0.635 14.934946) (xy 4.826 14.934946)
				(xy 4.826 17.018) (xy 15.494 17.018) (xy 15.494 14.934946) (xy 22.234906 14.934946) (xy 22.234906 -1.999996)
				(xy 24.1046 -1.999996) (xy 24.1046 17.5514)
			)
			(stroke
				(width 0)
				(type default)
			)
			(fill yes)
			(layer "F.SilkS")
		)
		(fp_poly
			(pts
				(arc
					(start 0.254 -1.27)
					(mid 0 -1.016)
					(end -0.254 -1.27)
				)
				(arc
					(start -0.254 -1.524)
					(mid 0 -1.778)
					(end 0.254 -1.524)
				)
			)
			(stroke
				(width 0)
				(type default)
			)
			(fill yes)
			(layer "F.SilkS")
		)
		(fp_poly
			(pts
				(arc
					(start 2.054098 -1.27)
					(mid 1.800098 -1.016)
					(end 1.546098 -1.27)
				)
				(arc
					(start 1.546098 -1.524)
					(mid 1.800098 -1.778)
					(end 2.054098 -1.524)
				)
			)
			(stroke
				(width 0)
				(type default)
			)
			(fill yes)
			(layer "F.SilkS")
		)
		(fp_poly
			(pts
				(arc
					(start 3.854196 -1.27)
					(mid 3.600196 -1.016)
					(end 3.346196 -1.27)
				)
				(arc
					(start 3.346196 -1.524)
					(mid 3.600196 -1.778)
					(end 3.854196 -1.524)
				)
			)
			(stroke
				(width 0)
				(type default)
			)
			(fill yes)
			(layer "F.SilkS")
		)
		(fp_poly
			(pts
				(arc
					(start 5.654294 -1.27)
					(mid 5.400294 -1.016)
					(end 5.146294 -1.27)
				)
				(arc
					(start 5.146294 -1.524)
					(mid 5.400294 -1.778)
					(end 5.654294 -1.524)
				)
			)
			(stroke
				(width 0)
				(type default)
			)
			(fill yes)
			(layer "F.SilkS")
		)
		(fp_poly
			(pts
				(arc
					(start 7.454392 -1.27)
					(mid 7.200392 -1.016)
					(end 6.946392 -1.27)
				)
				(arc
					(start 6.946392 -1.524)
					(mid 7.200392 -1.778)
					(end 7.454392 -1.524)
				)
			)
			(stroke
				(width 0)
				(type default)
			)
			(fill yes)
			(layer "F.SilkS")
		)
		(fp_poly
			(pts
				(arc
					(start 9.25449 -1.27)
					(mid 9.00049 -1.016)
					(end 8.74649 -1.27)
				)
				(arc
					(start 8.74649 -1.524)
					(mid 9.00049 -1.778)
					(end 9.25449 -1.524)
				)
			)
			(stroke
				(width 0)
				(type default)
			)
			(fill yes)
			(layer "F.SilkS")
		)
		(fp_poly
			(pts
				(arc
					(start 11.054588 -1.27)
					(mid 10.800588 -1.016)
					(end 10.546588 -1.27)
				)
				(arc
					(start 10.546588 -1.524)
					(mid 10.800588 -1.778)
					(end 11.054588 -1.524)
				)
			)
			(stroke
				(width 0)
				(type default)
			)
			(fill yes)
			(layer "F.SilkS")
		)
		(fp_poly
			(pts
				(arc
					(start 12.854686 -1.27)
					(mid 12.600686 -1.016)
					(end 12.346686 -1.27)
				)
				(arc
					(start 12.346686 -1.524)
					(mid 12.600686 -1.778)
					(end 12.854686 -1.524)
				)
			)
			(stroke
				(width 0)
				(type default)
			)
			(fill yes)
			(layer "F.SilkS")
		)
		(fp_poly
			(pts
				(arc
					(start 16.454882 -1.27)
					(mid 16.200882 -1.016)
					(end 15.946882 -1.27)
				)
				(arc
					(start 15.946882 -1.524)
					(mid 16.200882 -1.778)
					(end 16.454882 -1.524)
				)
			)
			(stroke
				(width 0)
				(type default)
			)
			(fill yes)
			(layer "F.SilkS")
		)
		(fp_poly
			(pts
				(arc
					(start 18.25498 -1.27)
					(mid 18.00098 -1.016)
					(end 17.74698 -1.27)
				)
				(arc
					(start 17.74698 -1.524)
					(mid 18.00098 -1.778)
					(end 18.25498 -1.524)
				)
			)
			(stroke
				(width 0)
				(type default)
			)
			(fill yes)
			(layer "F.SilkS")
		)
		(fp_poly
			(pts
				(arc
					(start 20.055078 -1.27)
					(mid 19.801078 -1.016)
					(end 19.547078 -1.27)
				)
				(arc
					(start 19.547078 -1.524)
					(mid 19.801078 -1.778)
					(end 20.055078 -1.524)
				)
			)
			(stroke
				(width 0)
				(type default)
			)
			(fill yes)
			(layer "F.SilkS")
		)
		(fp_poly
			(pts
				(arc
					(start 21.855176 -1.27)
					(mid 21.601176 -1.016)
					(end 21.347176 -1.27)
				)
				(arc
					(start 21.347176 -1.524)
					(mid 21.601176 -1.778)
					(end 21.855176 -1.524)
				)
			)
			(stroke
				(width 0)
				(type default)
			)
			(fill yes)
			(layer "F.SilkS")
		)
		(fp_rect
			(start -5.3848 19.685)
			(end 26.9748 -5.4864)
			(stroke
				(width 0)
				(type default)
			)
			(fill no)
			(layer "B.CrtYd")
		)
		(fp_rect
			(start -1.9558 17.2974)
			(end 23.8506 -17.2974)
			(stroke
				(width 0)
				(type default)
			)
			(fill no)
			(layer "F.CrtYd")
		)
		(fp_poly
			(pts
				(xy -6.9596 22.3012) (xy -6.9596 -22.3012) (xy 28.8544 -22.3012) (xy 28.8544 -0.00635) (xy 24.3586 -0.00635)
				(xy 24.3586 -17.8054) (xy -2.4638 -17.8054) (xy -2.4638 17.8054) (xy 24.3586 17.8054) (xy 24.3586 0.00635)
				(xy 28.8544 0.00635) (xy 28.8544 22.3012)
			)
			(stroke
				(width 0)
				(type default)
			)
			(fill no)
			(layer "F.CrtYd")
		)
		(fp_poly
			(pts
				(xy -2.4638 17.8054) (xy -2.4638 -17.8054) (xy 24.3586 -17.8054) (xy 24.3586 -0.00635) (xy 23.8506 -0.00635)
				(xy 23.8506 -17.2974) (xy -1.9558 -17.2974) (xy -1.9558 17.2974) (xy 23.8506 17.2974) (xy 23.8506 0.00635)
				(xy 24.3586 0.00635) (xy 24.3586 17.8054)
			)
			(stroke
				(width 0)
				(type default)
			)
			(fill no)
			(layer "F.CrtYd")
		)
		(fp_rect
			(start -10.3886 24.6888)
			(end 31.9786 -10.4902)
			(stroke
				(width 0)
				(type default)
			)
			(fill no)
			(layer "B.Fab")
		)
		(fp_rect
			(start -5.3848 19.685)
			(end 26.9748 -5.4864)
			(stroke
				(width 0)
				(type default)
			)
			(fill no)
			(layer "B.Fab")
		)
		(fp_rect
			(start -11.9634 27.305)
			(end 33.8582 -27.305)
			(stroke
				(width 0)
				(type default)
			)
			(fill no)
			(layer "F.Fab")
		)
		(fp_rect
			(start -6.9596 22.3012)
			(end 28.8544 -22.3012)
			(stroke
				(width 0)
				(type default)
			)
			(fill no)
			(layer "F.Fab")
		)
		(fp_rect
			(start -2.4638 17.8054)
			(end 24.3586 -17.8054)
			(stroke
				(width 0)
				(type default)
			)
			(fill no)
			(layer "F.Fab")
		)
		(fp_text user "Press Fit"
			(at 4.953 16.1798 0)
			(unlocked yes)
			(layer "F.SilkS")
			(effects
				(font
					(size 1.016 1.016)
					(thickness 0.1524)
				)
				(justify left)
			)
		)
		(fp_text user "Slit"
			(at 7.9502 -4.9276 0)
			(unlocked yes)
			(layer "F.SilkS")
			(effects
				(font
					(size 1.016 1.016)
					(thickness 0.1524)
				)
				(justify left)
			)
		)
		(fp_text user "Can not place BGA,CSP,Wave Solder Component"
			(at -14.400784 23.2918 0)
			(unlocked yes)
			(layer "B.Fab")
			(effects
				(font
					(size 1.016 1.016)
					(thickness 0.1524)
				)
				(justify left)
			)
		)
		(fp_text user "Can not place BGA,CSP,Wave Solder Component"
			(at -13.969238 -25.531826 0)
			(unlocked yes)
			(layer "F.Fab")
			(effects
				(font
					(size 1.016 1.016)
					(thickness 0.1524)
				)
				(justify left)
			)
		)
		(fp_text user "High Limit 2mm"
			(at 1.800098 21.1328 0)
			(unlocked yes)
			(layer "F.Fab")
			(effects
				(font
					(size 1.016 1.016)
					(thickness 0.1524)
				)
				(justify left)
			)
		)
		(pad "A1" thru_hole circle
			(at 0 0)
			(size 0.762 0.762)
			(drill 0.359918)
			(layers "*.Cu" "*.Mask")
			(remove_unused_layers no)
			(net "PWM_BMC_B_ZONE_C")
			(clearance 0.1651)
			(thermal_gap 0.1651)
		)
		(pad "A2" thru_hole circle
			(at 1.800098 0.999998)
			(size 0.762 0.762)
			(drill 0.359918)
			(layers "*.Cu" "*.Mask")
			(remove_unused_layers no)
			(net "PCIE_COMP_B_TO_SCC_B_1_DP")
			(clearance 0.1651)
			(thermal_gap 0.1651)
		)
		(pad "A3" thru_hole circle
			(at 3.599942 0)
			(size 0.762 0.762)
			(drill 0.359918)
			(layers "*.Cu" "*.Mask")
			(remove_unused_layers no)
			(net "I2C_DPB_B_SCL")
			(clearance 0.1651)
			(thermal_gap 0.1651)
		)
		(pad "A4" thru_hole circle
			(at 5.40004 0.999998)
			(size 0.762 0.762)
			(drill 0.359918)
			(layers "*.Cu" "*.Mask")
			(remove_unused_layers no)
			(net "PCIE_COMP_B_TO_SCC_B_3_DP")
			(clearance 0.1651)
			(thermal_gap 0.1651)
		)
		(pad "A5" thru_hole circle
			(at 7.199884 0)
			(size 0.762 0.762)
			(drill 0.359918)
			(layers "*.Cu" "*.Mask")
			(remove_unused_layers no)
			(net "I2C_BMC_A_EXP_B_SCL")
			(clearance 0.1651)
			(thermal_gap 0.1651)
		)
		(pad "A6" thru_hole circle
			(at 8.999982 0.999998)
			(size 0.762 0.762)
			(drill 0.359918)
			(layers "*.Cu" "*.Mask")
			(remove_unused_layers no)
			(net "PCIE_COMP_B_TO_SCC_B_5_DP")
			(clearance 0.1651)
			(thermal_gap 0.1651)
		)
		(pad "A7" thru_hole circle
			(at 10.80008 0)
			(size 0.762 0.762)
			(drill 0.359918)
			(layers "*.Cu" "*.Mask")
			(remove_unused_layers no)
			(net "UART_EXP_B_TX")
			(clearance 0.1651)
			(thermal_gap 0.1651)
		)
		(pad "A8" thru_hole circle
			(at 12.599924 0.999998)
			(size 0.762 0.762)
			(drill 0.359918)
			(layers "*.Cu" "*.Mask")
			(remove_unused_layers no)
			(net "PCIE_COMP_B_TO_SCC_B_7_DP")
			(clearance 0.1651)
			(thermal_gap 0.1651)
		)
		(pad "A9" thru_hole circle
			(at 16.20012 0)
			(size 0.762 0.762)
			(drill 0.359918)
			(layers "*.Cu" "*.Mask")
			(remove_unused_layers no)
			(net "SCC_B_STBY_PGOOD")
			(clearance 0.1651)
			(thermal_gap 0.1651)
		)
		(pad "A10" thru_hole circle
			(at 17.999964 -0.100076)
			(size 0.762 0.762)
			(drill 0.359918)
			(layers "*.Cu" "*.Mask")
			(remove_unused_layers no)
			(net "SCC_B_PWR_LED")
			(clearance 0.1651)
			(thermal_gap 0.1651)
		)
		(pad "A11" thru_hole circle
			(at 19.800062 0)
			(size 0.762 0.762)
			(drill 0.359918)
			(layers "*.Cu" "*.Mask")
			(remove_unused_layers no)
			(net "DRIVE_B_24_ACT")
			(clearance 0.1651)
			(thermal_gap 0.1651)
		)
		(pad "A12" thru_hole circle
			(at 21.599906 -0.100076)
			(size 0.762 0.762)
			(drill 0.359918)
			(layers "*.Cu" "*.Mask")
			(remove_unused_layers no)
			(net "BMC_B_EXP_B_SPARE_0")
			(clearance 0.1651)
			(thermal_gap 0.1651)
		)
		(pad "B1" thru_hole circle
			(at 0 1.400048)
			(size 0.762 0.762)
			(drill 0.359918)
			(layers "*.Cu" "*.Mask")
			(remove_unused_layers no)
			(net "PWM_BMC_B_ZONE_D")
			(clearance 0.1651)
			(thermal_gap 0.1651)
		)
		(pad "B2" thru_hole circle
			(at 1.800098 2.400046)
			(size 0.762 0.762)
			(drill 0.359918)
			(layers "*.Cu" "*.Mask")
			(remove_unused_layers no)
			(net "PCIE_COMP_B_TO_SCC_B_1_DN")
			(clearance 0.1651)
			(thermal_gap 0.1651)
		)
		(pad "B3" thru_hole circle
			(at 3.599942 1.400048)
			(size 0.762 0.762)
			(drill 0.359918)
			(layers "*.Cu" "*.Mask")
			(remove_unused_layers no)
			(net "I2C_DPB_B_SDA")
			(clearance 0.1651)
			(thermal_gap 0.1651)
		)
		(pad "B4" thru_hole circle
			(at 5.40004 2.400046)
			(size 0.762 0.762)
			(drill 0.359918)
			(layers "*.Cu" "*.Mask")
			(remove_unused_layers no)
			(net "PCIE_COMP_B_TO_SCC_B_3_DN")
			(clearance 0.1651)
			(thermal_gap 0.1651)
		)
		(pad "B5" thru_hole circle
			(at 7.199884 1.400048)
			(size 0.762 0.762)
			(drill 0.359918)
			(layers "*.Cu" "*.Mask")
			(remove_unused_layers no)
			(net "I2C_BMC_A_EXP_B_SDA")
			(clearance 0.1651)
			(thermal_gap 0.1651)
		)
		(pad "B6" thru_hole circle
			(at 8.999982 2.400046)
			(size 0.762 0.762)
			(drill 0.359918)
			(layers "*.Cu" "*.Mask")
			(remove_unused_layers no)
			(net "PCIE_COMP_B_TO_SCC_B_5_DN")
			(clearance 0.1651)
			(thermal_gap 0.1651)
		)
		(pad "B7" thru_hole circle
			(at 10.80008 1.400048)
			(size 0.762 0.762)
			(drill 0.359918)
			(layers "*.Cu" "*.Mask")
			(remove_unused_layers no)
			(net "UART_EXP_B_RX")
			(clearance 0.1651)
			(thermal_gap 0.1651)
		)
		(pad "B8" thru_hole circle
			(at 12.599924 2.400046)
			(size 0.762 0.762)
			(drill 0.359918)
			(layers "*.Cu" "*.Mask")
			(remove_unused_layers no)
			(net "PCIE_COMP_B_TO_SCC_B_7_DN")
			(clearance 0.1651)
			(thermal_gap 0.1651)
		)
		(pad "B9" thru_hole circle
			(at 16.20012 1.400048)
			(size 0.762 0.762)
			(drill 0.359918)
			(layers "*.Cu" "*.Mask")
			(remove_unused_layers no)
			(net "SCC_A_FULL_PWR_EN")
			(clearance 0.1651)
			(thermal_gap 0.1651)
		)
		(pad "B10" thru_hole circle
			(at 17.999964 0.999998)
			(size 0.762 0.762)
			(drill 0.359918)
			(layers "*.Cu" "*.Mask")
			(remove_unused_layers no)
			(net "FAN_0_INS_N")
			(clearance 0.1651)
			(thermal_gap 0.1651)
		)
		(pad "B11" thru_hole circle
			(at 19.800062 1.400048)
			(size 0.762 0.762)
			(drill 0.359918)
			(layers "*.Cu" "*.Mask")
			(remove_unused_layers no)
			(net "DRIVE_B_25_ACT")
			(clearance 0.1651)
			(thermal_gap 0.1651)
		)
		(pad "B12" thru_hole circle
			(at 21.599906 0.999998)
			(size 0.762 0.762)
			(drill 0.359918)
			(layers "*.Cu" "*.Mask")
			(remove_unused_layers no)
			(net "BMC_B_EXP_B_SPARE_1")
			(clearance 0.1651)
			(thermal_gap 0.1651)
		)
		(pad "C1" thru_hole circle
			(at 0 3.599942)
			(size 0.762 0.762)
			(drill 0.359918)
			(layers "*.Cu" "*.Mask")
			(remove_unused_layers no)
			(net "PCIE_COMP_B_TO_SCC_B_0_DP")
			(clearance 0.1651)
			(thermal_gap 0.1651)
		)
		(pad "C2" thru_hole circle
			(at 1.800098 4.59994)
			(size 0.762 0.762)
			(drill 0.359918)
			(layers "*.Cu" "*.Mask")
			(remove_unused_layers no)
			(net "I2C_SCC_B_SCL")
			(clearance 0.1651)
			(thermal_gap 0.1651)
		)
		(pad "C3" thru_hole circle
			(at 3.599942 3.599942)
			(size 0.762 0.762)
			(drill 0.359918)
			(layers "*.Cu" "*.Mask")
			(remove_unused_layers no)
			(net "PCIE_COMP_B_TO_SCC_B_2_DP")
			(clearance 0.1651)
			(thermal_gap 0.1651)
		)
		(pad "C4" thru_hole circle
			(at 5.40004 4.59994)
			(size 0.762 0.762)
			(drill 0.359918)
			(layers "*.Cu" "*.Mask")
			(remove_unused_layers no)
			(net "PWM_BMC_A_ZONE_C")
			(clearance 0.1651)
			(thermal_gap 0.1651)
		)
		(pad "C5" thru_hole circle
			(at 7.199884 3.599942)
			(size 0.762 0.762)
			(drill 0.359918)
			(layers "*.Cu" "*.Mask")
			(remove_unused_layers no)
			(net "PCIE_COMP_B_TO_SCC_B_4_DP")
			(clearance 0.1651)
			(thermal_gap 0.1651)
		)
		(pad "C6" thru_hole circle
			(at 8.999982 4.59994)
			(size 0.762 0.762)
			(drill 0.359918)
			(layers "*.Cu" "*.Mask")
			(remove_unused_layers no)
			(net "I2C_DRIVE_B_FLT_LED_SDA")
			(clearance 0.1651)
			(thermal_gap 0.1651)
		)
		(pad "C7" thru_hole circle
			(at 10.80008 3.599942)
			(size 0.762 0.762)
			(drill 0.359918)
			(layers "*.Cu" "*.Mask")
			(remove_unused_layers no)
			(net "PCIE_COMP_B_TO_SCC_B_6_DP")
			(clearance 0.1651)
			(thermal_gap 0.1651)
		)
		(pad "C8" thru_hole circle
			(at 12.599924 4.59994)
			(size 0.762 0.762)
			(drill 0.359918)
			(layers "*.Cu" "*.Mask")
			(remove_unused_layers no)
			(net "UART_IOC_B_TX")
			(clearance 0.1651)
			(thermal_gap 0.1651)
		)
		(pad "C9" thru_hole circle
			(at 16.20012 2.500122)
			(size 0.762 0.762)
			(drill 0.359918)
			(layers "*.Cu" "*.Mask")
			(remove_unused_layers no)
			(net "SCC_B_FULL_PWR_EN")
			(clearance 0.1651)
			(thermal_gap 0.1651)
		)
		(pad "C10" thru_hole circle
			(at 17.999964 2.400046)
			(size 0.762 0.762)
			(drill 0.359918)
			(layers "*.Cu" "*.Mask")
			(remove_unused_layers no)
			(net "FAN_1_INS_N")
			(clearance 0.1651)
			(thermal_gap 0.1651)
		)
		(pad "C11" thru_hole circle
			(at 19.800062 2.500122)
			(size 0.762 0.762)
			(drill 0.359918)
			(layers "*.Cu" "*.Mask")
			(remove_unused_layers no)
			(net "DRIVE_B_26_ACT")
			(clearance 0.1651)
			(thermal_gap 0.1651)
		)
		(pad "C12" thru_hole circle
			(at 21.599906 2.400046)
			(size 0.762 0.762)
			(drill 0.359918)
			(layers "*.Cu" "*.Mask")
			(remove_unused_layers no)
			(net "BMC_A_HEARTBEAT")
			(clearance 0.1651)
			(thermal_gap 0.1651)
		)
		(pad "D1" thru_hole circle
			(at 0 4.99999)
			(size 0.762 0.762)
			(drill 0.359918)
			(layers "*.Cu" "*.Mask")
			(remove_unused_layers no)
			(net "PCIE_COMP_B_TO_SCC_B_0_DN")
			(clearance 0.1651)
			(thermal_gap 0.1651)
		)
		(pad "D2" thru_hole circle
			(at 1.800098 5.999988)
			(size 0.762 0.762)
			(drill 0.359918)
			(layers "*.Cu" "*.Mask")
			(remove_unused_layers no)
			(net "I2C_SCC_B_SDA")
			(clearance 0.1651)
			(thermal_gap 0.1651)
		)
		(pad "D3" thru_hole circle
			(at 3.599942 4.99999)
			(size 0.762 0.762)
			(drill 0.359918)
			(layers "*.Cu" "*.Mask")
			(remove_unused_layers no)
			(net "PCIE_COMP_B_TO_SCC_B_2_DN")
			(clearance 0.1651)
			(thermal_gap 0.1651)
		)
		(pad "D4" thru_hole circle
			(at 5.40004 5.999988)
			(size 0.762 0.762)
			(drill 0.359918)
			(layers "*.Cu" "*.Mask")
			(remove_unused_layers no)
			(net "PWM_BMC_A_ZONE_D")
			(clearance 0.1651)
			(thermal_gap 0.1651)
		)
		(pad "D5" thru_hole circle
			(at 7.199884 4.99999)
			(size 0.762 0.762)
			(drill 0.359918)
			(layers "*.Cu" "*.Mask")
			(remove_unused_layers no)
			(net "PCIE_COMP_B_TO_SCC_B_4_DN")
			(clearance 0.1651)
			(thermal_gap 0.1651)
		)
		(pad "D6" thru_hole circle
			(at 8.999982 5.999988)
			(size 0.762 0.762)
			(drill 0.359918)
			(layers "*.Cu" "*.Mask")
			(remove_unused_layers no)
			(net "I2C_DRIVE_B_FLT_LED_SCL")
			(clearance 0.1651)
			(thermal_gap 0.1651)
		)
		(pad "D7" thru_hole circle
			(at 10.80008 4.99999)
			(size 0.762 0.762)
			(drill 0.359918)
			(layers "*.Cu" "*.Mask")
			(remove_unused_layers no)
			(net "PCIE_COMP_B_TO_SCC_B_6_DN")
			(clearance 0.1651)
			(thermal_gap 0.1651)
		)
		(pad "D8" thru_hole circle
			(at 12.599924 5.999988)
			(size 0.762 0.762)
			(drill 0.359918)
			(layers "*.Cu" "*.Mask")
			(remove_unused_layers no)
			(net "UART_IOC_B_RX")
			(clearance 0.1651)
			(thermal_gap 0.1651)
		)
		(pad "D9" thru_hole circle
			(at 16.20012 3.599942)
			(size 0.762 0.762)
			(drill 0.359918)
			(layers "*.Cu" "*.Mask")
			(remove_unused_layers no)
			(net "SCC_B_FULL_PGOOD")
			(clearance 0.1651)
			(thermal_gap 0.1651)
		)
		(pad "D10" thru_hole circle
			(at 17.999964 3.50012)
			(size 0.762 0.762)
			(drill 0.359918)
			(layers "*.Cu" "*.Mask")
			(remove_unused_layers no)
			(net "FAN_2_INS_N")
			(clearance 0.1651)
			(thermal_gap 0.1651)
		)
		(pad "D11" thru_hole circle
			(at 19.800062 3.599942)
			(size 0.762 0.762)
			(drill 0.359918)
			(layers "*.Cu" "*.Mask")
			(remove_unused_layers no)
			(net "DRIVE_B_27_ACT")
			(clearance 0.1651)
			(thermal_gap 0.1651)
		)
		(pad "D12" thru_hole circle
			(at 21.599906 3.50012)
			(size 0.762 0.762)
			(drill 0.359918)
			(layers "*.Cu" "*.Mask")
			(remove_unused_layers no)
			(net "BMC_B_HEARTBEAT")
			(clearance 0.1651)
			(thermal_gap 0.1651)
		)
		(pad "E1" thru_hole circle
			(at 0 7.199884)
			(size 0.762 0.762)
			(drill 0.359918)
			(layers "*.Cu" "*.Mask")
			(remove_unused_layers no)
			(net "PCIE_COMP_B_TO_SCC_B_CLK_0_DP")
			(clearance 0.1651)
			(thermal_gap 0.1651)
		)
		(pad "E2" thru_hole circle
			(at 1.800098 8.199882)
			(size 0.762 0.762)
			(drill 0.359918)
			(layers "*.Cu" "*.Mask")
			(remove_unused_layers no)
			(net "I2C_DPB_A_SCL_BUF")
			(clearance 0.1651)
			(thermal_gap 0.1651)
		)
		(pad "E3" thru_hole circle
			(at 3.599942 7.199884)
			(size 0.762 0.762)
			(drill 0.359918)
			(layers "*.Cu" "*.Mask")
			(remove_unused_layers no)
			(net "I2C_CLIP_A_SCL")
			(clearance 0.1651)
			(thermal_gap 0.1651)
		)
		(pad "E4" thru_hole circle
			(at 5.40004 8.199882)
			(size 0.762 0.762)
			(drill 0.359918)
			(layers "*.Cu" "*.Mask")
			(remove_unused_layers no)
			(net "COMP_B_EXP_B_SPARE_0")
			(clearance 0.1651)
			(thermal_gap 0.1651)
		)
		(pad "E5" thru_hole circle
			(at 7.199884 7.199884)
			(size 0.762 0.762)
			(drill 0.359918)
			(layers "*.Cu" "*.Mask")
			(remove_unused_layers no)
			(net "I2C_BMC_B_EXP_B_SCL")
			(clearance 0.1651)
			(thermal_gap 0.1651)
		)
		(pad "E6" thru_hole circle
			(at 8.999982 8.199882)
			(size 0.762 0.762)
			(drill 0.359918)
			(layers "*.Cu" "*.Mask")
			(remove_unused_layers no)
			(net "Net_57")
			(clearance 0.1651)
			(thermal_gap 0.1651)
		)
		(pad "E7" thru_hole circle
			(at 10.80008 7.199884)
			(size 0.762 0.762)
			(drill 0.359918)
			(layers "*.Cu" "*.Mask")
			(remove_unused_layers no)
			(net "UART_SDB_B_RX")
			(clearance 0.1651)
			(thermal_gap 0.1651)
		)
		(pad "E8" thru_hole circle
			(at 12.599924 8.199882)
			(size 0.762 0.762)
			(drill 0.359918)
			(layers "*.Cu" "*.Mask")
			(remove_unused_layers no)
			(net "PWM_SCC_A_ZONE_C")
			(clearance 0.1651)
			(thermal_gap 0.1651)
		)
		(pad "E9" thru_hole circle
			(at 16.20012 4.99999)
			(size 0.762 0.762)
			(drill 0.359918)
			(layers "*.Cu" "*.Mask")
			(remove_unused_layers no)
			(net "DRAWER_CLOSED_N")
			(clearance 0.1651)
			(thermal_gap 0.1651)
		)
		(pad "E10" thru_hole circle
			(at 17.999964 4.59994)
			(size 0.762 0.762)
			(drill 0.359918)
			(layers "*.Cu" "*.Mask")
			(remove_unused_layers no)
			(net "FAN_3_INS_N")
			(clearance 0.1651)
			(thermal_gap 0.1651)
		)
		(pad "E11" thru_hole circle
			(at 19.800062 4.99999)
			(size 0.762 0.762)
			(drill 0.359918)
			(layers "*.Cu" "*.Mask")
			(remove_unused_layers no)
			(net "DRIVE_B_28_ACT")
			(clearance 0.1651)
			(thermal_gap 0.1651)
		)
		(pad "E12" thru_hole circle
			(at 21.599906 4.59994)
			(size 0.762 0.762)
			(drill 0.359918)
			(layers "*.Cu" "*.Mask")
			(remove_unused_layers no)
			(net "SCC_A_HEARTBEAT")
			(clearance 0.1651)
			(thermal_gap 0.1651)
		)
		(pad "F1" thru_hole circle
			(at 0 8.599932)
			(size 0.762 0.762)
			(drill 0.359918)
			(layers "*.Cu" "*.Mask")
			(remove_unused_layers no)
			(net "PCIE_COMP_B_TO_SCC_B_CLK_0_DN")
			(clearance 0.1651)
			(thermal_gap 0.1651)
		)
		(pad "F2" thru_hole circle
			(at 1.800098 9.59993)
			(size 0.762 0.762)
			(drill 0.359918)
			(layers "*.Cu" "*.Mask")
			(remove_unused_layers no)
			(net "I2C_DPB_A_SDA_BUF")
			(clearance 0.1651)
			(thermal_gap 0.1651)
		)
		(pad "F3" thru_hole circle
			(at 3.599942 8.599932)
			(size 0.762 0.762)
			(drill 0.359918)
			(layers "*.Cu" "*.Mask")
			(remove_unused_layers no)
			(net "I2C_CLIP_A_SDA")
			(clearance 0.1651)
			(thermal_gap 0.1651)
		)
		(pad "F4" thru_hole circle
			(at 5.40004 9.59993)
			(size 0.762 0.762)
			(drill 0.359918)
			(layers "*.Cu" "*.Mask")
			(remove_unused_layers no)
			(net "PCIE_COMP_B_TO_SCC_B_RST_0")
			(clearance 0.1651)
			(thermal_gap 0.1651)
		)
		(pad "F5" thru_hole circle
			(at 7.199884 8.599932)
			(size 0.762 0.762)
			(drill 0.359918)
			(layers "*.Cu" "*.Mask")
			(remove_unused_layers no)
			(net "I2C_BMC_B_EXP_B_SDA")
			(clearance 0.1651)
			(thermal_gap 0.1651)
		)
		(pad "F6" thru_hole circle
			(at 8.999982 9.59993)
			(size 0.762 0.762)
			(drill 0.359918)
			(layers "*.Cu" "*.Mask")
			(remove_unused_layers no)
			(net "SCC_B_RESET_N")
			(clearance 0.1651)
			(thermal_gap 0.1651)
		)
		(pad "F7" thru_hole circle
			(at 10.80008 8.599932)
			(size 0.762 0.762)
			(drill 0.359918)
			(layers "*.Cu" "*.Mask")
			(remove_unused_layers no)
			(net "UART_SDB_B_TX")
			(clearance 0.1651)
			(thermal_gap 0.1651)
		)
		(pad "F8" thru_hole circle
			(at 12.599924 9.59993)
			(size 0.762 0.762)
			(drill 0.359918)
			(layers "*.Cu" "*.Mask")
			(remove_unused_layers no)
			(net "PWM_SCC_A_ZONE_D")
			(clearance 0.1651)
			(thermal_gap 0.1651)
		)
		(pad "F9" thru_hole circle
			(at 16.20012 6.100064)
			(size 0.762 0.762)
			(drill 0.359918)
			(layers "*.Cu" "*.Mask")
			(remove_unused_layers no)
			(net "P12V_IN_PGOOD")
			(clearance 0.1651)
			(thermal_gap 0.1651)
		)
		(pad "F10" thru_hole circle
			(at 17.999964 5.999988)
			(size 0.762 0.762)
			(drill 0.359918)
			(layers "*.Cu" "*.Mask")
			(remove_unused_layers no)
			(net "IOM_A_INS_N")
			(clearance 0.1651)
			(thermal_gap 0.1651)
		)
		(pad "F11" thru_hole circle
			(at 19.800062 6.100064)
			(size 0.762 0.762)
			(drill 0.359918)
			(layers "*.Cu" "*.Mask")
			(remove_unused_layers no)
			(net "DRIVE_B_29_ACT")
			(clearance 0.1651)
			(thermal_gap 0.1651)
		)
		(pad "F12" thru_hole circle
			(at 21.599906 5.999988)
			(size 0.762 0.762)
			(drill 0.359918)
			(layers "*.Cu" "*.Mask")
			(remove_unused_layers no)
			(net "SCC_B_HEARTBEAT")
			(clearance 0.1651)
			(thermal_gap 0.1651)
		)
		(pad "G1" thru_hole circle
			(at 0 10.80008)
			(size 0.762 0.762)
			(drill 0.359918)
			(layers "*.Cu" "*.Mask")
			(remove_unused_layers no)
			(net "PCIE_SCC_B_TO_COMP_B_0_DP")
			(clearance 0.1651)
			(thermal_gap 0.1651)
		)
		(pad "G2" thru_hole circle
			(at 1.800098 11.800078)
			(size 0.762 0.762)
			(drill 0.359918)
			(layers "*.Cu" "*.Mask")
			(remove_unused_layers no)
			(net "PCIE_SCC_B_TO_COMP_B_1_DP")
			(clearance 0.1651)
			(thermal_gap 0.1651)
		)
		(pad "G3" thru_hole circle
			(at 3.599942 10.80008)
			(size 0.762 0.762)
			(drill 0.359918)
			(layers "*.Cu" "*.Mask")
			(remove_unused_layers no)
			(net "PCIE_SCC_B_TO_COMP_B_2_DP")
			(clearance 0.1651)
			(thermal_gap 0.1651)
		)
		(pad "G4" thru_hole circle
			(at 5.40004 11.800078)
			(size 0.762 0.762)
			(drill 0.359918)
			(layers "*.Cu" "*.Mask")
			(remove_unused_layers no)
			(net "PCIE_SCC_B_TO_COMP_B_3_DP")
			(clearance 0.1651)
			(thermal_gap 0.1651)
		)
		(pad "G5" thru_hole circle
			(at 7.199884 10.80008)
			(size 0.762 0.762)
			(drill 0.359918)
			(layers "*.Cu" "*.Mask")
			(remove_unused_layers no)
			(net "PCIE_SCC_B_TO_COMP_B_4_DP")
			(clearance 0.1651)
			(thermal_gap 0.1651)
		)
		(pad "G6" thru_hole circle
			(at 8.999982 11.800078)
			(size 0.762 0.762)
			(drill 0.359918)
			(layers "*.Cu" "*.Mask")
			(remove_unused_layers no)
			(net "PCIE_SCC_B_TO_COMP_B_5_DP")
			(clearance 0.1651)
			(thermal_gap 0.1651)
		)
		(pad "G7" thru_hole circle
			(at 10.80008 10.80008)
			(size 0.762 0.762)
			(drill 0.359918)
			(layers "*.Cu" "*.Mask")
			(remove_unused_layers no)
			(net "PCIE_SCC_B_TO_COMP_B_6_DP")
			(clearance 0.1651)
			(thermal_gap 0.1651)
		)
		(pad "G8" thru_hole circle
			(at 12.599924 11.800078)
			(size 0.762 0.762)
			(drill 0.359918)
			(layers "*.Cu" "*.Mask")
			(remove_unused_layers no)
			(net "PCIE_SCC_B_TO_COMP_B_7_DP")
			(clearance 0.1651)
			(thermal_gap 0.1651)
		)
		(pad "G9" thru_hole circle
			(at 16.20012 7.199884)
			(size 0.762 0.762)
			(drill 0.359918)
			(layers "*.Cu" "*.Mask")
			(remove_unused_layers no)
			(net "P12V_B_PGOOD")
			(clearance 0.1651)
			(thermal_gap 0.1651)
		)
		(pad "G10" thru_hole circle
			(at 17.999964 7.100062)
			(size 0.762 0.762)
			(drill 0.359918)
			(layers "*.Cu" "*.Mask")
			(remove_unused_layers no)
			(net "IOM_B_INS_N")
			(clearance 0.1651)
			(thermal_gap 0.1651)
		)
		(pad "G11" thru_hole circle
			(at 19.800062 7.199884)
			(size 0.762 0.762)
			(drill 0.359918)
			(layers "*.Cu" "*.Mask")
			(remove_unused_layers no)
			(net "DRIVE_B_30_ACT")
			(clearance 0.1651)
			(thermal_gap 0.1651)
		)
		(pad "G12" thru_hole circle
			(at 21.599906 7.100062)
			(size 0.762 0.762)
			(drill 0.359918)
			(layers "*.Cu" "*.Mask")
			(remove_unused_layers no)
			(net "FRONT_FAN_LED0")
			(clearance 0.1651)
			(thermal_gap 0.1651)
		)
		(pad "GND1" thru_hole circle
			(at 0 2.500122)
			(size 0.762 0.762)
			(drill 0.359918)
			(layers "*.Cu" "*.Mask")
			(remove_unused_layers no)
			(net "GND")
			(clearance 0.1651)
			(thermal_gap 0.1651)
		)
		(pad "GND2" thru_hole circle
			(at 0 6.100064)
			(size 0.762 0.762)
			(drill 0.359918)
			(layers "*.Cu" "*.Mask")
			(remove_unused_layers no)
			(net "GND")
			(clearance 0.1651)
			(thermal_gap 0.1651)
		)
		(pad "GND3" thru_hole circle
			(at 0 9.700006)
			(size 0.762 0.762)
			(drill 0.359918)
			(layers "*.Cu" "*.Mask")
			(remove_unused_layers no)
			(net "GND")
			(clearance 0.1651)
			(thermal_gap 0.1651)
		)
		(pad "GND4" thru_hole circle
			(at 0 13.299948)
			(size 0.762 0.762)
			(drill 0.359918)
			(layers "*.Cu" "*.Mask")
			(remove_unused_layers no)
			(net "GND")
			(clearance 0.1651)
			(thermal_gap 0.1651)
		)
		(pad "GND5" thru_hole circle
			(at 1.800098 -0.100076)
			(size 0.762 0.762)
			(drill 0.359918)
			(layers "*.Cu" "*.Mask")
			(remove_unused_layers no)
			(net "GND")
			(clearance 0.1651)
			(thermal_gap 0.1651)
		)
		(pad "GND6" thru_hole circle
			(at 1.800098 3.50012)
			(size 0.762 0.762)
			(drill 0.359918)
			(layers "*.Cu" "*.Mask")
			(remove_unused_layers no)
			(net "GND")
			(clearance 0.1651)
			(thermal_gap 0.1651)
		)
		(pad "GND7" thru_hole circle
			(at 1.800098 7.100062)
			(size 0.762 0.762)
			(drill 0.359918)
			(layers "*.Cu" "*.Mask")
			(remove_unused_layers no)
			(net "GND")
			(clearance 0.1651)
			(thermal_gap 0.1651)
		)
		(pad "GND8" thru_hole circle
			(at 1.800098 10.700004)
			(size 0.762 0.762)
			(drill 0.359918)
			(layers "*.Cu" "*.Mask")
			(remove_unused_layers no)
			(net "GND")
			(clearance 0.1651)
			(thermal_gap 0.1651)
		)
		(pad "GND9" thru_hole circle
			(at 1.800098 14.299946)
			(size 0.762 0.762)
			(drill 0.359918)
			(layers "*.Cu" "*.Mask")
			(remove_unused_layers no)
			(net "GND")
			(clearance 0.1651)
			(thermal_gap 0.1651)
		)
		(pad "GND10" thru_hole circle
			(at 3.599942 2.500122)
			(size 0.762 0.762)
			(drill 0.359918)
			(layers "*.Cu" "*.Mask")
			(remove_unused_layers no)
			(net "GND")
			(clearance 0.1651)
			(thermal_gap 0.1651)
		)
		(pad "GND11" thru_hole circle
			(at 3.599942 6.100064)
			(size 0.762 0.762)
			(drill 0.359918)
			(layers "*.Cu" "*.Mask")
			(remove_unused_layers no)
			(net "GND")
			(clearance 0.1651)
			(thermal_gap 0.1651)
		)
		(pad "GND12" thru_hole circle
			(at 3.599942 9.700006)
			(size 0.762 0.762)
			(drill 0.359918)
			(layers "*.Cu" "*.Mask")
			(remove_unused_layers no)
			(net "GND")
			(clearance 0.1651)
			(thermal_gap 0.1651)
		)
		(pad "GND13" thru_hole circle
			(at 3.599942 13.299948)
			(size 0.762 0.762)
			(drill 0.359918)
			(layers "*.Cu" "*.Mask")
			(remove_unused_layers no)
			(net "GND")
			(clearance 0.1651)
			(thermal_gap 0.1651)
		)
		(pad "GND14" thru_hole circle
			(at 5.40004 -0.100076)
			(size 0.762 0.762)
			(drill 0.359918)
			(layers "*.Cu" "*.Mask")
			(remove_unused_layers no)
			(net "GND")
			(clearance 0.1651)
			(thermal_gap 0.1651)
		)
		(pad "GND15" thru_hole circle
			(at 5.40004 3.50012)
			(size 0.762 0.762)
			(drill 0.359918)
			(layers "*.Cu" "*.Mask")
			(remove_unused_layers no)
			(net "GND")
			(clearance 0.1651)
			(thermal_gap 0.1651)
		)
		(pad "GND16" thru_hole circle
			(at 5.40004 7.100062)
			(size 0.762 0.762)
			(drill 0.359918)
			(layers "*.Cu" "*.Mask")
			(remove_unused_layers no)
			(net "GND")
			(clearance 0.1651)
			(thermal_gap 0.1651)
		)
		(pad "GND17" thru_hole circle
			(at 5.40004 10.700004)
			(size 0.762 0.762)
			(drill 0.359918)
			(layers "*.Cu" "*.Mask")
			(remove_unused_layers no)
			(net "GND")
			(clearance 0.1651)
			(thermal_gap 0.1651)
		)
		(pad "GND18" thru_hole circle
			(at 5.40004 14.299946)
			(size 0.762 0.762)
			(drill 0.359918)
			(layers "*.Cu" "*.Mask")
			(remove_unused_layers no)
			(net "GND")
			(clearance 0.1651)
			(thermal_gap 0.1651)
		)
		(pad "GND19" thru_hole circle
			(at 7.199884 2.500122)
			(size 0.762 0.762)
			(drill 0.359918)
			(layers "*.Cu" "*.Mask")
			(remove_unused_layers no)
			(net "GND")
			(clearance 0.1651)
			(thermal_gap 0.1651)
		)
		(pad "GND20" thru_hole circle
			(at 7.199884 6.100064)
			(size 0.762 0.762)
			(drill 0.359918)
			(layers "*.Cu" "*.Mask")
			(remove_unused_layers no)
			(net "GND")
			(clearance 0.1651)
			(thermal_gap 0.1651)
		)
		(pad "GND21" thru_hole circle
			(at 7.199884 9.700006)
			(size 0.762 0.762)
			(drill 0.359918)
			(layers "*.Cu" "*.Mask")
			(remove_unused_layers no)
			(net "GND")
			(clearance 0.1651)
			(thermal_gap 0.1651)
		)
		(pad "GND22" thru_hole circle
			(at 7.199884 13.299948)
			(size 0.762 0.762)
			(drill 0.359918)
			(layers "*.Cu" "*.Mask")
			(remove_unused_layers no)
			(net "GND")
			(clearance 0.1651)
			(thermal_gap 0.1651)
		)
		(pad "GND23" thru_hole circle
			(at 8.999982 -0.100076)
			(size 0.762 0.762)
			(drill 0.359918)
			(layers "*.Cu" "*.Mask")
			(remove_unused_layers no)
			(net "GND")
			(clearance 0.1651)
			(thermal_gap 0.1651)
		)
		(pad "GND24" thru_hole circle
			(at 8.999982 3.50012)
			(size 0.762 0.762)
			(drill 0.359918)
			(layers "*.Cu" "*.Mask")
			(remove_unused_layers no)
			(net "GND")
			(clearance 0.1651)
			(thermal_gap 0.1651)
		)
		(pad "GND25" thru_hole circle
			(at 8.999982 7.100062)
			(size 0.762 0.762)
			(drill 0.359918)
			(layers "*.Cu" "*.Mask")
			(remove_unused_layers no)
			(net "GND")
			(clearance 0.1651)
			(thermal_gap 0.1651)
		)
		(pad "GND26" thru_hole circle
			(at 8.999982 10.700004)
			(size 0.762 0.762)
			(drill 0.359918)
			(layers "*.Cu" "*.Mask")
			(remove_unused_layers no)
			(net "GND")
			(clearance 0.1651)
			(thermal_gap 0.1651)
		)
		(pad "GND27" thru_hole circle
			(at 8.999982 14.299946)
			(size 0.762 0.762)
			(drill 0.359918)
			(layers "*.Cu" "*.Mask")
			(remove_unused_layers no)
			(net "GND")
			(clearance 0.1651)
			(thermal_gap 0.1651)
		)
		(pad "GND28" thru_hole circle
			(at 10.80008 2.500122)
			(size 0.762 0.762)
			(drill 0.359918)
			(layers "*.Cu" "*.Mask")
			(remove_unused_layers no)
			(net "GND")
			(clearance 0.1651)
			(thermal_gap 0.1651)
		)
		(pad "GND29" thru_hole circle
			(at 10.80008 6.100064)
			(size 0.762 0.762)
			(drill 0.359918)
			(layers "*.Cu" "*.Mask")
			(remove_unused_layers no)
			(net "GND")
			(clearance 0.1651)
			(thermal_gap 0.1651)
		)
		(pad "GND30" thru_hole circle
			(at 10.80008 9.700006)
			(size 0.762 0.762)
			(drill 0.359918)
			(layers "*.Cu" "*.Mask")
			(remove_unused_layers no)
			(net "GND")
			(clearance 0.1651)
			(thermal_gap 0.1651)
		)
		(pad "GND31" thru_hole circle
			(at 10.80008 13.299948)
			(size 0.762 0.762)
			(drill 0.359918)
			(layers "*.Cu" "*.Mask")
			(remove_unused_layers no)
			(net "GND")
			(clearance 0.1651)
			(thermal_gap 0.1651)
		)
		(pad "GND32" thru_hole circle
			(at 12.599924 -0.100076)
			(size 0.762 0.762)
			(drill 0.359918)
			(layers "*.Cu" "*.Mask")
			(remove_unused_layers no)
			(net "GND")
			(clearance 0.1651)
			(thermal_gap 0.1651)
		)
		(pad "GND33" thru_hole circle
			(at 12.599924 3.50012)
			(size 0.762 0.762)
			(drill 0.359918)
			(layers "*.Cu" "*.Mask")
			(remove_unused_layers no)
			(net "GND")
			(clearance 0.1651)
			(thermal_gap 0.1651)
		)
		(pad "GND34" thru_hole circle
			(at 12.599924 7.100062)
			(size 0.762 0.762)
			(drill 0.359918)
			(layers "*.Cu" "*.Mask")
			(remove_unused_layers no)
			(net "GND")
			(clearance 0.1651)
			(thermal_gap 0.1651)
		)
		(pad "GND35" thru_hole circle
			(at 12.599924 10.700004)
			(size 0.762 0.762)
			(drill 0.359918)
			(layers "*.Cu" "*.Mask")
			(remove_unused_layers no)
			(net "GND")
			(clearance 0.1651)
			(thermal_gap 0.1651)
		)
		(pad "GND36" thru_hole circle
			(at 12.599924 14.299946)
			(size 0.762 0.762)
			(drill 0.359918)
			(layers "*.Cu" "*.Mask")
			(remove_unused_layers no)
			(net "GND")
			(clearance 0.1651)
			(thermal_gap 0.1651)
		)
		(pad "H1" thru_hole circle
			(at 0 12.199874)
			(size 0.762 0.762)
			(drill 0.359918)
			(layers "*.Cu" "*.Mask")
			(remove_unused_layers no)
			(net "PCIE_SCC_B_TO_COMP_B_0_DN")
			(clearance 0.1651)
			(thermal_gap 0.1651)
		)
		(pad "H2" thru_hole circle
			(at 1.800098 13.200126)
			(size 0.762 0.762)
			(drill 0.359918)
			(layers "*.Cu" "*.Mask")
			(remove_unused_layers no)
			(net "PCIE_SCC_B_TO_COMP_B_1_DN")
			(clearance 0.1651)
			(thermal_gap 0.1651)
		)
		(pad "H3" thru_hole circle
			(at 3.599942 12.199874)
			(size 0.762 0.762)
			(drill 0.359918)
			(layers "*.Cu" "*.Mask")
			(remove_unused_layers no)
			(net "PCIE_SCC_B_TO_COMP_B_2_DN")
			(clearance 0.1651)
			(thermal_gap 0.1651)
		)
		(pad "H4" thru_hole circle
			(at 5.40004 13.200126)
			(size 0.762 0.762)
			(drill 0.359918)
			(layers "*.Cu" "*.Mask")
			(remove_unused_layers no)
			(net "PCIE_SCC_B_TO_COMP_B_3_DN")
			(clearance 0.1651)
			(thermal_gap 0.1651)
		)
		(pad "H5" thru_hole circle
			(at 7.199884 12.199874)
			(size 0.762 0.762)
			(drill 0.359918)
			(layers "*.Cu" "*.Mask")
			(remove_unused_layers no)
			(net "PCIE_SCC_B_TO_COMP_B_4_DN")
			(clearance 0.1651)
			(thermal_gap 0.1651)
		)
		(pad "H6" thru_hole circle
			(at 8.999982 13.200126)
			(size 0.762 0.762)
			(drill 0.359918)
			(layers "*.Cu" "*.Mask")
			(remove_unused_layers no)
			(net "PCIE_SCC_B_TO_COMP_B_5_DN")
			(clearance 0.1651)
			(thermal_gap 0.1651)
		)
		(pad "H7" thru_hole circle
			(at 10.80008 12.199874)
			(size 0.762 0.762)
			(drill 0.359918)
			(layers "*.Cu" "*.Mask")
			(remove_unused_layers no)
			(net "PCIE_SCC_B_TO_COMP_B_6_DN")
			(clearance 0.1651)
			(thermal_gap 0.1651)
		)
		(pad "H8" thru_hole circle
			(at 12.599924 13.200126)
			(size 0.762 0.762)
			(drill 0.359918)
			(layers "*.Cu" "*.Mask")
			(remove_unused_layers no)
			(net "PCIE_SCC_B_TO_COMP_B_7_DN")
			(clearance 0.1651)
			(thermal_gap 0.1651)
		)
		(pad "H9" thru_hole circle
			(at 16.20012 8.599932)
			(size 0.762 0.762)
			(drill 0.359918)
			(layers "*.Cu" "*.Mask")
			(remove_unused_layers no)
			(net "SCC_B_STBY_PWR_EN")
			(clearance 0.1651)
			(thermal_gap 0.1651)
		)
		(pad "H10" thru_hole circle
			(at 17.999964 8.199882)
			(size 0.762 0.762)
			(drill 0.359918)
			(layers "*.Cu" "*.Mask")
			(remove_unused_layers no)
			(net "SCC_A_INS_N")
			(clearance 0.1651)
			(thermal_gap 0.1651)
		)
		(pad "H11" thru_hole circle
			(at 19.800062 8.599932)
			(size 0.762 0.762)
			(drill 0.359918)
			(layers "*.Cu" "*.Mask")
			(remove_unused_layers no)
			(net "DRIVE_B_31_ACT")
			(clearance 0.1651)
			(thermal_gap 0.1651)
		)
		(pad "H12" thru_hole circle
			(at 21.599906 8.199882)
			(size 0.762 0.762)
			(drill 0.359918)
			(layers "*.Cu" "*.Mask")
			(remove_unused_layers no)
			(net "FRONT_FAN_LED1")
			(clearance 0.1651)
			(thermal_gap 0.1651)
		)
		(pad "J9" thru_hole circle
			(at 16.20012 9.700006)
			(size 0.762 0.762)
			(drill 0.359918)
			(layers "*.Cu" "*.Mask")
			(remove_unused_layers no)
			(net "DPB_PWR_BTN_BUF_B")
			(clearance 0.1651)
			(thermal_gap 0.1651)
		)
		(pad "J10" thru_hole circle
			(at 17.999964 9.59993)
			(size 0.762 0.762)
			(drill 0.359918)
			(layers "*.Cu" "*.Mask")
			(remove_unused_layers no)
			(net "SCC_B_INS_N")
			(clearance 0.1651)
			(thermal_gap 0.1651)
		)
		(pad "J11" thru_hole circle
			(at 19.800062 9.700006)
			(size 0.762 0.762)
			(drill 0.359918)
			(layers "*.Cu" "*.Mask")
			(remove_unused_layers no)
			(net "DRIVE_B_32_ACT")
			(clearance 0.1651)
			(thermal_gap 0.1651)
		)
		(pad "J12" thru_hole circle
			(at 21.599906 9.59993)
			(size 0.762 0.762)
			(drill 0.359918)
			(layers "*.Cu" "*.Mask")
			(remove_unused_layers no)
			(net "FRONT_FAN_LED2")
			(clearance 0.1651)
			(thermal_gap 0.1651)
		)
		(pad "K9" thru_hole circle
			(at 16.20012 10.80008)
			(size 0.762 0.762)
			(drill 0.359918)
			(layers "*.Cu" "*.Mask")
			(remove_unused_layers no)
			(net "SCC_B_FAULT_LED")
			(clearance 0.1651)
			(thermal_gap 0.1651)
		)
		(pad "K10" thru_hole circle
			(at 17.999964 10.700004)
			(size 0.762 0.762)
			(drill 0.359918)
			(layers "*.Cu" "*.Mask")
			(remove_unused_layers no)
			(net "SCC_B_TYPE_0")
			(clearance 0.1651)
			(thermal_gap 0.1651)
		)
		(pad "K11" thru_hole circle
			(at 19.800062 10.80008)
			(size 0.762 0.762)
			(drill 0.359918)
			(layers "*.Cu" "*.Mask")
			(remove_unused_layers no)
			(net "DRIVE_B_33_ACT")
			(clearance 0.1651)
			(thermal_gap 0.1651)
		)
		(pad "K12" thru_hole circle
			(at 21.599906 10.700004)
			(size 0.762 0.762)
			(drill 0.359918)
			(layers "*.Cu" "*.Mask")
			(remove_unused_layers no)
			(net "FRONT_FAN_LED3")
			(clearance 0.1651)
			(thermal_gap 0.1651)
		)
		(pad "L9" thru_hole circle
			(at 16.20012 12.199874)
			(size 0.762 0.762)
			(drill 0.359918)
			(layers "*.Cu" "*.Mask")
			(remove_unused_layers no)
			(net "SCC_B_TYPE_3")
			(clearance 0.1651)
			(thermal_gap 0.1651)
		)
		(pad "L10" thru_hole circle
			(at 17.999964 11.800078)
			(size 0.762 0.762)
			(drill 0.359918)
			(layers "*.Cu" "*.Mask")
			(remove_unused_layers no)
			(net "SCC_B_TYPE_1")
			(clearance 0.1651)
			(thermal_gap 0.1651)
		)
		(pad "L11" thru_hole circle
			(at 19.800062 12.199874)
			(size 0.762 0.762)
			(drill 0.359918)
			(layers "*.Cu" "*.Mask")
			(remove_unused_layers no)
			(net "DRIVE_B_34_ACT")
			(clearance 0.1651)
			(thermal_gap 0.1651)
		)
		(pad "L12" thru_hole circle
			(at 21.599906 11.800078)
			(size 0.762 0.762)
			(drill 0.359918)
			(layers "*.Cu" "*.Mask")
			(remove_unused_layers no)
			(net "P3V3_STBY_A")
			(clearance 0.1651)
			(thermal_gap 0.1651)
		)
		(pad "M9" thru_hole circle
			(at 16.20012 13.299948)
			(size 0.762 0.762)
			(drill 0.359918)
			(layers "*.Cu" "*.Mask")
			(remove_unused_layers no)
			(net "GND")
			(clearance 0.1651)
			(thermal_gap 0.1651)
		)
		(pad "M10" thru_hole circle
			(at 17.999964 13.200126)
			(size 0.762 0.762)
			(drill 0.359918)
			(layers "*.Cu" "*.Mask")
			(remove_unused_layers no)
			(net "SCC_B_TYPE_2")
			(clearance 0.1651)
			(thermal_gap 0.1651)
		)
		(pad "M11" thru_hole circle
			(at 19.800062 13.299948)
			(size 0.762 0.762)
			(drill 0.359918)
			(layers "*.Cu" "*.Mask")
			(remove_unused_layers no)
			(net "DRIVE_B_35_ACT")
			(clearance 0.1651)
			(thermal_gap 0.1651)
		)
		(pad "M12" thru_hole circle
			(at 21.599906 13.200126)
			(size 0.762 0.762)
			(drill 0.359918)
			(layers "*.Cu" "*.Mask")
			(remove_unused_layers no)
			(net "P3V3_STBY_B")
			(clearance 0.1651)
			(thermal_gap 0.1651)
		)
		(pad "N10" thru_hole circle
			(at 17.999964 14.299946)
			(size 0.762 0.762)
			(drill 0.359918)
			(layers "*.Cu" "*.Mask")
			(remove_unused_layers no)
			(net "GND")
			(clearance 0.1651)
			(thermal_gap 0.1651)
		)
		(pad "N12" thru_hole circle
			(at 21.599906 14.299946)
			(size 0.762 0.762)
			(drill 0.359918)
			(layers "*.Cu" "*.Mask")
			(remove_unused_layers no)
			(net "P5V_B")
			(clearance 0.1651)
			(thermal_gap 0.1651)
		)
	)
	(footprint ""
		(layer "F.Cu")
		(at 365.092234 -299.42028 -90)
		(property "Reference" "R294"
			(at 0 0 270)
			(layer "F.SilkS")
			(hide yes)
			(effects
				(font
					(size 1.27 1.27)
				)
			)
		)
		(property "Value" "2R6F-GP"
			(at -0.0508 -4.8514 270)
			(unlocked yes)
			(layer "F.Fab")
			(hide yes)
			(effects
				(font
					(size 1.016 1.016)
					(thickness 0.1524)
				)
			)
		)
		(property "Device Type" "R1206H26"
			(at 0 -6.3754 270)
			(unlocked yes)
			(layer "F.Fab")
			(hide yes)
			(effects
				(font
					(size 1.016 1.016)
					(thickness 0.1524)
				)
			)
		)
		(duplicate_pad_numbers_are_jumpers no)
		(fp_line
			(start -1.016 2.2352)
			(end -1.016 -2.2352)
			(stroke
				(width 0.1524)
				(type default)
			)
			(layer "F.SilkS")
		)
		(fp_line
			(start 1.016 2.2352)
			(end -1.016 2.2352)
			(stroke
				(width 0.1524)
				(type default)
			)
			(layer "F.SilkS")
		)
		(fp_line
			(start -1.016 -2.2352)
			(end 1.016 -2.2352)
			(stroke
				(width 0.1524)
				(type default)
			)
			(layer "F.SilkS")
		)
		(fp_line
			(start 1.016 -2.2352)
			(end 1.016 2.2352)
			(stroke
				(width 0.1524)
				(type default)
			)
			(layer "F.SilkS")
		)
		(fp_rect
			(start -1.0922 2.3114)
			(end 1.0922 -2.3114)
			(stroke
				(width 0)
				(type default)
			)
			(fill no)
			(layer "F.CrtYd")
		)
		(fp_poly
			(pts
				(xy -1.0922 -2.3114) (xy 1.0922 -2.3114) (xy 1.0922 2.3114) (xy -1.0922 2.3114)
			)
			(stroke
				(width 0)
				(type default)
			)
			(fill no)
			(layer "F.Fab")
		)
		(pad "1" smd rect
			(at 0 -1.397 270)
			(size 1.651 1.27)
			(layers "F.Cu" "F.Mask" "F.Paste")
			(net "P12V_HDD7")
		)
		(pad "2" smd rect
			(at 0 1.397 270)
			(size 1.651 1.27)
			(layers "F.Cu" "F.Mask" "F.Paste")
			(net "12V_PRE_7")
		)
	)
	(footprint ""
		(layer "F.Cu")
		(at 458.5589 -65.826894 180)
		(property "Reference" "C483"
			(at 0 0 180)
			(layer "F.SilkS")
			(hide yes)
			(effects
				(font
					(size 1.27 1.27)
				)
			)
		)
		(property "Value" "SC10U16V6KX-2GP"
			(at -0.0762 -5.1308 180)
			(unlocked yes)
			(layer "F.Fab")
			(hide yes)
			(effects
				(font
					(size 1.016 1.016)
					(thickness 0.1524)
				)
			)
		)
		(property "Device Type" "C1206H71"
			(at -0.127 -6.6548 180)
			(unlocked yes)
			(layer "F.Fab")
			(hide yes)
			(effects
				(font
					(size 1.016 1.016)
					(thickness 0.1524)
				)
			)
		)
		(duplicate_pad_numbers_are_jumpers no)
		(fp_line
			(start 1.016 2.2352)
			(end -1.016 2.2352)
			(stroke
				(width 0.1524)
				(type default)
			)
			(layer "F.SilkS")
		)
		(fp_line
			(start 1.016 0.8382)
			(end 1.016 2.2352)
			(stroke
				(width 0.1524)
				(type default)
			)
			(layer "F.SilkS")
		)
		(fp_line
			(start 1.016 -2.2352)
			(end 1.016 -0.8382)
			(stroke
				(width 0.1524)
				(type default)
			)
			(layer "F.SilkS")
		)
		(fp_line
			(start -1.016 2.2352)
			(end -1.016 0.8382)
			(stroke
				(width 0.1524)
				(type default)
			)
			(layer "F.SilkS")
		)
		(fp_line
			(start -1.016 -0.8382)
			(end -1.016 -2.2352)
			(stroke
				(width 0.1524)
				(type default)
			)
			(layer "F.SilkS")
		)
		(fp_line
			(start -1.016 -2.2352)
			(end 1.016 -2.2352)
			(stroke
				(width 0.1524)
				(type default)
			)
			(layer "F.SilkS")
		)
		(fp_rect
			(start -1.0922 2.3114)
			(end 1.0922 -2.3114)
			(stroke
				(width 0)
				(type default)
			)
			(fill no)
			(layer "F.CrtYd")
		)
		(fp_poly
			(pts
				(xy 1.0922 -2.3114) (xy 1.0922 2.3114) (xy -1.0922 2.3114) (xy -1.0922 -2.3114)
			)
			(stroke
				(width 0)
				(type default)
			)
			(fill no)
			(layer "F.Fab")
		)
		(pad "1" smd rect
			(at 0 -1.397 180)
			(size 1.651 1.27)
			(layers "F.Cu" "F.Mask" "F.Paste")
			(net "P5V_HDD34")
		)
		(pad "2" smd rect
			(at 0 1.397 180)
			(size 1.651 1.27)
			(layers "F.Cu" "F.Mask" "F.Paste")
			(net "GND")
		)
	)
	(footprint ""
		(layer "F.Cu")
		(at 7.440422 -175.988726 90)
		(property "Reference" "R146"
			(at 0 0 90)
			(layer "F.SilkS")
			(hide yes)
			(effects
				(font
					(size 1.27 1.27)
				)
			)
		)
		(property "Value" "4K7R2J-2-GP"
			(at 0.064008 -3.993896 90)
			(unlocked yes)
			(layer "F.Fab")
			(hide yes)
			(effects
				(font
					(size 1.016 1.016)
					(thickness 0.1524)
				)
			)
		)
		(property "Device Type" "R402H16"
			(at 0.064008 -5.517896 90)
			(unlocked yes)
			(layer "F.Fab")
			(hide yes)
			(effects
				(font
					(size 1.016 1.016)
					(thickness 0.1524)
				)
			)
		)
		(duplicate_pad_numbers_are_jumpers no)
		(fp_line
			(start 0.508 -0.9398)
			(end -0.508 -0.9398)
			(stroke
				(width 0.1524)
				(type default)
			)
			(layer "F.SilkS")
		)
		(fp_line
			(start -0.508 -0.9398)
			(end -0.508 0.9398)
			(stroke
				(width 0.1524)
				(type default)
			)
			(layer "F.SilkS")
		)
		(fp_rect
			(start -0.508 0.9398)
			(end 0.508 -0.9398)
			(stroke
				(width 0)
				(type default)
			)
			(fill no)
			(layer "F.CrtYd")
		)
		(fp_rect
			(start -0.508 0.9398)
			(end 0.508 -0.9398)
			(stroke
				(width 0)
				(type default)
			)
			(fill no)
			(layer "F.Fab")
		)
		(pad "1" smd custom
			(at 0 -0.4445 90)
			(size 0.1397 0.1397)
			(layers "F.Cu" "F.Mask" "F.Paste")
			(net "DRIVE_A_0_FLT_LED")
			(options
				(clearance outline)
				(anchor circle)
			)
			(primitives
				(gr_poly
					(pts
						(arc
							(start -0.1778 -0.2794)
							(mid -0.249642 -0.249642)
							(end -0.2794 -0.1778)
						)
						(arc
							(start -0.2794 0.1778)
							(mid -0.249642 0.249642)
							(end -0.1778 0.2794)
						)
						(arc
							(start 0.1778 0.2794)
							(mid 0.249642 0.249642)
							(end 0.2794 0.1778)
						)
						(arc
							(start 0.2794 -0.1778)
							(mid 0.249642 -0.249642)
							(end 0.1778 -0.2794)
						)
					)
					(width 0)
					(fill yes)
				)
			)
		)
		(pad "2" smd custom
			(at 0 0.4445 90)
			(size 0.1397 0.1397)
			(layers "F.Cu" "F.Mask" "F.Paste")
			(net "GND")
			(options
				(clearance outline)
				(anchor circle)
			)
			(primitives
				(gr_poly
					(pts
						(arc
							(start -0.1778 -0.2794)
							(mid -0.249642 -0.249642)
							(end -0.2794 -0.1778)
						)
						(arc
							(start -0.2794 0.1778)
							(mid -0.249642 0.249642)
							(end -0.1778 0.2794)
						)
						(arc
							(start 0.1778 0.2794)
							(mid 0.249642 0.249642)
							(end 0.2794 0.1778)
						)
						(arc
							(start 0.2794 -0.1778)
							(mid 0.249642 -0.249642)
							(end 0.1778 -0.2794)
						)
					)
					(width 0)
					(fill yes)
				)
			)
		)
	)
	(footprint ""
		(layer "F.Cu")
		(at 69.65061 -303.904396)
		(property "Reference" "Q253"
			(at 0 0 0)
			(layer "F.SilkS")
			(hide yes)
			(effects
				(font
					(size 1.27 1.27)
				)
			)
		)
		(property "Value" "2N7002K-2-GP"
			(at 0.127 -8.9662 0)
			(unlocked yes)
			(layer "F.Fab")
			(hide yes)
			(effects
				(font
					(size 1.016 1.016)
					(thickness 0.1524)
				)
			)
		)
		(property "Device Type" "SOT23DGS2D4H44"
			(at 0.127 -10.4902 0)
			(unlocked yes)
			(layer "F.Fab")
			(hide yes)
			(effects
				(font
					(size 1.016 1.016)
					(thickness 0.1524)
				)
			)
		)
		(duplicate_pad_numbers_are_jumpers no)
		(fp_line
			(start -1.651 -1.778)
			(end -1.651 1.778)
			(stroke
				(width 0.1524)
				(type default)
			)
			(layer "F.SilkS")
		)
		(fp_line
			(start -1.651 1.778)
			(end 1.651 1.778)
			(stroke
				(width 0.1524)
				(type default)
			)
			(layer "F.SilkS")
		)
		(fp_line
			(start 1.651 -1.778)
			(end -1.651 -1.778)
			(stroke
				(width 0.1524)
				(type default)
			)
			(layer "F.SilkS")
		)
		(fp_line
			(start 1.651 1.778)
			(end 1.651 -1.778)
			(stroke
				(width 0.1524)
				(type default)
			)
			(layer "F.SilkS")
		)
		(fp_poly
			(pts
				(xy -1.778 1.8796) (xy -1.778 -1.8796) (xy 1.778 -1.8796) (xy 1.778 1.8796)
			)
			(stroke
				(width 0)
				(type default)
			)
			(fill no)
			(layer "F.CrtYd")
		)
		(fp_poly
			(pts
				(xy -1.778 1.8796) (xy -1.778 -1.8796) (xy 1.778 -1.8796) (xy 1.778 1.8796)
			)
			(stroke
				(width 0)
				(type default)
			)
			(fill no)
			(layer "F.Fab")
		)
		(pad "D" smd custom
			(at 0 -0.9525)
			(size 0.1905 0.1905)
			(layers "F.Cu" "F.Mask" "F.Paste")
			(net "FLT_HDD26_N")
			(options
				(clearance outline)
				(anchor circle)
			)
			(primitives
				(gr_poly
					(pts
						(arc
							(start -0.1778 0.5715)
							(mid -0.321484 0.511984)
							(end -0.381 0.3683)
						)
						(arc
							(start -0.381 -0.3683)
							(mid -0.321484 -0.511984)
							(end -0.1778 -0.5715)
						)
						(arc
							(start 0.1778 -0.5715)
							(mid 0.321484 -0.511984)
							(end 0.381 -0.3683)
						)
						(arc
							(start 0.381 0.3683)
							(mid 0.321484 0.511984)
							(end 0.1778 0.5715)
						)
					)
					(width 0)
					(fill yes)
				)
			)
		)
		(pad "G" smd custom
			(at -0.98425 0.9525)
			(size 0.1905 0.1905)
			(layers "F.Cu" "F.Mask" "F.Paste")
			(net "DRIVE_B_26_FLT_LED")
			(options
				(clearance outline)
				(anchor circle)
			)
			(primitives
				(gr_poly
					(pts
						(arc
							(start -0.1778 0.5715)
							(mid -0.321484 0.511984)
							(end -0.381 0.3683)
						)
						(arc
							(start -0.381 -0.3683)
							(mid -0.321484 -0.511984)
							(end -0.1778 -0.5715)
						)
						(arc
							(start 0.1778 -0.5715)
							(mid 0.321484 -0.511984)
							(end 0.381 -0.3683)
						)
						(arc
							(start 0.381 0.3683)
							(mid 0.321484 0.511984)
							(end 0.1778 0.5715)
						)
					)
					(width 0)
					(fill yes)
				)
			)
		)
		(pad "S" smd custom
			(at 0.98425 0.9525)
			(size 0.1905 0.1905)
			(layers "F.Cu" "F.Mask" "F.Paste")
			(net "GND")
			(options
				(clearance outline)
				(anchor circle)
			)
			(primitives
				(gr_poly
					(pts
						(arc
							(start -0.1778 0.5715)
							(mid -0.321484 0.511984)
							(end -0.381 0.3683)
						)
						(arc
							(start -0.381 -0.3683)
							(mid -0.321484 -0.511984)
							(end -0.1778 -0.5715)
						)
						(arc
							(start 0.1778 -0.5715)
							(mid 0.321484 -0.511984)
							(end 0.381 -0.3683)
						)
						(arc
							(start 0.381 0.3683)
							(mid 0.321484 0.511984)
							(end 0.1778 0.5715)
						)
					)
					(width 0)
					(fill yes)
				)
			)
		)
	)
	(footprint ""
		(layer "F.Cu")
		(at 287.83661 -263.702292 -90)
		(property "Reference" "PCIE1"
			(at 0 0 270)
			(layer "F.SilkS")
			(hide yes)
			(effects
				(font
					(size 1.27 1.27)
				)
			)
		)
		(property "Value" "AMP-CONN76-8R-5-GP"
			(at -8.9408 -15.1892 270)
			(unlocked yes)
			(layer "F.Fab")
			(hide yes)
			(effects
				(font
					(size 1.016 1.016)
					(thickness 0.1524)
				)
			)
		)
		(property "Device Type" "PREFIT-76P-165151H483"
			(at -8.9408 -16.7132 270)
			(unlocked yes)
			(layer "F.Fab")
			(hide yes)
			(effects
				(font
					(size 1.016 1.016)
					(thickness 0.1524)
				)
			)
		)
		(duplicate_pad_numbers_are_jumpers no)
		(fp_line
			(start -1.905 13.0048)
			(end -1.905 -2.6162)
			(stroke
				(width 0.1524)
				(type default)
			)
			(layer "F.SilkS")
		)
		(fp_line
			(start 15.0876 13.0048)
			(end -1.905 13.0048)
			(stroke
				(width 0.1524)
				(type default)
			)
			(layer "F.SilkS")
		)
		(fp_line
			(start 0.0508 -2.032)
			(end 1.1176 -2.032)
			(stroke
				(width 0.1524)
				(type default)
			)
			(layer "F.SilkS")
		)
		(fp_line
			(start 1.1176 -2.032)
			(end 1.1176 -2.6162)
			(stroke
				(width 0.1524)
				(type default)
			)
			(layer "F.SilkS")
		)
		(fp_line
			(start -1.905 -2.6162)
			(end 0.0508 -2.6162)
			(stroke
				(width 0.1524)
				(type default)
			)
			(layer "F.SilkS")
		)
		(fp_line
			(start 0.0508 -2.6162)
			(end 0.0508 -2.032)
			(stroke
				(width 0.1524)
				(type default)
			)
			(layer "F.SilkS")
		)
		(fp_line
			(start 1.1176 -2.6162)
			(end 0.0508 -2.6162)
			(stroke
				(width 0.1524)
				(type default)
			)
			(layer "F.SilkS")
		)
		(fp_line
			(start 1.1176 -2.6162)
			(end 15.0876 -2.6162)
			(stroke
				(width 0.1524)
				(type default)
			)
			(layer "F.SilkS")
		)
		(fp_line
			(start 15.0876 -2.6162)
			(end 15.0876 13.0048)
			(stroke
				(width 0.1524)
				(type default)
			)
			(layer "F.SilkS")
		)
		(fp_poly
			(pts
				(xy -1.905 13.0048) (xy -1.905 -0.00762) (xy -0.635 -0.00762) (xy -0.635 12.954) (xy 13.234924 12.954)
				(xy 13.234924 -2.1336) (xy 2.4892 -2.1336) (xy 2.4892 -0.735076) (xy -0.635 -0.735076) (xy -0.635 -0.01016)
				(xy -1.905 -0.01016) (xy -1.905 -2.6162) (xy 0.0508 -2.6162) (xy 0.0508 -2.032) (xy 1.1176 -2.032)
				(xy 1.1176 -2.6162) (xy 15.0876 -2.6162) (xy 15.0876 13.0048)
			)
			(stroke
				(width 0)
				(type default)
			)
			(fill yes)
			(layer "F.SilkS")
		)
		(fp_poly
			(pts
				(arc
					(start 0.3302 12.401804)
					(mid 0 12.732004)
					(end -0.3302 12.401804)
				)
				(arc
					(start -0.3302 11.639804)
					(mid 0 11.309604)
					(end 0.3302 11.639804)
				)
			)
			(stroke
				(width 0)
				(type default)
			)
			(fill yes)
			(layer "F.SilkS")
		)
		(fp_poly
			(pts
				(arc
					(start 2.130298 12.401804)
					(mid 1.800098 12.732004)
					(end 1.469898 12.401804)
				)
				(arc
					(start 1.469898 11.639804)
					(mid 1.800098 11.309604)
					(end 2.130298 11.639804)
				)
			)
			(stroke
				(width 0)
				(type default)
			)
			(fill yes)
			(layer "F.SilkS")
		)
		(fp_poly
			(pts
				(arc
					(start 3.930142 12.401804)
					(mid 3.599942 12.732004)
					(end 3.269742 12.401804)
				)
				(arc
					(start 3.269742 11.639804)
					(mid 3.599942 11.309604)
					(end 3.930142 11.639804)
				)
			)
			(stroke
				(width 0)
				(type default)
			)
			(fill yes)
			(layer "F.SilkS")
		)
		(fp_poly
			(pts
				(arc
					(start 5.73024 12.401804)
					(mid 5.40004 12.732004)
					(end 5.06984 12.401804)
				)
				(arc
					(start 5.06984 11.639804)
					(mid 5.40004 11.309604)
					(end 5.73024 11.639804)
				)
			)
			(stroke
				(width 0)
				(type default)
			)
			(fill yes)
			(layer "F.SilkS")
		)
		(fp_poly
			(pts
				(arc
					(start 7.530084 12.401804)
					(mid 7.199884 12.732004)
					(end 6.869684 12.401804)
				)
				(arc
					(start 6.869684 11.639804)
					(mid 7.199884 11.309604)
					(end 7.530084 11.639804)
				)
			)
			(stroke
				(width 0)
				(type default)
			)
			(fill yes)
			(layer "F.SilkS")
		)
		(fp_poly
			(pts
				(arc
					(start 9.330182 12.401804)
					(mid 8.999982 12.732004)
					(end 8.669782 12.401804)
				)
				(arc
					(start 8.669782 11.639804)
					(mid 8.999982 11.309604)
					(end 9.330182 11.639804)
				)
			)
			(stroke
				(width 0)
				(type default)
			)
			(fill yes)
			(layer "F.SilkS")
		)
		(fp_poly
			(pts
				(arc
					(start 11.130026 12.401804)
					(mid 10.799826 12.732004)
					(end 10.469626 12.401804)
				)
				(arc
					(start 10.469626 11.639804)
					(mid 10.799826 11.309604)
					(end 11.130026 11.639804)
				)
			)
			(stroke
				(width 0)
				(type default)
			)
			(fill yes)
			(layer "F.SilkS")
		)
		(fp_poly
			(pts
				(arc
					(start 12.930124 12.401804)
					(mid 12.599924 12.732004)
					(end 12.269724 12.401804)
				)
				(arc
					(start 12.269724 11.639804)
					(mid 12.599924 11.309604)
					(end 12.930124 11.639804)
				)
			)
			(stroke
				(width 0)
				(type default)
			)
			(fill yes)
			(layer "F.SilkS")
		)
		(fp_rect
			(start -5.3848 16.0782)
			(end 17.9832 -5.4864)
			(stroke
				(width 0)
				(type default)
			)
			(fill no)
			(layer "B.CrtYd")
		)
		(fp_rect
			(start -1.651 12.7508)
			(end 14.8336 -2.3622)
			(stroke
				(width 0)
				(type default)
			)
			(fill no)
			(layer "F.CrtYd")
		)
		(fp_poly
			(pts
				(xy -6.6548 17.7546) (xy -6.6548 -7.366) (xy 19.8374 -7.366) (xy 19.8374 0) (xy 15.3416 0) (xy 15.3416 -2.8702)
				(xy -2.159 -2.8702) (xy -2.159 13.2588) (xy 15.3416 13.2588) (xy 15.3416 0.0127) (xy 19.8374 0.0127)
				(xy 19.8374 17.7546)
			)
			(stroke
				(width 0)
				(type default)
			)
			(fill no)
			(layer "F.CrtYd")
		)
		(fp_poly
			(pts
				(xy -2.159 13.2588) (xy -2.159 -2.8702) (xy 15.3416 -2.8702) (xy 15.3416 0) (xy 14.8336 0) (xy 14.8336 -2.3622)
				(xy -1.651 -2.3622) (xy -1.651 12.7508) (xy 14.8336 12.7508) (xy 14.8336 0.0127) (xy 15.3416 0.0127)
				(xy 15.3416 13.2588)
			)
			(stroke
				(width 0)
				(type default)
			)
			(fill no)
			(layer "F.CrtYd")
		)
		(fp_rect
			(start -10.3886 21.082)
			(end 22.987 -10.4902)
			(stroke
				(width 0)
				(type default)
			)
			(fill no)
			(layer "B.Fab")
		)
		(fp_rect
			(start -5.3848 16.0782)
			(end 17.9832 -5.4864)
			(stroke
				(width 0)
				(type default)
			)
			(fill no)
			(layer "B.Fab")
		)
		(fp_rect
			(start -11.6586 22.7584)
			(end 24.8412 -12.3698)
			(stroke
				(width 0)
				(type default)
			)
			(fill no)
			(layer "F.Fab")
		)
		(fp_rect
			(start -6.6548 17.7546)
			(end 19.8374 -7.366)
			(stroke
				(width 0)
				(type default)
			)
			(fill no)
			(layer "F.Fab")
		)
		(fp_rect
			(start -2.159 13.2588)
			(end 15.3416 -2.8702)
			(stroke
				(width 0)
				(type default)
			)
			(fill no)
			(layer "F.Fab")
		)
		(fp_text user "Press Fit"
			(at 2.751836 -1.2573 270)
			(unlocked yes)
			(layer "F.SilkS")
			(effects
				(font
					(size 1.016 1.016)
					(thickness 0.1524)
				)
				(justify left)
			)
		)
		(fp_text user "Can not place BGA,CSP,Wave Solder Component"
			(at -18.7452 17.6403 270)
			(unlocked yes)
			(layer "B.Fab")
			(effects
				(font
					(size 1.016 1.016)
					(thickness 0.1524)
				)
				(justify left)
			)
		)
		(fp_text user "Can not place BGA,CSP,Wave Solder Component"
			(at -18.30705 20.843494 270)
			(unlocked yes)
			(layer "F.Fab")
			(effects
				(font
					(size 1.016 1.016)
					(thickness 0.1524)
				)
				(justify left)
			)
		)
		(fp_text user "High Limit 2mm"
			(at -1.4478 15.9512 270)
			(unlocked yes)
			(layer "F.Fab")
			(effects
				(font
					(size 1.016 1.016)
					(thickness 0.1524)
				)
				(justify left)
			)
		)
		(pad "A1" thru_hole circle
			(at 0 0 270)
			(size 0.762 0.762)
			(drill 0.359918)
			(layers "*.Cu" "*.Mask")
			(remove_unused_layers no)
			(net "PCIE_COMP_A_TO_SCC_A_0_DP")
			(clearance 0.1651)
			(thermal_gap 0.1651)
		)
		(pad "A2" thru_hole circle
			(at 1.800098 0.999998 270)
			(size 0.762 0.762)
			(drill 0.359918)
			(layers "*.Cu" "*.Mask")
			(remove_unused_layers no)
			(net "PCIE_COMP_A_TO_SCC_A_1_DP")
			(clearance 0.1651)
			(thermal_gap 0.1651)
		)
		(pad "A3" thru_hole circle
			(at 3.599942 0 270)
			(size 0.762 0.762)
			(drill 0.359918)
			(layers "*.Cu" "*.Mask")
			(remove_unused_layers no)
			(net "PCIE_COMP_A_TO_SCC_A_2_DP")
			(clearance 0.1651)
			(thermal_gap 0.1651)
		)
		(pad "A4" thru_hole circle
			(at 5.40004 0.999998 270)
			(size 0.762 0.762)
			(drill 0.359918)
			(layers "*.Cu" "*.Mask")
			(remove_unused_layers no)
			(net "PCIE_COMP_A_TO_SCC_A_3_DP")
			(clearance 0.1651)
			(thermal_gap 0.1651)
		)
		(pad "A5" thru_hole circle
			(at 7.199884 0 270)
			(size 0.762 0.762)
			(drill 0.359918)
			(layers "*.Cu" "*.Mask")
			(remove_unused_layers no)
			(net "PCIE_COMP_A_TO_SCC_A_4_DP")
			(clearance 0.1651)
			(thermal_gap 0.1651)
		)
		(pad "A6" thru_hole circle
			(at 8.999982 0.999998 270)
			(size 0.762 0.762)
			(drill 0.359918)
			(layers "*.Cu" "*.Mask")
			(remove_unused_layers no)
			(net "PCIE_COMP_A_TO_SCC_A_5_DP")
			(clearance 0.1651)
			(thermal_gap 0.1651)
		)
		(pad "A7" thru_hole circle
			(at 10.80008 0 270)
			(size 0.762 0.762)
			(drill 0.359918)
			(layers "*.Cu" "*.Mask")
			(remove_unused_layers no)
			(net "PCIE_COMP_A_TO_SCC_A_6_DP")
			(clearance 0.1651)
			(thermal_gap 0.1651)
		)
		(pad "A8" thru_hole circle
			(at 12.599924 0.999998 270)
			(size 0.762 0.762)
			(drill 0.359918)
			(layers "*.Cu" "*.Mask")
			(remove_unused_layers no)
			(net "PCIE_COMP_A_TO_SCC_A_7_DP")
			(clearance 0.1651)
			(thermal_gap 0.1651)
		)
		(pad "B1" thru_hole circle
			(at 0 1.400048 270)
			(size 0.762 0.762)
			(drill 0.359918)
			(layers "*.Cu" "*.Mask")
			(remove_unused_layers no)
			(net "PCIE_COMP_A_TO_SCC_A_0_DN")
			(clearance 0.1651)
			(thermal_gap 0.1651)
		)
		(pad "B2" thru_hole circle
			(at 1.800098 2.400046 270)
			(size 0.762 0.762)
			(drill 0.359918)
			(layers "*.Cu" "*.Mask")
			(remove_unused_layers no)
			(net "PCIE_COMP_A_TO_SCC_A_1_DN")
			(clearance 0.1651)
			(thermal_gap 0.1651)
		)
		(pad "B3" thru_hole circle
			(at 3.599942 1.400048 270)
			(size 0.762 0.762)
			(drill 0.359918)
			(layers "*.Cu" "*.Mask")
			(remove_unused_layers no)
			(net "PCIE_COMP_A_TO_SCC_A_2_DN")
			(clearance 0.1651)
			(thermal_gap 0.1651)
		)
		(pad "B4" thru_hole circle
			(at 5.40004 2.400046 270)
			(size 0.762 0.762)
			(drill 0.359918)
			(layers "*.Cu" "*.Mask")
			(remove_unused_layers no)
			(net "PCIE_COMP_A_TO_SCC_A_3_DN")
			(clearance 0.1651)
			(thermal_gap 0.1651)
		)
		(pad "B5" thru_hole circle
			(at 7.199884 1.400048 270)
			(size 0.762 0.762)
			(drill 0.359918)
			(layers "*.Cu" "*.Mask")
			(remove_unused_layers no)
			(net "PCIE_COMP_A_TO_SCC_A_4_DN")
			(clearance 0.1651)
			(thermal_gap 0.1651)
		)
		(pad "B6" thru_hole circle
			(at 8.999982 2.400046 270)
			(size 0.762 0.762)
			(drill 0.359918)
			(layers "*.Cu" "*.Mask")
			(remove_unused_layers no)
			(net "PCIE_COMP_A_TO_SCC_A_5_DN")
			(clearance 0.1651)
			(thermal_gap 0.1651)
		)
		(pad "B7" thru_hole circle
			(at 10.80008 1.400048 270)
			(size 0.762 0.762)
			(drill 0.359918)
			(layers "*.Cu" "*.Mask")
			(remove_unused_layers no)
			(net "PCIE_COMP_A_TO_SCC_A_6_DN")
			(clearance 0.1651)
			(thermal_gap 0.1651)
		)
		(pad "B8" thru_hole circle
			(at 12.599924 2.400046 270)
			(size 0.762 0.762)
			(drill 0.359918)
			(layers "*.Cu" "*.Mask")
			(remove_unused_layers no)
			(net "PCIE_COMP_A_TO_SCC_A_7_DN")
			(clearance 0.1651)
			(thermal_gap 0.1651)
		)
		(pad "C1" thru_hole circle
			(at 0 3.599942 270)
			(size 0.762 0.762)
			(drill 0.359918)
			(layers "*.Cu" "*.Mask")
			(remove_unused_layers no)
			(net "PCIE_COMP_A_TO_SCC_A_CLK_0_DP")
			(clearance 0.1651)
			(thermal_gap 0.1651)
		)
		(pad "C2" thru_hole circle
			(at 1.800098 4.59994 270)
			(size 0.762 0.762)
			(drill 0.359918)
			(layers "*.Cu" "*.Mask")
			(remove_unused_layers no)
			(net "I2C_BMC_B_EXP_A_SCL")
			(clearance 0.1651)
			(thermal_gap 0.1651)
		)
		(pad "C3" thru_hole circle
			(at 3.599942 3.599942 270)
			(size 0.762 0.762)
			(drill 0.359918)
			(layers "*.Cu" "*.Mask")
			(remove_unused_layers no)
			(net "I2C_SCC_A_SCL_BUF")
			(clearance 0.1651)
			(thermal_gap 0.1651)
		)
		(pad "C4" thru_hole circle
			(at 5.40004 4.59994 270)
			(size 0.762 0.762)
			(drill 0.359918)
			(layers "*.Cu" "*.Mask")
			(remove_unused_layers no)
			(net "COMP_A_EXP_A_SPARE_0")
			(clearance 0.1651)
			(thermal_gap 0.1651)
		)
		(pad "C5" thru_hole circle
			(at 7.199884 3.599942 270)
			(size 0.762 0.762)
			(drill 0.359918)
			(layers "*.Cu" "*.Mask")
			(remove_unused_layers no)
			(net "UART_IOC_A_TX")
			(clearance 0.1651)
			(thermal_gap 0.1651)
		)
		(pad "C6" thru_hole circle
			(at 8.999982 4.59994 270)
			(size 0.762 0.762)
			(drill 0.359918)
			(layers "*.Cu" "*.Mask")
			(remove_unused_layers no)
			(net "BMC_A_EXP_A_SPARE_0")
			(clearance 0.1651)
			(thermal_gap 0.1651)
		)
		(pad "C7" thru_hole circle
			(at 10.80008 3.599942 270)
			(size 0.762 0.762)
			(drill 0.359918)
			(layers "*.Cu" "*.Mask")
			(remove_unused_layers no)
			(net "PCIE_COMP_A_TO_SCC_A_RST_0")
			(clearance 0.1651)
			(thermal_gap 0.1651)
		)
		(pad "C8" thru_hole circle
			(at 12.599924 4.59994 270)
			(size 0.762 0.762)
			(drill 0.359918)
			(layers "*.Cu" "*.Mask")
			(remove_unused_layers no)
			(net "I2C_BMC_A_EXP_A_SCL")
			(clearance 0.1651)
			(thermal_gap 0.1651)
		)
		(pad "D1" thru_hole circle
			(at 0 4.99999 270)
			(size 0.762 0.762)
			(drill 0.359918)
			(layers "*.Cu" "*.Mask")
			(remove_unused_layers no)
			(net "PCIE_COMP_A_TO_SCC_A_CLK_0_DN")
			(clearance 0.1651)
			(thermal_gap 0.1651)
		)
		(pad "D2" thru_hole circle
			(at 1.800098 5.999988 270)
			(size 0.762 0.762)
			(drill 0.359918)
			(layers "*.Cu" "*.Mask")
			(remove_unused_layers no)
			(net "I2C_BMC_B_EXP_A_SDA")
			(clearance 0.1651)
			(thermal_gap 0.1651)
		)
		(pad "D3" thru_hole circle
			(at 3.599942 4.99999 270)
			(size 0.762 0.762)
			(drill 0.359918)
			(layers "*.Cu" "*.Mask")
			(remove_unused_layers no)
			(net "I2C_SCC_A_SDA_BUF")
			(clearance 0.1651)
			(thermal_gap 0.1651)
		)
		(pad "D4" thru_hole circle
			(at 5.40004 5.999988 270)
			(size 0.762 0.762)
			(drill 0.359918)
			(layers "*.Cu" "*.Mask")
			(remove_unused_layers no)
			(net "Net_52")
			(clearance 0.1651)
			(thermal_gap 0.1651)
		)
		(pad "D5" thru_hole circle
			(at 7.199884 4.99999 270)
			(size 0.762 0.762)
			(drill 0.359918)
			(layers "*.Cu" "*.Mask")
			(remove_unused_layers no)
			(net "UART_IOC_A_RX")
			(clearance 0.1651)
			(thermal_gap 0.1651)
		)
		(pad "D6" thru_hole circle
			(at 8.999982 5.999988 270)
			(size 0.762 0.762)
			(drill 0.359918)
			(layers "*.Cu" "*.Mask")
			(remove_unused_layers no)
			(net "BMC_A_EXP_A_SPARE_1")
			(clearance 0.1651)
			(thermal_gap 0.1651)
		)
		(pad "D7" thru_hole circle
			(at 10.80008 4.99999 270)
			(size 0.762 0.762)
			(drill 0.359918)
			(layers "*.Cu" "*.Mask")
			(remove_unused_layers no)
			(net "BMC_B_HEARTBEAT")
			(clearance 0.1651)
			(thermal_gap 0.1651)
		)
		(pad "D8" thru_hole circle
			(at 12.599924 5.999988 270)
			(size 0.762 0.762)
			(drill 0.359918)
			(layers "*.Cu" "*.Mask")
			(remove_unused_layers no)
			(net "I2C_BMC_A_EXP_A_SDA")
			(clearance 0.1651)
			(thermal_gap 0.1651)
		)
		(pad "E1" thru_hole circle
			(at 0 7.199884 270)
			(size 0.762 0.762)
			(drill 0.359918)
			(layers "*.Cu" "*.Mask")
			(remove_unused_layers no)
			(net "PCIE_SCC_A_TO_COMP_A_0_DP")
			(clearance 0.1651)
			(thermal_gap 0.1651)
		)
		(pad "E2" thru_hole circle
			(at 1.800098 8.199882 270)
			(size 0.762 0.762)
			(drill 0.359918)
			(layers "*.Cu" "*.Mask")
			(remove_unused_layers no)
			(net "PCIE_SCC_A_TO_COMP_A_1_DP")
			(clearance 0.1651)
			(thermal_gap 0.1651)
		)
		(pad "E3" thru_hole circle
			(at 3.599942 7.199884 270)
			(size 0.762 0.762)
			(drill 0.359918)
			(layers "*.Cu" "*.Mask")
			(remove_unused_layers no)
			(net "PCIE_SCC_A_TO_COMP_A_2_DP")
			(clearance 0.1651)
			(thermal_gap 0.1651)
		)
		(pad "E4" thru_hole circle
			(at 5.40004 8.199882 270)
			(size 0.762 0.762)
			(drill 0.359918)
			(layers "*.Cu" "*.Mask")
			(remove_unused_layers no)
			(net "PCIE_SCC_A_TO_COMP_A_3_DP")
			(clearance 0.1651)
			(thermal_gap 0.1651)
		)
		(pad "E5" thru_hole circle
			(at 7.199884 7.199884 270)
			(size 0.762 0.762)
			(drill 0.359918)
			(layers "*.Cu" "*.Mask")
			(remove_unused_layers no)
			(net "PCIE_SCC_A_TO_COMP_A_4_DP")
			(clearance 0.1651)
			(thermal_gap 0.1651)
		)
		(pad "E6" thru_hole circle
			(at 8.999982 8.199882 270)
			(size 0.762 0.762)
			(drill 0.359918)
			(layers "*.Cu" "*.Mask")
			(remove_unused_layers no)
			(net "PCIE_SCC_A_TO_COMP_A_5_DP")
			(clearance 0.1651)
			(thermal_gap 0.1651)
		)
		(pad "E7" thru_hole circle
			(at 10.80008 7.199884 270)
			(size 0.762 0.762)
			(drill 0.359918)
			(layers "*.Cu" "*.Mask")
			(remove_unused_layers no)
			(net "PCIE_SCC_A_TO_COMP_A_6_DP")
			(clearance 0.1651)
			(thermal_gap 0.1651)
		)
		(pad "E8" thru_hole circle
			(at 12.599924 8.199882 270)
			(size 0.762 0.762)
			(drill 0.359918)
			(layers "*.Cu" "*.Mask")
			(remove_unused_layers no)
			(net "PCIE_SCC_A_TO_COMP_A_7_DP")
			(clearance 0.1651)
			(thermal_gap 0.1651)
		)
		(pad "F1" thru_hole circle
			(at 0 8.599932 270)
			(size 0.762 0.762)
			(drill 0.359918)
			(layers "*.Cu" "*.Mask")
			(remove_unused_layers no)
			(net "PCIE_SCC_A_TO_COMP_A_0_DN")
			(clearance 0.1651)
			(thermal_gap 0.1651)
		)
		(pad "F2" thru_hole circle
			(at 1.800098 9.59993 270)
			(size 0.762 0.762)
			(drill 0.359918)
			(layers "*.Cu" "*.Mask")
			(remove_unused_layers no)
			(net "PCIE_SCC_A_TO_COMP_A_1_DN")
			(clearance 0.1651)
			(thermal_gap 0.1651)
		)
		(pad "F3" thru_hole circle
			(at 3.599942 8.599932 270)
			(size 0.762 0.762)
			(drill 0.359918)
			(layers "*.Cu" "*.Mask")
			(remove_unused_layers no)
			(net "PCIE_SCC_A_TO_COMP_A_2_DN")
			(clearance 0.1651)
			(thermal_gap 0.1651)
		)
		(pad "F4" thru_hole circle
			(at 5.40004 9.59993 270)
			(size 0.762 0.762)
			(drill 0.359918)
			(layers "*.Cu" "*.Mask")
			(remove_unused_layers no)
			(net "PCIE_SCC_A_TO_COMP_A_3_DN")
			(clearance 0.1651)
			(thermal_gap 0.1651)
		)
		(pad "F5" thru_hole circle
			(at 7.199884 8.599932 270)
			(size 0.762 0.762)
			(drill 0.359918)
			(layers "*.Cu" "*.Mask")
			(remove_unused_layers no)
			(net "PCIE_SCC_A_TO_COMP_A_4_DN")
			(clearance 0.1651)
			(thermal_gap 0.1651)
		)
		(pad "F6" thru_hole circle
			(at 8.999982 9.59993 270)
			(size 0.762 0.762)
			(drill 0.359918)
			(layers "*.Cu" "*.Mask")
			(remove_unused_layers no)
			(net "PCIE_SCC_A_TO_COMP_A_5_DN")
			(clearance 0.1651)
			(thermal_gap 0.1651)
		)
		(pad "F7" thru_hole circle
			(at 10.80008 8.599932 270)
			(size 0.762 0.762)
			(drill 0.359918)
			(layers "*.Cu" "*.Mask")
			(remove_unused_layers no)
			(net "PCIE_SCC_A_TO_COMP_A_6_DN")
			(clearance 0.1651)
			(thermal_gap 0.1651)
		)
		(pad "F8" thru_hole circle
			(at 12.599924 9.59993 270)
			(size 0.762 0.762)
			(drill 0.359918)
			(layers "*.Cu" "*.Mask")
			(remove_unused_layers no)
			(net "PCIE_SCC_A_TO_COMP_A_7_DN")
			(clearance 0.1651)
			(thermal_gap 0.1651)
		)
		(pad "GND1" thru_hole circle
			(at 0 2.500122 270)
			(size 0.762 0.762)
			(drill 0.359918)
			(layers "*.Cu" "*.Mask")
			(remove_unused_layers no)
			(net "GND")
			(clearance 0.1651)
			(thermal_gap 0.1651)
		)
		(pad "GND2" thru_hole circle
			(at 0 6.100064 270)
			(size 0.762 0.762)
			(drill 0.359918)
			(layers "*.Cu" "*.Mask")
			(remove_unused_layers no)
			(net "GND")
			(clearance 0.1651)
			(thermal_gap 0.1651)
		)
		(pad "GND3" thru_hole circle
			(at 0 9.700006 270)
			(size 0.762 0.762)
			(drill 0.359918)
			(layers "*.Cu" "*.Mask")
			(remove_unused_layers no)
			(net "GND")
			(clearance 0.1651)
			(thermal_gap 0.1651)
		)
		(pad "GND4" thru_hole circle
			(at 1.800098 -0.100076 270)
			(size 0.762 0.762)
			(drill 0.359918)
			(layers "*.Cu" "*.Mask")
			(remove_unused_layers no)
			(net "GND")
			(clearance 0.1651)
			(thermal_gap 0.1651)
		)
		(pad "GND5" thru_hole circle
			(at 1.800098 3.50012 270)
			(size 0.762 0.762)
			(drill 0.359918)
			(layers "*.Cu" "*.Mask")
			(remove_unused_layers no)
			(net "GND")
			(clearance 0.1651)
			(thermal_gap 0.1651)
		)
		(pad "GND6" thru_hole circle
			(at 1.800098 7.100062 270)
			(size 0.762 0.762)
			(drill 0.359918)
			(layers "*.Cu" "*.Mask")
			(remove_unused_layers no)
			(net "GND")
			(clearance 0.1651)
			(thermal_gap 0.1651)
		)
		(pad "GND7" thru_hole circle
			(at 1.800098 10.700004 270)
			(size 0.762 0.762)
			(drill 0.359918)
			(layers "*.Cu" "*.Mask")
			(remove_unused_layers no)
			(net "GND")
			(clearance 0.1651)
			(thermal_gap 0.1651)
		)
		(pad "GND8" thru_hole circle
			(at 3.599942 2.500122 270)
			(size 0.762 0.762)
			(drill 0.359918)
			(layers "*.Cu" "*.Mask")
			(remove_unused_layers no)
			(net "GND")
			(clearance 0.1651)
			(thermal_gap 0.1651)
		)
		(pad "GND9" thru_hole circle
			(at 3.599942 6.100064 270)
			(size 0.762 0.762)
			(drill 0.359918)
			(layers "*.Cu" "*.Mask")
			(remove_unused_layers no)
			(net "GND")
			(clearance 0.1651)
			(thermal_gap 0.1651)
		)
		(pad "GND10" thru_hole circle
			(at 3.599942 9.700006 270)
			(size 0.762 0.762)
			(drill 0.359918)
			(layers "*.Cu" "*.Mask")
			(remove_unused_layers no)
			(net "GND")
			(clearance 0.1651)
			(thermal_gap 0.1651)
		)
		(pad "GND11" thru_hole circle
			(at 5.40004 -0.100076 270)
			(size 0.762 0.762)
			(drill 0.359918)
			(layers "*.Cu" "*.Mask")
			(remove_unused_layers no)
			(net "GND")
			(clearance 0.1651)
			(thermal_gap 0.1651)
		)
		(pad "GND12" thru_hole circle
			(at 5.40004 3.50012 270)
			(size 0.762 0.762)
			(drill 0.359918)
			(layers "*.Cu" "*.Mask")
			(remove_unused_layers no)
			(net "GND")
			(clearance 0.1651)
			(thermal_gap 0.1651)
		)
		(pad "GND13" thru_hole circle
			(at 5.40004 7.100062 270)
			(size 0.762 0.762)
			(drill 0.359918)
			(layers "*.Cu" "*.Mask")
			(remove_unused_layers no)
			(net "GND")
			(clearance 0.1651)
			(thermal_gap 0.1651)
		)
		(pad "GND14" thru_hole circle
			(at 5.40004 10.700004 270)
			(size 0.762 0.762)
			(drill 0.359918)
			(layers "*.Cu" "*.Mask")
			(remove_unused_layers no)
			(net "GND")
			(clearance 0.1651)
			(thermal_gap 0.1651)
		)
		(pad "GND15" thru_hole circle
			(at 7.199884 2.500122 270)
			(size 0.762 0.762)
			(drill 0.359918)
			(layers "*.Cu" "*.Mask")
			(remove_unused_layers no)
			(net "GND")
			(clearance 0.1651)
			(thermal_gap 0.1651)
		)
		(pad "GND16" thru_hole circle
			(at 7.199884 6.100064 270)
			(size 0.762 0.762)
			(drill 0.359918)
			(layers "*.Cu" "*.Mask")
			(remove_unused_layers no)
			(net "GND")
			(clearance 0.1651)
			(thermal_gap 0.1651)
		)
		(pad "GND17" thru_hole circle
			(at 7.199884 9.700006 270)
			(size 0.762 0.762)
			(drill 0.359918)
			(layers "*.Cu" "*.Mask")
			(remove_unused_layers no)
			(net "GND")
			(clearance 0.1651)
			(thermal_gap 0.1651)
		)
		(pad "GND18" thru_hole circle
			(at 8.999982 -0.100076 270)
			(size 0.762 0.762)
			(drill 0.359918)
			(layers "*.Cu" "*.Mask")
			(remove_unused_layers no)
			(net "GND")
			(clearance 0.1651)
			(thermal_gap 0.1651)
		)
		(pad "GND19" thru_hole circle
			(at 8.999982 3.50012 270)
			(size 0.762 0.762)
			(drill 0.359918)
			(layers "*.Cu" "*.Mask")
			(remove_unused_layers no)
			(net "GND")
			(clearance 0.1651)
			(thermal_gap 0.1651)
		)
		(pad "GND20" thru_hole circle
			(at 8.999982 7.100062 270)
			(size 0.762 0.762)
			(drill 0.359918)
			(layers "*.Cu" "*.Mask")
			(remove_unused_layers no)
			(net "GND")
			(clearance 0.1651)
			(thermal_gap 0.1651)
		)
		(pad "GND21" thru_hole circle
			(at 8.999982 10.700004 270)
			(size 0.762 0.762)
			(drill 0.359918)
			(layers "*.Cu" "*.Mask")
			(remove_unused_layers no)
			(net "GND")
			(clearance 0.1651)
			(thermal_gap 0.1651)
		)
		(pad "GND22" thru_hole circle
			(at 10.80008 2.500122 270)
			(size 0.762 0.762)
			(drill 0.359918)
			(layers "*.Cu" "*.Mask")
			(remove_unused_layers no)
			(net "GND")
			(clearance 0.1651)
			(thermal_gap 0.1651)
		)
		(pad "GND23" thru_hole circle
			(at 10.80008 6.100064 270)
			(size 0.762 0.762)
			(drill 0.359918)
			(layers "*.Cu" "*.Mask")
			(remove_unused_layers no)
			(net "GND")
			(clearance 0.1651)
			(thermal_gap 0.1651)
		)
		(pad "GND24" thru_hole circle
			(at 10.80008 9.700006 270)
			(size 0.762 0.762)
			(drill 0.359918)
			(layers "*.Cu" "*.Mask")
			(remove_unused_layers no)
			(net "GND")
			(clearance 0.1651)
			(thermal_gap 0.1651)
		)
		(pad "GND25" thru_hole circle
			(at 12.599924 -0.100076 270)
			(size 0.762 0.762)
			(drill 0.359918)
			(layers "*.Cu" "*.Mask")
			(remove_unused_layers no)
			(net "GND")
			(clearance 0.1651)
			(thermal_gap 0.1651)
		)
		(pad "GND26" thru_hole circle
			(at 12.599924 3.50012 270)
			(size 0.762 0.762)
			(drill 0.359918)
			(layers "*.Cu" "*.Mask")
			(remove_unused_layers no)
			(net "GND")
			(clearance 0.1651)
			(thermal_gap 0.1651)
		)
		(pad "GND27" thru_hole circle
			(at 12.599924 7.100062 270)
			(size 0.762 0.762)
			(drill 0.359918)
			(layers "*.Cu" "*.Mask")
			(remove_unused_layers no)
			(net "GND")
			(clearance 0.1651)
			(thermal_gap 0.1651)
		)
		(pad "GND28" thru_hole circle
			(at 12.599924 10.700004 270)
			(size 0.762 0.762)
			(drill 0.359918)
			(layers "*.Cu" "*.Mask")
			(remove_unused_layers no)
			(net "GND")
			(clearance 0.1651)
			(thermal_gap 0.1651)
		)
	)
	(footprint ""
		(layer "F.Cu")
		(at 86.545166 -14.92123 90)
		(property "Reference" "C15"
			(at 0 0 90)
			(layer "F.SilkS")
			(hide yes)
			(effects
				(font
					(size 1.27 1.27)
				)
			)
		)
		(property "Value" "SCD1U16V2KX-3GP"
			(at 1.1811 -2.7051 90)
			(unlocked yes)
			(layer "F.Fab")
			(hide yes)
			(effects
				(font
					(size 1.016 1.016)
					(thickness 0.1524)
				)
			)
		)
		(property "Device Type" "C402H22"
			(at 1.1811 -4.2291 90)
			(unlocked yes)
			(layer "F.Fab")
			(hide yes)
			(effects
				(font
					(size 1.016 1.016)
					(thickness 0.1524)
				)
			)
		)
		(duplicate_pad_numbers_are_jumpers no)
		(fp_rect
			(start -0.4318 0.9525)
			(end 0.4318 -0.9525)
			(stroke
				(width 0)
				(type default)
			)
			(fill no)
			(layer "F.CrtYd")
		)
		(fp_rect
			(start -0.4318 0.9525)
			(end 0.4318 -0.9525)
			(stroke
				(width 0)
				(type default)
			)
			(fill no)
			(layer "F.Fab")
		)
		(pad "1" smd custom
			(at 0 -0.4445 90)
			(size 0.1524 0.1524)
			(layers "F.Cu" "F.Mask" "F.Paste")
			(net "P3V3_STBY_A")
			(options
				(clearance outline)
				(anchor circle)
			)
			(primitives
				(gr_poly
					(pts
						(arc
							(start 0.3048 -0.2032)
							(mid 0.275042 -0.275042)
							(end 0.2032 -0.3048)
						)
						(arc
							(start -0.2032 -0.3048)
							(mid -0.275042 -0.275042)
							(end -0.3048 -0.2032)
						)
						(arc
							(start -0.3048 0.2032)
							(mid -0.275042 0.275042)
							(end -0.2032 0.3048)
						)
						(arc
							(start 0.2032 0.3048)
							(mid 0.275042 0.275042)
							(end 0.3048 0.2032)
						)
					)
					(width 0)
					(fill yes)
				)
			)
		)
		(pad "2" smd custom
			(at 0 0.4445 90)
			(size 0.1524 0.1524)
			(layers "F.Cu" "F.Mask" "F.Paste")
			(net "GND")
			(options
				(clearance outline)
				(anchor circle)
			)
			(primitives
				(gr_poly
					(pts
						(arc
							(start 0.3048 -0.2032)
							(mid 0.275042 -0.275042)
							(end 0.2032 -0.3048)
						)
						(arc
							(start -0.2032 -0.3048)
							(mid -0.275042 -0.275042)
							(end -0.3048 -0.2032)
						)
						(arc
							(start -0.3048 0.2032)
							(mid -0.275042 0.275042)
							(end -0.2032 0.3048)
						)
						(arc
							(start 0.2032 0.3048)
							(mid 0.275042 0.275042)
							(end 0.3048 0.2032)
						)
					)
					(width 0)
					(fill yes)
				)
			)
		)
	)
	(footprint ""
		(layer "F.Cu")
		(at 140.915898 -179.683918 -90)
		(property "Reference" "C252"
			(at 0 0 270)
			(layer "F.SilkS")
			(hide yes)
			(effects
				(font
					(size 1.27 1.27)
				)
			)
		)
		(property "Value" "SC4D7U25V5KX-1-GP"
			(at -0.0762 -6.1214 270)
			(unlocked yes)
			(layer "F.Fab")
			(hide yes)
			(effects
				(font
					(size 1.016 1.016)
					(thickness 0.1524)
				)
			)
		)
		(property "Device Type" "C805H58"
			(at -0.0762 -8.1534 270)
			(unlocked yes)
			(layer "F.Fab")
			(hide yes)
			(effects
				(font
					(size 1.016 1.016)
					(thickness 0.1524)
				)
			)
		)
		(duplicate_pad_numbers_are_jumpers no)
		(fp_line
			(start 0.635 0)
			(end -0.635 0)
			(stroke
				(width 0.508)
				(type default)
			)
			(layer "F.SilkS")
		)
		(fp_rect
			(start -0.9652 1.778)
			(end 0.9652 -1.778)
			(stroke
				(width 0)
				(type default)
			)
			(fill no)
			(layer "F.CrtYd")
		)
		(fp_poly
			(pts
				(xy -0.9652 -1.778) (xy 0.9652 -1.778) (xy 0.9652 1.778) (xy -0.9652 1.778)
			)
			(stroke
				(width 0)
				(type default)
			)
			(fill no)
			(layer "F.Fab")
		)
		(pad "1" smd rect
			(at 0 -0.9652 270)
			(size 1.397 1.143)
			(layers "F.Cu" "F.Mask" "F.Paste")
			(net "P12V_HDD16")
		)
		(pad "2" smd rect
			(at 0 0.9652 270)
			(size 1.397 1.143)
			(layers "F.Cu" "F.Mask" "F.Paste")
			(net "GND")
		)
	)
	(footprint ""
		(layer "F.Cu")
		(at 130.447796 -177.143918 -90)
		(property "Reference" "R475"
			(at 0 0 270)
			(layer "F.SilkS")
			(hide yes)
			(effects
				(font
					(size 1.27 1.27)
				)
			)
		)
		(property "Value" "10KR2F-2-GP"
			(at 0.064008 -3.993896 270)
			(unlocked yes)
			(layer "F.Fab")
			(hide yes)
			(effects
				(font
					(size 1.016 1.016)
					(thickness 0.1524)
				)
			)
		)
		(property "Device Type" "R402H16"
			(at 0.064008 -5.517896 270)
			(unlocked yes)
			(layer "F.Fab")
			(hide yes)
			(effects
				(font
					(size 1.016 1.016)
					(thickness 0.1524)
				)
			)
		)
		(duplicate_pad_numbers_are_jumpers no)
		(fp_line
			(start -0.508 -0.9398)
			(end -0.508 0.9398)
			(stroke
				(width 0.1524)
				(type default)
			)
			(layer "F.SilkS")
		)
		(fp_line
			(start 0.508 -0.9398)
			(end -0.508 -0.9398)
			(stroke
				(width 0.1524)
				(type default)
			)
			(layer "F.SilkS")
		)
		(fp_rect
			(start -0.508 0.9398)
			(end 0.508 -0.9398)
			(stroke
				(width 0)
				(type default)
			)
			(fill no)
			(layer "F.CrtYd")
		)
		(fp_rect
			(start -0.508 0.9398)
			(end 0.508 -0.9398)
			(stroke
				(width 0)
				(type default)
			)
			(fill no)
			(layer "F.Fab")
		)
		(pad "1" smd custom
			(at 0 -0.4445 270)
			(size 0.1397 0.1397)
			(layers "F.Cu" "F.Mask" "F.Paste")
			(net "P3V3_STBY_A")
			(options
				(clearance outline)
				(anchor circle)
			)
			(primitives
				(gr_poly
					(pts
						(arc
							(start -0.1778 -0.2794)
							(mid -0.249642 -0.249642)
							(end -0.2794 -0.1778)
						)
						(arc
							(start -0.2794 0.1778)
							(mid -0.249642 0.249642)
							(end -0.1778 0.2794)
						)
						(arc
							(start 0.1778 0.2794)
							(mid 0.249642 0.249642)
							(end 0.2794 0.1778)
						)
						(arc
							(start 0.2794 -0.1778)
							(mid 0.249642 -0.249642)
							(end 0.1778 -0.2794)
						)
					)
					(width 0)
					(fill yes)
				)
			)
		)
		(pad "2" smd custom
			(at 0 0.4445 270)
			(size 0.1397 0.1397)
			(layers "F.Cu" "F.Mask" "F.Paste")
			(net "HDD_PRSNT_15")
			(options
				(clearance outline)
				(anchor circle)
			)
			(primitives
				(gr_poly
					(pts
						(arc
							(start -0.1778 -0.2794)
							(mid -0.249642 -0.249642)
							(end -0.2794 -0.1778)
						)
						(arc
							(start -0.2794 0.1778)
							(mid -0.249642 0.249642)
							(end -0.1778 0.2794)
						)
						(arc
							(start 0.1778 0.2794)
							(mid 0.249642 0.249642)
							(end 0.2794 0.1778)
						)
						(arc
							(start 0.2794 -0.1778)
							(mid 0.249642 -0.249642)
							(end 0.1778 -0.2794)
						)
					)
					(width 0)
					(fill yes)
				)
			)
		)
	)
	(footprint ""
		(layer "F.Cu")
		(at 454.371202 -258.37515)
		(property "Reference" "TP258"
			(at 0 0 0)
			(layer "F.SilkS")
			(hide yes)
			(effects
				(font
					(size 1.27 1.27)
				)
			)
		)
		(property "Value" "TPAD32-GP"
			(at -0.0508 -1.6764 0)
			(unlocked yes)
			(layer "F.Fab")
			(hide yes)
			(effects
				(font
					(size 1.016 1.016)
					(thickness 0.1524)
				)
			)
		)
		(property "Device Type" "TPAD32"
			(at -0.0508 -3.2004 0)
			(unlocked yes)
			(layer "F.Fab")
			(hide yes)
			(effects
				(font
					(size 1.016 1.016)
					(thickness 0.1524)
				)
			)
		)
		(duplicate_pad_numbers_are_jumpers no)
		(fp_poly
			(pts
				(arc
					(start 0.4064 0)
					(mid -0.4064 0)
					(end 0.4064 0)
				)
			)
			(stroke
				(width 0)
				(type default)
			)
			(fill no)
			(layer "F.CrtYd")
		)
		(fp_poly
			(pts
				(arc
					(start 0.7112 0)
					(mid -0.7112 0)
					(end 0.7112 0)
				)
			)
			(stroke
				(width 0)
				(type default)
			)
			(fill no)
			(layer "F.Fab")
		)
		(pad "1" smd circle
			(at 0 0)
			(size 0.8128 0.8128)
			(layers "F.Cu" "F.Mask" "F.Paste")
			(net "P5V_A_3_PGOOD")
		)
	)
	(footprint ""
		(layer "F.Cu")
		(at 7.62 -304.292 180)
		(property "Reference" "R205"
			(at 0 0 180)
			(layer "F.SilkS")
			(hide yes)
			(effects
				(font
					(size 1.27 1.27)
				)
			)
		)
		(property "Value" "130R3F-GP"
			(at -0.0254 -2.5146 180)
			(unlocked yes)
			(layer "F.Fab")
			(hide yes)
			(effects
				(font
					(size 1.016 1.016)
					(thickness 0.1524)
				)
			)
		)
		(property "Device Type" "R603H22"
			(at -0.0254 -4.0386 180)
			(unlocked yes)
			(layer "F.Fab")
			(hide yes)
			(effects
				(font
					(size 1.016 1.016)
					(thickness 0.1524)
				)
			)
		)
		(duplicate_pad_numbers_are_jumpers no)
		(fp_line
			(start 0.2032 0)
			(end 0.4826 0)
			(stroke
				(width 0.2032)
				(type default)
			)
			(layer "F.SilkS")
		)
		(fp_line
			(start -0.4826 0)
			(end -0.2032 0)
			(stroke
				(width 0.2032)
				(type default)
			)
			(layer "F.SilkS")
		)
		(fp_rect
			(start -0.5842 1.3335)
			(end 0.5842 -1.3335)
			(stroke
				(width 0)
				(type default)
			)
			(fill no)
			(layer "F.CrtYd")
		)
		(fp_rect
			(start -0.5842 1.3335)
			(end 0.5842 -1.3335)
			(stroke
				(width 0)
				(type default)
			)
			(fill no)
			(layer "F.Fab")
		)
		(pad "1" smd custom
			(at 0 -0.762 180)
			(size 0.2159 0.2159)
			(layers "F.Cu" "F.Mask" "F.Paste")
			(net "P5V_B")
			(options
				(clearance outline)
				(anchor circle)
			)
			(primitives
				(gr_poly
					(pts
						(arc
							(start -0.3302 -0.4318)
							(mid -0.402042 -0.402042)
							(end -0.4318 -0.3302)
						)
						(arc
							(start -0.4318 0.3302)
							(mid -0.402042 0.402042)
							(end -0.3302 0.4318)
						)
						(arc
							(start 0.3302 0.4318)
							(mid 0.402042 0.402042)
							(end 0.4318 0.3302)
						)
						(arc
							(start 0.4318 -0.3302)
							(mid 0.402042 -0.402042)
							(end 0.3302 -0.4318)
						)
					)
					(width 0)
					(fill yes)
				)
			)
		)
		(pad "2" smd custom
			(at 0 0.762 180)
			(size 0.2159 0.2159)
			(layers "F.Cu" "F.Mask" "F.Paste")
			(net "FLT_HDD24")
			(options
				(clearance outline)
				(anchor circle)
			)
			(primitives
				(gr_poly
					(pts
						(arc
							(start -0.3302 -0.4318)
							(mid -0.402042 -0.402042)
							(end -0.4318 -0.3302)
						)
						(arc
							(start -0.4318 0.3302)
							(mid -0.402042 0.402042)
							(end -0.3302 0.4318)
						)
						(arc
							(start 0.3302 0.4318)
							(mid 0.402042 0.402042)
							(end 0.4318 0.3302)
						)
						(arc
							(start 0.4318 -0.3302)
							(mid 0.402042 -0.402042)
							(end 0.3302 -0.4318)
						)
					)
					(width 0)
					(fill yes)
				)
			)
		)
	)
	(footprint ""
		(layer "F.Cu")
		(at 138.653266 -143.898874 -90)
		(property "Reference" "R1041"
			(at 0 0 270)
			(layer "F.SilkS")
			(hide yes)
			(effects
				(font
					(size 1.27 1.27)
				)
			)
		)
		(property "Value" "0R2J-2-GP"
			(at 0.064008 -3.993896 270)
			(unlocked yes)
			(layer "F.Fab")
			(hide yes)
			(effects
				(font
					(size 1.016 1.016)
					(thickness 0.1524)
				)
			)
		)
		(property "Device Type" "R402H16"
			(at 0.064008 -5.517896 270)
			(unlocked yes)
			(layer "F.Fab")
			(hide yes)
			(effects
				(font
					(size 1.016 1.016)
					(thickness 0.1524)
				)
			)
		)
		(duplicate_pad_numbers_are_jumpers no)
		(fp_line
			(start -0.508 -0.9398)
			(end -0.508 0.9398)
			(stroke
				(width 0.1524)
				(type default)
			)
			(layer "F.SilkS")
		)
		(fp_line
			(start 0.508 -0.9398)
			(end -0.508 -0.9398)
			(stroke
				(width 0.1524)
				(type default)
			)
			(layer "F.SilkS")
		)
		(fp_rect
			(start -0.508 0.9398)
			(end 0.508 -0.9398)
			(stroke
				(width 0)
				(type default)
			)
			(fill no)
			(layer "F.CrtYd")
		)
		(fp_rect
			(start -0.508 0.9398)
			(end 0.508 -0.9398)
			(stroke
				(width 0)
				(type default)
			)
			(fill no)
			(layer "F.Fab")
		)
		(pad "1" smd custom
			(at 0 -0.4445 270)
			(size 0.1397 0.1397)
			(layers "F.Cu" "F.Mask" "F.Paste")
			(net "MB0_CM_ADR2_R")
			(options
				(clearance outline)
				(anchor circle)
			)
			(primitives
				(gr_poly
					(pts
						(arc
							(start -0.1778 -0.2794)
							(mid -0.249642 -0.249642)
							(end -0.2794 -0.1778)
						)
						(arc
							(start -0.2794 0.1778)
							(mid -0.249642 0.249642)
							(end -0.1778 0.2794)
						)
						(arc
							(start 0.1778 0.2794)
							(mid 0.249642 0.249642)
							(end 0.2794 0.1778)
						)
						(arc
							(start 0.2794 -0.1778)
							(mid 0.249642 -0.249642)
							(end 0.1778 -0.2794)
						)
					)
					(width 0)
					(fill yes)
				)
			)
		)
		(pad "2" smd custom
			(at 0 0.4445 270)
			(size 0.1397 0.1397)
			(layers "F.Cu" "F.Mask" "F.Paste")
			(net "AGND_CURRENT_MONOA")
			(options
				(clearance outline)
				(anchor circle)
			)
			(primitives
				(gr_poly
					(pts
						(arc
							(start -0.1778 -0.2794)
							(mid -0.249642 -0.249642)
							(end -0.2794 -0.1778)
						)
						(arc
							(start -0.2794 0.1778)
							(mid -0.249642 0.249642)
							(end -0.1778 0.2794)
						)
						(arc
							(start 0.1778 0.2794)
							(mid 0.249642 0.249642)
							(end 0.2794 0.1778)
						)
						(arc
							(start 0.2794 -0.1778)
							(mid 0.249642 -0.249642)
							(end 0.1778 -0.2794)
						)
					)
					(width 0)
					(fill yes)
				)
			)
		)
	)
	(footprint ""
		(layer "F.Cu")
		(at 469.898984 -279.098502 90)
		(property "Reference" "R399"
			(at 0 0 90)
			(layer "F.SilkS")
			(hide yes)
			(effects
				(font
					(size 1.27 1.27)
				)
			)
		)
		(property "Value" "200KR2F-L-GP"
			(at 0.064008 -3.993896 90)
			(unlocked yes)
			(layer "F.Fab")
			(hide yes)
			(effects
				(font
					(size 1.016 1.016)
					(thickness 0.1524)
				)
			)
		)
		(property "Device Type" "R402H16"
			(at 0.064008 -5.517896 90)
			(unlocked yes)
			(layer "F.Fab")
			(hide yes)
			(effects
				(font
					(size 1.016 1.016)
					(thickness 0.1524)
				)
			)
		)
		(duplicate_pad_numbers_are_jumpers no)
		(fp_line
			(start 0.508 -0.9398)
			(end -0.508 -0.9398)
			(stroke
				(width 0.1524)
				(type default)
			)
			(layer "F.SilkS")
		)
		(fp_line
			(start -0.508 -0.9398)
			(end -0.508 0.9398)
			(stroke
				(width 0.1524)
				(type default)
			)
			(layer "F.SilkS")
		)
		(fp_rect
			(start -0.508 0.9398)
			(end 0.508 -0.9398)
			(stroke
				(width 0)
				(type default)
			)
			(fill no)
			(layer "F.CrtYd")
		)
		(fp_rect
			(start -0.508 0.9398)
			(end 0.508 -0.9398)
			(stroke
				(width 0)
				(type default)
			)
			(fill no)
			(layer "F.Fab")
		)
		(pad "1" smd custom
			(at 0 -0.4445 90)
			(size 0.1397 0.1397)
			(layers "F.Cu" "F.Mask" "F.Paste")
			(net "SW_HDD_R11")
			(options
				(clearance outline)
				(anchor circle)
			)
			(primitives
				(gr_poly
					(pts
						(arc
							(start -0.1778 -0.2794)
							(mid -0.249642 -0.249642)
							(end -0.2794 -0.1778)
						)
						(arc
							(start -0.2794 0.1778)
							(mid -0.249642 0.249642)
							(end -0.1778 0.2794)
						)
						(arc
							(start 0.1778 0.2794)
							(mid 0.249642 0.249642)
							(end 0.2794 0.1778)
						)
						(arc
							(start 0.2794 -0.1778)
							(mid 0.249642 -0.249642)
							(end 0.1778 -0.2794)
						)
					)
					(width 0)
					(fill yes)
				)
			)
		)
		(pad "2" smd custom
			(at 0 0.4445 90)
			(size 0.1397 0.1397)
			(layers "F.Cu" "F.Mask" "F.Paste")
			(net "SW_HDD_N11")
			(options
				(clearance outline)
				(anchor circle)
			)
			(primitives
				(gr_poly
					(pts
						(arc
							(start -0.1778 -0.2794)
							(mid -0.249642 -0.249642)
							(end -0.2794 -0.1778)
						)
						(arc
							(start -0.2794 0.1778)
							(mid -0.249642 0.249642)
							(end -0.1778 0.2794)
						)
						(arc
							(start 0.1778 0.2794)
							(mid 0.249642 0.249642)
							(end 0.2794 0.1778)
						)
						(arc
							(start 0.2794 -0.1778)
							(mid 0.249642 -0.249642)
							(end 0.1778 -0.2794)
						)
					)
					(width 0)
					(fill yes)
				)
			)
		)
	)
	(footprint ""
		(layer "F.Cu")
		(at 69.620638 -188.85027)
		(property "Reference" "Q229"
			(at 0 0 0)
			(layer "F.SilkS")
			(hide yes)
			(effects
				(font
					(size 1.27 1.27)
				)
			)
		)
		(property "Value" "2N7002K-2-GP"
			(at 0.127 -8.9662 0)
			(unlocked yes)
			(layer "F.Fab")
			(hide yes)
			(effects
				(font
					(size 1.016 1.016)
					(thickness 0.1524)
				)
			)
		)
		(property "Device Type" "SOT23DGS2D4H44"
			(at 0.127 -10.4902 0)
			(unlocked yes)
			(layer "F.Fab")
			(hide yes)
			(effects
				(font
					(size 1.016 1.016)
					(thickness 0.1524)
				)
			)
		)
		(duplicate_pad_numbers_are_jumpers no)
		(fp_line
			(start -1.651 -1.778)
			(end -1.651 1.778)
			(stroke
				(width 0.1524)
				(type default)
			)
			(layer "F.SilkS")
		)
		(fp_line
			(start -1.651 1.778)
			(end 1.651 1.778)
			(stroke
				(width 0.1524)
				(type default)
			)
			(layer "F.SilkS")
		)
		(fp_line
			(start 1.651 -1.778)
			(end -1.651 -1.778)
			(stroke
				(width 0.1524)
				(type default)
			)
			(layer "F.SilkS")
		)
		(fp_line
			(start 1.651 1.778)
			(end 1.651 -1.778)
			(stroke
				(width 0.1524)
				(type default)
			)
			(layer "F.SilkS")
		)
		(fp_poly
			(pts
				(xy -1.778 1.8796) (xy -1.778 -1.8796) (xy 1.778 -1.8796) (xy 1.778 1.8796)
			)
			(stroke
				(width 0)
				(type default)
			)
			(fill no)
			(layer "F.CrtYd")
		)
		(fp_poly
			(pts
				(xy -1.778 1.8796) (xy -1.778 -1.8796) (xy 1.778 -1.8796) (xy 1.778 1.8796)
			)
			(stroke
				(width 0)
				(type default)
			)
			(fill no)
			(layer "F.Fab")
		)
		(pad "D" smd custom
			(at 0 -0.9525)
			(size 0.1905 0.1905)
			(layers "F.Cu" "F.Mask" "F.Paste")
			(net "FLT_HDD2_N")
			(options
				(clearance outline)
				(anchor circle)
			)
			(primitives
				(gr_poly
					(pts
						(arc
							(start -0.1778 0.5715)
							(mid -0.321484 0.511984)
							(end -0.381 0.3683)
						)
						(arc
							(start -0.381 -0.3683)
							(mid -0.321484 -0.511984)
							(end -0.1778 -0.5715)
						)
						(arc
							(start 0.1778 -0.5715)
							(mid 0.321484 -0.511984)
							(end 0.381 -0.3683)
						)
						(arc
							(start 0.381 0.3683)
							(mid 0.321484 0.511984)
							(end 0.1778 0.5715)
						)
					)
					(width 0)
					(fill yes)
				)
			)
		)
		(pad "G" smd custom
			(at -0.98425 0.9525)
			(size 0.1905 0.1905)
			(layers "F.Cu" "F.Mask" "F.Paste")
			(net "DRIVE_A_2_FLT_LED")
			(options
				(clearance outline)
				(anchor circle)
			)
			(primitives
				(gr_poly
					(pts
						(arc
							(start -0.1778 0.5715)
							(mid -0.321484 0.511984)
							(end -0.381 0.3683)
						)
						(arc
							(start -0.381 -0.3683)
							(mid -0.321484 -0.511984)
							(end -0.1778 -0.5715)
						)
						(arc
							(start 0.1778 -0.5715)
							(mid 0.321484 -0.511984)
							(end 0.381 -0.3683)
						)
						(arc
							(start 0.381 0.3683)
							(mid 0.321484 0.511984)
							(end 0.1778 0.5715)
						)
					)
					(width 0)
					(fill yes)
				)
			)
		)
		(pad "S" smd custom
			(at 0.98425 0.9525)
			(size 0.1905 0.1905)
			(layers "F.Cu" "F.Mask" "F.Paste")
			(net "GND")
			(options
				(clearance outline)
				(anchor circle)
			)
			(primitives
				(gr_poly
					(pts
						(arc
							(start -0.1778 0.5715)
							(mid -0.321484 0.511984)
							(end -0.381 0.3683)
						)
						(arc
							(start -0.381 -0.3683)
							(mid -0.321484 -0.511984)
							(end -0.1778 -0.5715)
						)
						(arc
							(start 0.1778 -0.5715)
							(mid 0.321484 -0.511984)
							(end 0.381 -0.3683)
						)
						(arc
							(start 0.381 0.3683)
							(mid 0.321484 0.511984)
							(end 0.1778 0.5715)
						)
					)
					(width 0)
					(fill yes)
				)
			)
		)
	)
	(footprint ""
		(layer "F.Cu")
		(at 233.903266 -261.722362)
		(property "Reference" "R38"
			(at 0 0 0)
			(layer "F.SilkS")
			(hide yes)
			(effects
				(font
					(size 1.27 1.27)
				)
			)
		)
		(property "Value" "4K7R2F-GP"
			(at 0.064008 -3.993896 0)
			(unlocked yes)
			(layer "F.Fab")
			(hide yes)
			(effects
				(font
					(size 1.016 1.016)
					(thickness 0.1524)
				)
			)
		)
		(property "Device Type" "R402H16"
			(at 0.064008 -5.517896 0)
			(unlocked yes)
			(layer "F.Fab")
			(hide yes)
			(effects
				(font
					(size 1.016 1.016)
					(thickness 0.1524)
				)
			)
		)
		(duplicate_pad_numbers_are_jumpers no)
		(fp_line
			(start -0.508 -0.9398)
			(end -0.508 0.9398)
			(stroke
				(width 0.1524)
				(type default)
			)
			(layer "F.SilkS")
		)
		(fp_line
			(start 0.508 -0.9398)
			(end -0.508 -0.9398)
			(stroke
				(width 0.1524)
				(type default)
			)
			(layer "F.SilkS")
		)
		(fp_rect
			(start -0.508 0.9398)
			(end 0.508 -0.9398)
			(stroke
				(width 0)
				(type default)
			)
			(fill no)
			(layer "F.CrtYd")
		)
		(fp_rect
			(start -0.508 0.9398)
			(end 0.508 -0.9398)
			(stroke
				(width 0)
				(type default)
			)
			(fill no)
			(layer "F.Fab")
		)
		(pad "1" smd custom
			(at 0 -0.4445)
			(size 0.1397 0.1397)
			(layers "F.Cu" "F.Mask" "F.Paste")
			(net "P3V3_STBY_A")
			(options
				(clearance outline)
				(anchor circle)
			)
			(primitives
				(gr_poly
					(pts
						(arc
							(start -0.1778 -0.2794)
							(mid -0.249642 -0.249642)
							(end -0.2794 -0.1778)
						)
						(arc
							(start -0.2794 0.1778)
							(mid -0.249642 0.249642)
							(end -0.1778 0.2794)
						)
						(arc
							(start 0.1778 0.2794)
							(mid 0.249642 0.249642)
							(end 0.2794 0.1778)
						)
						(arc
							(start 0.2794 -0.1778)
							(mid 0.249642 -0.249642)
							(end 0.1778 -0.2794)
						)
					)
					(width 0)
					(fill yes)
				)
			)
		)
		(pad "2" smd custom
			(at 0 0.4445)
			(size 0.1397 0.1397)
			(layers "F.Cu" "F.Mask" "F.Paste")
			(net "IO_EXP4_A2")
			(options
				(clearance outline)
				(anchor circle)
			)
			(primitives
				(gr_poly
					(pts
						(arc
							(start -0.1778 -0.2794)
							(mid -0.249642 -0.249642)
							(end -0.2794 -0.1778)
						)
						(arc
							(start -0.2794 0.1778)
							(mid -0.249642 0.249642)
							(end -0.1778 0.2794)
						)
						(arc
							(start 0.1778 0.2794)
							(mid 0.249642 0.249642)
							(end 0.2794 0.1778)
						)
						(arc
							(start 0.2794 -0.1778)
							(mid 0.249642 -0.249642)
							(end 0.1778 -0.2794)
						)
					)
					(width 0)
					(fill yes)
				)
			)
		)
	)
	(footprint ""
		(layer "F.Cu")
		(at 3.849878 -120.499886)
		(property "Reference" ""
			(at 0 0 0)
			(layer "F.SilkS")
			(hide yes)
			(effects
				(font
					(size 1.27 1.27)
				)
			)
		)
		(property "Value" "*"
			(at -4.9911 1.5494 0)
			(unlocked yes)
			(layer "F.Fab")
			(hide yes)
			(effects
				(font
					(size 1.016 1.016)
					(thickness 0.1524)
				)
			)
		)
		(duplicate_pad_numbers_are_jumpers no)
		(fp_poly
			(pts
				(arc
					(start 4.064 0)
					(mid -4.064 0)
					(end 4.064 0)
				)
			)
			(stroke
				(width 0)
				(type default)
			)
			(fill no)
			(layer "B.CrtYd")
		)
		(fp_poly
			(pts
				(arc
					(start 4.064 0)
					(mid -4.064 0)
					(end 4.064 0)
				)
			)
			(stroke
				(width 0)
				(type default)
			)
			(fill no)
			(layer "F.CrtYd")
		)
		(fp_poly
			(pts
				(arc
					(start 4.064 0)
					(mid -4.064 0)
					(end 4.064 0)
				)
			)
			(stroke
				(width 0)
				(type default)
			)
			(fill no)
			(layer "B.Fab")
		)
		(fp_poly
			(pts
				(arc
					(start 4.064 0)
					(mid -4.064 0)
					(end 4.064 0)
				)
			)
			(stroke
				(width 0)
				(type default)
			)
			(fill no)
			(layer "F.Fab")
		)
		(pad "1" thru_hole circle
			(at 0 0)
			(size 7.5184 7.5184)
			(drill oval 6.223 4.2164)
			(layers "*.Cu" "*.Mask")
			(remove_unused_layers no)
			(net "Net_58")
			(clearance -1.143)
			(thermal_gap 0.1524)
			(padstack
				(mode front_inner_back)
				(layer "Inner"
					(shape oval)
					(size 4.9276 6.9342)
					(clearance 0.1524)
				)
				(layer "B.Cu"
					(shape circle)
					(size 7.5184 7.5184)
					(clearance -1.143)
				)
			)
		)
		(zone
			(layers "F.Cu" "B.Cu" "In1.Cu" "In2.Cu" "In3.Cu" "In4.Cu" "In5.Cu" "In6.Cu"
				"In7.Cu" "In8.Cu" "In9.Cu" "In10.Cu"
			)
			(hatch none 0.5)
			(connect_pads
				(clearance 0)
			)
			(min_thickness 0.25)
			(keepout
				(tracks not_allowed)
				(vias allowed)
				(pads allowed)
				(copperpour not_allowed)
				(footprints allowed)
			)
			(placement
				(enabled no)
				(sheetname "")
			)
			(fill
				(thermal_gap 0.5)
				(thermal_bridge_width 0.5)
				(island_removal_mode 0)
			)
			(polygon
				(pts
					(arc
						(start 7.609078 -120.499886)
						(mid 0.090678 -120.499886)
						(end 7.609078 -120.499886)
					)
				)
			)
		)
	)
	(footprint ""
		(layer "F.Cu")
		(at 263.233662 -342.897968 90)
		(property "Reference" "R980"
			(at 0 0 90)
			(layer "F.SilkS")
			(hide yes)
			(effects
				(font
					(size 1.27 1.27)
				)
			)
		)
		(property "Value" "0R2J-2-GP"
			(at 0.064008 -3.993896 90)
			(unlocked yes)
			(layer "F.Fab")
			(hide yes)
			(effects
				(font
					(size 1.016 1.016)
					(thickness 0.1524)
				)
			)
		)
		(property "Device Type" "R402H16"
			(at 0.064008 -5.517896 90)
			(unlocked yes)
			(layer "F.Fab")
			(hide yes)
			(effects
				(font
					(size 1.016 1.016)
					(thickness 0.1524)
				)
			)
		)
		(duplicate_pad_numbers_are_jumpers no)
		(fp_line
			(start 0.508 -0.9398)
			(end -0.508 -0.9398)
			(stroke
				(width 0.1524)
				(type default)
			)
			(layer "F.SilkS")
		)
		(fp_line
			(start -0.508 -0.9398)
			(end -0.508 0.9398)
			(stroke
				(width 0.1524)
				(type default)
			)
			(layer "F.SilkS")
		)
		(fp_rect
			(start -0.508 0.9398)
			(end 0.508 -0.9398)
			(stroke
				(width 0)
				(type default)
			)
			(fill no)
			(layer "F.CrtYd")
		)
		(fp_rect
			(start -0.508 0.9398)
			(end 0.508 -0.9398)
			(stroke
				(width 0)
				(type default)
			)
			(fill no)
			(layer "F.Fab")
		)
		(pad "1" smd custom
			(at 0 -0.4445 90)
			(size 0.1397 0.1397)
			(layers "F.Cu" "F.Mask" "F.Paste")
			(net "GND")
			(options
				(clearance outline)
				(anchor circle)
			)
			(primitives
				(gr_poly
					(pts
						(arc
							(start -0.1778 -0.2794)
							(mid -0.249642 -0.249642)
							(end -0.2794 -0.1778)
						)
						(arc
							(start -0.2794 0.1778)
							(mid -0.249642 0.249642)
							(end -0.1778 0.2794)
						)
						(arc
							(start 0.1778 0.2794)
							(mid 0.249642 0.249642)
							(end 0.2794 0.1778)
						)
						(arc
							(start 0.2794 -0.1778)
							(mid 0.249642 -0.249642)
							(end 0.1778 -0.2794)
						)
					)
					(width 0)
					(fill yes)
				)
			)
		)
		(pad "2" smd custom
			(at 0 0.4445 90)
			(size 0.1397 0.1397)
			(layers "F.Cu" "F.Mask" "F.Paste")
			(net "SCC_A_SLOT_ID_0")
			(options
				(clearance outline)
				(anchor circle)
			)
			(primitives
				(gr_poly
					(pts
						(arc
							(start -0.1778 -0.2794)
							(mid -0.249642 -0.249642)
							(end -0.2794 -0.1778)
						)
						(arc
							(start -0.2794 0.1778)
							(mid -0.249642 0.249642)
							(end -0.1778 0.2794)
						)
						(arc
							(start 0.1778 0.2794)
							(mid 0.249642 0.249642)
							(end 0.2794 0.1778)
						)
						(arc
							(start 0.2794 -0.1778)
							(mid 0.249642 -0.249642)
							(end 0.1778 -0.2794)
						)
					)
					(width 0)
					(fill yes)
				)
			)
		)
	)
	(footprint ""
		(layer "F.Cu")
		(at 263.53897 -380.367794)
		(property "Reference" "Q227"
			(at 0 0 0)
			(layer "F.SilkS")
			(hide yes)
			(effects
				(font
					(size 1.27 1.27)
				)
			)
		)
		(property "Value" "IRFH8201TRPBF-GP"
			(at -4.2164 -4.3688 0)
			(unlocked yes)
			(layer "F.Fab")
			(hide yes)
			(effects
				(font
					(size 1.016 1.016)
					(thickness 0.1524)
				)
			)
		)
		(property "Device Type" "PPAK-5PH42"
			(at -4.2164 -5.8928 0)
			(unlocked yes)
			(layer "F.Fab")
			(hide yes)
			(effects
				(font
					(size 1.016 1.016)
					(thickness 0.1524)
				)
			)
		)
		(duplicate_pad_numbers_are_jumpers no)
		(fp_line
			(start -3.0353 4.9276)
			(end -3.0353 3.9624)
			(stroke
				(width 0.3302)
				(type default)
			)
			(layer "F.SilkS")
		)
		(fp_line
			(start -2.8956 -2.794)
			(end 2.8956 -2.794)
			(stroke
				(width 0.1524)
				(type default)
			)
			(layer "F.SilkS")
		)
		(fp_line
			(start -2.8956 4.826)
			(end -2.8956 -2.794)
			(stroke
				(width 0.1524)
				(type default)
			)
			(layer "F.SilkS")
		)
		(fp_line
			(start -1.9431 4.9276)
			(end -3.0353 4.9276)
			(stroke
				(width 0.3302)
				(type default)
			)
			(layer "F.SilkS")
		)
		(fp_line
			(start 2.8956 -2.794)
			(end 2.8956 4.826)
			(stroke
				(width 0.1524)
				(type default)
			)
			(layer "F.SilkS")
		)
		(fp_line
			(start 2.8956 4.826)
			(end -2.8956 4.826)
			(stroke
				(width 0.1524)
				(type default)
			)
			(layer "F.SilkS")
		)
		(fp_poly
			(pts
				(xy -2.3622 5.334) (xy -1.4986 5.334) (xy -1.9304 4.9022)
			)
			(stroke
				(width 0)
				(type default)
			)
			(fill yes)
			(layer "F.SilkS")
		)
		(fp_poly
			(pts
				(xy -2.6416 -0.3556) (xy -0.3556 -0.3556) (xy -0.3556 -2.54) (xy -2.6416 -2.54)
			)
			(stroke
				(width 0)
				(type default)
			)
			(fill yes)
			(layer "F.Paste")
		)
		(fp_poly
			(pts
				(xy -2.6416 2.54) (xy -0.3556 2.54) (xy -0.3556 0.3556) (xy -2.6416 0.3556)
			)
			(stroke
				(width 0)
				(type default)
			)
			(fill yes)
			(layer "F.Paste")
		)
		(fp_poly
			(pts
				(xy 0.3556 -0.3556) (xy 2.6416 -0.3556) (xy 2.6416 -2.54) (xy 0.3556 -2.54)
			)
			(stroke
				(width 0)
				(type default)
			)
			(fill yes)
			(layer "F.Paste")
		)
		(fp_poly
			(pts
				(xy 0.3556 2.54) (xy 2.6416 2.54) (xy 2.6416 0.3556) (xy 0.3556 0.3556)
			)
			(stroke
				(width 0)
				(type default)
			)
			(fill yes)
			(layer "F.Paste")
		)
		(fp_rect
			(start -2.5781 3.9878)
			(end 2.5781 -2.1082)
			(stroke
				(width 0)
				(type default)
			)
			(fill no)
			(layer "F.CrtYd")
		)
		(fp_poly
			(pts
				(xy -3.1496 5.08) (xy -3.1496 -3.048) (xy 3.1496 -3.048) (xy 3.1496 3.9751) (xy 2.5781 3.9751) (xy 2.5781 -2.1082)
				(xy -2.5781 -2.1082) (xy -2.5781 3.9878) (xy 3.1496 3.9878) (xy 3.1496 5.08)
			)
			(stroke
				(width 0)
				(type default)
			)
			(fill no)
			(layer "F.CrtYd")
		)
		(fp_rect
			(start -3.1496 5.08)
			(end 3.1496 -3.048)
			(stroke
				(width 0)
				(type default)
			)
			(fill no)
			(layer "F.Fab")
		)
		(pad "1" smd rect
			(at -1.905 3.81)
			(size 0.762 1.524)
			(layers "F.Cu" "F.Mask" "F.Paste")
			(net "P12V_A")
		)
		(pad "2" smd rect
			(at -0.635 3.81)
			(size 0.762 1.524)
			(layers "F.Cu" "F.Mask" "F.Paste")
			(net "P12V_A")
		)
		(pad "3" smd rect
			(at 0.635 3.81)
			(size 0.762 1.524)
			(layers "F.Cu" "F.Mask" "F.Paste")
			(net "P12V_A")
		)
		(pad "4" smd rect
			(at 1.905 3.81)
			(size 0.762 1.524)
			(layers "F.Cu" "F.Mask" "F.Paste")
			(net "MB3_12V_CTRL_GATE2")
		)
		(pad "5" smd rect
			(at 0 0)
			(size 5.2832 5.08)
			(layers "F.Cu" "F.Mask" "F.Paste")
			(net "MB3_P12V_IN_R")
		)
		(pad "6" smd rect
			(at 0.635 -2.032)
			(size 0.0254 0.0254)
			(layers "F.Cu" "F.Mask" "F.Paste")
			(net "MB3_P12V_IN_R")
		)
		(pad "7" smd rect
			(at -0.635 -2.032)
			(size 0.0254 0.0254)
			(layers "F.Cu" "F.Mask" "F.Paste")
			(net "MB3_P12V_IN_R")
		)
		(pad "8" smd rect
			(at -1.905 -2.032)
			(size 0.0254 0.0254)
			(layers "F.Cu" "F.Mask" "F.Paste")
			(net "MB3_P12V_IN_R")
		)
	)
	(footprint ""
		(layer "F.Cu")
		(at 245.364 -231.14)
		(property "Reference" "R81"
			(at 0 0 0)
			(layer "F.SilkS")
			(hide yes)
			(effects
				(font
					(size 1.27 1.27)
				)
			)
		)
		(property "Value" "4K7R2F-GP"
			(at 0.064008 -3.993896 0)
			(unlocked yes)
			(layer "F.Fab")
			(hide yes)
			(effects
				(font
					(size 1.016 1.016)
					(thickness 0.1524)
				)
			)
		)
		(property "Device Type" "R402H16"
			(at 0.064008 -5.517896 0)
			(unlocked yes)
			(layer "F.Fab")
			(hide yes)
			(effects
				(font
					(size 1.016 1.016)
					(thickness 0.1524)
				)
			)
		)
		(duplicate_pad_numbers_are_jumpers no)
		(fp_line
			(start -0.508 -0.9398)
			(end -0.508 0.9398)
			(stroke
				(width 0.1524)
				(type default)
			)
			(layer "F.SilkS")
		)
		(fp_line
			(start 0.508 -0.9398)
			(end -0.508 -0.9398)
			(stroke
				(width 0.1524)
				(type default)
			)
			(layer "F.SilkS")
		)
		(fp_rect
			(start -0.508 0.9398)
			(end 0.508 -0.9398)
			(stroke
				(width 0)
				(type default)
			)
			(fill no)
			(layer "F.CrtYd")
		)
		(fp_rect
			(start -0.508 0.9398)
			(end 0.508 -0.9398)
			(stroke
				(width 0)
				(type default)
			)
			(fill no)
			(layer "F.Fab")
		)
		(pad "1" smd custom
			(at 0 -0.4445)
			(size 0.1397 0.1397)
			(layers "F.Cu" "F.Mask" "F.Paste")
			(net "IO_EXP2_A2")
			(options
				(clearance outline)
				(anchor circle)
			)
			(primitives
				(gr_poly
					(pts
						(arc
							(start -0.1778 -0.2794)
							(mid -0.249642 -0.249642)
							(end -0.2794 -0.1778)
						)
						(arc
							(start -0.2794 0.1778)
							(mid -0.249642 0.249642)
							(end -0.1778 0.2794)
						)
						(arc
							(start 0.1778 0.2794)
							(mid 0.249642 0.249642)
							(end 0.2794 0.1778)
						)
						(arc
							(start 0.2794 -0.1778)
							(mid 0.249642 -0.249642)
							(end 0.1778 -0.2794)
						)
					)
					(width 0)
					(fill yes)
				)
			)
		)
		(pad "2" smd custom
			(at 0 0.4445)
			(size 0.1397 0.1397)
			(layers "F.Cu" "F.Mask" "F.Paste")
			(net "GND")
			(options
				(clearance outline)
				(anchor circle)
			)
			(primitives
				(gr_poly
					(pts
						(arc
							(start -0.1778 -0.2794)
							(mid -0.249642 -0.249642)
							(end -0.2794 -0.1778)
						)
						(arc
							(start -0.2794 0.1778)
							(mid -0.249642 0.249642)
							(end -0.1778 0.2794)
						)
						(arc
							(start 0.1778 0.2794)
							(mid 0.249642 0.249642)
							(end 0.2794 0.1778)
						)
						(arc
							(start 0.2794 -0.1778)
							(mid 0.249642 -0.249642)
							(end 0.1778 -0.2794)
						)
					)
					(width 0)
					(fill yes)
				)
			)
		)
	)
	(footprint ""
		(layer "F.Cu")
		(at 113.581942 -272.726404 180)
		(property "Reference" "R207"
			(at 0 0 180)
			(layer "F.SilkS")
			(hide yes)
			(effects
				(font
					(size 1.27 1.27)
				)
			)
		)
		(property "Value" "1KR2F-3-GP"
			(at 0.064008 -3.993896 180)
			(unlocked yes)
			(layer "F.Fab")
			(hide yes)
			(effects
				(font
					(size 1.016 1.016)
					(thickness 0.1524)
				)
			)
		)
		(property "Device Type" "R402H16"
			(at 0.064008 -5.517896 180)
			(unlocked yes)
			(layer "F.Fab")
			(hide yes)
			(effects
				(font
					(size 1.016 1.016)
					(thickness 0.1524)
				)
			)
		)
		(duplicate_pad_numbers_are_jumpers no)
		(fp_line
			(start 0.508 -0.9398)
			(end -0.508 -0.9398)
			(stroke
				(width 0.1524)
				(type default)
			)
			(layer "F.SilkS")
		)
		(fp_line
			(start -0.508 -0.9398)
			(end -0.508 0.9398)
			(stroke
				(width 0.1524)
				(type default)
			)
			(layer "F.SilkS")
		)
		(fp_rect
			(start -0.508 0.9398)
			(end 0.508 -0.9398)
			(stroke
				(width 0)
				(type default)
			)
			(fill no)
			(layer "F.CrtYd")
		)
		(fp_rect
			(start -0.508 0.9398)
			(end 0.508 -0.9398)
			(stroke
				(width 0)
				(type default)
			)
			(fill no)
			(layer "F.Fab")
		)
		(pad "1" smd custom
			(at 0 -0.4445 180)
			(size 0.1397 0.1397)
			(layers "F.Cu" "F.Mask" "F.Paste")
			(net "P3V3_STBY_A")
			(options
				(clearance outline)
				(anchor circle)
			)
			(primitives
				(gr_poly
					(pts
						(arc
							(start -0.1778 -0.2794)
							(mid -0.249642 -0.249642)
							(end -0.2794 -0.1778)
						)
						(arc
							(start -0.2794 0.1778)
							(mid -0.249642 0.249642)
							(end -0.1778 0.2794)
						)
						(arc
							(start 0.1778 0.2794)
							(mid 0.249642 0.249642)
							(end 0.2794 0.1778)
						)
						(arc
							(start 0.2794 -0.1778)
							(mid 0.249642 -0.249642)
							(end 0.1778 -0.2794)
						)
					)
					(width 0)
					(fill yes)
				)
			)
		)
		(pad "2" smd custom
			(at 0 0.4445 180)
			(size 0.1397 0.1397)
			(layers "F.Cu" "F.Mask" "F.Paste")
			(net "SW_PWR_R_HDD3")
			(options
				(clearance outline)
				(anchor circle)
			)
			(primitives
				(gr_poly
					(pts
						(arc
							(start -0.1778 -0.2794)
							(mid -0.249642 -0.249642)
							(end -0.2794 -0.1778)
						)
						(arc
							(start -0.2794 0.1778)
							(mid -0.249642 0.249642)
							(end -0.1778 0.2794)
						)
						(arc
							(start 0.1778 0.2794)
							(mid 0.249642 0.249642)
							(end 0.2794 0.1778)
						)
						(arc
							(start 0.2794 -0.1778)
							(mid 0.249642 -0.249642)
							(end 0.1778 -0.2794)
						)
					)
					(width 0)
					(fill yes)
				)
			)
		)
	)
	(footprint ""
		(layer "F.Cu")
		(at 393.90955 -288.638742 90)
		(property "Reference" "C152"
			(at 0 0 90)
			(layer "F.SilkS")
			(hide yes)
			(effects
				(font
					(size 1.27 1.27)
				)
			)
		)
		(property "Value" "SCD033U25V2KX-GP"
			(at 1.1811 -2.7051 90)
			(unlocked yes)
			(layer "F.Fab")
			(hide yes)
			(effects
				(font
					(size 1.016 1.016)
					(thickness 0.1524)
				)
			)
		)
		(property "Device Type" "C402H22"
			(at 1.1811 -4.2291 90)
			(unlocked yes)
			(layer "F.Fab")
			(hide yes)
			(effects
				(font
					(size 1.016 1.016)
					(thickness 0.1524)
				)
			)
		)
		(duplicate_pad_numbers_are_jumpers no)
		(fp_rect
			(start -0.4318 0.9525)
			(end 0.4318 -0.9525)
			(stroke
				(width 0)
				(type default)
			)
			(fill no)
			(layer "F.CrtYd")
		)
		(fp_rect
			(start -0.4318 0.9525)
			(end 0.4318 -0.9525)
			(stroke
				(width 0)
				(type default)
			)
			(fill no)
			(layer "F.Fab")
		)
		(pad "1" smd custom
			(at 0 -0.4445 90)
			(size 0.1524 0.1524)
			(layers "F.Cu" "F.Mask" "F.Paste")
			(net "SW_HDD_P8")
			(options
				(clearance outline)
				(anchor circle)
			)
			(primitives
				(gr_poly
					(pts
						(arc
							(start 0.3048 -0.2032)
							(mid 0.275042 -0.275042)
							(end 0.2032 -0.3048)
						)
						(arc
							(start -0.2032 -0.3048)
							(mid -0.275042 -0.275042)
							(end -0.3048 -0.2032)
						)
						(arc
							(start -0.3048 0.2032)
							(mid -0.275042 0.275042)
							(end -0.2032 0.3048)
						)
						(arc
							(start 0.2032 0.3048)
							(mid 0.275042 0.275042)
							(end 0.3048 0.2032)
						)
					)
					(width 0)
					(fill yes)
				)
			)
		)
		(pad "2" smd custom
			(at 0 0.4445 90)
			(size 0.1524 0.1524)
			(layers "F.Cu" "F.Mask" "F.Paste")
			(net "GND")
			(options
				(clearance outline)
				(anchor circle)
			)
			(primitives
				(gr_poly
					(pts
						(arc
							(start 0.3048 -0.2032)
							(mid 0.275042 -0.275042)
							(end 0.2032 -0.3048)
						)
						(arc
							(start -0.2032 -0.3048)
							(mid -0.275042 -0.275042)
							(end -0.3048 -0.2032)
						)
						(arc
							(start -0.3048 0.2032)
							(mid -0.275042 0.275042)
							(end -0.2032 0.3048)
						)
						(arc
							(start 0.2032 0.3048)
							(mid 0.275042 0.275042)
							(end 0.3048 0.2032)
						)
					)
					(width 0)
					(fill yes)
				)
			)
		)
	)
	(footprint ""
		(layer "F.Cu")
		(at 265.1506 -230.3018)
		(property "Reference" "R97"
			(at 0 0 0)
			(layer "F.SilkS")
			(hide yes)
			(effects
				(font
					(size 1.27 1.27)
				)
			)
		)
		(property "Value" "4K7R2F-GP"
			(at 0.064008 -3.993896 0)
			(unlocked yes)
			(layer "F.Fab")
			(hide yes)
			(effects
				(font
					(size 1.016 1.016)
					(thickness 0.1524)
				)
			)
		)
		(property "Device Type" "R402H16"
			(at 0.064008 -5.517896 0)
			(unlocked yes)
			(layer "F.Fab")
			(hide yes)
			(effects
				(font
					(size 1.016 1.016)
					(thickness 0.1524)
				)
			)
		)
		(duplicate_pad_numbers_are_jumpers no)
		(fp_line
			(start -0.508 -0.9398)
			(end -0.508 0.9398)
			(stroke
				(width 0.1524)
				(type default)
			)
			(layer "F.SilkS")
		)
		(fp_line
			(start 0.508 -0.9398)
			(end -0.508 -0.9398)
			(stroke
				(width 0.1524)
				(type default)
			)
			(layer "F.SilkS")
		)
		(fp_rect
			(start -0.508 0.9398)
			(end 0.508 -0.9398)
			(stroke
				(width 0)
				(type default)
			)
			(fill no)
			(layer "F.CrtYd")
		)
		(fp_rect
			(start -0.508 0.9398)
			(end 0.508 -0.9398)
			(stroke
				(width 0)
				(type default)
			)
			(fill no)
			(layer "F.Fab")
		)
		(pad "1" smd custom
			(at 0 -0.4445)
			(size 0.1397 0.1397)
			(layers "F.Cu" "F.Mask" "F.Paste")
			(net "IO_EXP3_A1")
			(options
				(clearance outline)
				(anchor circle)
			)
			(primitives
				(gr_poly
					(pts
						(arc
							(start -0.1778 -0.2794)
							(mid -0.249642 -0.249642)
							(end -0.2794 -0.1778)
						)
						(arc
							(start -0.2794 0.1778)
							(mid -0.249642 0.249642)
							(end -0.1778 0.2794)
						)
						(arc
							(start 0.1778 0.2794)
							(mid 0.249642 0.249642)
							(end 0.2794 0.1778)
						)
						(arc
							(start 0.2794 -0.1778)
							(mid 0.249642 -0.249642)
							(end 0.1778 -0.2794)
						)
					)
					(width 0)
					(fill yes)
				)
			)
		)
		(pad "2" smd custom
			(at 0 0.4445)
			(size 0.1397 0.1397)
			(layers "F.Cu" "F.Mask" "F.Paste")
			(net "GND")
			(options
				(clearance outline)
				(anchor circle)
			)
			(primitives
				(gr_poly
					(pts
						(arc
							(start -0.1778 -0.2794)
							(mid -0.249642 -0.249642)
							(end -0.2794 -0.1778)
						)
						(arc
							(start -0.2794 0.1778)
							(mid -0.249642 0.249642)
							(end -0.1778 0.2794)
						)
						(arc
							(start 0.1778 0.2794)
							(mid 0.249642 0.249642)
							(end 0.2794 0.1778)
						)
						(arc
							(start 0.2794 -0.1778)
							(mid 0.249642 -0.249642)
							(end 0.1778 -0.2794)
						)
					)
					(width 0)
					(fill yes)
				)
			)
		)
	)
	(footprint ""
		(layer "F.Cu")
		(at 384.734562 -44.219368 -90)
		(property "Reference" "C454"
			(at 0 0 270)
			(layer "F.SilkS")
			(hide yes)
			(effects
				(font
					(size 1.27 1.27)
				)
			)
		)
		(property "Value" "SCD01U16V1KX-GP"
			(at -2.8321 -1.7399 270)
			(unlocked yes)
			(layer "F.Fab")
			(hide yes)
			(effects
				(font
					(size 1.016 1.016)
					(thickness 0.1524)
				)
			)
		)
		(property "Device Type" "C0201H13"
			(at -2.8321 -3.2639 270)
			(unlocked yes)
			(layer "F.Fab")
			(hide yes)
			(effects
				(font
					(size 1.016 1.016)
					(thickness 0.1524)
				)
			)
		)
		(duplicate_pad_numbers_are_jumpers no)
		(fp_rect
			(start -0.2794 0.6477)
			(end 0.2794 -0.6477)
			(stroke
				(width 0)
				(type default)
			)
			(fill no)
			(layer "F.CrtYd")
		)
		(fp_rect
			(start -0.2794 0.6477)
			(end 0.2794 -0.6477)
			(stroke
				(width 0)
				(type default)
			)
			(fill no)
			(layer "F.Fab")
		)
		(pad "1" smd custom
			(at 0 -0.2794 270)
			(size 0.0762 0.0762)
			(layers "F.Cu" "F.Mask" "F.Paste")
			(net "SAS_HDD_RX_N32")
			(options
				(clearance outline)
				(anchor circle)
			)
			(primitives
				(gr_poly
					(pts
						(arc
							(start 0.1524 -0.127)
							(mid 0.137521 -0.162921)
							(end 0.1016 -0.1778)
						)
						(arc
							(start -0.1016 -0.1778)
							(mid -0.137521 -0.162921)
							(end -0.1524 -0.127)
						)
						(arc
							(start -0.1524 0.127)
							(mid -0.137521 0.162921)
							(end -0.1016 0.1778)
						)
						(arc
							(start 0.1016 0.1778)
							(mid 0.137521 0.162921)
							(end 0.1524 0.127)
						)
					)
					(width 0)
					(fill yes)
				)
			)
		)
		(pad "2" smd custom
			(at 0 0.2794 270)
			(size 0.0762 0.0762)
			(layers "F.Cu" "F.Mask" "F.Paste")
			(net "PHY_SCC_A_TO_DRV_A_32_DN")
			(options
				(clearance outline)
				(anchor circle)
			)
			(primitives
				(gr_poly
					(pts
						(arc
							(start 0.1524 -0.127)
							(mid 0.137521 -0.162921)
							(end 0.1016 -0.1778)
						)
						(arc
							(start -0.1016 -0.1778)
							(mid -0.137521 -0.162921)
							(end -0.1524 -0.127)
						)
						(arc
							(start -0.1524 0.127)
							(mid -0.137521 0.162921)
							(end -0.1016 0.1778)
						)
						(arc
							(start 0.1016 0.1778)
							(mid 0.137521 0.162921)
							(end 0.1524 0.127)
						)
					)
					(width 0)
					(fill yes)
				)
			)
		)
	)
	(footprint ""
		(layer "F.Cu")
		(at 444.4238 -295.0972 -90)
		(property "Reference" "R364"
			(at 0 0 270)
			(layer "F.SilkS")
			(hide yes)
			(effects
				(font
					(size 1.27 1.27)
				)
			)
		)
		(property "Value" "220R3F-1-GP"
			(at -0.0254 -2.5146 270)
			(unlocked yes)
			(layer "F.Fab")
			(hide yes)
			(effects
				(font
					(size 1.016 1.016)
					(thickness 0.1524)
				)
			)
		)
		(property "Device Type" "R603H22"
			(at -0.0254 -4.0386 270)
			(unlocked yes)
			(layer "F.Fab")
			(hide yes)
			(effects
				(font
					(size 1.016 1.016)
					(thickness 0.1524)
				)
			)
		)
		(duplicate_pad_numbers_are_jumpers no)
		(fp_line
			(start -0.4826 0)
			(end -0.2032 0)
			(stroke
				(width 0.2032)
				(type default)
			)
			(layer "F.SilkS")
		)
		(fp_line
			(start 0.2032 0)
			(end 0.4826 0)
			(stroke
				(width 0.2032)
				(type default)
			)
			(layer "F.SilkS")
		)
		(fp_rect
			(start -0.5842 1.3335)
			(end 0.5842 -1.3335)
			(stroke
				(width 0)
				(type default)
			)
			(fill no)
			(layer "F.CrtYd")
		)
		(fp_rect
			(start -0.5842 1.3335)
			(end 0.5842 -1.3335)
			(stroke
				(width 0)
				(type default)
			)
			(fill no)
			(layer "F.Fab")
		)
		(pad "1" smd custom
			(at 0 -0.762 270)
			(size 0.2159 0.2159)
			(layers "F.Cu" "F.Mask" "F.Paste")
			(net "HDD_PRSNT_10")
			(options
				(clearance outline)
				(anchor circle)
			)
			(primitives
				(gr_poly
					(pts
						(arc
							(start -0.3302 -0.4318)
							(mid -0.402042 -0.402042)
							(end -0.4318 -0.3302)
						)
						(arc
							(start -0.4318 0.3302)
							(mid -0.402042 0.402042)
							(end -0.3302 0.4318)
						)
						(arc
							(start 0.3302 0.4318)
							(mid 0.402042 0.402042)
							(end 0.4318 0.3302)
						)
						(arc
							(start 0.4318 -0.3302)
							(mid 0.402042 -0.402042)
							(end 0.3302 -0.4318)
						)
					)
					(width 0)
					(fill yes)
				)
			)
		)
		(pad "2" smd custom
			(at 0 0.762 270)
			(size 0.2159 0.2159)
			(layers "F.Cu" "F.Mask" "F.Paste")
			(net "DRIVE_A_10_INS")
			(options
				(clearance outline)
				(anchor circle)
			)
			(primitives
				(gr_poly
					(pts
						(arc
							(start -0.3302 -0.4318)
							(mid -0.402042 -0.402042)
							(end -0.4318 -0.3302)
						)
						(arc
							(start -0.4318 0.3302)
							(mid -0.402042 0.402042)
							(end -0.3302 0.4318)
						)
						(arc
							(start 0.3302 0.4318)
							(mid 0.402042 0.402042)
							(end 0.4318 0.3302)
						)
						(arc
							(start 0.4318 -0.3302)
							(mid 0.402042 -0.402042)
							(end 0.3302 -0.4318)
						)
					)
					(width 0)
					(fill yes)
				)
			)
		)
	)
	(footprint ""
		(layer "F.Cu")
		(at 469.942926 -59.857894)
		(property "Reference" "Q212"
			(at 0 0 0)
			(layer "F.SilkS")
			(hide yes)
			(effects
				(font
					(size 1.27 1.27)
				)
			)
		)
		(property "Value" "AO4407AL-GP"
			(at -3.707384 -1.5367 0)
			(unlocked yes)
			(layer "F.Fab")
			(hide yes)
			(effects
				(font
					(size 1.016 1.016)
					(thickness 0.1524)
				)
			)
		)
		(property "Device Type" "SOIC8H69"
			(at -3.707384 -3.0607 0)
			(unlocked yes)
			(layer "F.Fab")
			(hide yes)
			(effects
				(font
					(size 1.016 1.016)
					(thickness 0.1524)
				)
			)
		)
		(duplicate_pad_numbers_are_jumpers no)
		(fp_line
			(start -2.7432 -1.4224)
			(end -2.7432 1.4224)
			(stroke
				(width 0.1524)
				(type default)
			)
			(layer "F.SilkS")
		)
		(fp_line
			(start -2.7432 1.4224)
			(end -2.6416 1.4224)
			(stroke
				(width 0.1524)
				(type default)
			)
			(layer "F.SilkS")
		)
		(fp_line
			(start -2.7432 1.4224)
			(end 2.1336 1.4224)
			(stroke
				(width 0.1524)
				(type default)
			)
			(layer "F.SilkS")
		)
		(fp_line
			(start -2.7178 -0.508)
			(end -2.1844 -0.0508)
			(stroke
				(width 0.1524)
				(type default)
			)
			(layer "F.SilkS")
		)
		(fp_line
			(start -2.6289 3.4417)
			(end -2.6289 1.4732)
			(stroke
				(width 0.381)
				(type default)
			)
			(layer "F.SilkS")
		)
		(fp_line
			(start -2.1844 -0.0508)
			(end -2.7178 0.508)
			(stroke
				(width 0.1524)
				(type default)
			)
			(layer "F.SilkS")
		)
		(fp_line
			(start 2.1336 -1.4224)
			(end -2.7432 -1.4224)
			(stroke
				(width 0.1524)
				(type default)
			)
			(layer "F.SilkS")
		)
		(fp_line
			(start 2.1336 1.4224)
			(end 2.1336 -1.4224)
			(stroke
				(width 0.1524)
				(type default)
			)
			(layer "F.SilkS")
		)
		(fp_poly
			(pts
				(xy -2.2098 -1.4224) (xy -2.2098 1.4224) (xy 2.2098 1.4224) (xy 2.2098 -1.4224)
			)
			(stroke
				(width 0)
				(type default)
			)
			(fill yes)
			(layer "F.SilkS")
		)
		(fp_rect
			(start -2.450084 2.999994)
			(end 2.450084 -2.999994)
			(stroke
				(width 0)
				(type default)
			)
			(fill no)
			(layer "F.CrtYd")
		)
		(fp_poly
			(pts
				(xy -2.8194 3.6322) (xy -2.8194 -3.6322) (xy 2.8194 -3.6322) (xy 2.8194 1.18364) (xy 2.450084 1.18364)
				(xy 2.450084 -2.999994) (xy -2.450084 -2.999994) (xy -2.450084 2.999994) (xy 2.450084 2.999994)
				(xy 2.450084 1.18618) (xy 2.8194 1.18618) (xy 2.8194 3.6322)
			)
			(stroke
				(width 0)
				(type default)
			)
			(fill no)
			(layer "F.CrtYd")
		)
		(fp_rect
			(start -2.8194 3.6322)
			(end 2.8194 -3.6322)
			(stroke
				(width 0)
				(type default)
			)
			(fill no)
			(layer "F.Fab")
		)
		(pad "1" smd rect
			(at -1.905 2.54)
			(size 0.635 1.651)
			(layers "F.Cu" "F.Mask" "F.Paste")
			(net "P12V_A")
		)
		(pad "2" smd rect
			(at -0.635 2.54)
			(size 0.635 1.651)
			(layers "F.Cu" "F.Mask" "F.Paste")
			(net "P12V_A")
		)
		(pad "3" smd rect
			(at 0.635 2.54)
			(size 0.635 1.651)
			(layers "F.Cu" "F.Mask" "F.Paste")
			(net "P12V_A")
		)
		(pad "4" smd rect
			(at 1.905 2.54)
			(size 0.635 1.651)
			(layers "F.Cu" "F.Mask" "F.Paste")
			(net "SW_HDD_N35")
		)
		(pad "5" smd rect
			(at 1.905 -2.54)
			(size 0.635 1.651)
			(layers "F.Cu" "F.Mask" "F.Paste")
			(net "P12V_HDD35")
		)
		(pad "6" smd rect
			(at 0.635 -2.54)
			(size 0.635 1.651)
			(layers "F.Cu" "F.Mask" "F.Paste")
			(net "P12V_HDD35")
		)
		(pad "7" smd rect
			(at -0.635 -2.54)
			(size 0.635 1.651)
			(layers "F.Cu" "F.Mask" "F.Paste")
			(net "P12V_HDD35")
		)
		(pad "8" smd rect
			(at -1.905 -2.54)
			(size 0.635 1.651)
			(layers "F.Cu" "F.Mask" "F.Paste")
			(net "P12V_HDD35")
		)
	)
	(footprint ""
		(layer "F.Cu")
		(at 14.842998 -283.482542 -90)
		(property "Reference" "R973"
			(at 0 0 270)
			(layer "F.SilkS")
			(hide yes)
			(effects
				(font
					(size 1.27 1.27)
				)
			)
		)
		(property "Value" "300KR2F-GP"
			(at 0.064008 -3.993896 270)
			(unlocked yes)
			(layer "F.Fab")
			(hide yes)
			(effects
				(font
					(size 1.016 1.016)
					(thickness 0.1524)
				)
			)
		)
		(property "Device Type" "R402H16"
			(at 0.064008 -5.517896 270)
			(unlocked yes)
			(layer "F.Fab")
			(hide yes)
			(effects
				(font
					(size 1.016 1.016)
					(thickness 0.1524)
				)
			)
		)
		(duplicate_pad_numbers_are_jumpers no)
		(fp_line
			(start -0.508 -0.9398)
			(end -0.508 0.9398)
			(stroke
				(width 0.1524)
				(type default)
			)
			(layer "F.SilkS")
		)
		(fp_line
			(start 0.508 -0.9398)
			(end -0.508 -0.9398)
			(stroke
				(width 0.1524)
				(type default)
			)
			(layer "F.SilkS")
		)
		(fp_rect
			(start -0.508 0.9398)
			(end 0.508 -0.9398)
			(stroke
				(width 0)
				(type default)
			)
			(fill no)
			(layer "F.CrtYd")
		)
		(fp_rect
			(start -0.508 0.9398)
			(end 0.508 -0.9398)
			(stroke
				(width 0)
				(type default)
			)
			(fill no)
			(layer "F.Fab")
		)
		(pad "1" smd custom
			(at 0 -0.4445 270)
			(size 0.1397 0.1397)
			(layers "F.Cu" "F.Mask" "F.Paste")
			(net "SW_HDD_N0")
			(options
				(clearance outline)
				(anchor circle)
			)
			(primitives
				(gr_poly
					(pts
						(arc
							(start -0.1778 -0.2794)
							(mid -0.249642 -0.249642)
							(end -0.2794 -0.1778)
						)
						(arc
							(start -0.2794 0.1778)
							(mid -0.249642 0.249642)
							(end -0.1778 0.2794)
						)
						(arc
							(start 0.1778 0.2794)
							(mid 0.249642 0.249642)
							(end 0.2794 0.1778)
						)
						(arc
							(start 0.2794 -0.1778)
							(mid 0.249642 -0.249642)
							(end 0.1778 -0.2794)
						)
					)
					(width 0)
					(fill yes)
				)
			)
		)
		(pad "2" smd custom
			(at 0 0.4445 270)
			(size 0.1397 0.1397)
			(layers "F.Cu" "F.Mask" "F.Paste")
			(net "P12V_A")
			(options
				(clearance outline)
				(anchor circle)
			)
			(primitives
				(gr_poly
					(pts
						(arc
							(start -0.1778 -0.2794)
							(mid -0.249642 -0.249642)
							(end -0.2794 -0.1778)
						)
						(arc
							(start -0.2794 0.1778)
							(mid -0.249642 0.249642)
							(end -0.1778 0.2794)
						)
						(arc
							(start 0.1778 0.2794)
							(mid 0.249642 0.249642)
							(end 0.2794 0.1778)
						)
						(arc
							(start 0.2794 -0.1778)
							(mid 0.249642 -0.249642)
							(end 0.1778 -0.2794)
						)
					)
					(width 0)
					(fill yes)
				)
			)
		)
	)
	(footprint ""
		(layer "F.Cu")
		(at 69.60997 -298.219368)
		(property "Reference" "Q289"
			(at 0 0 0)
			(layer "F.SilkS")
			(hide yes)
			(effects
				(font
					(size 1.27 1.27)
				)
			)
		)
		(property "Value" "SSM3K324R-GP"
			(at 0.127 -8.9662 0)
			(unlocked yes)
			(layer "F.Fab")
			(hide yes)
			(effects
				(font
					(size 1.016 1.016)
					(thickness 0.1524)
				)
			)
		)
		(property "Device Type" "SOT23DGS2D4H35"
			(at 0.127 -10.4902 0)
			(unlocked yes)
			(layer "F.Fab")
			(hide yes)
			(effects
				(font
					(size 1.016 1.016)
					(thickness 0.1524)
				)
			)
		)
		(duplicate_pad_numbers_are_jumpers no)
		(fp_line
			(start -1.651 -1.778)
			(end -1.651 1.778)
			(stroke
				(width 0.1524)
				(type default)
			)
			(layer "F.SilkS")
		)
		(fp_line
			(start -1.651 1.778)
			(end 1.651 1.778)
			(stroke
				(width 0.1524)
				(type default)
			)
			(layer "F.SilkS")
		)
		(fp_line
			(start 1.651 -1.778)
			(end -1.651 -1.778)
			(stroke
				(width 0.1524)
				(type default)
			)
			(layer "F.SilkS")
		)
		(fp_line
			(start 1.651 1.778)
			(end 1.651 -1.778)
			(stroke
				(width 0.1524)
				(type default)
			)
			(layer "F.SilkS")
		)
		(fp_poly
			(pts
				(xy -1.778 1.8796) (xy -1.778 -1.8796) (xy 1.778 -1.8796) (xy 1.778 1.8796)
			)
			(stroke
				(width 0)
				(type default)
			)
			(fill no)
			(layer "F.CrtYd")
		)
		(fp_poly
			(pts
				(xy -1.778 1.8796) (xy -1.778 -1.8796) (xy 1.778 -1.8796) (xy 1.778 1.8796)
			)
			(stroke
				(width 0)
				(type default)
			)
			(fill no)
			(layer "F.Fab")
		)
		(pad "D" smd custom
			(at 0 -0.9525)
			(size 0.1905 0.1905)
			(layers "F.Cu" "F.Mask" "F.Paste")
			(net "DRV_ACT_26_N")
			(options
				(clearance outline)
				(anchor circle)
			)
			(primitives
				(gr_poly
					(pts
						(arc
							(start -0.1778 0.5715)
							(mid -0.321484 0.511984)
							(end -0.381 0.3683)
						)
						(arc
							(start -0.381 -0.3683)
							(mid -0.321484 -0.511984)
							(end -0.1778 -0.5715)
						)
						(arc
							(start 0.1778 -0.5715)
							(mid 0.321484 -0.511984)
							(end 0.381 -0.3683)
						)
						(arc
							(start 0.381 0.3683)
							(mid 0.321484 0.511984)
							(end 0.1778 0.5715)
						)
					)
					(width 0)
					(fill yes)
				)
			)
		)
		(pad "G" smd custom
			(at -0.98425 0.9525)
			(size 0.1905 0.1905)
			(layers "F.Cu" "F.Mask" "F.Paste")
			(net "DRIVE_B_26_ACT")
			(options
				(clearance outline)
				(anchor circle)
			)
			(primitives
				(gr_poly
					(pts
						(arc
							(start -0.1778 0.5715)
							(mid -0.321484 0.511984)
							(end -0.381 0.3683)
						)
						(arc
							(start -0.381 -0.3683)
							(mid -0.321484 -0.511984)
							(end -0.1778 -0.5715)
						)
						(arc
							(start 0.1778 -0.5715)
							(mid 0.321484 -0.511984)
							(end 0.381 -0.3683)
						)
						(arc
							(start 0.381 0.3683)
							(mid 0.321484 0.511984)
							(end 0.1778 0.5715)
						)
					)
					(width 0)
					(fill yes)
				)
			)
		)
		(pad "S" smd custom
			(at 0.98425 0.9525)
			(size 0.1905 0.1905)
			(layers "F.Cu" "F.Mask" "F.Paste")
			(net "GND")
			(options
				(clearance outline)
				(anchor circle)
			)
			(primitives
				(gr_poly
					(pts
						(arc
							(start -0.1778 0.5715)
							(mid -0.321484 0.511984)
							(end -0.381 0.3683)
						)
						(arc
							(start -0.381 -0.3683)
							(mid -0.321484 -0.511984)
							(end -0.1778 -0.5715)
						)
						(arc
							(start 0.1778 -0.5715)
							(mid 0.321484 -0.511984)
							(end 0.381 -0.3683)
						)
						(arc
							(start 0.381 0.3683)
							(mid 0.321484 0.511984)
							(end 0.1778 0.5715)
						)
					)
					(width 0)
					(fill yes)
				)
			)
		)
	)
	(footprint ""
		(layer "F.Cu")
		(at 35.271202 -255.42875 -90)
		(property "Reference" "R1207"
			(at 0 0 270)
			(layer "F.SilkS")
			(hide yes)
			(effects
				(font
					(size 1.27 1.27)
				)
			)
		)
		(property "Value" "0R2J-2-GP"
			(at 0.064008 -3.993896 270)
			(unlocked yes)
			(layer "F.Fab")
			(hide yes)
			(effects
				(font
					(size 1.016 1.016)
					(thickness 0.1524)
				)
			)
		)
		(property "Device Type" "R402H16"
			(at 0.064008 -5.517896 270)
			(unlocked yes)
			(layer "F.Fab")
			(hide yes)
			(effects
				(font
					(size 1.016 1.016)
					(thickness 0.1524)
				)
			)
		)
		(duplicate_pad_numbers_are_jumpers no)
		(fp_line
			(start -0.508 -0.9398)
			(end -0.508 0.9398)
			(stroke
				(width 0.1524)
				(type default)
			)
			(layer "F.SilkS")
		)
		(fp_line
			(start 0.508 -0.9398)
			(end -0.508 -0.9398)
			(stroke
				(width 0.1524)
				(type default)
			)
			(layer "F.SilkS")
		)
		(fp_rect
			(start -0.508 0.9398)
			(end 0.508 -0.9398)
			(stroke
				(width 0)
				(type default)
			)
			(fill no)
			(layer "F.CrtYd")
		)
		(fp_rect
			(start -0.508 0.9398)
			(end 0.508 -0.9398)
			(stroke
				(width 0)
				(type default)
			)
			(fill no)
			(layer "F.Fab")
		)
		(pad "1" smd custom
			(at 0 -0.4445 270)
			(size 0.1397 0.1397)
			(layers "F.Cu" "F.Mask" "F.Paste")
			(net "P12V_A_PGOOD")
			(options
				(clearance outline)
				(anchor circle)
			)
			(primitives
				(gr_poly
					(pts
						(arc
							(start -0.1778 -0.2794)
							(mid -0.249642 -0.249642)
							(end -0.2794 -0.1778)
						)
						(arc
							(start -0.2794 0.1778)
							(mid -0.249642 0.249642)
							(end -0.1778 0.2794)
						)
						(arc
							(start 0.1778 0.2794)
							(mid 0.249642 0.249642)
							(end 0.2794 0.1778)
						)
						(arc
							(start 0.2794 -0.1778)
							(mid 0.249642 -0.249642)
							(end 0.1778 -0.2794)
						)
					)
					(width 0)
					(fill yes)
				)
			)
		)
		(pad "2" smd custom
			(at 0 0.4445 270)
			(size 0.1397 0.1397)
			(layers "F.Cu" "F.Mask" "F.Paste")
			(net "P5V_A_EN_R")
			(options
				(clearance outline)
				(anchor circle)
			)
			(primitives
				(gr_poly
					(pts
						(arc
							(start -0.1778 -0.2794)
							(mid -0.249642 -0.249642)
							(end -0.2794 -0.1778)
						)
						(arc
							(start -0.2794 0.1778)
							(mid -0.249642 0.249642)
							(end -0.1778 0.2794)
						)
						(arc
							(start 0.1778 0.2794)
							(mid 0.249642 0.249642)
							(end 0.2794 0.1778)
						)
						(arc
							(start 0.2794 -0.1778)
							(mid 0.249642 -0.249642)
							(end 0.1778 -0.2794)
						)
					)
					(width 0)
					(fill yes)
				)
			)
		)
	)
	(footprint ""
		(layer "F.Cu")
		(at 127.113284 -44.219368 90)
		(property "Reference" "C389"
			(at 0 0 90)
			(layer "F.SilkS")
			(hide yes)
			(effects
				(font
					(size 1.27 1.27)
				)
			)
		)
		(property "Value" "SCD01U16V1KX-GP"
			(at -2.8321 -1.7399 90)
			(unlocked yes)
			(layer "F.Fab")
			(hide yes)
			(effects
				(font
					(size 1.016 1.016)
					(thickness 0.1524)
				)
			)
		)
		(property "Device Type" "C0201H13"
			(at -2.8321 -3.2639 90)
			(unlocked yes)
			(layer "F.Fab")
			(hide yes)
			(effects
				(font
					(size 1.016 1.016)
					(thickness 0.1524)
				)
			)
		)
		(duplicate_pad_numbers_are_jumpers no)
		(fp_rect
			(start -0.2794 0.6477)
			(end 0.2794 -0.6477)
			(stroke
				(width 0)
				(type default)
			)
			(fill no)
			(layer "F.CrtYd")
		)
		(fp_rect
			(start -0.2794 0.6477)
			(end 0.2794 -0.6477)
			(stroke
				(width 0)
				(type default)
			)
			(fill no)
			(layer "F.Fab")
		)
		(pad "1" smd custom
			(at 0 -0.2794 90)
			(size 0.0762 0.0762)
			(layers "F.Cu" "F.Mask" "F.Paste")
			(net "SAS_HDD_RX_N27")
			(options
				(clearance outline)
				(anchor circle)
			)
			(primitives
				(gr_poly
					(pts
						(arc
							(start 0.1524 -0.127)
							(mid 0.137521 -0.162921)
							(end 0.1016 -0.1778)
						)
						(arc
							(start -0.1016 -0.1778)
							(mid -0.137521 -0.162921)
							(end -0.1524 -0.127)
						)
						(arc
							(start -0.1524 0.127)
							(mid -0.137521 0.162921)
							(end -0.1016 0.1778)
						)
						(arc
							(start 0.1016 0.1778)
							(mid 0.137521 0.162921)
							(end 0.1524 0.127)
						)
					)
					(width 0)
					(fill yes)
				)
			)
		)
		(pad "2" smd custom
			(at 0 0.2794 90)
			(size 0.0762 0.0762)
			(layers "F.Cu" "F.Mask" "F.Paste")
			(net "PHY_SCC_A_TO_DRV_A_27_DN")
			(options
				(clearance outline)
				(anchor circle)
			)
			(primitives
				(gr_poly
					(pts
						(arc
							(start 0.1524 -0.127)
							(mid 0.137521 -0.162921)
							(end 0.1016 -0.1778)
						)
						(arc
							(start -0.1016 -0.1778)
							(mid -0.137521 -0.162921)
							(end -0.1524 -0.127)
						)
						(arc
							(start -0.1524 0.127)
							(mid -0.137521 0.162921)
							(end -0.1016 0.1778)
						)
						(arc
							(start 0.1016 0.1778)
							(mid 0.137521 0.162921)
							(end 0.1524 0.127)
						)
					)
					(width 0)
					(fill yes)
				)
			)
		)
	)
	(footprint ""
		(layer "F.Cu")
		(at 30.14853 -253.763018 90)
		(property "Reference" "R1215"
			(at 0 0 90)
			(layer "F.SilkS")
			(hide yes)
			(effects
				(font
					(size 1.27 1.27)
				)
			)
		)
		(property "Value" "100KR2F-L1-GP"
			(at 0.064008 -3.993896 90)
			(unlocked yes)
			(layer "F.Fab")
			(hide yes)
			(effects
				(font
					(size 1.016 1.016)
					(thickness 0.1524)
				)
			)
		)
		(property "Device Type" "R402H16"
			(at 0.064008 -5.517896 90)
			(unlocked yes)
			(layer "F.Fab")
			(hide yes)
			(effects
				(font
					(size 1.016 1.016)
					(thickness 0.1524)
				)
			)
		)
		(duplicate_pad_numbers_are_jumpers no)
		(fp_line
			(start 0.508 -0.9398)
			(end -0.508 -0.9398)
			(stroke
				(width 0.1524)
				(type default)
			)
			(layer "F.SilkS")
		)
		(fp_line
			(start -0.508 -0.9398)
			(end -0.508 0.9398)
			(stroke
				(width 0.1524)
				(type default)
			)
			(layer "F.SilkS")
		)
		(fp_rect
			(start -0.508 0.9398)
			(end 0.508 -0.9398)
			(stroke
				(width 0)
				(type default)
			)
			(fill no)
			(layer "F.CrtYd")
		)
		(fp_rect
			(start -0.508 0.9398)
			(end 0.508 -0.9398)
			(stroke
				(width 0)
				(type default)
			)
			(fill no)
			(layer "F.Fab")
		)
		(pad "1" smd custom
			(at 0 -0.4445 90)
			(size 0.1397 0.1397)
			(layers "F.Cu" "F.Mask" "F.Paste")
			(net "AGND_P5V_A")
			(options
				(clearance outline)
				(anchor circle)
			)
			(primitives
				(gr_poly
					(pts
						(arc
							(start -0.1778 -0.2794)
							(mid -0.249642 -0.249642)
							(end -0.2794 -0.1778)
						)
						(arc
							(start -0.2794 0.1778)
							(mid -0.249642 0.249642)
							(end -0.1778 0.2794)
						)
						(arc
							(start 0.1778 0.2794)
							(mid 0.249642 0.249642)
							(end 0.2794 0.1778)
						)
						(arc
							(start 0.2794 -0.1778)
							(mid 0.249642 -0.249642)
							(end 0.1778 -0.2794)
						)
					)
					(width 0)
					(fill yes)
				)
			)
		)
		(pad "2" smd custom
			(at 0 0.4445 90)
			(size 0.1397 0.1397)
			(layers "F.Cu" "F.Mask" "F.Paste")
			(net "P5V_A_MODE")
			(options
				(clearance outline)
				(anchor circle)
			)
			(primitives
				(gr_poly
					(pts
						(arc
							(start -0.1778 -0.2794)
							(mid -0.249642 -0.249642)
							(end -0.2794 -0.1778)
						)
						(arc
							(start -0.2794 0.1778)
							(mid -0.249642 0.249642)
							(end -0.1778 0.2794)
						)
						(arc
							(start 0.1778 0.2794)
							(mid 0.249642 0.249642)
							(end 0.2794 0.1778)
						)
						(arc
							(start 0.2794 -0.1778)
							(mid 0.249642 -0.249642)
							(end 0.1778 -0.2794)
						)
					)
					(width 0)
					(fill yes)
				)
			)
		)
	)
	(footprint ""
		(layer "F.Cu")
		(at 190.5 -173.1772 90)
		(property "Reference" "C267"
			(at 0 0 90)
			(layer "F.SilkS")
			(hide yes)
			(effects
				(font
					(size 1.27 1.27)
				)
			)
		)
		(property "Value" "SCD01U50V2KX-1GP"
			(at 1.1811 -2.7051 90)
			(unlocked yes)
			(layer "F.Fab")
			(hide yes)
			(effects
				(font
					(size 1.016 1.016)
					(thickness 0.1524)
				)
			)
		)
		(property "Device Type" "C402H22"
			(at 1.1811 -4.2291 90)
			(unlocked yes)
			(layer "F.Fab")
			(hide yes)
			(effects
				(font
					(size 1.016 1.016)
					(thickness 0.1524)
				)
			)
		)
		(duplicate_pad_numbers_are_jumpers no)
		(fp_rect
			(start -0.4318 0.9525)
			(end 0.4318 -0.9525)
			(stroke
				(width 0)
				(type default)
			)
			(fill no)
			(layer "F.CrtYd")
		)
		(fp_rect
			(start -0.4318 0.9525)
			(end 0.4318 -0.9525)
			(stroke
				(width 0)
				(type default)
			)
			(fill no)
			(layer "F.Fab")
		)
		(pad "1" smd custom
			(at 0 -0.4445 90)
			(size 0.1524 0.1524)
			(layers "F.Cu" "F.Mask" "F.Paste")
			(net "HDD_PRSNT_17")
			(options
				(clearance outline)
				(anchor circle)
			)
			(primitives
				(gr_poly
					(pts
						(arc
							(start 0.3048 -0.2032)
							(mid 0.275042 -0.275042)
							(end 0.2032 -0.3048)
						)
						(arc
							(start -0.2032 -0.3048)
							(mid -0.275042 -0.275042)
							(end -0.3048 -0.2032)
						)
						(arc
							(start -0.3048 0.2032)
							(mid -0.275042 0.275042)
							(end -0.2032 0.3048)
						)
						(arc
							(start 0.2032 0.3048)
							(mid 0.275042 0.275042)
							(end 0.3048 0.2032)
						)
					)
					(width 0)
					(fill yes)
				)
			)
		)
		(pad "2" smd custom
			(at 0 0.4445 90)
			(size 0.1524 0.1524)
			(layers "F.Cu" "F.Mask" "F.Paste")
			(net "GND")
			(options
				(clearance outline)
				(anchor circle)
			)
			(primitives
				(gr_poly
					(pts
						(arc
							(start 0.3048 -0.2032)
							(mid 0.275042 -0.275042)
							(end 0.2032 -0.3048)
						)
						(arc
							(start -0.2032 -0.3048)
							(mid -0.275042 -0.275042)
							(end -0.3048 -0.2032)
						)
						(arc
							(start -0.3048 0.2032)
							(mid -0.275042 0.275042)
							(end -0.2032 0.3048)
						)
						(arc
							(start 0.2032 0.3048)
							(mid 0.275042 0.275042)
							(end 0.3048 0.2032)
						)
					)
					(width 0)
					(fill yes)
				)
			)
		)
	)
	(footprint ""
		(layer "F.Cu")
		(at 441.349892 -324.39991)
		(property "Reference" "RLED35"
			(at 0 0 0)
			(layer "F.SilkS")
			(hide yes)
			(effects
				(font
					(size 1.27 1.27)
				)
			)
		)
		(property "Value" "LED-BY-19-GP"
			(at -2.132076 1.414018 0)
			(unlocked yes)
			(layer "F.Fab")
			(hide yes)
			(effects
				(font
					(size 1.016 1.016)
					(thickness 0.1524)
				)
			)
		)
		(property "Device Type" "LED-1615-4PH26"
			(at -2.132076 -0.109982 0)
			(unlocked yes)
			(layer "F.Fab")
			(hide yes)
			(effects
				(font
					(size 1.016 1.016)
					(thickness 0.1524)
				)
			)
		)
		(duplicate_pad_numbers_are_jumpers no)
		(fp_line
			(start -1.2954 0.254)
			(end -1.2954 1.6002)
			(stroke
				(width 0.508)
				(type default)
			)
			(layer "F.SilkS")
		)
		(fp_line
			(start -1.2954 1.6002)
			(end 1.2954 1.6002)
			(stroke
				(width 0.508)
				(type default)
			)
			(layer "F.SilkS")
		)
		(fp_line
			(start -1.1176 -1.4224)
			(end 1.1176 -1.4224)
			(stroke
				(width 0.1524)
				(type default)
			)
			(layer "F.SilkS")
		)
		(fp_line
			(start -1.1176 1.4224)
			(end -1.1176 -1.4224)
			(stroke
				(width 0.1524)
				(type default)
			)
			(layer "F.SilkS")
		)
		(fp_line
			(start 1.1176 -1.4224)
			(end 1.1176 1.4224)
			(stroke
				(width 0.1524)
				(type default)
			)
			(layer "F.SilkS")
		)
		(fp_line
			(start 1.1176 1.4224)
			(end -1.1176 1.4224)
			(stroke
				(width 0.1524)
				(type default)
			)
			(layer "F.SilkS")
		)
		(fp_line
			(start 1.2954 1.6002)
			(end 1.2954 0.254)
			(stroke
				(width 0.508)
				(type default)
			)
			(layer "F.SilkS")
		)
		(fp_rect
			(start -0.7493 0.8001)
			(end 0.7493 -0.8001)
			(stroke
				(width 0)
				(type default)
			)
			(fill no)
			(layer "F.CrtYd")
		)
		(fp_poly
			(pts
				(xy -1.3716 1.6764) (xy -1.3716 -1.6764) (xy 1.3716 -1.6764) (xy 1.3716 0.0635) (xy 0.7493 0.0635)
				(xy 0.7493 -0.8001) (xy -0.7493 -0.8001) (xy -0.7493 0.8001) (xy 0.7493 0.8001) (xy 0.7493 0.0762)
				(xy 1.3716 0.0762) (xy 1.3716 1.6764)
			)
			(stroke
				(width 0)
				(type default)
			)
			(fill no)
			(layer "F.CrtYd")
		)
		(fp_rect
			(start -1.3716 1.6764)
			(end 1.3716 -1.6764)
			(stroke
				(width 0)
				(type default)
			)
			(fill no)
			(layer "F.Fab")
		)
		(pad "1" smd rect
			(at 0.50038 -0.73025)
			(size 0.7112 0.8636)
			(layers "F.Cu" "F.Mask" "F.Paste")
			(net "DRV_ACT_34")
		)
		(pad "2" smd rect
			(at -0.50038 -0.73025)
			(size 0.7112 0.8636)
			(layers "F.Cu" "F.Mask" "F.Paste")
			(net "FLT_HDD34")
		)
		(pad "3" smd rect
			(at 0.50038 0.73025)
			(size 0.7112 0.8636)
			(layers "F.Cu" "F.Mask" "F.Paste")
			(net "DRV_ACT_34_N")
		)
		(pad "4" smd rect
			(at -0.50038 0.73025)
			(size 0.7112 0.8636)
			(layers "F.Cu" "F.Mask" "F.Paste")
			(net "FLT_HDD34_N")
		)
	)
	(footprint ""
		(layer "F.Cu")
		(at 416.284664 -273.660616 -90)
		(property "Reference" "C156"
			(at 0 0 270)
			(layer "F.SilkS")
			(hide yes)
			(effects
				(font
					(size 1.27 1.27)
				)
			)
		)
		(property "Value" "SCD01U16V1KX-GP"
			(at -2.8321 -1.7399 270)
			(unlocked yes)
			(layer "F.Fab")
			(hide yes)
			(effects
				(font
					(size 1.016 1.016)
					(thickness 0.1524)
				)
			)
		)
		(property "Device Type" "C0201H13"
			(at -2.8321 -3.2639 270)
			(unlocked yes)
			(layer "F.Fab")
			(hide yes)
			(effects
				(font
					(size 1.016 1.016)
					(thickness 0.1524)
				)
			)
		)
		(duplicate_pad_numbers_are_jumpers no)
		(fp_rect
			(start -0.2794 0.6477)
			(end 0.2794 -0.6477)
			(stroke
				(width 0)
				(type default)
			)
			(fill no)
			(layer "F.CrtYd")
		)
		(fp_rect
			(start -0.2794 0.6477)
			(end 0.2794 -0.6477)
			(stroke
				(width 0)
				(type default)
			)
			(fill no)
			(layer "F.Fab")
		)
		(pad "1" smd custom
			(at 0 -0.2794 270)
			(size 0.0762 0.0762)
			(layers "F.Cu" "F.Mask" "F.Paste")
			(net "SAS_HDD_RX_P9")
			(options
				(clearance outline)
				(anchor circle)
			)
			(primitives
				(gr_poly
					(pts
						(arc
							(start 0.1524 -0.127)
							(mid 0.137521 -0.162921)
							(end 0.1016 -0.1778)
						)
						(arc
							(start -0.1016 -0.1778)
							(mid -0.137521 -0.162921)
							(end -0.1524 -0.127)
						)
						(arc
							(start -0.1524 0.127)
							(mid -0.137521 0.162921)
							(end -0.1016 0.1778)
						)
						(arc
							(start 0.1016 0.1778)
							(mid 0.137521 0.162921)
							(end 0.1524 0.127)
						)
					)
					(width 0)
					(fill yes)
				)
			)
		)
		(pad "2" smd custom
			(at 0 0.2794 270)
			(size 0.0762 0.0762)
			(layers "F.Cu" "F.Mask" "F.Paste")
			(net "PHY_SCC_A_TO_DRV_A_9_DP")
			(options
				(clearance outline)
				(anchor circle)
			)
			(primitives
				(gr_poly
					(pts
						(arc
							(start 0.1524 -0.127)
							(mid 0.137521 -0.162921)
							(end 0.1016 -0.1778)
						)
						(arc
							(start -0.1016 -0.1778)
							(mid -0.137521 -0.162921)
							(end -0.1524 -0.127)
						)
						(arc
							(start -0.1524 0.127)
							(mid -0.137521 0.162921)
							(end -0.1016 0.1778)
						)
						(arc
							(start 0.1016 0.1778)
							(mid 0.137521 0.162921)
							(end 0.1524 0.127)
						)
					)
					(width 0)
					(fill yes)
				)
			)
		)
	)
	(footprint ""
		(layer "F.Cu")
		(at 155.803854 -28.531566 -90)
		(property "Reference" "R378"
			(at 0 0 270)
			(layer "F.SilkS")
			(hide yes)
			(effects
				(font
					(size 1.27 1.27)
				)
			)
		)
		(property "Value" "100KR2F-L1-GP"
			(at 0.064008 -3.993896 270)
			(unlocked yes)
			(layer "F.Fab")
			(hide yes)
			(effects
				(font
					(size 1.016 1.016)
					(thickness 0.1524)
				)
			)
		)
		(property "Device Type" "R402H16"
			(at 0.064008 -5.517896 270)
			(unlocked yes)
			(layer "F.Fab")
			(hide yes)
			(effects
				(font
					(size 1.016 1.016)
					(thickness 0.1524)
				)
			)
		)
		(duplicate_pad_numbers_are_jumpers no)
		(fp_line
			(start -0.508 -0.9398)
			(end -0.508 0.9398)
			(stroke
				(width 0.1524)
				(type default)
			)
			(layer "F.SilkS")
		)
		(fp_line
			(start 0.508 -0.9398)
			(end -0.508 -0.9398)
			(stroke
				(width 0.1524)
				(type default)
			)
			(layer "F.SilkS")
		)
		(fp_rect
			(start -0.508 0.9398)
			(end 0.508 -0.9398)
			(stroke
				(width 0)
				(type default)
			)
			(fill no)
			(layer "F.CrtYd")
		)
		(fp_rect
			(start -0.508 0.9398)
			(end 0.508 -0.9398)
			(stroke
				(width 0)
				(type default)
			)
			(fill no)
			(layer "F.Fab")
		)
		(pad "1" smd custom
			(at 0 -0.4445 270)
			(size 0.1397 0.1397)
			(layers "F.Cu" "F.Mask" "F.Paste")
			(net "P3V3_STBY_A")
			(options
				(clearance outline)
				(anchor circle)
			)
			(primitives
				(gr_poly
					(pts
						(arc
							(start -0.1778 -0.2794)
							(mid -0.249642 -0.249642)
							(end -0.2794 -0.1778)
						)
						(arc
							(start -0.2794 0.1778)
							(mid -0.249642 0.249642)
							(end -0.1778 0.2794)
						)
						(arc
							(start 0.1778 0.2794)
							(mid 0.249642 0.249642)
							(end 0.2794 0.1778)
						)
						(arc
							(start 0.2794 -0.1778)
							(mid 0.249642 -0.249642)
							(end 0.1778 -0.2794)
						)
					)
					(width 0)
					(fill yes)
				)
			)
		)
		(pad "2" smd custom
			(at 0 0.4445 270)
			(size 0.1397 0.1397)
			(layers "F.Cu" "F.Mask" "F.Paste")
			(net "IOM_A_INS_N")
			(options
				(clearance outline)
				(anchor circle)
			)
			(primitives
				(gr_poly
					(pts
						(arc
							(start -0.1778 -0.2794)
							(mid -0.249642 -0.249642)
							(end -0.2794 -0.1778)
						)
						(arc
							(start -0.2794 0.1778)
							(mid -0.249642 0.249642)
							(end -0.1778 0.2794)
						)
						(arc
							(start 0.1778 0.2794)
							(mid 0.249642 0.249642)
							(end 0.2794 0.1778)
						)
						(arc
							(start 0.2794 -0.1778)
							(mid 0.249642 -0.249642)
							(end 0.1778 -0.2794)
						)
					)
					(width 0)
					(fill yes)
				)
			)
		)
	)
	(footprint ""
		(layer "F.Cu")
		(at 86.832948 -292.270942)
		(property "Reference" "R175"
			(at 0 0 0)
			(layer "F.SilkS")
			(hide yes)
			(effects
				(font
					(size 1.27 1.27)
				)
			)
		)
		(property "Value" "2R6F-GP"
			(at -0.0508 -4.8514 0)
			(unlocked yes)
			(layer "F.Fab")
			(hide yes)
			(effects
				(font
					(size 1.016 1.016)
					(thickness 0.1524)
				)
			)
		)
		(property "Device Type" "R1206H26"
			(at 0 -6.3754 0)
			(unlocked yes)
			(layer "F.Fab")
			(hide yes)
			(effects
				(font
					(size 1.016 1.016)
					(thickness 0.1524)
				)
			)
		)
		(duplicate_pad_numbers_are_jumpers no)
		(fp_line
			(start -1.016 -2.2352)
			(end 1.016 -2.2352)
			(stroke
				(width 0.1524)
				(type default)
			)
			(layer "F.SilkS")
		)
		(fp_line
			(start -1.016 2.2352)
			(end -1.016 -2.2352)
			(stroke
				(width 0.1524)
				(type default)
			)
			(layer "F.SilkS")
		)
		(fp_line
			(start 1.016 -2.2352)
			(end 1.016 2.2352)
			(stroke
				(width 0.1524)
				(type default)
			)
			(layer "F.SilkS")
		)
		(fp_line
			(start 1.016 2.2352)
			(end -1.016 2.2352)
			(stroke
				(width 0.1524)
				(type default)
			)
			(layer "F.SilkS")
		)
		(fp_rect
			(start -1.0922 2.3114)
			(end 1.0922 -2.3114)
			(stroke
				(width 0)
				(type default)
			)
			(fill no)
			(layer "F.CrtYd")
		)
		(fp_poly
			(pts
				(xy -1.0922 -2.3114) (xy 1.0922 -2.3114) (xy 1.0922 2.3114) (xy -1.0922 2.3114)
			)
			(stroke
				(width 0)
				(type default)
			)
			(fill no)
			(layer "F.Fab")
		)
		(pad "1" smd rect
			(at 0 -1.397)
			(size 1.651 1.27)
			(layers "F.Cu" "F.Mask" "F.Paste")
			(net "P5V_HDD2")
		)
		(pad "2" smd rect
			(at 0 1.397)
			(size 1.651 1.27)
			(layers "F.Cu" "F.Mask" "F.Paste")
			(net "5V_PRE_2")
		)
	)
	(footprint ""
		(layer "F.Cu")
		(at 464.9089 -171.809918 -90)
		(property "Reference" "R651"
			(at 0 0 270)
			(layer "F.SilkS")
			(hide yes)
			(effects
				(font
					(size 1.27 1.27)
				)
			)
		)
		(property "Value" "300KR2F-GP"
			(at 0.064008 -3.993896 270)
			(unlocked yes)
			(layer "F.Fab")
			(hide yes)
			(effects
				(font
					(size 1.016 1.016)
					(thickness 0.1524)
				)
			)
		)
		(property "Device Type" "R402H16"
			(at 0.064008 -5.517896 270)
			(unlocked yes)
			(layer "F.Fab")
			(hide yes)
			(effects
				(font
					(size 1.016 1.016)
					(thickness 0.1524)
				)
			)
		)
		(duplicate_pad_numbers_are_jumpers no)
		(fp_line
			(start -0.508 -0.9398)
			(end -0.508 0.9398)
			(stroke
				(width 0.1524)
				(type default)
			)
			(layer "F.SilkS")
		)
		(fp_line
			(start 0.508 -0.9398)
			(end -0.508 -0.9398)
			(stroke
				(width 0.1524)
				(type default)
			)
			(layer "F.SilkS")
		)
		(fp_rect
			(start -0.508 0.9398)
			(end 0.508 -0.9398)
			(stroke
				(width 0)
				(type default)
			)
			(fill no)
			(layer "F.CrtYd")
		)
		(fp_rect
			(start -0.508 0.9398)
			(end 0.508 -0.9398)
			(stroke
				(width 0)
				(type default)
			)
			(fill no)
			(layer "F.Fab")
		)
		(pad "1" smd custom
			(at 0 -0.4445 270)
			(size 0.1397 0.1397)
			(layers "F.Cu" "F.Mask" "F.Paste")
			(net "SW_HDD_N22")
			(options
				(clearance outline)
				(anchor circle)
			)
			(primitives
				(gr_poly
					(pts
						(arc
							(start -0.1778 -0.2794)
							(mid -0.249642 -0.249642)
							(end -0.2794 -0.1778)
						)
						(arc
							(start -0.2794 0.1778)
							(mid -0.249642 0.249642)
							(end -0.1778 0.2794)
						)
						(arc
							(start 0.1778 0.2794)
							(mid 0.249642 0.249642)
							(end 0.2794 0.1778)
						)
						(arc
							(start 0.2794 -0.1778)
							(mid 0.249642 -0.249642)
							(end 0.1778 -0.2794)
						)
					)
					(width 0)
					(fill yes)
				)
			)
		)
		(pad "2" smd custom
			(at 0 0.4445 270)
			(size 0.1397 0.1397)
			(layers "F.Cu" "F.Mask" "F.Paste")
			(net "P12V_A")
			(options
				(clearance outline)
				(anchor circle)
			)
			(primitives
				(gr_poly
					(pts
						(arc
							(start -0.1778 -0.2794)
							(mid -0.249642 -0.249642)
							(end -0.2794 -0.1778)
						)
						(arc
							(start -0.2794 0.1778)
							(mid -0.249642 0.249642)
							(end -0.1778 0.2794)
						)
						(arc
							(start 0.1778 0.2794)
							(mid 0.249642 0.249642)
							(end 0.2794 0.1778)
						)
						(arc
							(start 0.2794 -0.1778)
							(mid 0.249642 -0.249642)
							(end 0.1778 -0.2794)
						)
					)
					(width 0)
					(fill yes)
				)
			)
		)
	)
	(footprint ""
		(layer "F.Cu")
		(at 224.553526 -134.616698 -90)
		(property "Reference" "TP220"
			(at 0 0 270)
			(layer "F.SilkS")
			(hide yes)
			(effects
				(font
					(size 1.27 1.27)
				)
			)
		)
		(property "Value" "TPAD32-GP"
			(at -0.0508 -1.6764 270)
			(unlocked yes)
			(layer "F.Fab")
			(hide yes)
			(effects
				(font
					(size 1.016 1.016)
					(thickness 0.1524)
				)
			)
		)
		(property "Device Type" "TPAD32"
			(at -0.0508 -3.2004 270)
			(unlocked yes)
			(layer "F.Fab")
			(hide yes)
			(effects
				(font
					(size 1.016 1.016)
					(thickness 0.1524)
				)
			)
		)
		(duplicate_pad_numbers_are_jumpers no)
		(fp_poly
			(pts
				(arc
					(start 0 -0.4064)
					(mid 0 0.4064)
					(end 0 -0.4064)
				)
			)
			(stroke
				(width 0)
				(type default)
			)
			(fill no)
			(layer "F.CrtYd")
		)
		(fp_poly
			(pts
				(arc
					(start 0 -0.7112)
					(mid 0 0.7112)
					(end 0 -0.7112)
				)
			)
			(stroke
				(width 0)
				(type default)
			)
			(fill no)
			(layer "F.Fab")
		)
		(pad "1" smd circle
			(at 0 0 270)
			(size 0.8128 0.8128)
			(layers "F.Cu" "F.Mask" "F.Paste")
			(net "TP_PCIE_COMP_A_CLK_1_DN")
		)
	)
	(footprint ""
		(layer "F.Cu")
		(at 345.641676 -293.871396)
		(property "Reference" "Q258"
			(at 0 0 0)
			(layer "F.SilkS")
			(hide yes)
			(effects
				(font
					(size 1.27 1.27)
				)
			)
		)
		(property "Value" "2N7002K-2-GP"
			(at 0.127 -8.9662 0)
			(unlocked yes)
			(layer "F.Fab")
			(hide yes)
			(effects
				(font
					(size 1.016 1.016)
					(thickness 0.1524)
				)
			)
		)
		(property "Device Type" "SOT23DGS2D4H44"
			(at 0.127 -10.4902 0)
			(unlocked yes)
			(layer "F.Fab")
			(hide yes)
			(effects
				(font
					(size 1.016 1.016)
					(thickness 0.1524)
				)
			)
		)
		(duplicate_pad_numbers_are_jumpers no)
		(fp_line
			(start -1.651 -1.778)
			(end -1.651 1.778)
			(stroke
				(width 0.1524)
				(type default)
			)
			(layer "F.SilkS")
		)
		(fp_line
			(start -1.651 1.778)
			(end 1.651 1.778)
			(stroke
				(width 0.1524)
				(type default)
			)
			(layer "F.SilkS")
		)
		(fp_line
			(start 1.651 -1.778)
			(end -1.651 -1.778)
			(stroke
				(width 0.1524)
				(type default)
			)
			(layer "F.SilkS")
		)
		(fp_line
			(start 1.651 1.778)
			(end 1.651 -1.778)
			(stroke
				(width 0.1524)
				(type default)
			)
			(layer "F.SilkS")
		)
		(fp_poly
			(pts
				(xy -1.778 1.8796) (xy -1.778 -1.8796) (xy 1.778 -1.8796) (xy 1.778 1.8796)
			)
			(stroke
				(width 0)
				(type default)
			)
			(fill no)
			(layer "F.CrtYd")
		)
		(fp_poly
			(pts
				(xy -1.778 1.8796) (xy -1.778 -1.8796) (xy 1.778 -1.8796) (xy 1.778 1.8796)
			)
			(stroke
				(width 0)
				(type default)
			)
			(fill no)
			(layer "F.Fab")
		)
		(pad "D" smd custom
			(at 0 -0.9525)
			(size 0.1905 0.1905)
			(layers "F.Cu" "F.Mask" "F.Paste")
			(net "FLT_HDD31_N")
			(options
				(clearance outline)
				(anchor circle)
			)
			(primitives
				(gr_poly
					(pts
						(arc
							(start -0.1778 0.5715)
							(mid -0.321484 0.511984)
							(end -0.381 0.3683)
						)
						(arc
							(start -0.381 -0.3683)
							(mid -0.321484 -0.511984)
							(end -0.1778 -0.5715)
						)
						(arc
							(start 0.1778 -0.5715)
							(mid 0.321484 -0.511984)
							(end 0.381 -0.3683)
						)
						(arc
							(start 0.381 0.3683)
							(mid 0.321484 0.511984)
							(end 0.1778 0.5715)
						)
					)
					(width 0)
					(fill yes)
				)
			)
		)
		(pad "G" smd custom
			(at -0.98425 0.9525)
			(size 0.1905 0.1905)
			(layers "F.Cu" "F.Mask" "F.Paste")
			(net "DRIVE_B_31_FLT_LED")
			(options
				(clearance outline)
				(anchor circle)
			)
			(primitives
				(gr_poly
					(pts
						(arc
							(start -0.1778 0.5715)
							(mid -0.321484 0.511984)
							(end -0.381 0.3683)
						)
						(arc
							(start -0.381 -0.3683)
							(mid -0.321484 -0.511984)
							(end -0.1778 -0.5715)
						)
						(arc
							(start 0.1778 -0.5715)
							(mid 0.321484 -0.511984)
							(end 0.381 -0.3683)
						)
						(arc
							(start 0.381 0.3683)
							(mid 0.321484 0.511984)
							(end 0.1778 0.5715)
						)
					)
					(width 0)
					(fill yes)
				)
			)
		)
		(pad "S" smd custom
			(at 0.98425 0.9525)
			(size 0.1905 0.1905)
			(layers "F.Cu" "F.Mask" "F.Paste")
			(net "GND")
			(options
				(clearance outline)
				(anchor circle)
			)
			(primitives
				(gr_poly
					(pts
						(arc
							(start -0.1778 0.5715)
							(mid -0.321484 0.511984)
							(end -0.381 0.3683)
						)
						(arc
							(start -0.381 -0.3683)
							(mid -0.321484 -0.511984)
							(end -0.1778 -0.5715)
						)
						(arc
							(start 0.1778 -0.5715)
							(mid 0.321484 -0.511984)
							(end 0.381 -0.3683)
						)
						(arc
							(start 0.381 0.3683)
							(mid 0.321484 0.511984)
							(end 0.1778 0.5715)
						)
					)
					(width 0)
					(fill yes)
				)
			)
		)
	)
	(footprint ""
		(layer "F.Cu")
		(at 16.824198 -282.110942 90)
		(property "Reference" "R965"
			(at 0 0 90)
			(layer "F.SilkS")
			(hide yes)
			(effects
				(font
					(size 1.27 1.27)
				)
			)
		)
		(property "Value" "4K7R2J-2-GP"
			(at 0.064008 -3.993896 90)
			(unlocked yes)
			(layer "F.Fab")
			(hide yes)
			(effects
				(font
					(size 1.016 1.016)
					(thickness 0.1524)
				)
			)
		)
		(property "Device Type" "R402H16"
			(at 0.064008 -5.517896 90)
			(unlocked yes)
			(layer "F.Fab")
			(hide yes)
			(effects
				(font
					(size 1.016 1.016)
					(thickness 0.1524)
				)
			)
		)
		(duplicate_pad_numbers_are_jumpers no)
		(fp_line
			(start 0.508 -0.9398)
			(end -0.508 -0.9398)
			(stroke
				(width 0.1524)
				(type default)
			)
			(layer "F.SilkS")
		)
		(fp_line
			(start -0.508 -0.9398)
			(end -0.508 0.9398)
			(stroke
				(width 0.1524)
				(type default)
			)
			(layer "F.SilkS")
		)
		(fp_rect
			(start -0.508 0.9398)
			(end 0.508 -0.9398)
			(stroke
				(width 0)
				(type default)
			)
			(fill no)
			(layer "F.CrtYd")
		)
		(fp_rect
			(start -0.508 0.9398)
			(end 0.508 -0.9398)
			(stroke
				(width 0)
				(type default)
			)
			(fill no)
			(layer "F.Fab")
		)
		(pad "1" smd custom
			(at 0 -0.4445 90)
			(size 0.1397 0.1397)
			(layers "F.Cu" "F.Mask" "F.Paste")
			(net "P12V_A")
			(options
				(clearance outline)
				(anchor circle)
			)
			(primitives
				(gr_poly
					(pts
						(arc
							(start -0.1778 -0.2794)
							(mid -0.249642 -0.249642)
							(end -0.2794 -0.1778)
						)
						(arc
							(start -0.2794 0.1778)
							(mid -0.249642 0.249642)
							(end -0.1778 0.2794)
						)
						(arc
							(start 0.1778 0.2794)
							(mid 0.249642 0.249642)
							(end 0.2794 0.1778)
						)
						(arc
							(start 0.2794 -0.1778)
							(mid 0.249642 -0.249642)
							(end 0.1778 -0.2794)
						)
					)
					(width 0)
					(fill yes)
				)
			)
		)
		(pad "2" smd custom
			(at 0 0.4445 90)
			(size 0.1397 0.1397)
			(layers "F.Cu" "F.Mask" "F.Paste")
			(net "SW_HDD_P0")
			(options
				(clearance outline)
				(anchor circle)
			)
			(primitives
				(gr_poly
					(pts
						(arc
							(start -0.1778 -0.2794)
							(mid -0.249642 -0.249642)
							(end -0.2794 -0.1778)
						)
						(arc
							(start -0.2794 0.1778)
							(mid -0.249642 0.249642)
							(end -0.1778 0.2794)
						)
						(arc
							(start 0.1778 0.2794)
							(mid 0.249642 0.249642)
							(end 0.2794 0.1778)
						)
						(arc
							(start 0.2794 -0.1778)
							(mid 0.249642 -0.249642)
							(end 0.1778 -0.2794)
						)
					)
					(width 0)
					(fill yes)
				)
			)
		)
	)
	(footprint ""
		(layer "F.Cu")
		(at 267.00099 -147.408138 90)
		(property "Reference" "TP188"
			(at 0 0 90)
			(layer "F.SilkS")
			(hide yes)
			(effects
				(font
					(size 1.27 1.27)
				)
			)
		)
		(property "Value" "TPAD32-GP"
			(at -0.0508 -1.6764 90)
			(unlocked yes)
			(layer "F.Fab")
			(hide yes)
			(effects
				(font
					(size 1.016 1.016)
					(thickness 0.1524)
				)
			)
		)
		(property "Device Type" "TPAD32"
			(at -0.0508 -3.2004 90)
			(unlocked yes)
			(layer "F.Fab")
			(hide yes)
			(effects
				(font
					(size 1.016 1.016)
					(thickness 0.1524)
				)
			)
		)
		(duplicate_pad_numbers_are_jumpers no)
		(fp_poly
			(pts
				(arc
					(start 0 0.4064)
					(mid 0 -0.4064)
					(end 0 0.4064)
				)
			)
			(stroke
				(width 0)
				(type default)
			)
			(fill no)
			(layer "F.CrtYd")
		)
		(fp_poly
			(pts
				(arc
					(start 0 0.7112)
					(mid 0 -0.7112)
					(end 0 0.7112)
				)
			)
			(stroke
				(width 0)
				(type default)
			)
			(fill no)
			(layer "F.Fab")
		)
		(pad "1" smd circle
			(at 0 0 90)
			(size 0.8128 0.8128)
			(layers "F.Cu" "F.Mask" "F.Paste")
			(net "TP_COMP_B_KR_P0_RX_DN")
		)
	)
	(footprint ""
		(layer "F.Cu")
		(at 351.4598 -141.1986)
		(property "Reference" "Q222"
			(at 0 0 0)
			(layer "F.SilkS")
			(hide yes)
			(effects
				(font
					(size 1.27 1.27)
				)
			)
		)
		(property "Value" "IRFH8201TRPBF-GP"
			(at -4.2164 -4.3688 0)
			(unlocked yes)
			(layer "F.Fab")
			(hide yes)
			(effects
				(font
					(size 1.016 1.016)
					(thickness 0.1524)
				)
			)
		)
		(property "Device Type" "PPAK-5PH42"
			(at -4.2164 -5.8928 0)
			(unlocked yes)
			(layer "F.Fab")
			(hide yes)
			(effects
				(font
					(size 1.016 1.016)
					(thickness 0.1524)
				)
			)
		)
		(duplicate_pad_numbers_are_jumpers no)
		(fp_line
			(start -3.0353 4.9276)
			(end -3.0353 3.9624)
			(stroke
				(width 0.3302)
				(type default)
			)
			(layer "F.SilkS")
		)
		(fp_line
			(start -2.8956 -2.794)
			(end 2.8956 -2.794)
			(stroke
				(width 0.1524)
				(type default)
			)
			(layer "F.SilkS")
		)
		(fp_line
			(start -2.8956 4.826)
			(end -2.8956 -2.794)
			(stroke
				(width 0.1524)
				(type default)
			)
			(layer "F.SilkS")
		)
		(fp_line
			(start -1.9431 4.9276)
			(end -3.0353 4.9276)
			(stroke
				(width 0.3302)
				(type default)
			)
			(layer "F.SilkS")
		)
		(fp_line
			(start 2.8956 -2.794)
			(end 2.8956 4.826)
			(stroke
				(width 0.1524)
				(type default)
			)
			(layer "F.SilkS")
		)
		(fp_line
			(start 2.8956 4.826)
			(end -2.8956 4.826)
			(stroke
				(width 0.1524)
				(type default)
			)
			(layer "F.SilkS")
		)
		(fp_poly
			(pts
				(xy -2.3622 5.334) (xy -1.4986 5.334) (xy -1.9304 4.9022)
			)
			(stroke
				(width 0)
				(type default)
			)
			(fill yes)
			(layer "F.SilkS")
		)
		(fp_poly
			(pts
				(xy -2.6416 -0.3556) (xy -0.3556 -0.3556) (xy -0.3556 -2.54) (xy -2.6416 -2.54)
			)
			(stroke
				(width 0)
				(type default)
			)
			(fill yes)
			(layer "F.Paste")
		)
		(fp_poly
			(pts
				(xy -2.6416 2.54) (xy -0.3556 2.54) (xy -0.3556 0.3556) (xy -2.6416 0.3556)
			)
			(stroke
				(width 0)
				(type default)
			)
			(fill yes)
			(layer "F.Paste")
		)
		(fp_poly
			(pts
				(xy 0.3556 -0.3556) (xy 2.6416 -0.3556) (xy 2.6416 -2.54) (xy 0.3556 -2.54)
			)
			(stroke
				(width 0)
				(type default)
			)
			(fill yes)
			(layer "F.Paste")
		)
		(fp_poly
			(pts
				(xy 0.3556 2.54) (xy 2.6416 2.54) (xy 2.6416 0.3556) (xy 0.3556 0.3556)
			)
			(stroke
				(width 0)
				(type default)
			)
			(fill yes)
			(layer "F.Paste")
		)
		(fp_rect
			(start -2.5781 3.9878)
			(end 2.5781 -2.1082)
			(stroke
				(width 0)
				(type default)
			)
			(fill no)
			(layer "F.CrtYd")
		)
		(fp_poly
			(pts
				(xy -3.1496 5.08) (xy -3.1496 -3.048) (xy 3.1496 -3.048) (xy 3.1496 3.9751) (xy 2.5781 3.9751) (xy 2.5781 -2.1082)
				(xy -2.5781 -2.1082) (xy -2.5781 3.9878) (xy 3.1496 3.9878) (xy 3.1496 5.08)
			)
			(stroke
				(width 0)
				(type default)
			)
			(fill no)
			(layer "F.CrtYd")
		)
		(fp_rect
			(start -3.1496 5.08)
			(end 3.1496 -3.048)
			(stroke
				(width 0)
				(type default)
			)
			(fill no)
			(layer "F.Fab")
		)
		(pad "1" smd rect
			(at -1.905 3.81)
			(size 0.762 1.524)
			(layers "F.Cu" "F.Mask" "F.Paste")
			(net "P12V_B_COMP")
		)
		(pad "2" smd rect
			(at -0.635 3.81)
			(size 0.762 1.524)
			(layers "F.Cu" "F.Mask" "F.Paste")
			(net "P12V_B_COMP")
		)
		(pad "3" smd rect
			(at 0.635 3.81)
			(size 0.762 1.524)
			(layers "F.Cu" "F.Mask" "F.Paste")
			(net "P12V_B_COMP")
		)
		(pad "4" smd rect
			(at 1.905 3.81)
			(size 0.762 1.524)
			(layers "F.Cu" "F.Mask" "F.Paste")
			(net "MB1_12V_CTRL_GATE1")
		)
		(pad "5" smd rect
			(at 0 0)
			(size 5.2832 5.08)
			(layers "F.Cu" "F.Mask" "F.Paste")
			(net "MB1_P12V_B_R")
		)
		(pad "6" smd rect
			(at 0.635 -2.032)
			(size 0.0254 0.0254)
			(layers "F.Cu" "F.Mask" "F.Paste")
			(net "MB1_P12V_B_R")
		)
		(pad "7" smd rect
			(at -0.635 -2.032)
			(size 0.0254 0.0254)
			(layers "F.Cu" "F.Mask" "F.Paste")
			(net "MB1_P12V_B_R")
		)
		(pad "8" smd rect
			(at -1.905 -2.032)
			(size 0.0254 0.0254)
			(layers "F.Cu" "F.Mask" "F.Paste")
			(net "MB1_P12V_B_R")
		)
	)
	(footprint ""
		(layer "F.Cu")
		(at 44.466002 -148.64715 180)
		(property "Reference" "R1240"
			(at 0 0 180)
			(layer "F.SilkS")
			(hide yes)
			(effects
				(font
					(size 1.27 1.27)
				)
			)
		)
		(property "Value" "619KR2F-GP"
			(at 0.064008 -3.993896 180)
			(unlocked yes)
			(layer "F.Fab")
			(hide yes)
			(effects
				(font
					(size 1.016 1.016)
					(thickness 0.1524)
				)
			)
		)
		(property "Device Type" "R402H16"
			(at 0.064008 -5.517896 180)
			(unlocked yes)
			(layer "F.Fab")
			(hide yes)
			(effects
				(font
					(size 1.016 1.016)
					(thickness 0.1524)
				)
			)
		)
		(duplicate_pad_numbers_are_jumpers no)
		(fp_line
			(start 0.508 -0.9398)
			(end -0.508 -0.9398)
			(stroke
				(width 0.1524)
				(type default)
			)
			(layer "F.SilkS")
		)
		(fp_line
			(start -0.508 -0.9398)
			(end -0.508 0.9398)
			(stroke
				(width 0.1524)
				(type default)
			)
			(layer "F.SilkS")
		)
		(fp_rect
			(start -0.508 0.9398)
			(end 0.508 -0.9398)
			(stroke
				(width 0)
				(type default)
			)
			(fill no)
			(layer "F.CrtYd")
		)
		(fp_rect
			(start -0.508 0.9398)
			(end 0.508 -0.9398)
			(stroke
				(width 0)
				(type default)
			)
			(fill no)
			(layer "F.Fab")
		)
		(pad "1" smd custom
			(at 0 -0.4445 180)
			(size 0.1397 0.1397)
			(layers "F.Cu" "F.Mask" "F.Paste")
			(net "P5V_B_RF")
			(options
				(clearance outline)
				(anchor circle)
			)
			(primitives
				(gr_poly
					(pts
						(arc
							(start -0.1778 -0.2794)
							(mid -0.249642 -0.249642)
							(end -0.2794 -0.1778)
						)
						(arc
							(start -0.2794 0.1778)
							(mid -0.249642 0.249642)
							(end -0.1778 0.2794)
						)
						(arc
							(start 0.1778 0.2794)
							(mid 0.249642 0.249642)
							(end 0.2794 0.1778)
						)
						(arc
							(start 0.2794 -0.1778)
							(mid 0.249642 -0.249642)
							(end 0.1778 -0.2794)
						)
					)
					(width 0)
					(fill yes)
				)
			)
		)
		(pad "2" smd custom
			(at 0 0.4445 180)
			(size 0.1397 0.1397)
			(layers "F.Cu" "F.Mask" "F.Paste")
			(net "AGND_P5V_B")
			(options
				(clearance outline)
				(anchor circle)
			)
			(primitives
				(gr_poly
					(pts
						(arc
							(start -0.1778 -0.2794)
							(mid -0.249642 -0.249642)
							(end -0.2794 -0.1778)
						)
						(arc
							(start -0.2794 0.1778)
							(mid -0.249642 0.249642)
							(end -0.1778 0.2794)
						)
						(arc
							(start 0.1778 0.2794)
							(mid 0.249642 0.249642)
							(end 0.2794 0.1778)
						)
						(arc
							(start 0.2794 -0.1778)
							(mid 0.249642 -0.249642)
							(end 0.1778 -0.2794)
						)
					)
					(width 0)
					(fill yes)
				)
			)
		)
	)
	(footprint ""
		(layer "F.Cu")
		(at 232.791 -244.1194 180)
		(property "Reference" "R69"
			(at 0 0 180)
			(layer "F.SilkS")
			(hide yes)
			(effects
				(font
					(size 1.27 1.27)
				)
			)
		)
		(property "Value" "4K7R2F-GP"
			(at 0.064008 -3.993896 180)
			(unlocked yes)
			(layer "F.Fab")
			(hide yes)
			(effects
				(font
					(size 1.016 1.016)
					(thickness 0.1524)
				)
			)
		)
		(property "Device Type" "R402H16"
			(at 0.064008 -5.517896 180)
			(unlocked yes)
			(layer "F.Fab")
			(hide yes)
			(effects
				(font
					(size 1.016 1.016)
					(thickness 0.1524)
				)
			)
		)
		(duplicate_pad_numbers_are_jumpers no)
		(fp_line
			(start 0.508 -0.9398)
			(end -0.508 -0.9398)
			(stroke
				(width 0.1524)
				(type default)
			)
			(layer "F.SilkS")
		)
		(fp_line
			(start -0.508 -0.9398)
			(end -0.508 0.9398)
			(stroke
				(width 0.1524)
				(type default)
			)
			(layer "F.SilkS")
		)
		(fp_rect
			(start -0.508 0.9398)
			(end 0.508 -0.9398)
			(stroke
				(width 0)
				(type default)
			)
			(fill no)
			(layer "F.CrtYd")
		)
		(fp_rect
			(start -0.508 0.9398)
			(end 0.508 -0.9398)
			(stroke
				(width 0)
				(type default)
			)
			(fill no)
			(layer "F.Fab")
		)
		(pad "1" smd custom
			(at 0 -0.4445 180)
			(size 0.1397 0.1397)
			(layers "F.Cu" "F.Mask" "F.Paste")
			(net "IO_EXP1_A2")
			(options
				(clearance outline)
				(anchor circle)
			)
			(primitives
				(gr_poly
					(pts
						(arc
							(start -0.1778 -0.2794)
							(mid -0.249642 -0.249642)
							(end -0.2794 -0.1778)
						)
						(arc
							(start -0.2794 0.1778)
							(mid -0.249642 0.249642)
							(end -0.1778 0.2794)
						)
						(arc
							(start 0.1778 0.2794)
							(mid 0.249642 0.249642)
							(end 0.2794 0.1778)
						)
						(arc
							(start 0.2794 -0.1778)
							(mid 0.249642 -0.249642)
							(end 0.1778 -0.2794)
						)
					)
					(width 0)
					(fill yes)
				)
			)
		)
		(pad "2" smd custom
			(at 0 0.4445 180)
			(size 0.1397 0.1397)
			(layers "F.Cu" "F.Mask" "F.Paste")
			(net "GND")
			(options
				(clearance outline)
				(anchor circle)
			)
			(primitives
				(gr_poly
					(pts
						(arc
							(start -0.1778 -0.2794)
							(mid -0.249642 -0.249642)
							(end -0.2794 -0.1778)
						)
						(arc
							(start -0.2794 0.1778)
							(mid -0.249642 0.249642)
							(end -0.1778 0.2794)
						)
						(arc
							(start 0.1778 0.2794)
							(mid 0.249642 0.249642)
							(end 0.2794 0.1778)
						)
						(arc
							(start 0.2794 -0.1778)
							(mid 0.249642 -0.249642)
							(end 0.1778 -0.2794)
						)
					)
					(width 0)
					(fill yes)
				)
			)
		)
	)
	(footprint ""
		(layer "F.Cu")
		(at 162.378898 -295.064942 90)
		(property "Reference" "R226"
			(at 0 0 90)
			(layer "F.SilkS")
			(hide yes)
			(effects
				(font
					(size 1.27 1.27)
				)
			)
		)
		(property "Value" "220R3F-1-GP"
			(at -0.0254 -2.5146 90)
			(unlocked yes)
			(layer "F.Fab")
			(hide yes)
			(effects
				(font
					(size 1.016 1.016)
					(thickness 0.1524)
				)
			)
		)
		(property "Device Type" "R603H22"
			(at -0.0254 -4.0386 90)
			(unlocked yes)
			(layer "F.Fab")
			(hide yes)
			(effects
				(font
					(size 1.016 1.016)
					(thickness 0.1524)
				)
			)
		)
		(duplicate_pad_numbers_are_jumpers no)
		(fp_line
			(start 0.2032 0)
			(end 0.4826 0)
			(stroke
				(width 0.2032)
				(type default)
			)
			(layer "F.SilkS")
		)
		(fp_line
			(start -0.4826 0)
			(end -0.2032 0)
			(stroke
				(width 0.2032)
				(type default)
			)
			(layer "F.SilkS")
		)
		(fp_rect
			(start -0.5842 1.3335)
			(end 0.5842 -1.3335)
			(stroke
				(width 0)
				(type default)
			)
			(fill no)
			(layer "F.CrtYd")
		)
		(fp_rect
			(start -0.5842 1.3335)
			(end 0.5842 -1.3335)
			(stroke
				(width 0)
				(type default)
			)
			(fill no)
			(layer "F.Fab")
		)
		(pad "1" smd custom
			(at 0 -0.762 90)
			(size 0.2159 0.2159)
			(layers "F.Cu" "F.Mask" "F.Paste")
			(net "HDD_PRSNT_4")
			(options
				(clearance outline)
				(anchor circle)
			)
			(primitives
				(gr_poly
					(pts
						(arc
							(start -0.3302 -0.4318)
							(mid -0.402042 -0.402042)
							(end -0.4318 -0.3302)
						)
						(arc
							(start -0.4318 0.3302)
							(mid -0.402042 0.402042)
							(end -0.3302 0.4318)
						)
						(arc
							(start 0.3302 0.4318)
							(mid 0.402042 0.402042)
							(end 0.4318 0.3302)
						)
						(arc
							(start 0.4318 -0.3302)
							(mid 0.402042 -0.402042)
							(end 0.3302 -0.4318)
						)
					)
					(width 0)
					(fill yes)
				)
			)
		)
		(pad "2" smd custom
			(at 0 0.762 90)
			(size 0.2159 0.2159)
			(layers "F.Cu" "F.Mask" "F.Paste")
			(net "DRIVE_A_4_INS")
			(options
				(clearance outline)
				(anchor circle)
			)
			(primitives
				(gr_poly
					(pts
						(arc
							(start -0.3302 -0.4318)
							(mid -0.402042 -0.402042)
							(end -0.4318 -0.3302)
						)
						(arc
							(start -0.4318 0.3302)
							(mid -0.402042 0.402042)
							(end -0.3302 0.4318)
						)
						(arc
							(start 0.3302 0.4318)
							(mid 0.402042 0.402042)
							(end 0.4318 0.3302)
						)
						(arc
							(start 0.4318 -0.3302)
							(mid 0.402042 -0.402042)
							(end 0.3302 -0.4318)
						)
					)
					(width 0)
					(fill yes)
				)
			)
		)
	)
	(footprint ""
		(layer "F.Cu")
		(at 174.895002 -242.25377)
		(property "Reference" "R223"
			(at 0 0 0)
			(layer "F.SilkS")
			(hide yes)
			(effects
				(font
					(size 1.27 1.27)
				)
			)
		)
		(property "Value" "130R3F-GP"
			(at -0.0254 -2.5146 0)
			(unlocked yes)
			(layer "F.Fab")
			(hide yes)
			(effects
				(font
					(size 1.016 1.016)
					(thickness 0.1524)
				)
			)
		)
		(property "Device Type" "R603H22"
			(at -0.0254 -4.0386 0)
			(unlocked yes)
			(layer "F.Fab")
			(hide yes)
			(effects
				(font
					(size 1.016 1.016)
					(thickness 0.1524)
				)
			)
		)
		(duplicate_pad_numbers_are_jumpers no)
		(fp_line
			(start -0.4826 0)
			(end -0.2032 0)
			(stroke
				(width 0.2032)
				(type default)
			)
			(layer "F.SilkS")
		)
		(fp_line
			(start 0.2032 0)
			(end 0.4826 0)
			(stroke
				(width 0.2032)
				(type default)
			)
			(layer "F.SilkS")
		)
		(fp_rect
			(start -0.5842 1.3335)
			(end 0.5842 -1.3335)
			(stroke
				(width 0)
				(type default)
			)
			(fill no)
			(layer "F.CrtYd")
		)
		(fp_rect
			(start -0.5842 1.3335)
			(end 0.5842 -1.3335)
			(stroke
				(width 0)
				(type default)
			)
			(fill no)
			(layer "F.Fab")
		)
		(pad "1" smd custom
			(at 0 -0.762)
			(size 0.2159 0.2159)
			(layers "F.Cu" "F.Mask" "F.Paste")
			(net "P5V_A_1")
			(options
				(clearance outline)
				(anchor circle)
			)
			(primitives
				(gr_poly
					(pts
						(arc
							(start -0.3302 -0.4318)
							(mid -0.402042 -0.402042)
							(end -0.4318 -0.3302)
						)
						(arc
							(start -0.4318 0.3302)
							(mid -0.402042 0.402042)
							(end -0.3302 0.4318)
						)
						(arc
							(start 0.3302 0.4318)
							(mid 0.402042 0.402042)
							(end 0.4318 0.3302)
						)
						(arc
							(start 0.4318 -0.3302)
							(mid 0.402042 -0.402042)
							(end 0.3302 -0.4318)
						)
					)
					(width 0)
					(fill yes)
				)
			)
		)
		(pad "2" smd custom
			(at 0 0.762)
			(size 0.2159 0.2159)
			(layers "F.Cu" "F.Mask" "F.Paste")
			(net "FLT_HDD5")
			(options
				(clearance outline)
				(anchor circle)
			)
			(primitives
				(gr_poly
					(pts
						(arc
							(start -0.3302 -0.4318)
							(mid -0.402042 -0.402042)
							(end -0.4318 -0.3302)
						)
						(arc
							(start -0.4318 0.3302)
							(mid -0.402042 0.402042)
							(end -0.3302 0.4318)
						)
						(arc
							(start 0.3302 0.4318)
							(mid 0.402042 0.402042)
							(end 0.4318 0.3302)
						)
						(arc
							(start 0.4318 -0.3302)
							(mid 0.402042 -0.402042)
							(end 0.3302 -0.4318)
						)
					)
					(width 0)
					(fill yes)
				)
			)
		)
	)
	(footprint ""
		(layer "F.Cu")
		(at 152.425654 -134.7724 90)
		(property "Reference" "C541"
			(at 0 0 90)
			(layer "F.SilkS")
			(hide yes)
			(effects
				(font
					(size 1.27 1.27)
				)
			)
		)
		(property "Value" "SC1KP50V2KX-1GP"
			(at 1.1811 -2.7051 90)
			(unlocked yes)
			(layer "F.Fab")
			(hide yes)
			(effects
				(font
					(size 1.016 1.016)
					(thickness 0.1524)
				)
			)
		)
		(property "Device Type" "C402H22"
			(at 1.1811 -4.2291 90)
			(unlocked yes)
			(layer "F.Fab")
			(hide yes)
			(effects
				(font
					(size 1.016 1.016)
					(thickness 0.1524)
				)
			)
		)
		(duplicate_pad_numbers_are_jumpers no)
		(fp_rect
			(start -0.4318 0.9525)
			(end 0.4318 -0.9525)
			(stroke
				(width 0)
				(type default)
			)
			(fill no)
			(layer "F.CrtYd")
		)
		(fp_rect
			(start -0.4318 0.9525)
			(end 0.4318 -0.9525)
			(stroke
				(width 0)
				(type default)
			)
			(fill no)
			(layer "F.Fab")
		)
		(pad "1" smd custom
			(at 0 -0.4445 90)
			(size 0.1524 0.1524)
			(layers "F.Cu" "F.Mask" "F.Paste")
			(net "MB0_TEMP_B")
			(options
				(clearance outline)
				(anchor circle)
			)
			(primitives
				(gr_poly
					(pts
						(arc
							(start 0.3048 -0.2032)
							(mid 0.275042 -0.275042)
							(end 0.2032 -0.3048)
						)
						(arc
							(start -0.2032 -0.3048)
							(mid -0.275042 -0.275042)
							(end -0.3048 -0.2032)
						)
						(arc
							(start -0.3048 0.2032)
							(mid -0.275042 0.275042)
							(end -0.2032 0.3048)
						)
						(arc
							(start 0.2032 0.3048)
							(mid 0.275042 0.275042)
							(end 0.3048 0.2032)
						)
					)
					(width 0)
					(fill yes)
				)
			)
		)
		(pad "2" smd custom
			(at 0 0.4445 90)
			(size 0.1524 0.1524)
			(layers "F.Cu" "F.Mask" "F.Paste")
			(net "MB0_TEMP_E")
			(options
				(clearance outline)
				(anchor circle)
			)
			(primitives
				(gr_poly
					(pts
						(arc
							(start 0.3048 -0.2032)
							(mid 0.275042 -0.275042)
							(end 0.2032 -0.3048)
						)
						(arc
							(start -0.2032 -0.3048)
							(mid -0.275042 -0.275042)
							(end -0.3048 -0.2032)
						)
						(arc
							(start -0.3048 0.2032)
							(mid -0.275042 0.275042)
							(end -0.2032 0.3048)
						)
						(arc
							(start 0.2032 0.3048)
							(mid 0.275042 0.275042)
							(end 0.3048 0.2032)
						)
					)
					(width 0)
					(fill yes)
				)
			)
		)
	)
	(footprint ""
		(layer "F.Cu")
		(at 427.390052 -164.596318 90)
		(property "Reference" "C321"
			(at 0 0 90)
			(layer "F.SilkS")
			(hide yes)
			(effects
				(font
					(size 1.27 1.27)
				)
			)
		)
		(property "Value" "SCD033U25V2KX-GP"
			(at 1.1811 -2.7051 90)
			(unlocked yes)
			(layer "F.Fab")
			(hide yes)
			(effects
				(font
					(size 1.016 1.016)
					(thickness 0.1524)
				)
			)
		)
		(property "Device Type" "C402H22"
			(at 1.1811 -4.2291 90)
			(unlocked yes)
			(layer "F.Fab")
			(hide yes)
			(effects
				(font
					(size 1.016 1.016)
					(thickness 0.1524)
				)
			)
		)
		(duplicate_pad_numbers_are_jumpers no)
		(fp_rect
			(start -0.4318 0.9525)
			(end 0.4318 -0.9525)
			(stroke
				(width 0)
				(type default)
			)
			(fill no)
			(layer "F.CrtYd")
		)
		(fp_rect
			(start -0.4318 0.9525)
			(end 0.4318 -0.9525)
			(stroke
				(width 0)
				(type default)
			)
			(fill no)
			(layer "F.Fab")
		)
		(pad "1" smd custom
			(at 0 -0.4445 90)
			(size 0.1524 0.1524)
			(layers "F.Cu" "F.Mask" "F.Paste")
			(net "SW_HDD_P21")
			(options
				(clearance outline)
				(anchor circle)
			)
			(primitives
				(gr_poly
					(pts
						(arc
							(start 0.3048 -0.2032)
							(mid 0.275042 -0.275042)
							(end 0.2032 -0.3048)
						)
						(arc
							(start -0.2032 -0.3048)
							(mid -0.275042 -0.275042)
							(end -0.3048 -0.2032)
						)
						(arc
							(start -0.3048 0.2032)
							(mid -0.275042 0.275042)
							(end -0.2032 0.3048)
						)
						(arc
							(start 0.2032 0.3048)
							(mid 0.275042 0.275042)
							(end 0.3048 0.2032)
						)
					)
					(width 0)
					(fill yes)
				)
			)
		)
		(pad "2" smd custom
			(at 0 0.4445 90)
			(size 0.1524 0.1524)
			(layers "F.Cu" "F.Mask" "F.Paste")
			(net "GND")
			(options
				(clearance outline)
				(anchor circle)
			)
			(primitives
				(gr_poly
					(pts
						(arc
							(start 0.3048 -0.2032)
							(mid 0.275042 -0.275042)
							(end 0.2032 -0.3048)
						)
						(arc
							(start -0.2032 -0.3048)
							(mid -0.275042 -0.275042)
							(end -0.3048 -0.2032)
						)
						(arc
							(start -0.3048 0.2032)
							(mid -0.275042 0.275042)
							(end -0.2032 0.3048)
						)
						(arc
							(start 0.2032 0.3048)
							(mid 0.275042 0.275042)
							(end 0.3048 0.2032)
						)
					)
					(width 0)
					(fill yes)
				)
			)
		)
	)
	(footprint ""
		(layer "F.Cu")
		(at 55.790846 -189.462918 180)
		(property "Reference" "C216"
			(at 0 0 180)
			(layer "F.SilkS")
			(hide yes)
			(effects
				(font
					(size 1.27 1.27)
				)
			)
		)
		(property "Value" "SC1U25V3KX-GP"
			(at 0 -2.8194 180)
			(unlocked yes)
			(layer "F.Fab")
			(hide yes)
			(effects
				(font
					(size 1.016 1.016)
					(thickness 0.1524)
				)
			)
		)
		(property "Device Type" "C603H36"
			(at 0 -4.3434 180)
			(unlocked yes)
			(layer "F.Fab")
			(hide yes)
			(effects
				(font
					(size 1.016 1.016)
					(thickness 0.1524)
				)
			)
		)
		(duplicate_pad_numbers_are_jumpers no)
		(fp_line
			(start 0.508 0)
			(end -0.508 0)
			(stroke
				(width 0.2032)
				(type default)
			)
			(layer "F.SilkS")
		)
		(fp_rect
			(start -0.5842 1.3335)
			(end 0.5842 -1.3335)
			(stroke
				(width 0)
				(type default)
			)
			(fill no)
			(layer "F.CrtYd")
		)
		(fp_rect
			(start -0.5842 1.3335)
			(end 0.5842 -1.3335)
			(stroke
				(width 0)
				(type default)
			)
			(fill no)
			(layer "F.Fab")
		)
		(pad "1" smd custom
			(at 0 -0.762 180)
			(size 0.2159 0.2159)
			(layers "F.Cu" "F.Mask" "F.Paste")
			(net "P12V_HDD13")
			(options
				(clearance outline)
				(anchor circle)
			)
			(primitives
				(gr_poly
					(pts
						(arc
							(start -0.3302 -0.4318)
							(mid -0.402042 -0.402042)
							(end -0.4318 -0.3302)
						)
						(arc
							(start -0.4318 0.3302)
							(mid -0.402042 0.402042)
							(end -0.3302 0.4318)
						)
						(arc
							(start 0.3302 0.4318)
							(mid 0.402042 0.402042)
							(end 0.4318 0.3302)
						)
						(arc
							(start 0.4318 -0.3302)
							(mid 0.402042 -0.402042)
							(end 0.3302 -0.4318)
						)
					)
					(width 0)
					(fill yes)
				)
			)
		)
		(pad "2" smd custom
			(at 0 0.762 180)
			(size 0.2159 0.2159)
			(layers "F.Cu" "F.Mask" "F.Paste")
			(net "GND")
			(options
				(clearance outline)
				(anchor circle)
			)
			(primitives
				(gr_poly
					(pts
						(arc
							(start -0.3302 -0.4318)
							(mid -0.402042 -0.402042)
							(end -0.4318 -0.3302)
						)
						(arc
							(start -0.4318 0.3302)
							(mid -0.402042 0.402042)
							(end -0.3302 0.4318)
						)
						(arc
							(start 0.3302 0.4318)
							(mid 0.402042 0.402042)
							(end 0.4318 0.3302)
						)
						(arc
							(start 0.4318 -0.3302)
							(mid 0.402042 -0.402042)
							(end 0.3302 -0.4318)
						)
					)
					(width 0)
					(fill yes)
				)
			)
		)
	)
	(footprint ""
		(layer "F.Cu")
		(at 16.874998 -161.649918 180)
		(property "Reference" "D12"
			(at 0 0 180)
			(layer "F.SilkS")
			(hide yes)
			(effects
				(font
					(size 1.27 1.27)
				)
			)
		)
		(property "Value" "RB551V30-GP"
			(at 0 -6.7818 180)
			(unlocked yes)
			(layer "F.Fab")
			(hide yes)
			(effects
				(font
					(size 1.016 1.016)
					(thickness 0.1524)
				)
			)
		)
		(property "Device Type" "SOD323AKH38"
			(at 0 -8.6868 180)
			(unlocked yes)
			(layer "F.Fab")
			(hide yes)
			(effects
				(font
					(size 1.016 1.016)
					(thickness 0.1524)
				)
			)
		)
		(duplicate_pad_numbers_are_jumpers no)
		(fp_line
			(start 0.889 2.159)
			(end -0.889 2.159)
			(stroke
				(width 0.1524)
				(type default)
			)
			(layer "F.SilkS")
		)
		(fp_line
			(start 0.889 -1.9304)
			(end 0.889 2.159)
			(stroke
				(width 0.1524)
				(type default)
			)
			(layer "F.SilkS")
		)
		(fp_line
			(start 0.762 2.0574)
			(end -0.762 2.0574)
			(stroke
				(width 0.508)
				(type default)
			)
			(layer "F.SilkS")
		)
		(fp_line
			(start -0.889 2.159)
			(end -0.889 -1.9304)
			(stroke
				(width 0.1524)
				(type default)
			)
			(layer "F.SilkS")
		)
		(fp_line
			(start -0.889 -1.9304)
			(end 0.889 -1.9304)
			(stroke
				(width 0.1524)
				(type default)
			)
			(layer "F.SilkS")
		)
		(fp_rect
			(start -1.016 2.3114)
			(end 1.016 -2.0066)
			(stroke
				(width 0)
				(type default)
			)
			(fill no)
			(layer "F.CrtYd")
		)
		(fp_poly
			(pts
				(xy -1.016 -2.0066) (xy 1.016 -2.0066) (xy 1.016 2.3114) (xy -1.016 2.3114)
			)
			(stroke
				(width 0)
				(type default)
			)
			(fill no)
			(layer "F.Fab")
		)
		(pad "A" smd rect
			(at 0 -1.143 180)
			(size 0.5588 1.016)
			(layers "F.Cu" "F.Mask" "F.Paste")
			(net "SW_HDD_R12")
		)
		(pad "K" smd rect
			(at 0 1.143 180)
			(size 0.5588 1.016)
			(layers "F.Cu" "F.Mask" "F.Paste")
			(net "SW_HDD_N12")
		)
	)
	(footprint ""
		(layer "F.Cu")
		(at 55.486046 -71.287894)
		(property "Reference" "C369"
			(at 0 0 0)
			(layer "F.SilkS")
			(hide yes)
			(effects
				(font
					(size 1.27 1.27)
				)
			)
		)
		(property "Value" "SC4D7U25V5KX-1-GP"
			(at -0.0762 -6.1214 0)
			(unlocked yes)
			(layer "F.Fab")
			(hide yes)
			(effects
				(font
					(size 1.016 1.016)
					(thickness 0.1524)
				)
			)
		)
		(property "Device Type" "C805H58"
			(at -0.0762 -8.1534 0)
			(unlocked yes)
			(layer "F.Fab")
			(hide yes)
			(effects
				(font
					(size 1.016 1.016)
					(thickness 0.1524)
				)
			)
		)
		(duplicate_pad_numbers_are_jumpers no)
		(fp_line
			(start 0.635 0)
			(end -0.635 0)
			(stroke
				(width 0.508)
				(type default)
			)
			(layer "F.SilkS")
		)
		(fp_rect
			(start -0.9652 1.778)
			(end 0.9652 -1.778)
			(stroke
				(width 0)
				(type default)
			)
			(fill no)
			(layer "F.CrtYd")
		)
		(fp_poly
			(pts
				(xy -0.9652 -1.778) (xy 0.9652 -1.778) (xy 0.9652 1.778) (xy -0.9652 1.778)
			)
			(stroke
				(width 0)
				(type default)
			)
			(fill no)
			(layer "F.Fab")
		)
		(pad "1" smd rect
			(at 0 -0.9652)
			(size 1.397 1.143)
			(layers "F.Cu" "F.Mask" "F.Paste")
			(net "P12V_HDD25")
		)
		(pad "2" smd rect
			(at 0 0.9652)
			(size 1.397 1.143)
			(layers "F.Cu" "F.Mask" "F.Paste")
			(net "GND")
		)
	)
	(footprint ""
		(layer "F.Cu")
		(at 331.47 -188.954918 180)
		(property "Reference" "C278"
			(at 0 0 180)
			(layer "F.SilkS")
			(hide yes)
			(effects
				(font
					(size 1.27 1.27)
				)
			)
		)
		(property "Value" "SC4D7U25V5KX-1-GP"
			(at -0.0762 -6.1214 180)
			(unlocked yes)
			(layer "F.Fab")
			(hide yes)
			(effects
				(font
					(size 1.016 1.016)
					(thickness 0.1524)
				)
			)
		)
		(property "Device Type" "C805H58"
			(at -0.0762 -8.1534 180)
			(unlocked yes)
			(layer "F.Fab")
			(hide yes)
			(effects
				(font
					(size 1.016 1.016)
					(thickness 0.1524)
				)
			)
		)
		(duplicate_pad_numbers_are_jumpers no)
		(fp_line
			(start 0.635 0)
			(end -0.635 0)
			(stroke
				(width 0.508)
				(type default)
			)
			(layer "F.SilkS")
		)
		(fp_rect
			(start -0.9652 1.778)
			(end 0.9652 -1.778)
			(stroke
				(width 0)
				(type default)
			)
			(fill no)
			(layer "F.CrtYd")
		)
		(fp_poly
			(pts
				(xy -0.9652 -1.778) (xy 0.9652 -1.778) (xy 0.9652 1.778) (xy -0.9652 1.778)
			)
			(stroke
				(width 0)
				(type default)
			)
			(fill no)
			(layer "F.Fab")
		)
		(pad "1" smd rect
			(at 0 -0.9652 180)
			(size 1.397 1.143)
			(layers "F.Cu" "F.Mask" "F.Paste")
			(net "P12V_HDD18")
		)
		(pad "2" smd rect
			(at 0 0.9652 180)
			(size 1.397 1.143)
			(layers "F.Cu" "F.Mask" "F.Paste")
			(net "GND")
		)
	)
	(footprint ""
		(layer "F.Cu")
		(at 374.588532 -245.303802 -90)
		(property "Reference" "R486"
			(at 0 0 270)
			(layer "F.SilkS")
			(hide yes)
			(effects
				(font
					(size 1.27 1.27)
				)
			)
		)
		(property "Value" "4K7R2J-2-GP"
			(at 0.064008 -3.993896 270)
			(unlocked yes)
			(layer "F.Fab")
			(hide yes)
			(effects
				(font
					(size 1.016 1.016)
					(thickness 0.1524)
				)
			)
		)
		(property "Device Type" "R402H16"
			(at 0.064008 -5.517896 270)
			(unlocked yes)
			(layer "F.Fab")
			(hide yes)
			(effects
				(font
					(size 1.016 1.016)
					(thickness 0.1524)
				)
			)
		)
		(duplicate_pad_numbers_are_jumpers no)
		(fp_line
			(start -0.508 -0.9398)
			(end -0.508 0.9398)
			(stroke
				(width 0.1524)
				(type default)
			)
			(layer "F.SilkS")
		)
		(fp_line
			(start 0.508 -0.9398)
			(end -0.508 -0.9398)
			(stroke
				(width 0.1524)
				(type default)
			)
			(layer "F.SilkS")
		)
		(fp_rect
			(start -0.508 0.9398)
			(end 0.508 -0.9398)
			(stroke
				(width 0)
				(type default)
			)
			(fill no)
			(layer "F.CrtYd")
		)
		(fp_rect
			(start -0.508 0.9398)
			(end 0.508 -0.9398)
			(stroke
				(width 0)
				(type default)
			)
			(fill no)
			(layer "F.Fab")
		)
		(pad "1" smd custom
			(at 0 -0.4445 270)
			(size 0.1397 0.1397)
			(layers "F.Cu" "F.Mask" "F.Paste")
			(net "DRIVE_A_8_FLT_LED")
			(options
				(clearance outline)
				(anchor circle)
			)
			(primitives
				(gr_poly
					(pts
						(arc
							(start -0.1778 -0.2794)
							(mid -0.249642 -0.249642)
							(end -0.2794 -0.1778)
						)
						(arc
							(start -0.2794 0.1778)
							(mid -0.249642 0.249642)
							(end -0.1778 0.2794)
						)
						(arc
							(start 0.1778 0.2794)
							(mid 0.249642 0.249642)
							(end 0.2794 0.1778)
						)
						(arc
							(start 0.2794 -0.1778)
							(mid 0.249642 -0.249642)
							(end 0.1778 -0.2794)
						)
					)
					(width 0)
					(fill yes)
				)
			)
		)
		(pad "2" smd custom
			(at 0 0.4445 270)
			(size 0.1397 0.1397)
			(layers "F.Cu" "F.Mask" "F.Paste")
			(net "GND")
			(options
				(clearance outline)
				(anchor circle)
			)
			(primitives
				(gr_poly
					(pts
						(arc
							(start -0.1778 -0.2794)
							(mid -0.249642 -0.249642)
							(end -0.2794 -0.1778)
						)
						(arc
							(start -0.2794 0.1778)
							(mid -0.249642 0.249642)
							(end -0.1778 0.2794)
						)
						(arc
							(start 0.1778 0.2794)
							(mid 0.249642 0.249642)
							(end 0.2794 0.1778)
						)
						(arc
							(start 0.2794 -0.1778)
							(mid 0.249642 -0.249642)
							(end 0.1778 -0.2794)
						)
					)
					(width 0)
					(fill yes)
				)
			)
		)
	)
	(footprint ""
		(layer "F.Cu")
		(at 118.382796 -62.270894)
		(property "Reference" "R750"
			(at 0 0 0)
			(layer "F.SilkS")
			(hide yes)
			(effects
				(font
					(size 1.27 1.27)
				)
			)
		)
		(property "Value" "2R6F-GP"
			(at -0.0508 -4.8514 0)
			(unlocked yes)
			(layer "F.Fab")
			(hide yes)
			(effects
				(font
					(size 1.016 1.016)
					(thickness 0.1524)
				)
			)
		)
		(property "Device Type" "R1206H26"
			(at 0 -6.3754 0)
			(unlocked yes)
			(layer "F.Fab")
			(hide yes)
			(effects
				(font
					(size 1.016 1.016)
					(thickness 0.1524)
				)
			)
		)
		(duplicate_pad_numbers_are_jumpers no)
		(fp_line
			(start -1.016 -2.2352)
			(end 1.016 -2.2352)
			(stroke
				(width 0.1524)
				(type default)
			)
			(layer "F.SilkS")
		)
		(fp_line
			(start -1.016 2.2352)
			(end -1.016 -2.2352)
			(stroke
				(width 0.1524)
				(type default)
			)
			(layer "F.SilkS")
		)
		(fp_line
			(start 1.016 -2.2352)
			(end 1.016 2.2352)
			(stroke
				(width 0.1524)
				(type default)
			)
			(layer "F.SilkS")
		)
		(fp_line
			(start 1.016 2.2352)
			(end -1.016 2.2352)
			(stroke
				(width 0.1524)
				(type default)
			)
			(layer "F.SilkS")
		)
		(fp_rect
			(start -1.0922 2.3114)
			(end 1.0922 -2.3114)
			(stroke
				(width 0)
				(type default)
			)
			(fill no)
			(layer "F.CrtYd")
		)
		(fp_poly
			(pts
				(xy -1.0922 -2.3114) (xy 1.0922 -2.3114) (xy 1.0922 2.3114) (xy -1.0922 2.3114)
			)
			(stroke
				(width 0)
				(type default)
			)
			(fill no)
			(layer "F.Fab")
		)
		(pad "1" smd rect
			(at 0 -1.397)
			(size 1.651 1.27)
			(layers "F.Cu" "F.Mask" "F.Paste")
			(net "P5V_HDD27")
		)
		(pad "2" smd rect
			(at 0 1.397)
			(size 1.651 1.27)
			(layers "F.Cu" "F.Mask" "F.Paste")
			(net "5V_PRE_27")
		)
	)
	(footprint ""
		(layer "F.Cu")
		(at 475.149926 -61.000894 -90)
		(property "Reference" "C496"
			(at 0 0 270)
			(layer "F.SilkS")
			(hide yes)
			(effects
				(font
					(size 1.27 1.27)
				)
			)
		)
		(property "Value" "SC10U16V6KX-2GP"
			(at -0.0762 -5.1308 270)
			(unlocked yes)
			(layer "F.Fab")
			(hide yes)
			(effects
				(font
					(size 1.016 1.016)
					(thickness 0.1524)
				)
			)
		)
		(property "Device Type" "C1206H71"
			(at -0.127 -6.6548 270)
			(unlocked yes)
			(layer "F.Fab")
			(hide yes)
			(effects
				(font
					(size 1.016 1.016)
					(thickness 0.1524)
				)
			)
		)
		(duplicate_pad_numbers_are_jumpers no)
		(fp_line
			(start -1.016 2.2352)
			(end -1.016 0.8382)
			(stroke
				(width 0.1524)
				(type default)
			)
			(layer "F.SilkS")
		)
		(fp_line
			(start 1.016 2.2352)
			(end -1.016 2.2352)
			(stroke
				(width 0.1524)
				(type default)
			)
			(layer "F.SilkS")
		)
		(fp_line
			(start 1.016 0.8382)
			(end 1.016 2.2352)
			(stroke
				(width 0.1524)
				(type default)
			)
			(layer "F.SilkS")
		)
		(fp_line
			(start -1.016 -0.8382)
			(end -1.016 -2.2352)
			(stroke
				(width 0.1524)
				(type default)
			)
			(layer "F.SilkS")
		)
		(fp_line
			(start -1.016 -2.2352)
			(end 1.016 -2.2352)
			(stroke
				(width 0.1524)
				(type default)
			)
			(layer "F.SilkS")
		)
		(fp_line
			(start 1.016 -2.2352)
			(end 1.016 -0.8382)
			(stroke
				(width 0.1524)
				(type default)
			)
			(layer "F.SilkS")
		)
		(fp_rect
			(start -1.0922 2.3114)
			(end 1.0922 -2.3114)
			(stroke
				(width 0)
				(type default)
			)
			(fill no)
			(layer "F.CrtYd")
		)
		(fp_poly
			(pts
				(xy 1.0922 -2.3114) (xy 1.0922 2.3114) (xy -1.0922 2.3114) (xy -1.0922 -2.3114)
			)
			(stroke
				(width 0)
				(type default)
			)
			(fill no)
			(layer "F.Fab")
		)
		(pad "1" smd rect
			(at 0 -1.397 270)
			(size 1.651 1.27)
			(layers "F.Cu" "F.Mask" "F.Paste")
			(net "P5V_HDD35")
		)
		(pad "2" smd rect
			(at 0 1.397 270)
			(size 1.651 1.27)
			(layers "F.Cu" "F.Mask" "F.Paste")
			(net "GND")
		)
	)
	(footprint ""
		(layer "F.Cu")
		(at 287.83661 -357.705152 -90)
		(property "Reference" "SAS1"
			(at 0 0 270)
			(layer "F.SilkS")
			(hide yes)
			(effects
				(font
					(size 1.27 1.27)
				)
			)
		)
		(property "Value" "AMP-CONN342-10R-2-GP"
			(at 20.955 -16.7386 270)
			(unlocked yes)
			(layer "F.Fab")
			(hide yes)
			(effects
				(font
					(size 1.016 1.016)
					(thickness 0.1524)
				)
			)
		)
		(property "Device Type" "PREFIT-342P-668151H483"
			(at 20.955 -18.2626 270)
			(unlocked yes)
			(layer "F.Fab")
			(hide yes)
			(effects
				(font
					(size 1.016 1.016)
					(thickness 0.1524)
				)
			)
		)
		(duplicate_pad_numbers_are_jumpers no)
		(fp_line
			(start 65.3923 13.0048)
			(end -1.9431 13.0048)
			(stroke
				(width 0.1524)
				(type default)
			)
			(layer "F.SilkS")
		)
		(fp_line
			(start 0.381 -1.905)
			(end 1.397 -1.905)
			(stroke
				(width 0.1524)
				(type default)
			)
			(layer "F.SilkS")
		)
		(fp_line
			(start 0.381 -1.905)
			(end 0.381 -2.6162)
			(stroke
				(width 0.1524)
				(type default)
			)
			(layer "F.SilkS")
		)
		(fp_line
			(start 1.397 -1.905)
			(end 1.397 -2.6162)
			(stroke
				(width 0.1524)
				(type default)
			)
			(layer "F.SilkS")
		)
		(fp_line
			(start -1.9431 -2.6162)
			(end -1.9431 13.0048)
			(stroke
				(width 0.1524)
				(type default)
			)
			(layer "F.SilkS")
		)
		(fp_line
			(start 0.381 -2.6162)
			(end -1.9431 -2.6162)
			(stroke
				(width 0.1524)
				(type default)
			)
			(layer "F.SilkS")
		)
		(fp_line
			(start 1.397 -2.6162)
			(end 65.3923 -2.6162)
			(stroke
				(width 0.1524)
				(type default)
			)
			(layer "F.SilkS")
		)
		(fp_line
			(start 65.3923 -2.6162)
			(end 65.3923 13.0048)
			(stroke
				(width 0.1524)
				(type default)
			)
			(layer "F.SilkS")
		)
		(fp_poly
			(pts
				(xy -1.9431 13.0048) (xy -1.9431 -2.6162) (xy 0.381 -2.6162) (xy 0.381 -1.905) (xy 1.397 -1.905)
				(xy 1.397 -2.6162) (xy 26.035 -2.6162) (xy 26.035 -0.735076) (xy -0.635 -0.735076) (xy -0.635 11.335004)
				(xy 64.77 11.335004) (xy 64.77 -0.735076) (xy 36.957 -0.735076) (xy 36.957 -2.6162) (xy 65.3923 -2.6162)
				(xy 65.3923 13.0048)
			)
			(stroke
				(width 0)
				(type default)
			)
			(fill yes)
			(layer "F.SilkS")
		)
		(fp_poly
			(pts
				(arc
					(start 64.516 10.414)
					(mid 64.262 10.668)
					(end 64.008 10.414)
				)
				(arc
					(start 64.008 10.16)
					(mid 64.262 9.906)
					(end 64.516 10.16)
				)
			)
			(stroke
				(width 0)
				(type default)
			)
			(fill yes)
			(layer "F.SilkS")
		)
		(fp_poly
			(pts
				(arc
					(start 64.516 9.144)
					(mid 64.262 9.398)
					(end 64.008 9.144)
				)
				(arc
					(start 64.008 8.89)
					(mid 64.262 8.636)
					(end 64.516 8.89)
				)
			)
			(stroke
				(width 0)
				(type default)
			)
			(fill yes)
			(layer "F.SilkS")
		)
		(fp_poly
			(pts
				(arc
					(start 64.516 7.874)
					(mid 64.262 8.128)
					(end 64.008 7.874)
				)
				(arc
					(start 64.008 7.62)
					(mid 64.262 7.366)
					(end 64.516 7.62)
				)
			)
			(stroke
				(width 0)
				(type default)
			)
			(fill yes)
			(layer "F.SilkS")
		)
		(fp_poly
			(pts
				(arc
					(start 64.516 6.604)
					(mid 64.262 6.858)
					(end 64.008 6.604)
				)
				(arc
					(start 64.008 6.35)
					(mid 64.262 6.096)
					(end 64.516 6.35)
				)
			)
			(stroke
				(width 0)
				(type default)
			)
			(fill yes)
			(layer "F.SilkS")
		)
		(fp_poly
			(pts
				(arc
					(start 64.516 5.334)
					(mid 64.262 5.588)
					(end 64.008 5.334)
				)
				(arc
					(start 64.008 5.08)
					(mid 64.262 4.826)
					(end 64.516 5.08)
				)
			)
			(stroke
				(width 0)
				(type default)
			)
			(fill yes)
			(layer "F.SilkS")
		)
		(fp_poly
			(pts
				(arc
					(start 64.516 4.064)
					(mid 64.262 4.318)
					(end 64.008 4.064)
				)
				(arc
					(start 64.008 3.81)
					(mid 64.262 3.556)
					(end 64.516 3.81)
				)
			)
			(stroke
				(width 0)
				(type default)
			)
			(fill yes)
			(layer "F.SilkS")
		)
		(fp_poly
			(pts
				(arc
					(start 64.516 2.794)
					(mid 64.262 3.048)
					(end 64.008 2.794)
				)
				(arc
					(start 64.008 2.54)
					(mid 64.262 2.286)
					(end 64.516 2.54)
				)
			)
			(stroke
				(width 0)
				(type default)
			)
			(fill yes)
			(layer "F.SilkS")
		)
		(fp_poly
			(pts
				(arc
					(start 64.516 1.524)
					(mid 64.262 1.778)
					(end 64.008 1.524)
				)
				(arc
					(start 64.008 1.27)
					(mid 64.262 1.016)
					(end 64.516 1.27)
				)
			)
			(stroke
				(width 0)
				(type default)
			)
			(fill yes)
			(layer "F.SilkS")
		)
		(fp_poly
			(pts
				(arc
					(start 64.516 0.254)
					(mid 64.262 0.508)
					(end 64.008 0.254)
				)
				(arc
					(start 64.008 0)
					(mid 64.262 -0.254)
					(end 64.516 0)
				)
			)
			(stroke
				(width 0)
				(type default)
			)
			(fill yes)
			(layer "F.SilkS")
		)
		(fp_rect
			(start -5.3848 16.0782)
			(end 68.3768 -5.4864)
			(stroke
				(width 0)
				(type default)
			)
			(fill no)
			(layer "B.CrtYd")
		)
		(fp_rect
			(start -1.6891 12.7508)
			(end 65.1383 -2.3622)
			(stroke
				(width 0)
				(type default)
			)
			(fill no)
			(layer "F.CrtYd")
		)
		(fp_poly
			(pts
				(xy -6.6929 17.7546) (xy -6.6929 -7.366) (xy 70.1421 -7.366) (xy 70.1421 0) (xy 65.6463 0) (xy 65.6463 -2.8702)
				(xy -2.1971 -2.8702) (xy -2.1971 13.2588) (xy 65.6463 13.2588) (xy 65.6463 0.0127) (xy 70.1421 0.0127)
				(xy 70.1421 17.7546)
			)
			(stroke
				(width 0)
				(type default)
			)
			(fill no)
			(layer "F.CrtYd")
		)
		(fp_poly
			(pts
				(xy -2.1971 13.2588) (xy -2.1971 -2.8702) (xy 65.6463 -2.8702) (xy 65.6463 0) (xy 65.1383 0) (xy 65.1383 -2.3622)
				(xy -1.6891 -2.3622) (xy -1.6891 12.7508) (xy 65.1383 12.7508) (xy 65.1383 0.0127) (xy 65.6463 0.0127)
				(xy 65.6463 13.2588)
			)
			(stroke
				(width 0)
				(type default)
			)
			(fill no)
			(layer "F.CrtYd")
		)
		(fp_rect
			(start -10.3886 21.082)
			(end 73.3806 -10.4902)
			(stroke
				(width 0)
				(type default)
			)
			(fill no)
			(layer "B.Fab")
		)
		(fp_rect
			(start -5.3848 16.0782)
			(end 68.3768 -5.4864)
			(stroke
				(width 0)
				(type default)
			)
			(fill no)
			(layer "B.Fab")
		)
		(fp_rect
			(start -11.6967 22.7584)
			(end 75.1459 -12.3698)
			(stroke
				(width 0)
				(type default)
			)
			(fill no)
			(layer "F.Fab")
		)
		(fp_rect
			(start -6.6929 17.7546)
			(end 70.1421 -7.366)
			(stroke
				(width 0)
				(type default)
			)
			(fill no)
			(layer "F.Fab")
		)
		(fp_rect
			(start -2.1971 13.2588)
			(end 65.6463 -2.8702)
			(stroke
				(width 0)
				(type default)
			)
			(fill no)
			(layer "F.Fab")
		)
		(fp_text user "Press Fit"
			(at 26.416 -1.6002 270)
			(unlocked yes)
			(layer "F.SilkS")
			(effects
				(font
					(size 1.016 1.016)
					(thickness 0.1524)
				)
				(justify left)
			)
		)
		(fp_text user "Can not place BGA,CSP,Wave Solder Component"
			(at 6.985 18.8468 270)
			(unlocked yes)
			(layer "B.Fab")
			(effects
				(font
					(size 1.016 1.016)
					(thickness 0.1524)
				)
				(justify left)
			)
		)
		(fp_text user "Can not place BGA,CSP,Wave Solder Component"
			(at 7.62 20.4978 270)
			(unlocked yes)
			(layer "F.Fab")
			(effects
				(font
					(size 1.016 1.016)
					(thickness 0.1524)
				)
				(justify left)
			)
		)
		(fp_text user "High Limit 2mm"
			(at 24.003 15.5448 270)
			(unlocked yes)
			(layer "F.Fab")
			(effects
				(font
					(size 1.016 1.016)
					(thickness 0.1524)
				)
				(justify left)
			)
		)
		(pad "A1" thru_hole circle
			(at 0 0 270)
			(size 0.762 0.762)
			(drill 0.359918)
			(layers "*.Cu" "*.Mask")
			(remove_unused_layers no)
			(net "PHY_DRV_A_TO_SCC_A_0_DN")
			(clearance 0.1651)
			(thermal_gap 0.1651)
		)
		(pad "A2" thru_hole circle
			(at 1.800098 0.999998 270)
			(size 0.762 0.762)
			(drill 0.359918)
			(layers "*.Cu" "*.Mask")
			(remove_unused_layers no)
			(net "PHY_DRV_A_TO_SCC_A_1_DN")
			(clearance 0.1651)
			(thermal_gap 0.1651)
		)
		(pad "A3" thru_hole circle
			(at 3.599942 0 270)
			(size 0.762 0.762)
			(drill 0.359918)
			(layers "*.Cu" "*.Mask")
			(remove_unused_layers no)
			(net "PHY_DRV_A_TO_SCC_A_2_DN")
			(clearance 0.1651)
			(thermal_gap 0.1651)
		)
		(pad "A4" thru_hole circle
			(at 5.40004 0.999998 270)
			(size 0.762 0.762)
			(drill 0.359918)
			(layers "*.Cu" "*.Mask")
			(remove_unused_layers no)
			(net "PHY_DRV_A_TO_SCC_A_3_DN")
			(clearance 0.1651)
			(thermal_gap 0.1651)
		)
		(pad "A5" thru_hole circle
			(at 7.199884 0 270)
			(size 0.762 0.762)
			(drill 0.359918)
			(layers "*.Cu" "*.Mask")
			(remove_unused_layers no)
			(net "PHY_DRV_A_TO_SCC_A_4_DN")
			(clearance 0.1651)
			(thermal_gap 0.1651)
		)
		(pad "A6" thru_hole circle
			(at 8.999982 0.999998 270)
			(size 0.762 0.762)
			(drill 0.359918)
			(layers "*.Cu" "*.Mask")
			(remove_unused_layers no)
			(net "PHY_DRV_A_TO_SCC_A_5_DN")
			(clearance 0.1651)
			(thermal_gap 0.1651)
		)
		(pad "A7" thru_hole circle
			(at 10.80008 0 270)
			(size 0.762 0.762)
			(drill 0.359918)
			(layers "*.Cu" "*.Mask")
			(remove_unused_layers no)
			(net "PHY_DRV_A_TO_SCC_A_11_DN")
			(clearance 0.1651)
			(thermal_gap 0.1651)
		)
		(pad "A8" thru_hole circle
			(at 12.599924 0.999998 270)
			(size 0.762 0.762)
			(drill 0.359918)
			(layers "*.Cu" "*.Mask")
			(remove_unused_layers no)
			(net "PHY_DRV_A_TO_SCC_A_10_DN")
			(clearance 0.1651)
			(thermal_gap 0.1651)
		)
		(pad "A9" thru_hole circle
			(at 14.400022 0 270)
			(size 0.762 0.762)
			(drill 0.359918)
			(layers "*.Cu" "*.Mask")
			(remove_unused_layers no)
			(net "PHY_DRV_A_TO_SCC_A_9_DN")
			(clearance 0.1651)
			(thermal_gap 0.1651)
		)
		(pad "A10" thru_hole circle
			(at 16.20012 0.999998 270)
			(size 0.762 0.762)
			(drill 0.359918)
			(layers "*.Cu" "*.Mask")
			(remove_unused_layers no)
			(net "PHY_DRV_A_TO_SCC_A_8_DN")
			(clearance 0.1651)
			(thermal_gap 0.1651)
		)
		(pad "A11" thru_hole circle
			(at 17.999964 0 270)
			(size 0.762 0.762)
			(drill 0.359918)
			(layers "*.Cu" "*.Mask")
			(remove_unused_layers no)
			(net "PHY_DRV_A_TO_SCC_A_7_DN")
			(clearance 0.1651)
			(thermal_gap 0.1651)
		)
		(pad "A12" thru_hole circle
			(at 19.800062 0.999998 270)
			(size 0.762 0.762)
			(drill 0.359918)
			(layers "*.Cu" "*.Mask")
			(remove_unused_layers no)
			(net "PHY_DRV_A_TO_SCC_A_6_DN")
			(clearance 0.1651)
			(thermal_gap 0.1651)
		)
		(pad "A13" thru_hole circle
			(at 21.599906 0 270)
			(size 0.762 0.762)
			(drill 0.359918)
			(layers "*.Cu" "*.Mask")
			(remove_unused_layers no)
			(net "PHY_DRV_A_TO_SCC_A_12_DN")
			(clearance 0.1651)
			(thermal_gap 0.1651)
		)
		(pad "A14" thru_hole circle
			(at 23.400004 0.999998 270)
			(size 0.762 0.762)
			(drill 0.359918)
			(layers "*.Cu" "*.Mask")
			(remove_unused_layers no)
			(net "PHY_DRV_A_TO_SCC_A_13_DN")
			(clearance 0.1651)
			(thermal_gap 0.1651)
		)
		(pad "A15" thru_hole circle
			(at 25.200102 0 270)
			(size 0.762 0.762)
			(drill 0.359918)
			(layers "*.Cu" "*.Mask")
			(remove_unused_layers no)
			(net "PHY_DRV_A_TO_SCC_A_14_DN")
			(clearance 0.1651)
			(thermal_gap 0.1651)
		)
		(pad "A16" thru_hole circle
			(at 26.999946 0.999998 270)
			(size 0.762 0.762)
			(drill 0.359918)
			(layers "*.Cu" "*.Mask")
			(remove_unused_layers no)
			(net "PHY_DRV_A_TO_SCC_A_15_DN")
			(clearance 0.1651)
			(thermal_gap 0.1651)
		)
		(pad "A17" thru_hole circle
			(at 28.800044 0 270)
			(size 0.762 0.762)
			(drill 0.359918)
			(layers "*.Cu" "*.Mask")
			(remove_unused_layers no)
			(net "PHY_DRV_A_TO_SCC_A_16_DN")
			(clearance 0.1651)
			(thermal_gap 0.1651)
		)
		(pad "A18" thru_hole circle
			(at 30.599888 0.999998 270)
			(size 0.762 0.762)
			(drill 0.359918)
			(layers "*.Cu" "*.Mask")
			(remove_unused_layers no)
			(net "PHY_DRV_A_TO_SCC_A_17_DN")
			(clearance 0.1651)
			(thermal_gap 0.1651)
		)
		(pad "A19" thru_hole circle
			(at 32.399986 0 270)
			(size 0.762 0.762)
			(drill 0.359918)
			(layers "*.Cu" "*.Mask")
			(remove_unused_layers no)
			(net "PHY_DRV_A_TO_SCC_A_23_DN")
			(clearance 0.1651)
			(thermal_gap 0.1651)
		)
		(pad "A20" thru_hole circle
			(at 34.200084 0.999998 270)
			(size 0.762 0.762)
			(drill 0.359918)
			(layers "*.Cu" "*.Mask")
			(remove_unused_layers no)
			(net "PHY_DRV_A_TO_SCC_A_22_DN")
			(clearance 0.1651)
			(thermal_gap 0.1651)
		)
		(pad "A21" thru_hole circle
			(at 35.999928 0 270)
			(size 0.762 0.762)
			(drill 0.359918)
			(layers "*.Cu" "*.Mask")
			(remove_unused_layers no)
			(net "PHY_DRV_A_TO_SCC_A_21_DN")
			(clearance 0.1651)
			(thermal_gap 0.1651)
		)
		(pad "A22" thru_hole circle
			(at 37.800026 0.999998 270)
			(size 0.762 0.762)
			(drill 0.359918)
			(layers "*.Cu" "*.Mask")
			(remove_unused_layers no)
			(net "PHY_DRV_A_TO_SCC_A_20_DN")
			(clearance 0.1651)
			(thermal_gap 0.1651)
		)
		(pad "A23" thru_hole circle
			(at 39.600124 0 270)
			(size 0.762 0.762)
			(drill 0.359918)
			(layers "*.Cu" "*.Mask")
			(remove_unused_layers no)
			(net "PHY_DRV_A_TO_SCC_A_19_DN")
			(clearance 0.1651)
			(thermal_gap 0.1651)
		)
		(pad "A24" thru_hole circle
			(at 41.399968 0.999998 270)
			(size 0.762 0.762)
			(drill 0.359918)
			(layers "*.Cu" "*.Mask")
			(remove_unused_layers no)
			(net "PHY_DRV_A_TO_SCC_A_18_DN")
			(clearance 0.1651)
			(thermal_gap 0.1651)
		)
		(pad "A25" thru_hole circle
			(at 43.200066 0 270)
			(size 0.762 0.762)
			(drill 0.359918)
			(layers "*.Cu" "*.Mask")
			(remove_unused_layers no)
			(net "PHY_DRV_A_TO_SCC_A_24_DN")
			(clearance 0.1651)
			(thermal_gap 0.1651)
		)
		(pad "A26" thru_hole circle
			(at 44.99991 0.999998 270)
			(size 0.762 0.762)
			(drill 0.359918)
			(layers "*.Cu" "*.Mask")
			(remove_unused_layers no)
			(net "PHY_DRV_A_TO_SCC_A_25_DN")
			(clearance 0.1651)
			(thermal_gap 0.1651)
		)
		(pad "A27" thru_hole circle
			(at 46.800008 0 270)
			(size 0.762 0.762)
			(drill 0.359918)
			(layers "*.Cu" "*.Mask")
			(remove_unused_layers no)
			(net "PHY_DRV_A_TO_SCC_A_26_DN")
			(clearance 0.1651)
			(thermal_gap 0.1651)
		)
		(pad "A28" thru_hole circle
			(at 48.600106 0.999998 270)
			(size 0.762 0.762)
			(drill 0.359918)
			(layers "*.Cu" "*.Mask")
			(remove_unused_layers no)
			(net "PHY_DRV_A_TO_SCC_A_27_DN")
			(clearance 0.1651)
			(thermal_gap 0.1651)
		)
		(pad "A29" thru_hole circle
			(at 50.39995 0 270)
			(size 0.762 0.762)
			(drill 0.359918)
			(layers "*.Cu" "*.Mask")
			(remove_unused_layers no)
			(net "PHY_DRV_A_TO_SCC_A_28_DN")
			(clearance 0.1651)
			(thermal_gap 0.1651)
		)
		(pad "A30" thru_hole circle
			(at 52.200048 0.999998 270)
			(size 0.762 0.762)
			(drill 0.359918)
			(layers "*.Cu" "*.Mask")
			(remove_unused_layers no)
			(net "PHY_DRV_A_TO_SCC_A_29_DN")
			(clearance 0.1651)
			(thermal_gap 0.1651)
		)
		(pad "A31" thru_hole circle
			(at 53.999892 0 270)
			(size 0.762 0.762)
			(drill 0.359918)
			(layers "*.Cu" "*.Mask")
			(remove_unused_layers no)
			(net "PHY_DRV_A_TO_SCC_A_35_DN")
			(clearance 0.1651)
			(thermal_gap 0.1651)
		)
		(pad "A32" thru_hole circle
			(at 55.79999 0.999998 270)
			(size 0.762 0.762)
			(drill 0.359918)
			(layers "*.Cu" "*.Mask")
			(remove_unused_layers no)
			(net "PHY_DRV_A_TO_SCC_A_34_DN")
			(clearance 0.1651)
			(thermal_gap 0.1651)
		)
		(pad "A33" thru_hole circle
			(at 57.600088 0 270)
			(size 0.762 0.762)
			(drill 0.359918)
			(layers "*.Cu" "*.Mask")
			(remove_unused_layers no)
			(net "PHY_DRV_A_TO_SCC_A_33_DN")
			(clearance 0.1651)
			(thermal_gap 0.1651)
		)
		(pad "A34" thru_hole circle
			(at 59.399932 0.999998 270)
			(size 0.762 0.762)
			(drill 0.359918)
			(layers "*.Cu" "*.Mask")
			(remove_unused_layers no)
			(net "PHY_DRV_A_TO_SCC_A_32_DN")
			(clearance 0.1651)
			(thermal_gap 0.1651)
		)
		(pad "A35" thru_hole circle
			(at 61.20003 0 270)
			(size 0.762 0.762)
			(drill 0.359918)
			(layers "*.Cu" "*.Mask")
			(remove_unused_layers no)
			(net "PHY_DRV_A_TO_SCC_A_31_DN")
			(clearance 0.1651)
			(thermal_gap 0.1651)
		)
		(pad "A36" thru_hole circle
			(at 62.999874 0.999998 270)
			(size 0.762 0.762)
			(drill 0.359918)
			(layers "*.Cu" "*.Mask")
			(remove_unused_layers no)
			(net "PHY_DRV_A_TO_SCC_A_30_DN")
			(clearance 0.1651)
			(thermal_gap 0.1651)
		)
		(pad "B1" thru_hole circle
			(at 0 1.400048 270)
			(size 0.762 0.762)
			(drill 0.359918)
			(layers "*.Cu" "*.Mask")
			(remove_unused_layers no)
			(net "PHY_DRV_A_TO_SCC_A_0_DP")
			(clearance 0.1651)
			(thermal_gap 0.1651)
		)
		(pad "B2" thru_hole circle
			(at 1.800098 2.400046 270)
			(size 0.762 0.762)
			(drill 0.359918)
			(layers "*.Cu" "*.Mask")
			(remove_unused_layers no)
			(net "PHY_DRV_A_TO_SCC_A_1_DP")
			(clearance 0.1651)
			(thermal_gap 0.1651)
		)
		(pad "B3" thru_hole circle
			(at 3.599942 1.400048 270)
			(size 0.762 0.762)
			(drill 0.359918)
			(layers "*.Cu" "*.Mask")
			(remove_unused_layers no)
			(net "PHY_DRV_A_TO_SCC_A_2_DP")
			(clearance 0.1651)
			(thermal_gap 0.1651)
		)
		(pad "B4" thru_hole circle
			(at 5.40004 2.400046 270)
			(size 0.762 0.762)
			(drill 0.359918)
			(layers "*.Cu" "*.Mask")
			(remove_unused_layers no)
			(net "PHY_DRV_A_TO_SCC_A_3_DP")
			(clearance 0.1651)
			(thermal_gap 0.1651)
		)
		(pad "B5" thru_hole circle
			(at 7.199884 1.400048 270)
			(size 0.762 0.762)
			(drill 0.359918)
			(layers "*.Cu" "*.Mask")
			(remove_unused_layers no)
			(net "PHY_DRV_A_TO_SCC_A_4_DP")
			(clearance 0.1651)
			(thermal_gap 0.1651)
		)
		(pad "B6" thru_hole circle
			(at 8.999982 2.400046 270)
			(size 0.762 0.762)
			(drill 0.359918)
			(layers "*.Cu" "*.Mask")
			(remove_unused_layers no)
			(net "PHY_DRV_A_TO_SCC_A_5_DP")
			(clearance 0.1651)
			(thermal_gap 0.1651)
		)
		(pad "B7" thru_hole circle
			(at 10.80008 1.400048 270)
			(size 0.762 0.762)
			(drill 0.359918)
			(layers "*.Cu" "*.Mask")
			(remove_unused_layers no)
			(net "PHY_DRV_A_TO_SCC_A_11_DP")
			(clearance 0.1651)
			(thermal_gap 0.1651)
		)
		(pad "B8" thru_hole circle
			(at 12.599924 2.400046 270)
			(size 0.762 0.762)
			(drill 0.359918)
			(layers "*.Cu" "*.Mask")
			(remove_unused_layers no)
			(net "PHY_DRV_A_TO_SCC_A_10_DP")
			(clearance 0.1651)
			(thermal_gap 0.1651)
		)
		(pad "B9" thru_hole circle
			(at 14.400022 1.400048 270)
			(size 0.762 0.762)
			(drill 0.359918)
			(layers "*.Cu" "*.Mask")
			(remove_unused_layers no)
			(net "PHY_DRV_A_TO_SCC_A_9_DP")
			(clearance 0.1651)
			(thermal_gap 0.1651)
		)
		(pad "B10" thru_hole circle
			(at 16.20012 2.400046 270)
			(size 0.762 0.762)
			(drill 0.359918)
			(layers "*.Cu" "*.Mask")
			(remove_unused_layers no)
			(net "PHY_DRV_A_TO_SCC_A_8_DP")
			(clearance 0.1651)
			(thermal_gap 0.1651)
		)
		(pad "B11" thru_hole circle
			(at 17.999964 1.400048 270)
			(size 0.762 0.762)
			(drill 0.359918)
			(layers "*.Cu" "*.Mask")
			(remove_unused_layers no)
			(net "PHY_DRV_A_TO_SCC_A_7_DP")
			(clearance 0.1651)
			(thermal_gap 0.1651)
		)
		(pad "B12" thru_hole circle
			(at 19.800062 2.400046 270)
			(size 0.762 0.762)
			(drill 0.359918)
			(layers "*.Cu" "*.Mask")
			(remove_unused_layers no)
			(net "PHY_DRV_A_TO_SCC_A_6_DP")
			(clearance 0.1651)
			(thermal_gap 0.1651)
		)
		(pad "B13" thru_hole circle
			(at 21.599906 1.400048 270)
			(size 0.762 0.762)
			(drill 0.359918)
			(layers "*.Cu" "*.Mask")
			(remove_unused_layers no)
			(net "PHY_DRV_A_TO_SCC_A_12_DP")
			(clearance 0.1651)
			(thermal_gap 0.1651)
		)
		(pad "B14" thru_hole circle
			(at 23.400004 2.400046 270)
			(size 0.762 0.762)
			(drill 0.359918)
			(layers "*.Cu" "*.Mask")
			(remove_unused_layers no)
			(net "PHY_DRV_A_TO_SCC_A_13_DP")
			(clearance 0.1651)
			(thermal_gap 0.1651)
		)
		(pad "B15" thru_hole circle
			(at 25.200102 1.400048 270)
			(size 0.762 0.762)
			(drill 0.359918)
			(layers "*.Cu" "*.Mask")
			(remove_unused_layers no)
			(net "PHY_DRV_A_TO_SCC_A_14_DP")
			(clearance 0.1651)
			(thermal_gap 0.1651)
		)
		(pad "B16" thru_hole circle
			(at 26.999946 2.400046 270)
			(size 0.762 0.762)
			(drill 0.359918)
			(layers "*.Cu" "*.Mask")
			(remove_unused_layers no)
			(net "PHY_DRV_A_TO_SCC_A_15_DP")
			(clearance 0.1651)
			(thermal_gap 0.1651)
		)
		(pad "B17" thru_hole circle
			(at 28.800044 1.400048 270)
			(size 0.762 0.762)
			(drill 0.359918)
			(layers "*.Cu" "*.Mask")
			(remove_unused_layers no)
			(net "PHY_DRV_A_TO_SCC_A_16_DP")
			(clearance 0.1651)
			(thermal_gap 0.1651)
		)
		(pad "B18" thru_hole circle
			(at 30.599888 2.400046 270)
			(size 0.762 0.762)
			(drill 0.359918)
			(layers "*.Cu" "*.Mask")
			(remove_unused_layers no)
			(net "PHY_DRV_A_TO_SCC_A_17_DP")
			(clearance 0.1651)
			(thermal_gap 0.1651)
		)
		(pad "B19" thru_hole circle
			(at 32.399986 1.400048 270)
			(size 0.762 0.762)
			(drill 0.359918)
			(layers "*.Cu" "*.Mask")
			(remove_unused_layers no)
			(net "PHY_DRV_A_TO_SCC_A_23_DP")
			(clearance 0.1651)
			(thermal_gap 0.1651)
		)
		(pad "B20" thru_hole circle
			(at 34.200084 2.400046 270)
			(size 0.762 0.762)
			(drill 0.359918)
			(layers "*.Cu" "*.Mask")
			(remove_unused_layers no)
			(net "PHY_DRV_A_TO_SCC_A_22_DP")
			(clearance 0.1651)
			(thermal_gap 0.1651)
		)
		(pad "B21" thru_hole circle
			(at 35.999928 1.400048 270)
			(size 0.762 0.762)
			(drill 0.359918)
			(layers "*.Cu" "*.Mask")
			(remove_unused_layers no)
			(net "PHY_DRV_A_TO_SCC_A_21_DP")
			(clearance 0.1651)
			(thermal_gap 0.1651)
		)
		(pad "B22" thru_hole circle
			(at 37.800026 2.400046 270)
			(size 0.762 0.762)
			(drill 0.359918)
			(layers "*.Cu" "*.Mask")
			(remove_unused_layers no)
			(net "PHY_DRV_A_TO_SCC_A_20_DP")
			(clearance 0.1651)
			(thermal_gap 0.1651)
		)
		(pad "B23" thru_hole circle
			(at 39.600124 1.400048 270)
			(size 0.762 0.762)
			(drill 0.359918)
			(layers "*.Cu" "*.Mask")
			(remove_unused_layers no)
			(net "PHY_DRV_A_TO_SCC_A_19_DP")
			(clearance 0.1651)
			(thermal_gap 0.1651)
		)
		(pad "B24" thru_hole circle
			(at 41.399968 2.400046 270)
			(size 0.762 0.762)
			(drill 0.359918)
			(layers "*.Cu" "*.Mask")
			(remove_unused_layers no)
			(net "PHY_DRV_A_TO_SCC_A_18_DP")
			(clearance 0.1651)
			(thermal_gap 0.1651)
		)
		(pad "B25" thru_hole circle
			(at 43.200066 1.400048 270)
			(size 0.762 0.762)
			(drill 0.359918)
			(layers "*.Cu" "*.Mask")
			(remove_unused_layers no)
			(net "PHY_DRV_A_TO_SCC_A_24_DP")
			(clearance 0.1651)
			(thermal_gap 0.1651)
		)
		(pad "B26" thru_hole circle
			(at 44.99991 2.400046 270)
			(size 0.762 0.762)
			(drill 0.359918)
			(layers "*.Cu" "*.Mask")
			(remove_unused_layers no)
			(net "PHY_DRV_A_TO_SCC_A_25_DP")
			(clearance 0.1651)
			(thermal_gap 0.1651)
		)
		(pad "B27" thru_hole circle
			(at 46.800008 1.400048 270)
			(size 0.762 0.762)
			(drill 0.359918)
			(layers "*.Cu" "*.Mask")
			(remove_unused_layers no)
			(net "PHY_DRV_A_TO_SCC_A_26_DP")
			(clearance 0.1651)
			(thermal_gap 0.1651)
		)
		(pad "B28" thru_hole circle
			(at 48.600106 2.400046 270)
			(size 0.762 0.762)
			(drill 0.359918)
			(layers "*.Cu" "*.Mask")
			(remove_unused_layers no)
			(net "PHY_DRV_A_TO_SCC_A_27_DP")
			(clearance 0.1651)
			(thermal_gap 0.1651)
		)
		(pad "B29" thru_hole circle
			(at 50.39995 1.400048 270)
			(size 0.762 0.762)
			(drill 0.359918)
			(layers "*.Cu" "*.Mask")
			(remove_unused_layers no)
			(net "PHY_DRV_A_TO_SCC_A_28_DP")
			(clearance 0.1651)
			(thermal_gap 0.1651)
		)
		(pad "B30" thru_hole circle
			(at 52.200048 2.400046 270)
			(size 0.762 0.762)
			(drill 0.359918)
			(layers "*.Cu" "*.Mask")
			(remove_unused_layers no)
			(net "PHY_DRV_A_TO_SCC_A_29_DP")
			(clearance 0.1651)
			(thermal_gap 0.1651)
		)
		(pad "B31" thru_hole circle
			(at 53.999892 1.400048 270)
			(size 0.762 0.762)
			(drill 0.359918)
			(layers "*.Cu" "*.Mask")
			(remove_unused_layers no)
			(net "PHY_DRV_A_TO_SCC_A_35_DP")
			(clearance 0.1651)
			(thermal_gap 0.1651)
		)
		(pad "B32" thru_hole circle
			(at 55.79999 2.400046 270)
			(size 0.762 0.762)
			(drill 0.359918)
			(layers "*.Cu" "*.Mask")
			(remove_unused_layers no)
			(net "PHY_DRV_A_TO_SCC_A_34_DP")
			(clearance 0.1651)
			(thermal_gap 0.1651)
		)
		(pad "B33" thru_hole circle
			(at 57.600088 1.400048 270)
			(size 0.762 0.762)
			(drill 0.359918)
			(layers "*.Cu" "*.Mask")
			(remove_unused_layers no)
			(net "PHY_DRV_A_TO_SCC_A_33_DP")
			(clearance 0.1651)
			(thermal_gap 0.1651)
		)
		(pad "B34" thru_hole circle
			(at 59.399932 2.400046 270)
			(size 0.762 0.762)
			(drill 0.359918)
			(layers "*.Cu" "*.Mask")
			(remove_unused_layers no)
			(net "PHY_DRV_A_TO_SCC_A_32_DP")
			(clearance 0.1651)
			(thermal_gap 0.1651)
		)
		(pad "B35" thru_hole circle
			(at 61.20003 1.400048 270)
			(size 0.762 0.762)
			(drill 0.359918)
			(layers "*.Cu" "*.Mask")
			(remove_unused_layers no)
			(net "PHY_DRV_A_TO_SCC_A_31_DP")
			(clearance 0.1651)
			(thermal_gap 0.1651)
		)
		(pad "B36" thru_hole circle
			(at 62.999874 2.400046 270)
			(size 0.762 0.762)
			(drill 0.359918)
			(layers "*.Cu" "*.Mask")
			(remove_unused_layers no)
			(net "PHY_DRV_A_TO_SCC_A_30_DP")
			(clearance 0.1651)
			(thermal_gap 0.1651)
		)
		(pad "C1" thru_hole circle
			(at 0 3.599942 270)
			(size 0.762 0.762)
			(drill 0.359918)
			(layers "*.Cu" "*.Mask")
			(remove_unused_layers no)
			(net "SCC_A_STBY_PGOOD")
			(clearance 0.1651)
			(thermal_gap 0.1651)
		)
		(pad "C2" thru_hole circle
			(at 1.800098 4.59994 270)
			(size 0.762 0.762)
			(drill 0.359918)
			(layers "*.Cu" "*.Mask")
			(remove_unused_layers no)
			(net "P3V3_STBY_A")
			(clearance 0.1651)
			(thermal_gap 0.1651)
		)
		(pad "C3" thru_hole circle
			(at 3.599942 3.599942 270)
			(size 0.762 0.762)
			(drill 0.359918)
			(layers "*.Cu" "*.Mask")
			(remove_unused_layers no)
			(net "SCC_A_HEARTBEAT")
			(clearance 0.1651)
			(thermal_gap 0.1651)
		)
		(pad "C4" thru_hole circle
			(at 5.40004 4.59994 270)
			(size 0.762 0.762)
			(drill 0.359918)
			(layers "*.Cu" "*.Mask")
			(remove_unused_layers no)
			(net "SCC_A_SLOT_ID_0")
			(clearance 0.1651)
			(thermal_gap 0.1651)
		)
		(pad "C5" thru_hole circle
			(at 7.199884 3.599942 270)
			(size 0.762 0.762)
			(drill 0.359918)
			(layers "*.Cu" "*.Mask")
			(remove_unused_layers no)
			(net "SCC_A_TYPE_0")
			(clearance 0.1651)
			(thermal_gap 0.1651)
		)
		(pad "C6" thru_hole circle
			(at 8.999982 4.59994 270)
			(size 0.762 0.762)
			(drill 0.359918)
			(layers "*.Cu" "*.Mask")
			(remove_unused_layers no)
			(net "SCC_A_TYPE_2")
			(clearance 0.1651)
			(thermal_gap 0.1651)
		)
		(pad "C7" thru_hole circle
			(at 10.80008 3.599942 270)
			(size 0.762 0.762)
			(drill 0.359918)
			(layers "*.Cu" "*.Mask")
			(remove_unused_layers no)
			(net "UART_SDB_A_TX")
			(clearance 0.1651)
			(thermal_gap 0.1651)
		)
		(pad "C8" thru_hole circle
			(at 12.599924 4.59994 270)
			(size 0.762 0.762)
			(drill 0.359918)
			(layers "*.Cu" "*.Mask")
			(remove_unused_layers no)
			(net "PWM_SCC_A_ZONE_C")
			(clearance 0.1651)
			(thermal_gap 0.1651)
		)
		(pad "C9" thru_hole circle
			(at 14.400022 3.599942 270)
			(size 0.762 0.762)
			(drill 0.359918)
			(layers "*.Cu" "*.Mask")
			(remove_unused_layers no)
			(net "SCC_A_PWR_LED")
			(clearance 0.1651)
			(thermal_gap 0.1651)
		)
		(pad "C10" thru_hole circle
			(at 16.20012 4.59994 270)
			(size 0.762 0.762)
			(drill 0.359918)
			(layers "*.Cu" "*.Mask")
			(remove_unused_layers no)
			(net "SCC_A_FAULT_LED")
			(clearance 0.1651)
			(thermal_gap 0.1651)
		)
		(pad "C11" thru_hole circle
			(at 17.999964 3.599942 270)
			(size 0.762 0.762)
			(drill 0.359918)
			(layers "*.Cu" "*.Mask")
			(remove_unused_layers no)
			(net "DRIVE_INSERT_ALERT_A_N")
			(clearance 0.1651)
			(thermal_gap 0.1651)
		)
		(pad "C12" thru_hole circle
			(at 19.800062 4.59994 270)
			(size 0.762 0.762)
			(drill 0.359918)
			(layers "*.Cu" "*.Mask")
			(remove_unused_layers no)
			(net "I2C_CLIP_A_SCL")
			(clearance 0.1651)
			(thermal_gap 0.1651)
		)
		(pad "C13" thru_hole circle
			(at 21.599906 3.599942 270)
			(size 0.762 0.762)
			(drill 0.359918)
			(layers "*.Cu" "*.Mask")
			(remove_unused_layers no)
			(net "UART_EXP_A_TX")
			(clearance 0.1651)
			(thermal_gap 0.1651)
		)
		(pad "C14" thru_hole circle
			(at 23.400004 4.59994 270)
			(size 0.762 0.762)
			(drill 0.359918)
			(layers "*.Cu" "*.Mask")
			(remove_unused_layers no)
			(net "I2C_DPB_A_SCL_BUF")
			(clearance 0.1651)
			(thermal_gap 0.1651)
		)
		(pad "C15" thru_hole circle
			(at 25.200102 3.599942 270)
			(size 0.762 0.762)
			(drill 0.359918)
			(layers "*.Cu" "*.Mask")
			(remove_unused_layers no)
			(net "I2C_DRIVE_A_PWR_SCL")
			(clearance 0.1651)
			(thermal_gap 0.1651)
		)
		(pad "C16" thru_hole circle
			(at 26.999946 4.59994 270)
			(size 0.762 0.762)
			(drill 0.359918)
			(layers "*.Cu" "*.Mask")
			(remove_unused_layers no)
			(net "I2C_DRIVE_A_INS_SCL")
			(clearance 0.1651)
			(thermal_gap 0.1651)
		)
		(pad "C17" thru_hole circle
			(at 28.800044 3.599942 270)
			(size 0.762 0.762)
			(drill 0.359918)
			(layers "*.Cu" "*.Mask")
			(remove_unused_layers no)
			(net "I2C_DRIVE_A_FLT_LED_SCL")
			(clearance 0.1651)
			(thermal_gap 0.1651)
		)
		(pad "C18" thru_hole circle
			(at 30.599888 4.59994 270)
			(size 0.762 0.762)
			(drill 0.359918)
			(layers "*.Cu" "*.Mask")
			(remove_unused_layers no)
			(net "DRIVE_A_0_ACT")
			(clearance 0.1651)
			(thermal_gap 0.1651)
		)
		(pad "C19" thru_hole circle
			(at 32.399986 3.599942 270)
			(size 0.762 0.762)
			(drill 0.359918)
			(layers "*.Cu" "*.Mask")
			(remove_unused_layers no)
			(net "DRIVE_A_2_ACT")
			(clearance 0.1651)
			(thermal_gap 0.1651)
		)
		(pad "C20" thru_hole circle
			(at 34.200084 4.59994 270)
			(size 0.762 0.762)
			(drill 0.359918)
			(layers "*.Cu" "*.Mask")
			(remove_unused_layers no)
			(net "DRIVE_A_4_ACT")
			(clearance 0.1651)
			(thermal_gap 0.1651)
		)
		(pad "C21" thru_hole circle
			(at 35.999928 3.599942 270)
			(size 0.762 0.762)
			(drill 0.359918)
			(layers "*.Cu" "*.Mask")
			(remove_unused_layers no)
			(net "DRIVE_A_6_ACT")
			(clearance 0.1651)
			(thermal_gap 0.1651)
		)
		(pad "C22" thru_hole circle
			(at 37.800026 4.59994 270)
			(size 0.762 0.762)
			(drill 0.359918)
			(layers "*.Cu" "*.Mask")
			(remove_unused_layers no)
			(net "DRIVE_A_8_ACT")
			(clearance 0.1651)
			(thermal_gap 0.1651)
		)
		(pad "C23" thru_hole circle
			(at 39.600124 3.599942 270)
			(size 0.762 0.762)
			(drill 0.359918)
			(layers "*.Cu" "*.Mask")
			(remove_unused_layers no)
			(net "DRIVE_A_10_ACT")
			(clearance 0.1651)
			(thermal_gap 0.1651)
		)
		(pad "C24" thru_hole circle
			(at 41.399968 4.59994 270)
			(size 0.762 0.762)
			(drill 0.359918)
			(layers "*.Cu" "*.Mask")
			(remove_unused_layers no)
			(net "DRIVE_A_12_ACT")
			(clearance 0.1651)
			(thermal_gap 0.1651)
		)
		(pad "C25" thru_hole circle
			(at 43.200066 3.599942 270)
			(size 0.762 0.762)
			(drill 0.359918)
			(layers "*.Cu" "*.Mask")
			(remove_unused_layers no)
			(net "DRIVE_A_14_ACT")
			(clearance 0.1651)
			(thermal_gap 0.1651)
		)
		(pad "C26" thru_hole circle
			(at 44.99991 4.59994 270)
			(size 0.762 0.762)
			(drill 0.359918)
			(layers "*.Cu" "*.Mask")
			(remove_unused_layers no)
			(net "DRIVE_A_16_ACT")
			(clearance 0.1651)
			(thermal_gap 0.1651)
		)
		(pad "C27" thru_hole circle
			(at 46.800008 3.599942 270)
			(size 0.762 0.762)
			(drill 0.359918)
			(layers "*.Cu" "*.Mask")
			(remove_unused_layers no)
			(net "DRIVE_A_18_ACT")
			(clearance 0.1651)
			(thermal_gap 0.1651)
		)
		(pad "C28" thru_hole circle
			(at 48.600106 4.59994 270)
			(size 0.762 0.762)
			(drill 0.359918)
			(layers "*.Cu" "*.Mask")
			(remove_unused_layers no)
			(net "DRIVE_A_20_ACT")
			(clearance 0.1651)
			(thermal_gap 0.1651)
		)
		(pad "C29" thru_hole circle
			(at 50.39995 3.599942 270)
			(size 0.762 0.762)
			(drill 0.359918)
			(layers "*.Cu" "*.Mask")
			(remove_unused_layers no)
			(net "DRIVE_A_22_ACT")
			(clearance 0.1651)
			(thermal_gap 0.1651)
		)
		(pad "C30" thru_hole circle
			(at 52.200048 4.59994 270)
			(size 0.762 0.762)
			(drill 0.359918)
			(layers "*.Cu" "*.Mask")
			(remove_unused_layers no)
			(net "DRIVE_A_24_ACT")
			(clearance 0.1651)
			(thermal_gap 0.1651)
		)
		(pad "C31" thru_hole circle
			(at 53.999892 3.599942 270)
			(size 0.762 0.762)
			(drill 0.359918)
			(layers "*.Cu" "*.Mask")
			(remove_unused_layers no)
			(net "DRIVE_A_26_ACT")
			(clearance 0.1651)
			(thermal_gap 0.1651)
		)
		(pad "C32" thru_hole circle
			(at 55.79999 4.59994 270)
			(size 0.762 0.762)
			(drill 0.359918)
			(layers "*.Cu" "*.Mask")
			(remove_unused_layers no)
			(net "DRIVE_A_28_ACT")
			(clearance 0.1651)
			(thermal_gap 0.1651)
		)
		(pad "C33" thru_hole circle
			(at 57.600088 3.599942 270)
			(size 0.762 0.762)
			(drill 0.359918)
			(layers "*.Cu" "*.Mask")
			(remove_unused_layers no)
			(net "DRIVE_A_30_ACT")
			(clearance 0.1651)
			(thermal_gap 0.1651)
		)
		(pad "C34" thru_hole circle
			(at 59.399932 4.59994 270)
			(size 0.762 0.762)
			(drill 0.359918)
			(layers "*.Cu" "*.Mask")
			(remove_unused_layers no)
			(net "DRIVE_A_32_ACT")
			(clearance 0.1651)
			(thermal_gap 0.1651)
		)
		(pad "C35" thru_hole circle
			(at 61.20003 3.599942 270)
			(size 0.762 0.762)
			(drill 0.359918)
			(layers "*.Cu" "*.Mask")
			(remove_unused_layers no)
			(net "DRIVE_A_34_ACT")
			(clearance 0.1651)
			(thermal_gap 0.1651)
		)
		(pad "C36" thru_hole circle
			(at 62.999874 4.59994 270)
			(size 0.762 0.762)
			(drill 0.359918)
			(layers "*.Cu" "*.Mask")
			(remove_unused_layers no)
			(net "SCC_A_HS_EN")
			(clearance 0.1651)
			(thermal_gap 0.1651)
		)
		(pad "D1" thru_hole circle
			(at 0 4.99999 270)
			(size 0.762 0.762)
			(drill 0.359918)
			(layers "*.Cu" "*.Mask")
			(remove_unused_layers no)
			(net "BMC_A_HEARTBEAT")
			(clearance 0.1651)
			(thermal_gap 0.1651)
		)
		(pad "D2" thru_hole circle
			(at 1.800098 5.999988 270)
			(size 0.762 0.762)
			(drill 0.359918)
			(layers "*.Cu" "*.Mask")
			(remove_unused_layers no)
			(net "SCC_A_STBY_PWR_EN")
			(clearance 0.1651)
			(thermal_gap 0.1651)
		)
		(pad "D3" thru_hole circle
			(at 3.599942 4.99999 270)
			(size 0.762 0.762)
			(drill 0.359918)
			(layers "*.Cu" "*.Mask")
			(remove_unused_layers no)
			(net "SCC_B_HEARTBEAT")
			(clearance 0.1651)
			(thermal_gap 0.1651)
		)
		(pad "D4" thru_hole circle
			(at 5.40004 5.999988 270)
			(size 0.762 0.762)
			(drill 0.359918)
			(layers "*.Cu" "*.Mask")
			(remove_unused_layers no)
			(net "SCC_A_SLOT_ID_1")
			(clearance 0.1651)
			(thermal_gap 0.1651)
		)
		(pad "D5" thru_hole circle
			(at 7.199884 4.99999 270)
			(size 0.762 0.762)
			(drill 0.359918)
			(layers "*.Cu" "*.Mask")
			(remove_unused_layers no)
			(net "SCC_A_TYPE_1")
			(clearance 0.1651)
			(thermal_gap 0.1651)
		)
		(pad "D6" thru_hole circle
			(at 8.999982 5.999988 270)
			(size 0.762 0.762)
			(drill 0.359918)
			(layers "*.Cu" "*.Mask")
			(remove_unused_layers no)
			(net "SCC_A_TYPE_3")
			(clearance 0.1651)
			(thermal_gap 0.1651)
		)
		(pad "D7" thru_hole circle
			(at 10.80008 4.99999 270)
			(size 0.762 0.762)
			(drill 0.359918)
			(layers "*.Cu" "*.Mask")
			(remove_unused_layers no)
			(net "UART_SDB_A_RX")
			(clearance 0.1651)
			(thermal_gap 0.1651)
		)
		(pad "D8" thru_hole circle
			(at 12.599924 5.999988 270)
			(size 0.762 0.762)
			(drill 0.359918)
			(layers "*.Cu" "*.Mask")
			(remove_unused_layers no)
			(net "PWM_SCC_A_ZONE_D")
			(clearance 0.1651)
			(thermal_gap 0.1651)
		)
		(pad "D9" thru_hole circle
			(at 14.400022 4.99999 270)
			(size 0.762 0.762)
			(drill 0.359918)
			(layers "*.Cu" "*.Mask")
			(remove_unused_layers no)
			(net "SCC_A_FULL_PWR_EN")
			(clearance 0.1651)
			(thermal_gap 0.1651)
		)
		(pad "D10" thru_hole circle
			(at 16.20012 5.999988 270)
			(size 0.762 0.762)
			(drill 0.359918)
			(layers "*.Cu" "*.Mask")
			(remove_unused_layers no)
			(net "SCC_A_RESET_N")
			(clearance 0.1651)
			(thermal_gap 0.1651)
		)
		(pad "D11" thru_hole circle
			(at 17.999964 4.99999 270)
			(size 0.762 0.762)
			(drill 0.359918)
			(layers "*.Cu" "*.Mask")
			(remove_unused_layers no)
			(net "SCC_A_INS_N")
			(clearance 0.1651)
			(thermal_gap 0.1651)
		)
		(pad "D12" thru_hole circle
			(at 19.800062 5.999988 270)
			(size 0.762 0.762)
			(drill 0.359918)
			(layers "*.Cu" "*.Mask")
			(remove_unused_layers no)
			(net "I2C_CLIP_A_SDA")
			(clearance 0.1651)
			(thermal_gap 0.1651)
		)
		(pad "D13" thru_hole circle
			(at 21.599906 4.99999 270)
			(size 0.762 0.762)
			(drill 0.359918)
			(layers "*.Cu" "*.Mask")
			(remove_unused_layers no)
			(net "UART_EXP_A_RX")
			(clearance 0.1651)
			(thermal_gap 0.1651)
		)
		(pad "D14" thru_hole circle
			(at 23.400004 5.999988 270)
			(size 0.762 0.762)
			(drill 0.359918)
			(layers "*.Cu" "*.Mask")
			(remove_unused_layers no)
			(net "I2C_DPB_A_SDA_BUF")
			(clearance 0.1651)
			(thermal_gap 0.1651)
		)
		(pad "D15" thru_hole circle
			(at 25.200102 4.99999 270)
			(size 0.762 0.762)
			(drill 0.359918)
			(layers "*.Cu" "*.Mask")
			(remove_unused_layers no)
			(net "I2C_DRIVE_A_PWR_SDA")
			(clearance 0.1651)
			(thermal_gap 0.1651)
		)
		(pad "D16" thru_hole circle
			(at 26.999946 5.999988 270)
			(size 0.762 0.762)
			(drill 0.359918)
			(layers "*.Cu" "*.Mask")
			(remove_unused_layers no)
			(net "I2C_DRIVE_A_INS_SDA")
			(clearance 0.1651)
			(thermal_gap 0.1651)
		)
		(pad "D17" thru_hole circle
			(at 28.800044 4.99999 270)
			(size 0.762 0.762)
			(drill 0.359918)
			(layers "*.Cu" "*.Mask")
			(remove_unused_layers no)
			(net "I2C_DRIVE_A_FLT_LED_SDA")
			(clearance 0.1651)
			(thermal_gap 0.1651)
		)
		(pad "D18" thru_hole circle
			(at 30.599888 5.999988 270)
			(size 0.762 0.762)
			(drill 0.359918)
			(layers "*.Cu" "*.Mask")
			(remove_unused_layers no)
			(net "DRIVE_A_1_ACT")
			(clearance 0.1651)
			(thermal_gap 0.1651)
		)
		(pad "D19" thru_hole circle
			(at 32.399986 4.99999 270)
			(size 0.762 0.762)
			(drill 0.359918)
			(layers "*.Cu" "*.Mask")
			(remove_unused_layers no)
			(net "DRIVE_A_3_ACT")
			(clearance 0.1651)
			(thermal_gap 0.1651)
		)
		(pad "D20" thru_hole circle
			(at 34.200084 5.999988 270)
			(size 0.762 0.762)
			(drill 0.359918)
			(layers "*.Cu" "*.Mask")
			(remove_unused_layers no)
			(net "DRIVE_A_5_ACT")
			(clearance 0.1651)
			(thermal_gap 0.1651)
		)
		(pad "D21" thru_hole circle
			(at 35.999928 4.99999 270)
			(size 0.762 0.762)
			(drill 0.359918)
			(layers "*.Cu" "*.Mask")
			(remove_unused_layers no)
			(net "DRIVE_A_7_ACT")
			(clearance 0.1651)
			(thermal_gap 0.1651)
		)
		(pad "D22" thru_hole circle
			(at 37.800026 5.999988 270)
			(size 0.762 0.762)
			(drill 0.359918)
			(layers "*.Cu" "*.Mask")
			(remove_unused_layers no)
			(net "DRIVE_A_9_ACT")
			(clearance 0.1651)
			(thermal_gap 0.1651)
		)
		(pad "D23" thru_hole circle
			(at 39.600124 4.99999 270)
			(size 0.762 0.762)
			(drill 0.359918)
			(layers "*.Cu" "*.Mask")
			(remove_unused_layers no)
			(net "DRIVE_A_11_ACT")
			(clearance 0.1651)
			(thermal_gap 0.1651)
		)
		(pad "D24" thru_hole circle
			(at 41.399968 5.999988 270)
			(size 0.762 0.762)
			(drill 0.359918)
			(layers "*.Cu" "*.Mask")
			(remove_unused_layers no)
			(net "DRIVE_A_13_ACT")
			(clearance 0.1651)
			(thermal_gap 0.1651)
		)
		(pad "D25" thru_hole circle
			(at 43.200066 4.99999 270)
			(size 0.762 0.762)
			(drill 0.359918)
			(layers "*.Cu" "*.Mask")
			(remove_unused_layers no)
			(net "DRIVE_A_15_ACT")
			(clearance 0.1651)
			(thermal_gap 0.1651)
		)
		(pad "D26" thru_hole circle
			(at 44.99991 5.999988 270)
			(size 0.762 0.762)
			(drill 0.359918)
			(layers "*.Cu" "*.Mask")
			(remove_unused_layers no)
			(net "DRIVE_A_17_ACT")
			(clearance 0.1651)
			(thermal_gap 0.1651)
		)
		(pad "D27" thru_hole circle
			(at 46.800008 4.99999 270)
			(size 0.762 0.762)
			(drill 0.359918)
			(layers "*.Cu" "*.Mask")
			(remove_unused_layers no)
			(net "DRIVE_A_19_ACT")
			(clearance 0.1651)
			(thermal_gap 0.1651)
		)
		(pad "D28" thru_hole circle
			(at 48.600106 5.999988 270)
			(size 0.762 0.762)
			(drill 0.359918)
			(layers "*.Cu" "*.Mask")
			(remove_unused_layers no)
			(net "DRIVE_A_21_ACT")
			(clearance 0.1651)
			(thermal_gap 0.1651)
		)
		(pad "D29" thru_hole circle
			(at 50.39995 4.99999 270)
			(size 0.762 0.762)
			(drill 0.359918)
			(layers "*.Cu" "*.Mask")
			(remove_unused_layers no)
			(net "DRIVE_A_23_ACT")
			(clearance 0.1651)
			(thermal_gap 0.1651)
		)
		(pad "D30" thru_hole circle
			(at 52.200048 5.999988 270)
			(size 0.762 0.762)
			(drill 0.359918)
			(layers "*.Cu" "*.Mask")
			(remove_unused_layers no)
			(net "DRIVE_A_25_ACT")
			(clearance 0.1651)
			(thermal_gap 0.1651)
		)
		(pad "D31" thru_hole circle
			(at 53.999892 4.99999 270)
			(size 0.762 0.762)
			(drill 0.359918)
			(layers "*.Cu" "*.Mask")
			(remove_unused_layers no)
			(net "DRIVE_A_27_ACT")
			(clearance 0.1651)
			(thermal_gap 0.1651)
		)
		(pad "D32" thru_hole circle
			(at 55.79999 5.999988 270)
			(size 0.762 0.762)
			(drill 0.359918)
			(layers "*.Cu" "*.Mask")
			(remove_unused_layers no)
			(net "DRIVE_A_29_ACT")
			(clearance 0.1651)
			(thermal_gap 0.1651)
		)
		(pad "D33" thru_hole circle
			(at 57.600088 4.99999 270)
			(size 0.762 0.762)
			(drill 0.359918)
			(layers "*.Cu" "*.Mask")
			(remove_unused_layers no)
			(net "DRIVE_A_31_ACT")
			(clearance 0.1651)
			(thermal_gap 0.1651)
		)
		(pad "D34" thru_hole circle
			(at 59.399932 5.999988 270)
			(size 0.762 0.762)
			(drill 0.359918)
			(layers "*.Cu" "*.Mask")
			(remove_unused_layers no)
			(net "DRIVE_A_33_ACT")
			(clearance 0.1651)
			(thermal_gap 0.1651)
		)
		(pad "D35" thru_hole circle
			(at 61.20003 4.99999 270)
			(size 0.762 0.762)
			(drill 0.359918)
			(layers "*.Cu" "*.Mask")
			(remove_unused_layers no)
			(net "DRIVE_A_35_ACT")
			(clearance 0.1651)
			(thermal_gap 0.1651)
		)
		(pad "D36" thru_hole circle
			(at 62.999874 5.999988 270)
			(size 0.762 0.762)
			(drill 0.359918)
			(layers "*.Cu" "*.Mask")
			(remove_unused_layers no)
			(net "SCC_A_FULL_PGOOD")
			(clearance 0.1651)
			(thermal_gap 0.1651)
		)
		(pad "E1" thru_hole circle
			(at 0 7.199884 270)
			(size 0.762 0.762)
			(drill 0.359918)
			(layers "*.Cu" "*.Mask")
			(remove_unused_layers no)
			(net "PHY_SCC_A_TO_DRV_A_0_DP")
			(clearance 0.1651)
			(thermal_gap 0.1651)
		)
		(pad "E2" thru_hole circle
			(at 1.800098 8.199882 270)
			(size 0.762 0.762)
			(drill 0.359918)
			(layers "*.Cu" "*.Mask")
			(remove_unused_layers no)
			(net "PHY_SCC_A_TO_DRV_A_1_DP")
			(clearance 0.1651)
			(thermal_gap 0.1651)
		)
		(pad "E3" thru_hole circle
			(at 3.599942 7.199884 270)
			(size 0.762 0.762)
			(drill 0.359918)
			(layers "*.Cu" "*.Mask")
			(remove_unused_layers no)
			(net "PHY_SCC_A_TO_DRV_A_2_DP")
			(clearance 0.1651)
			(thermal_gap 0.1651)
		)
		(pad "E4" thru_hole circle
			(at 5.40004 8.199882 270)
			(size 0.762 0.762)
			(drill 0.359918)
			(layers "*.Cu" "*.Mask")
			(remove_unused_layers no)
			(net "PHY_SCC_A_TO_DRV_A_3_DP")
			(clearance 0.1651)
			(thermal_gap 0.1651)
		)
		(pad "E5" thru_hole circle
			(at 7.199884 7.199884 270)
			(size 0.762 0.762)
			(drill 0.359918)
			(layers "*.Cu" "*.Mask")
			(remove_unused_layers no)
			(net "PHY_SCC_A_TO_DRV_A_4_DP")
			(clearance 0.1651)
			(thermal_gap 0.1651)
		)
		(pad "E6" thru_hole circle
			(at 8.999982 8.199882 270)
			(size 0.762 0.762)
			(drill 0.359918)
			(layers "*.Cu" "*.Mask")
			(remove_unused_layers no)
			(net "PHY_SCC_A_TO_DRV_A_5_DP")
			(clearance 0.1651)
			(thermal_gap 0.1651)
		)
		(pad "E7" thru_hole circle
			(at 10.80008 7.199884 270)
			(size 0.762 0.762)
			(drill 0.359918)
			(layers "*.Cu" "*.Mask")
			(remove_unused_layers no)
			(net "PHY_SCC_A_TO_DRV_A_11_DP")
			(clearance 0.1651)
			(thermal_gap 0.1651)
		)
		(pad "E8" thru_hole circle
			(at 12.599924 8.199882 270)
			(size 0.762 0.762)
			(drill 0.359918)
			(layers "*.Cu" "*.Mask")
			(remove_unused_layers no)
			(net "PHY_SCC_A_TO_DRV_A_10_DP")
			(clearance 0.1651)
			(thermal_gap 0.1651)
		)
		(pad "E9" thru_hole circle
			(at 14.400022 7.199884 270)
			(size 0.762 0.762)
			(drill 0.359918)
			(layers "*.Cu" "*.Mask")
			(remove_unused_layers no)
			(net "PHY_SCC_A_TO_DRV_A_9_DP")
			(clearance 0.1651)
			(thermal_gap 0.1651)
		)
		(pad "E10" thru_hole circle
			(at 16.20012 8.199882 270)
			(size 0.762 0.762)
			(drill 0.359918)
			(layers "*.Cu" "*.Mask")
			(remove_unused_layers no)
			(net "PHY_SCC_A_TO_DRV_A_8_DP")
			(clearance 0.1651)
			(thermal_gap 0.1651)
		)
		(pad "E11" thru_hole circle
			(at 17.999964 7.199884 270)
			(size 0.762 0.762)
			(drill 0.359918)
			(layers "*.Cu" "*.Mask")
			(remove_unused_layers no)
			(net "PHY_SCC_A_TO_DRV_A_7_DP")
			(clearance 0.1651)
			(thermal_gap 0.1651)
		)
		(pad "E12" thru_hole circle
			(at 19.800062 8.199882 270)
			(size 0.762 0.762)
			(drill 0.359918)
			(layers "*.Cu" "*.Mask")
			(remove_unused_layers no)
			(net "PHY_SCC_A_TO_DRV_A_6_DP")
			(clearance 0.1651)
			(thermal_gap 0.1651)
		)
		(pad "E13" thru_hole circle
			(at 21.599906 7.199884 270)
			(size 0.762 0.762)
			(drill 0.359918)
			(layers "*.Cu" "*.Mask")
			(remove_unused_layers no)
			(net "PHY_SCC_A_TO_DRV_A_12_DP")
			(clearance 0.1651)
			(thermal_gap 0.1651)
		)
		(pad "E14" thru_hole circle
			(at 23.400004 8.199882 270)
			(size 0.762 0.762)
			(drill 0.359918)
			(layers "*.Cu" "*.Mask")
			(remove_unused_layers no)
			(net "PHY_SCC_A_TO_DRV_A_13_DP")
			(clearance 0.1651)
			(thermal_gap 0.1651)
		)
		(pad "E15" thru_hole circle
			(at 25.200102 7.199884 270)
			(size 0.762 0.762)
			(drill 0.359918)
			(layers "*.Cu" "*.Mask")
			(remove_unused_layers no)
			(net "PHY_SCC_A_TO_DRV_A_14_DP")
			(clearance 0.1651)
			(thermal_gap 0.1651)
		)
		(pad "E16" thru_hole circle
			(at 26.999946 8.199882 270)
			(size 0.762 0.762)
			(drill 0.359918)
			(layers "*.Cu" "*.Mask")
			(remove_unused_layers no)
			(net "PHY_SCC_A_TO_DRV_A_15_DP")
			(clearance 0.1651)
			(thermal_gap 0.1651)
		)
		(pad "E17" thru_hole circle
			(at 28.800044 7.199884 270)
			(size 0.762 0.762)
			(drill 0.359918)
			(layers "*.Cu" "*.Mask")
			(remove_unused_layers no)
			(net "PHY_SCC_A_TO_DRV_A_16_DP")
			(clearance 0.1651)
			(thermal_gap 0.1651)
		)
		(pad "E18" thru_hole circle
			(at 30.599888 8.199882 270)
			(size 0.762 0.762)
			(drill 0.359918)
			(layers "*.Cu" "*.Mask")
			(remove_unused_layers no)
			(net "PHY_SCC_A_TO_DRV_A_17_DP")
			(clearance 0.1651)
			(thermal_gap 0.1651)
		)
		(pad "E19" thru_hole circle
			(at 32.399986 7.199884 270)
			(size 0.762 0.762)
			(drill 0.359918)
			(layers "*.Cu" "*.Mask")
			(remove_unused_layers no)
			(net "PHY_SCC_A_TO_DRV_A_23_DP")
			(clearance 0.1651)
			(thermal_gap 0.1651)
		)
		(pad "E20" thru_hole circle
			(at 34.200084 8.199882 270)
			(size 0.762 0.762)
			(drill 0.359918)
			(layers "*.Cu" "*.Mask")
			(remove_unused_layers no)
			(net "PHY_SCC_A_TO_DRV_A_22_DP")
			(clearance 0.1651)
			(thermal_gap 0.1651)
		)
		(pad "E21" thru_hole circle
			(at 35.999928 7.199884 270)
			(size 0.762 0.762)
			(drill 0.359918)
			(layers "*.Cu" "*.Mask")
			(remove_unused_layers no)
			(net "PHY_SCC_A_TO_DRV_A_21_DP")
			(clearance 0.1651)
			(thermal_gap 0.1651)
		)
		(pad "E22" thru_hole circle
			(at 37.800026 8.199882 270)
			(size 0.762 0.762)
			(drill 0.359918)
			(layers "*.Cu" "*.Mask")
			(remove_unused_layers no)
			(net "PHY_SCC_A_TO_DRV_A_20_DP")
			(clearance 0.1651)
			(thermal_gap 0.1651)
		)
		(pad "E23" thru_hole circle
			(at 39.600124 7.199884 270)
			(size 0.762 0.762)
			(drill 0.359918)
			(layers "*.Cu" "*.Mask")
			(remove_unused_layers no)
			(net "PHY_SCC_A_TO_DRV_A_19_DP")
			(clearance 0.1651)
			(thermal_gap 0.1651)
		)
		(pad "E24" thru_hole circle
			(at 41.399968 8.199882 270)
			(size 0.762 0.762)
			(drill 0.359918)
			(layers "*.Cu" "*.Mask")
			(remove_unused_layers no)
			(net "PHY_SCC_A_TO_DRV_A_18_DP")
			(clearance 0.1651)
			(thermal_gap 0.1651)
		)
		(pad "E25" thru_hole circle
			(at 43.200066 7.199884 270)
			(size 0.762 0.762)
			(drill 0.359918)
			(layers "*.Cu" "*.Mask")
			(remove_unused_layers no)
			(net "PHY_SCC_A_TO_DRV_A_24_DP")
			(clearance 0.1651)
			(thermal_gap 0.1651)
		)
		(pad "E26" thru_hole circle
			(at 44.99991 8.199882 270)
			(size 0.762 0.762)
			(drill 0.359918)
			(layers "*.Cu" "*.Mask")
			(remove_unused_layers no)
			(net "PHY_SCC_A_TO_DRV_A_25_DP")
			(clearance 0.1651)
			(thermal_gap 0.1651)
		)
		(pad "E27" thru_hole circle
			(at 46.800008 7.199884 270)
			(size 0.762 0.762)
			(drill 0.359918)
			(layers "*.Cu" "*.Mask")
			(remove_unused_layers no)
			(net "PHY_SCC_A_TO_DRV_A_26_DP")
			(clearance 0.1651)
			(thermal_gap 0.1651)
		)
		(pad "E28" thru_hole circle
			(at 48.600106 8.199882 270)
			(size 0.762 0.762)
			(drill 0.359918)
			(layers "*.Cu" "*.Mask")
			(remove_unused_layers no)
			(net "PHY_SCC_A_TO_DRV_A_27_DP")
			(clearance 0.1651)
			(thermal_gap 0.1651)
		)
		(pad "E29" thru_hole circle
			(at 50.39995 7.199884 270)
			(size 0.762 0.762)
			(drill 0.359918)
			(layers "*.Cu" "*.Mask")
			(remove_unused_layers no)
			(net "PHY_SCC_A_TO_DRV_A_28_DP")
			(clearance 0.1651)
			(thermal_gap 0.1651)
		)
		(pad "E30" thru_hole circle
			(at 52.200048 8.199882 270)
			(size 0.762 0.762)
			(drill 0.359918)
			(layers "*.Cu" "*.Mask")
			(remove_unused_layers no)
			(net "PHY_SCC_A_TO_DRV_A_29_DP")
			(clearance 0.1651)
			(thermal_gap 0.1651)
		)
		(pad "E31" thru_hole circle
			(at 53.999892 7.199884 270)
			(size 0.762 0.762)
			(drill 0.359918)
			(layers "*.Cu" "*.Mask")
			(remove_unused_layers no)
			(net "PHY_SCC_A_TO_DRV_A_35_DP")
			(clearance 0.1651)
			(thermal_gap 0.1651)
		)
		(pad "E32" thru_hole circle
			(at 55.79999 8.199882 270)
			(size 0.762 0.762)
			(drill 0.359918)
			(layers "*.Cu" "*.Mask")
			(remove_unused_layers no)
			(net "PHY_SCC_A_TO_DRV_A_34_DP")
			(clearance 0.1651)
			(thermal_gap 0.1651)
		)
		(pad "E33" thru_hole circle
			(at 57.600088 7.199884 270)
			(size 0.762 0.762)
			(drill 0.359918)
			(layers "*.Cu" "*.Mask")
			(remove_unused_layers no)
			(net "PHY_SCC_A_TO_DRV_A_33_DP")
			(clearance 0.1651)
			(thermal_gap 0.1651)
		)
		(pad "E34" thru_hole circle
			(at 59.399932 8.199882 270)
			(size 0.762 0.762)
			(drill 0.359918)
			(layers "*.Cu" "*.Mask")
			(remove_unused_layers no)
			(net "PHY_SCC_A_TO_DRV_A_32_DP")
			(clearance 0.1651)
			(thermal_gap 0.1651)
		)
		(pad "E35" thru_hole circle
			(at 61.20003 7.199884 270)
			(size 0.762 0.762)
			(drill 0.359918)
			(layers "*.Cu" "*.Mask")
			(remove_unused_layers no)
			(net "PHY_SCC_A_TO_DRV_A_31_DP")
			(clearance 0.1651)
			(thermal_gap 0.1651)
		)
		(pad "E36" thru_hole circle
			(at 62.999874 8.199882 270)
			(size 0.762 0.762)
			(drill 0.359918)
			(layers "*.Cu" "*.Mask")
			(remove_unused_layers no)
			(net "PHY_SCC_A_TO_DRV_A_30_DP")
			(clearance 0.1651)
			(thermal_gap 0.1651)
		)
		(pad "F1" thru_hole circle
			(at 0 8.599932 270)
			(size 0.762 0.762)
			(drill 0.359918)
			(layers "*.Cu" "*.Mask")
			(remove_unused_layers no)
			(net "PHY_SCC_A_TO_DRV_A_0_DN")
			(clearance 0.1651)
			(thermal_gap 0.1651)
		)
		(pad "F2" thru_hole circle
			(at 1.800098 9.59993 270)
			(size 0.762 0.762)
			(drill 0.359918)
			(layers "*.Cu" "*.Mask")
			(remove_unused_layers no)
			(net "PHY_SCC_A_TO_DRV_A_1_DN")
			(clearance 0.1651)
			(thermal_gap 0.1651)
		)
		(pad "F3" thru_hole circle
			(at 3.599942 8.599932 270)
			(size 0.762 0.762)
			(drill 0.359918)
			(layers "*.Cu" "*.Mask")
			(remove_unused_layers no)
			(net "PHY_SCC_A_TO_DRV_A_2_DN")
			(clearance 0.1651)
			(thermal_gap 0.1651)
		)
		(pad "F4" thru_hole circle
			(at 5.40004 9.59993 270)
			(size 0.762 0.762)
			(drill 0.359918)
			(layers "*.Cu" "*.Mask")
			(remove_unused_layers no)
			(net "PHY_SCC_A_TO_DRV_A_3_DN")
			(clearance 0.1651)
			(thermal_gap 0.1651)
		)
		(pad "F5" thru_hole circle
			(at 7.199884 8.599932 270)
			(size 0.762 0.762)
			(drill 0.359918)
			(layers "*.Cu" "*.Mask")
			(remove_unused_layers no)
			(net "PHY_SCC_A_TO_DRV_A_4_DN")
			(clearance 0.1651)
			(thermal_gap 0.1651)
		)
		(pad "F6" thru_hole circle
			(at 8.999982 9.59993 270)
			(size 0.762 0.762)
			(drill 0.359918)
			(layers "*.Cu" "*.Mask")
			(remove_unused_layers no)
			(net "PHY_SCC_A_TO_DRV_A_5_DN")
			(clearance 0.1651)
			(thermal_gap 0.1651)
		)
		(pad "F7" thru_hole circle
			(at 10.80008 8.599932 270)
			(size 0.762 0.762)
			(drill 0.359918)
			(layers "*.Cu" "*.Mask")
			(remove_unused_layers no)
			(net "PHY_SCC_A_TO_DRV_A_11_DN")
			(clearance 0.1651)
			(thermal_gap 0.1651)
		)
		(pad "F8" thru_hole circle
			(at 12.599924 9.59993 270)
			(size 0.762 0.762)
			(drill 0.359918)
			(layers "*.Cu" "*.Mask")
			(remove_unused_layers no)
			(net "PHY_SCC_A_TO_DRV_A_10_DN")
			(clearance 0.1651)
			(thermal_gap 0.1651)
		)
		(pad "F9" thru_hole circle
			(at 14.400022 8.599932 270)
			(size 0.762 0.762)
			(drill 0.359918)
			(layers "*.Cu" "*.Mask")
			(remove_unused_layers no)
			(net "PHY_SCC_A_TO_DRV_A_9_DN")
			(clearance 0.1651)
			(thermal_gap 0.1651)
		)
		(pad "F10" thru_hole circle
			(at 16.20012 9.59993 270)
			(size 0.762 0.762)
			(drill 0.359918)
			(layers "*.Cu" "*.Mask")
			(remove_unused_layers no)
			(net "PHY_SCC_A_TO_DRV_A_8_DN")
			(clearance 0.1651)
			(thermal_gap 0.1651)
		)
		(pad "F11" thru_hole circle
			(at 17.999964 8.599932 270)
			(size 0.762 0.762)
			(drill 0.359918)
			(layers "*.Cu" "*.Mask")
			(remove_unused_layers no)
			(net "PHY_SCC_A_TO_DRV_A_7_DN")
			(clearance 0.1651)
			(thermal_gap 0.1651)
		)
		(pad "F12" thru_hole circle
			(at 19.800062 9.59993 270)
			(size 0.762 0.762)
			(drill 0.359918)
			(layers "*.Cu" "*.Mask")
			(remove_unused_layers no)
			(net "PHY_SCC_A_TO_DRV_A_6_DN")
			(clearance 0.1651)
			(thermal_gap 0.1651)
		)
		(pad "F13" thru_hole circle
			(at 21.599906 8.599932 270)
			(size 0.762 0.762)
			(drill 0.359918)
			(layers "*.Cu" "*.Mask")
			(remove_unused_layers no)
			(net "PHY_SCC_A_TO_DRV_A_12_DN")
			(clearance 0.1651)
			(thermal_gap 0.1651)
		)
		(pad "F14" thru_hole circle
			(at 23.400004 9.59993 270)
			(size 0.762 0.762)
			(drill 0.359918)
			(layers "*.Cu" "*.Mask")
			(remove_unused_layers no)
			(net "PHY_SCC_A_TO_DRV_A_13_DN")
			(clearance 0.1651)
			(thermal_gap 0.1651)
		)
		(pad "F15" thru_hole circle
			(at 25.200102 8.599932 270)
			(size 0.762 0.762)
			(drill 0.359918)
			(layers "*.Cu" "*.Mask")
			(remove_unused_layers no)
			(net "PHY_SCC_A_TO_DRV_A_14_DN")
			(clearance 0.1651)
			(thermal_gap 0.1651)
		)
		(pad "F16" thru_hole circle
			(at 26.999946 9.59993 270)
			(size 0.762 0.762)
			(drill 0.359918)
			(layers "*.Cu" "*.Mask")
			(remove_unused_layers no)
			(net "PHY_SCC_A_TO_DRV_A_15_DN")
			(clearance 0.1651)
			(thermal_gap 0.1651)
		)
		(pad "F17" thru_hole circle
			(at 28.800044 8.599932 270)
			(size 0.762 0.762)
			(drill 0.359918)
			(layers "*.Cu" "*.Mask")
			(remove_unused_layers no)
			(net "PHY_SCC_A_TO_DRV_A_16_DN")
			(clearance 0.1651)
			(thermal_gap 0.1651)
		)
		(pad "F18" thru_hole circle
			(at 30.599888 9.59993 270)
			(size 0.762 0.762)
			(drill 0.359918)
			(layers "*.Cu" "*.Mask")
			(remove_unused_layers no)
			(net "PHY_SCC_A_TO_DRV_A_17_DN")
			(clearance 0.1651)
			(thermal_gap 0.1651)
		)
		(pad "F19" thru_hole circle
			(at 32.399986 8.599932 270)
			(size 0.762 0.762)
			(drill 0.359918)
			(layers "*.Cu" "*.Mask")
			(remove_unused_layers no)
			(net "PHY_SCC_A_TO_DRV_A_23_DN")
			(clearance 0.1651)
			(thermal_gap 0.1651)
		)
		(pad "F20" thru_hole circle
			(at 34.200084 9.59993 270)
			(size 0.762 0.762)
			(drill 0.359918)
			(layers "*.Cu" "*.Mask")
			(remove_unused_layers no)
			(net "PHY_SCC_A_TO_DRV_A_22_DN")
			(clearance 0.1651)
			(thermal_gap 0.1651)
		)
		(pad "F21" thru_hole circle
			(at 35.999928 8.599932 270)
			(size 0.762 0.762)
			(drill 0.359918)
			(layers "*.Cu" "*.Mask")
			(remove_unused_layers no)
			(net "PHY_SCC_A_TO_DRV_A_21_DN")
			(clearance 0.1651)
			(thermal_gap 0.1651)
		)
		(pad "F22" thru_hole circle
			(at 37.800026 9.59993 270)
			(size 0.762 0.762)
			(drill 0.359918)
			(layers "*.Cu" "*.Mask")
			(remove_unused_layers no)
			(net "PHY_SCC_A_TO_DRV_A_20_DN")
			(clearance 0.1651)
			(thermal_gap 0.1651)
		)
		(pad "F23" thru_hole circle
			(at 39.600124 8.599932 270)
			(size 0.762 0.762)
			(drill 0.359918)
			(layers "*.Cu" "*.Mask")
			(remove_unused_layers no)
			(net "PHY_SCC_A_TO_DRV_A_19_DN")
			(clearance 0.1651)
			(thermal_gap 0.1651)
		)
		(pad "F24" thru_hole circle
			(at 41.399968 9.59993 270)
			(size 0.762 0.762)
			(drill 0.359918)
			(layers "*.Cu" "*.Mask")
			(remove_unused_layers no)
			(net "PHY_SCC_A_TO_DRV_A_18_DN")
			(clearance 0.1651)
			(thermal_gap 0.1651)
		)
		(pad "F25" thru_hole circle
			(at 43.200066 8.599932 270)
			(size 0.762 0.762)
			(drill 0.359918)
			(layers "*.Cu" "*.Mask")
			(remove_unused_layers no)
			(net "PHY_SCC_A_TO_DRV_A_24_DN")
			(clearance 0.1651)
			(thermal_gap 0.1651)
		)
		(pad "F26" thru_hole circle
			(at 44.99991 9.59993 270)
			(size 0.762 0.762)
			(drill 0.359918)
			(layers "*.Cu" "*.Mask")
			(remove_unused_layers no)
			(net "PHY_SCC_A_TO_DRV_A_25_DN")
			(clearance 0.1651)
			(thermal_gap 0.1651)
		)
		(pad "F27" thru_hole circle
			(at 46.800008 8.599932 270)
			(size 0.762 0.762)
			(drill 0.359918)
			(layers "*.Cu" "*.Mask")
			(remove_unused_layers no)
			(net "PHY_SCC_A_TO_DRV_A_26_DN")
			(clearance 0.1651)
			(thermal_gap 0.1651)
		)
		(pad "F28" thru_hole circle
			(at 48.600106 9.59993 270)
			(size 0.762 0.762)
			(drill 0.359918)
			(layers "*.Cu" "*.Mask")
			(remove_unused_layers no)
			(net "PHY_SCC_A_TO_DRV_A_27_DN")
			(clearance 0.1651)
			(thermal_gap 0.1651)
		)
		(pad "F29" thru_hole circle
			(at 50.39995 8.599932 270)
			(size 0.762 0.762)
			(drill 0.359918)
			(layers "*.Cu" "*.Mask")
			(remove_unused_layers no)
			(net "PHY_SCC_A_TO_DRV_A_28_DN")
			(clearance 0.1651)
			(thermal_gap 0.1651)
		)
		(pad "F30" thru_hole circle
			(at 52.200048 9.59993 270)
			(size 0.762 0.762)
			(drill 0.359918)
			(layers "*.Cu" "*.Mask")
			(remove_unused_layers no)
			(net "PHY_SCC_A_TO_DRV_A_29_DN")
			(clearance 0.1651)
			(thermal_gap 0.1651)
		)
		(pad "F31" thru_hole circle
			(at 53.999892 8.599932 270)
			(size 0.762 0.762)
			(drill 0.359918)
			(layers "*.Cu" "*.Mask")
			(remove_unused_layers no)
			(net "PHY_SCC_A_TO_DRV_A_35_DN")
			(clearance 0.1651)
			(thermal_gap 0.1651)
		)
		(pad "F32" thru_hole circle
			(at 55.79999 9.59993 270)
			(size 0.762 0.762)
			(drill 0.359918)
			(layers "*.Cu" "*.Mask")
			(remove_unused_layers no)
			(net "PHY_SCC_A_TO_DRV_A_34_DN")
			(clearance 0.1651)
			(thermal_gap 0.1651)
		)
		(pad "F33" thru_hole circle
			(at 57.600088 8.599932 270)
			(size 0.762 0.762)
			(drill 0.359918)
			(layers "*.Cu" "*.Mask")
			(remove_unused_layers no)
			(net "PHY_SCC_A_TO_DRV_A_33_DN")
			(clearance 0.1651)
			(thermal_gap 0.1651)
		)
		(pad "F34" thru_hole circle
			(at 59.399932 9.59993 270)
			(size 0.762 0.762)
			(drill 0.359918)
			(layers "*.Cu" "*.Mask")
			(remove_unused_layers no)
			(net "PHY_SCC_A_TO_DRV_A_32_DN")
			(clearance 0.1651)
			(thermal_gap 0.1651)
		)
		(pad "F35" thru_hole circle
			(at 61.20003 8.599932 270)
			(size 0.762 0.762)
			(drill 0.359918)
			(layers "*.Cu" "*.Mask")
			(remove_unused_layers no)
			(net "PHY_SCC_A_TO_DRV_A_31_DN")
			(clearance 0.1651)
			(thermal_gap 0.1651)
		)
		(pad "F36" thru_hole circle
			(at 62.999874 9.59993 270)
			(size 0.762 0.762)
			(drill 0.359918)
			(layers "*.Cu" "*.Mask")
			(remove_unused_layers no)
			(net "PHY_SCC_A_TO_DRV_A_30_DN")
			(clearance 0.1651)
			(thermal_gap 0.1651)
		)
		(pad "GND1" thru_hole circle
			(at 0 2.500122 270)
			(size 0.762 0.762)
			(drill 0.359918)
			(layers "*.Cu" "*.Mask")
			(remove_unused_layers no)
			(net "GND")
			(clearance 0.1651)
			(thermal_gap 0.1651)
		)
		(pad "GND2" thru_hole circle
			(at 0 6.100064 270)
			(size 0.762 0.762)
			(drill 0.359918)
			(layers "*.Cu" "*.Mask")
			(remove_unused_layers no)
			(net "GND")
			(clearance 0.1651)
			(thermal_gap 0.1651)
		)
		(pad "GND3" thru_hole circle
			(at 0 9.700006 270)
			(size 0.762 0.762)
			(drill 0.359918)
			(layers "*.Cu" "*.Mask")
			(remove_unused_layers no)
			(net "GND")
			(clearance 0.1651)
			(thermal_gap 0.1651)
		)
		(pad "GND4" thru_hole circle
			(at 1.800098 -0.100076 270)
			(size 0.762 0.762)
			(drill 0.359918)
			(layers "*.Cu" "*.Mask")
			(remove_unused_layers no)
			(net "GND")
			(clearance 0.1651)
			(thermal_gap 0.1651)
		)
		(pad "GND5" thru_hole circle
			(at 1.800098 3.50012 270)
			(size 0.762 0.762)
			(drill 0.359918)
			(layers "*.Cu" "*.Mask")
			(remove_unused_layers no)
			(net "GND")
			(clearance 0.1651)
			(thermal_gap 0.1651)
		)
		(pad "GND6" thru_hole circle
			(at 1.800098 7.100062 270)
			(size 0.762 0.762)
			(drill 0.359918)
			(layers "*.Cu" "*.Mask")
			(remove_unused_layers no)
			(net "GND")
			(clearance 0.1651)
			(thermal_gap 0.1651)
		)
		(pad "GND7" thru_hole circle
			(at 1.800098 10.700004 270)
			(size 0.762 0.762)
			(drill 0.359918)
			(layers "*.Cu" "*.Mask")
			(remove_unused_layers no)
			(net "GND")
			(clearance 0.1651)
			(thermal_gap 0.1651)
		)
		(pad "GND8" thru_hole circle
			(at 3.599942 2.500122 270)
			(size 0.762 0.762)
			(drill 0.359918)
			(layers "*.Cu" "*.Mask")
			(remove_unused_layers no)
			(net "GND")
			(clearance 0.1651)
			(thermal_gap 0.1651)
		)
		(pad "GND9" thru_hole circle
			(at 3.599942 6.100064 270)
			(size 0.762 0.762)
			(drill 0.359918)
			(layers "*.Cu" "*.Mask")
			(remove_unused_layers no)
			(net "GND")
			(clearance 0.1651)
			(thermal_gap 0.1651)
		)
		(pad "GND10" thru_hole circle
			(at 3.599942 9.700006 270)
			(size 0.762 0.762)
			(drill 0.359918)
			(layers "*.Cu" "*.Mask")
			(remove_unused_layers no)
			(net "GND")
			(clearance 0.1651)
			(thermal_gap 0.1651)
		)
		(pad "GND11" thru_hole circle
			(at 5.40004 -0.100076 270)
			(size 0.762 0.762)
			(drill 0.359918)
			(layers "*.Cu" "*.Mask")
			(remove_unused_layers no)
			(net "GND")
			(clearance 0.1651)
			(thermal_gap 0.1651)
		)
		(pad "GND12" thru_hole circle
			(at 5.40004 3.50012 270)
			(size 0.762 0.762)
			(drill 0.359918)
			(layers "*.Cu" "*.Mask")
			(remove_unused_layers no)
			(net "GND")
			(clearance 0.1651)
			(thermal_gap 0.1651)
		)
		(pad "GND13" thru_hole circle
			(at 5.40004 7.100062 270)
			(size 0.762 0.762)
			(drill 0.359918)
			(layers "*.Cu" "*.Mask")
			(remove_unused_layers no)
			(net "GND")
			(clearance 0.1651)
			(thermal_gap 0.1651)
		)
		(pad "GND14" thru_hole circle
			(at 5.40004 10.700004 270)
			(size 0.762 0.762)
			(drill 0.359918)
			(layers "*.Cu" "*.Mask")
			(remove_unused_layers no)
			(net "GND")
			(clearance 0.1651)
			(thermal_gap 0.1651)
		)
		(pad "GND15" thru_hole circle
			(at 7.199884 2.500122 270)
			(size 0.762 0.762)
			(drill 0.359918)
			(layers "*.Cu" "*.Mask")
			(remove_unused_layers no)
			(net "GND")
			(clearance 0.1651)
			(thermal_gap 0.1651)
		)
		(pad "GND16" thru_hole circle
			(at 7.199884 6.100064 270)
			(size 0.762 0.762)
			(drill 0.359918)
			(layers "*.Cu" "*.Mask")
			(remove_unused_layers no)
			(net "GND")
			(clearance 0.1651)
			(thermal_gap 0.1651)
		)
		(pad "GND17" thru_hole circle
			(at 7.199884 9.700006 270)
			(size 0.762 0.762)
			(drill 0.359918)
			(layers "*.Cu" "*.Mask")
			(remove_unused_layers no)
			(net "GND")
			(clearance 0.1651)
			(thermal_gap 0.1651)
		)
		(pad "GND18" thru_hole circle
			(at 8.999982 -0.100076 270)
			(size 0.762 0.762)
			(drill 0.359918)
			(layers "*.Cu" "*.Mask")
			(remove_unused_layers no)
			(net "GND")
			(clearance 0.1651)
			(thermal_gap 0.1651)
		)
		(pad "GND19" thru_hole circle
			(at 8.999982 3.50012 270)
			(size 0.762 0.762)
			(drill 0.359918)
			(layers "*.Cu" "*.Mask")
			(remove_unused_layers no)
			(net "GND")
			(clearance 0.1651)
			(thermal_gap 0.1651)
		)
		(pad "GND20" thru_hole circle
			(at 8.999982 7.100062 270)
			(size 0.762 0.762)
			(drill 0.359918)
			(layers "*.Cu" "*.Mask")
			(remove_unused_layers no)
			(net "GND")
			(clearance 0.1651)
			(thermal_gap 0.1651)
		)
		(pad "GND21" thru_hole circle
			(at 8.999982 10.700004 270)
			(size 0.762 0.762)
			(drill 0.359918)
			(layers "*.Cu" "*.Mask")
			(remove_unused_layers no)
			(net "GND")
			(clearance 0.1651)
			(thermal_gap 0.1651)
		)
		(pad "GND22" thru_hole circle
			(at 10.80008 2.500122 270)
			(size 0.762 0.762)
			(drill 0.359918)
			(layers "*.Cu" "*.Mask")
			(remove_unused_layers no)
			(net "GND")
			(clearance 0.1651)
			(thermal_gap 0.1651)
		)
		(pad "GND23" thru_hole circle
			(at 10.80008 6.100064 270)
			(size 0.762 0.762)
			(drill 0.359918)
			(layers "*.Cu" "*.Mask")
			(remove_unused_layers no)
			(net "GND")
			(clearance 0.1651)
			(thermal_gap 0.1651)
		)
		(pad "GND24" thru_hole circle
			(at 10.80008 9.700006 270)
			(size 0.762 0.762)
			(drill 0.359918)
			(layers "*.Cu" "*.Mask")
			(remove_unused_layers no)
			(net "GND")
			(clearance 0.1651)
			(thermal_gap 0.1651)
		)
		(pad "GND25" thru_hole circle
			(at 12.599924 -0.100076 270)
			(size 0.762 0.762)
			(drill 0.359918)
			(layers "*.Cu" "*.Mask")
			(remove_unused_layers no)
			(net "GND")
			(clearance 0.1651)
			(thermal_gap 0.1651)
		)
		(pad "GND26" thru_hole circle
			(at 12.599924 3.50012 270)
			(size 0.762 0.762)
			(drill 0.359918)
			(layers "*.Cu" "*.Mask")
			(remove_unused_layers no)
			(net "GND")
			(clearance 0.1651)
			(thermal_gap 0.1651)
		)
		(pad "GND27" thru_hole circle
			(at 12.599924 7.100062 270)
			(size 0.762 0.762)
			(drill 0.359918)
			(layers "*.Cu" "*.Mask")
			(remove_unused_layers no)
			(net "GND")
			(clearance 0.1651)
			(thermal_gap 0.1651)
		)
		(pad "GND28" thru_hole circle
			(at 12.599924 10.700004 270)
			(size 0.762 0.762)
			(drill 0.359918)
			(layers "*.Cu" "*.Mask")
			(remove_unused_layers no)
			(net "GND")
			(clearance 0.1651)
			(thermal_gap 0.1651)
		)
		(pad "GND29" thru_hole circle
			(at 14.400022 2.500122 270)
			(size 0.762 0.762)
			(drill 0.359918)
			(layers "*.Cu" "*.Mask")
			(remove_unused_layers no)
			(net "GND")
			(clearance 0.1651)
			(thermal_gap 0.1651)
		)
		(pad "GND30" thru_hole circle
			(at 14.400022 6.100064 270)
			(size 0.762 0.762)
			(drill 0.359918)
			(layers "*.Cu" "*.Mask")
			(remove_unused_layers no)
			(net "GND")
			(clearance 0.1651)
			(thermal_gap 0.1651)
		)
		(pad "GND31" thru_hole circle
			(at 14.400022 9.700006 270)
			(size 0.762 0.762)
			(drill 0.359918)
			(layers "*.Cu" "*.Mask")
			(remove_unused_layers no)
			(net "GND")
			(clearance 0.1651)
			(thermal_gap 0.1651)
		)
		(pad "GND32" thru_hole circle
			(at 16.20012 -0.100076 270)
			(size 0.762 0.762)
			(drill 0.359918)
			(layers "*.Cu" "*.Mask")
			(remove_unused_layers no)
			(net "GND")
			(clearance 0.1651)
			(thermal_gap 0.1651)
		)
		(pad "GND33" thru_hole circle
			(at 16.20012 3.50012 270)
			(size 0.762 0.762)
			(drill 0.359918)
			(layers "*.Cu" "*.Mask")
			(remove_unused_layers no)
			(net "GND")
			(clearance 0.1651)
			(thermal_gap 0.1651)
		)
		(pad "GND34" thru_hole circle
			(at 16.20012 7.100062 270)
			(size 0.762 0.762)
			(drill 0.359918)
			(layers "*.Cu" "*.Mask")
			(remove_unused_layers no)
			(net "GND")
			(clearance 0.1651)
			(thermal_gap 0.1651)
		)
		(pad "GND35" thru_hole circle
			(at 16.20012 10.700004 270)
			(size 0.762 0.762)
			(drill 0.359918)
			(layers "*.Cu" "*.Mask")
			(remove_unused_layers no)
			(net "GND")
			(clearance 0.1651)
			(thermal_gap 0.1651)
		)
		(pad "GND36" thru_hole circle
			(at 17.999964 2.500122 270)
			(size 0.762 0.762)
			(drill 0.359918)
			(layers "*.Cu" "*.Mask")
			(remove_unused_layers no)
			(net "GND")
			(clearance 0.1651)
			(thermal_gap 0.1651)
		)
		(pad "GND37" thru_hole circle
			(at 17.999964 6.100064 270)
			(size 0.762 0.762)
			(drill 0.359918)
			(layers "*.Cu" "*.Mask")
			(remove_unused_layers no)
			(net "GND")
			(clearance 0.1651)
			(thermal_gap 0.1651)
		)
		(pad "GND38" thru_hole circle
			(at 17.999964 9.700006 270)
			(size 0.762 0.762)
			(drill 0.359918)
			(layers "*.Cu" "*.Mask")
			(remove_unused_layers no)
			(net "GND")
			(clearance 0.1651)
			(thermal_gap 0.1651)
		)
		(pad "GND39" thru_hole circle
			(at 19.800062 -0.100076 270)
			(size 0.762 0.762)
			(drill 0.359918)
			(layers "*.Cu" "*.Mask")
			(remove_unused_layers no)
			(net "GND")
			(clearance 0.1651)
			(thermal_gap 0.1651)
		)
		(pad "GND40" thru_hole circle
			(at 19.800062 3.50012 270)
			(size 0.762 0.762)
			(drill 0.359918)
			(layers "*.Cu" "*.Mask")
			(remove_unused_layers no)
			(net "GND")
			(clearance 0.1651)
			(thermal_gap 0.1651)
		)
		(pad "GND41" thru_hole circle
			(at 19.800062 7.100062 270)
			(size 0.762 0.762)
			(drill 0.359918)
			(layers "*.Cu" "*.Mask")
			(remove_unused_layers no)
			(net "GND")
			(clearance 0.1651)
			(thermal_gap 0.1651)
		)
		(pad "GND42" thru_hole circle
			(at 19.800062 10.700004 270)
			(size 0.762 0.762)
			(drill 0.359918)
			(layers "*.Cu" "*.Mask")
			(remove_unused_layers no)
			(net "GND")
			(clearance 0.1651)
			(thermal_gap 0.1651)
		)
		(pad "GND43" thru_hole circle
			(at 21.599906 2.500122 270)
			(size 0.762 0.762)
			(drill 0.359918)
			(layers "*.Cu" "*.Mask")
			(remove_unused_layers no)
			(net "GND")
			(clearance 0.1651)
			(thermal_gap 0.1651)
		)
		(pad "GND44" thru_hole circle
			(at 21.599906 6.100064 270)
			(size 0.762 0.762)
			(drill 0.359918)
			(layers "*.Cu" "*.Mask")
			(remove_unused_layers no)
			(net "GND")
			(clearance 0.1651)
			(thermal_gap 0.1651)
		)
		(pad "GND45" thru_hole circle
			(at 21.599906 9.700006 270)
			(size 0.762 0.762)
			(drill 0.359918)
			(layers "*.Cu" "*.Mask")
			(remove_unused_layers no)
			(net "GND")
			(clearance 0.1651)
			(thermal_gap 0.1651)
		)
		(pad "GND46" thru_hole circle
			(at 23.400004 -0.100076 270)
			(size 0.762 0.762)
			(drill 0.359918)
			(layers "*.Cu" "*.Mask")
			(remove_unused_layers no)
			(net "GND")
			(clearance 0.1651)
			(thermal_gap 0.1651)
		)
		(pad "GND47" thru_hole circle
			(at 23.400004 3.50012 270)
			(size 0.762 0.762)
			(drill 0.359918)
			(layers "*.Cu" "*.Mask")
			(remove_unused_layers no)
			(net "GND")
			(clearance 0.1651)
			(thermal_gap 0.1651)
		)
		(pad "GND48" thru_hole circle
			(at 23.400004 7.100062 270)
			(size 0.762 0.762)
			(drill 0.359918)
			(layers "*.Cu" "*.Mask")
			(remove_unused_layers no)
			(net "GND")
			(clearance 0.1651)
			(thermal_gap 0.1651)
		)
		(pad "GND49" thru_hole circle
			(at 23.400004 10.700004 270)
			(size 0.762 0.762)
			(drill 0.359918)
			(layers "*.Cu" "*.Mask")
			(remove_unused_layers no)
			(net "GND")
			(clearance 0.1651)
			(thermal_gap 0.1651)
		)
		(pad "GND50" thru_hole circle
			(at 25.200102 2.500122 270)
			(size 0.762 0.762)
			(drill 0.359918)
			(layers "*.Cu" "*.Mask")
			(remove_unused_layers no)
			(net "GND")
			(clearance 0.1651)
			(thermal_gap 0.1651)
		)
		(pad "GND51" thru_hole circle
			(at 25.200102 6.100064 270)
			(size 0.762 0.762)
			(drill 0.359918)
			(layers "*.Cu" "*.Mask")
			(remove_unused_layers no)
			(net "GND")
			(clearance 0.1651)
			(thermal_gap 0.1651)
		)
		(pad "GND52" thru_hole circle
			(at 25.200102 9.700006 270)
			(size 0.762 0.762)
			(drill 0.359918)
			(layers "*.Cu" "*.Mask")
			(remove_unused_layers no)
			(net "GND")
			(clearance 0.1651)
			(thermal_gap 0.1651)
		)
		(pad "GND53" thru_hole circle
			(at 26.999946 -0.100076 270)
			(size 0.762 0.762)
			(drill 0.359918)
			(layers "*.Cu" "*.Mask")
			(remove_unused_layers no)
			(net "GND")
			(clearance 0.1651)
			(thermal_gap 0.1651)
		)
		(pad "GND54" thru_hole circle
			(at 26.999946 3.50012 270)
			(size 0.762 0.762)
			(drill 0.359918)
			(layers "*.Cu" "*.Mask")
			(remove_unused_layers no)
			(net "GND")
			(clearance 0.1651)
			(thermal_gap 0.1651)
		)
		(pad "GND55" thru_hole circle
			(at 26.999946 7.100062 270)
			(size 0.762 0.762)
			(drill 0.359918)
			(layers "*.Cu" "*.Mask")
			(remove_unused_layers no)
			(net "GND")
			(clearance 0.1651)
			(thermal_gap 0.1651)
		)
		(pad "GND56" thru_hole circle
			(at 26.999946 10.700004 270)
			(size 0.762 0.762)
			(drill 0.359918)
			(layers "*.Cu" "*.Mask")
			(remove_unused_layers no)
			(net "GND")
			(clearance 0.1651)
			(thermal_gap 0.1651)
		)
		(pad "GND57" thru_hole circle
			(at 28.800044 2.500122 270)
			(size 0.762 0.762)
			(drill 0.359918)
			(layers "*.Cu" "*.Mask")
			(remove_unused_layers no)
			(net "GND")
			(clearance 0.1651)
			(thermal_gap 0.1651)
		)
		(pad "GND58" thru_hole circle
			(at 28.800044 6.100064 270)
			(size 0.762 0.762)
			(drill 0.359918)
			(layers "*.Cu" "*.Mask")
			(remove_unused_layers no)
			(net "GND")
			(clearance 0.1651)
			(thermal_gap 0.1651)
		)
		(pad "GND59" thru_hole circle
			(at 28.800044 9.700006 270)
			(size 0.762 0.762)
			(drill 0.359918)
			(layers "*.Cu" "*.Mask")
			(remove_unused_layers no)
			(net "GND")
			(clearance 0.1651)
			(thermal_gap 0.1651)
		)
		(pad "GND60" thru_hole circle
			(at 30.599888 -0.100076 270)
			(size 0.762 0.762)
			(drill 0.359918)
			(layers "*.Cu" "*.Mask")
			(remove_unused_layers no)
			(net "GND")
			(clearance 0.1651)
			(thermal_gap 0.1651)
		)
		(pad "GND61" thru_hole circle
			(at 30.599888 3.50012 270)
			(size 0.762 0.762)
			(drill 0.359918)
			(layers "*.Cu" "*.Mask")
			(remove_unused_layers no)
			(net "GND")
			(clearance 0.1651)
			(thermal_gap 0.1651)
		)
		(pad "GND62" thru_hole circle
			(at 30.599888 7.100062 270)
			(size 0.762 0.762)
			(drill 0.359918)
			(layers "*.Cu" "*.Mask")
			(remove_unused_layers no)
			(net "GND")
			(clearance 0.1651)
			(thermal_gap 0.1651)
		)
		(pad "GND63" thru_hole circle
			(at 30.599888 10.700004 270)
			(size 0.762 0.762)
			(drill 0.359918)
			(layers "*.Cu" "*.Mask")
			(remove_unused_layers no)
			(net "GND")
			(clearance 0.1651)
			(thermal_gap 0.1651)
		)
		(pad "GND64" thru_hole circle
			(at 32.399986 2.500122 270)
			(size 0.762 0.762)
			(drill 0.359918)
			(layers "*.Cu" "*.Mask")
			(remove_unused_layers no)
			(net "GND")
			(clearance 0.1651)
			(thermal_gap 0.1651)
		)
		(pad "GND65" thru_hole circle
			(at 32.399986 6.100064 270)
			(size 0.762 0.762)
			(drill 0.359918)
			(layers "*.Cu" "*.Mask")
			(remove_unused_layers no)
			(net "GND")
			(clearance 0.1651)
			(thermal_gap 0.1651)
		)
		(pad "GND66" thru_hole circle
			(at 32.399986 9.700006 270)
			(size 0.762 0.762)
			(drill 0.359918)
			(layers "*.Cu" "*.Mask")
			(remove_unused_layers no)
			(net "GND")
			(clearance 0.1651)
			(thermal_gap 0.1651)
		)
		(pad "GND67" thru_hole circle
			(at 34.200084 -0.100076 270)
			(size 0.762 0.762)
			(drill 0.359918)
			(layers "*.Cu" "*.Mask")
			(remove_unused_layers no)
			(net "GND")
			(clearance 0.1651)
			(thermal_gap 0.1651)
		)
		(pad "GND68" thru_hole circle
			(at 34.200084 3.50012 270)
			(size 0.762 0.762)
			(drill 0.359918)
			(layers "*.Cu" "*.Mask")
			(remove_unused_layers no)
			(net "GND")
			(clearance 0.1651)
			(thermal_gap 0.1651)
		)
		(pad "GND69" thru_hole circle
			(at 34.200084 7.100062 270)
			(size 0.762 0.762)
			(drill 0.359918)
			(layers "*.Cu" "*.Mask")
			(remove_unused_layers no)
			(net "GND")
			(clearance 0.1651)
			(thermal_gap 0.1651)
		)
		(pad "GND70" thru_hole circle
			(at 34.200084 10.700004 270)
			(size 0.762 0.762)
			(drill 0.359918)
			(layers "*.Cu" "*.Mask")
			(remove_unused_layers no)
			(net "GND")
			(clearance 0.1651)
			(thermal_gap 0.1651)
		)
		(pad "GND71" thru_hole circle
			(at 35.999928 2.500122 270)
			(size 0.762 0.762)
			(drill 0.359918)
			(layers "*.Cu" "*.Mask")
			(remove_unused_layers no)
			(net "GND")
			(clearance 0.1651)
			(thermal_gap 0.1651)
		)
		(pad "GND72" thru_hole circle
			(at 35.999928 6.100064 270)
			(size 0.762 0.762)
			(drill 0.359918)
			(layers "*.Cu" "*.Mask")
			(remove_unused_layers no)
			(net "GND")
			(clearance 0.1651)
			(thermal_gap 0.1651)
		)
		(pad "GND73" thru_hole circle
			(at 35.999928 9.700006 270)
			(size 0.762 0.762)
			(drill 0.359918)
			(layers "*.Cu" "*.Mask")
			(remove_unused_layers no)
			(net "GND")
			(clearance 0.1651)
			(thermal_gap 0.1651)
		)
		(pad "GND74" thru_hole circle
			(at 37.800026 -0.100076 270)
			(size 0.762 0.762)
			(drill 0.359918)
			(layers "*.Cu" "*.Mask")
			(remove_unused_layers no)
			(net "GND")
			(clearance 0.1651)
			(thermal_gap 0.1651)
		)
		(pad "GND75" thru_hole circle
			(at 37.800026 3.50012 270)
			(size 0.762 0.762)
			(drill 0.359918)
			(layers "*.Cu" "*.Mask")
			(remove_unused_layers no)
			(net "GND")
			(clearance 0.1651)
			(thermal_gap 0.1651)
		)
		(pad "GND76" thru_hole circle
			(at 37.800026 7.100062 270)
			(size 0.762 0.762)
			(drill 0.359918)
			(layers "*.Cu" "*.Mask")
			(remove_unused_layers no)
			(net "GND")
			(clearance 0.1651)
			(thermal_gap 0.1651)
		)
		(pad "GND77" thru_hole circle
			(at 37.800026 10.700004 270)
			(size 0.762 0.762)
			(drill 0.359918)
			(layers "*.Cu" "*.Mask")
			(remove_unused_layers no)
			(net "GND")
			(clearance 0.1651)
			(thermal_gap 0.1651)
		)
		(pad "GND78" thru_hole circle
			(at 39.600124 2.500122 270)
			(size 0.762 0.762)
			(drill 0.359918)
			(layers "*.Cu" "*.Mask")
			(remove_unused_layers no)
			(net "GND")
			(clearance 0.1651)
			(thermal_gap 0.1651)
		)
		(pad "GND79" thru_hole circle
			(at 39.600124 6.100064 270)
			(size 0.762 0.762)
			(drill 0.359918)
			(layers "*.Cu" "*.Mask")
			(remove_unused_layers no)
			(net "GND")
			(clearance 0.1651)
			(thermal_gap 0.1651)
		)
		(pad "GND80" thru_hole circle
			(at 39.600124 9.700006 270)
			(size 0.762 0.762)
			(drill 0.359918)
			(layers "*.Cu" "*.Mask")
			(remove_unused_layers no)
			(net "GND")
			(clearance 0.1651)
			(thermal_gap 0.1651)
		)
		(pad "GND81" thru_hole circle
			(at 41.399968 -0.100076 270)
			(size 0.762 0.762)
			(drill 0.359918)
			(layers "*.Cu" "*.Mask")
			(remove_unused_layers no)
			(net "GND")
			(clearance 0.1651)
			(thermal_gap 0.1651)
		)
		(pad "GND82" thru_hole circle
			(at 41.399968 3.50012 270)
			(size 0.762 0.762)
			(drill 0.359918)
			(layers "*.Cu" "*.Mask")
			(remove_unused_layers no)
			(net "GND")
			(clearance 0.1651)
			(thermal_gap 0.1651)
		)
		(pad "GND83" thru_hole circle
			(at 41.399968 7.100062 270)
			(size 0.762 0.762)
			(drill 0.359918)
			(layers "*.Cu" "*.Mask")
			(remove_unused_layers no)
			(net "GND")
			(clearance 0.1651)
			(thermal_gap 0.1651)
		)
		(pad "GND84" thru_hole circle
			(at 41.399968 10.700004 270)
			(size 0.762 0.762)
			(drill 0.359918)
			(layers "*.Cu" "*.Mask")
			(remove_unused_layers no)
			(net "GND")
			(clearance 0.1651)
			(thermal_gap 0.1651)
		)
		(pad "GND85" thru_hole circle
			(at 43.200066 2.500122 270)
			(size 0.762 0.762)
			(drill 0.359918)
			(layers "*.Cu" "*.Mask")
			(remove_unused_layers no)
			(net "GND")
			(clearance 0.1651)
			(thermal_gap 0.1651)
		)
		(pad "GND86" thru_hole circle
			(at 43.200066 6.100064 270)
			(size 0.762 0.762)
			(drill 0.359918)
			(layers "*.Cu" "*.Mask")
			(remove_unused_layers no)
			(net "GND")
			(clearance 0.1651)
			(thermal_gap 0.1651)
		)
		(pad "GND87" thru_hole circle
			(at 43.200066 9.700006 270)
			(size 0.762 0.762)
			(drill 0.359918)
			(layers "*.Cu" "*.Mask")
			(remove_unused_layers no)
			(net "GND")
			(clearance 0.1651)
			(thermal_gap 0.1651)
		)
		(pad "GND88" thru_hole circle
			(at 44.99991 -0.100076 270)
			(size 0.762 0.762)
			(drill 0.359918)
			(layers "*.Cu" "*.Mask")
			(remove_unused_layers no)
			(net "GND")
			(clearance 0.1651)
			(thermal_gap 0.1651)
		)
		(pad "GND89" thru_hole circle
			(at 44.99991 3.50012 270)
			(size 0.762 0.762)
			(drill 0.359918)
			(layers "*.Cu" "*.Mask")
			(remove_unused_layers no)
			(net "GND")
			(clearance 0.1651)
			(thermal_gap 0.1651)
		)
		(pad "GND90" thru_hole circle
			(at 44.99991 7.100062 270)
			(size 0.762 0.762)
			(drill 0.359918)
			(layers "*.Cu" "*.Mask")
			(remove_unused_layers no)
			(net "GND")
			(clearance 0.1651)
			(thermal_gap 0.1651)
		)
		(pad "GND91" thru_hole circle
			(at 44.99991 10.700004 270)
			(size 0.762 0.762)
			(drill 0.359918)
			(layers "*.Cu" "*.Mask")
			(remove_unused_layers no)
			(net "GND")
			(clearance 0.1651)
			(thermal_gap 0.1651)
		)
		(pad "GND92" thru_hole circle
			(at 46.800008 2.500122 270)
			(size 0.762 0.762)
			(drill 0.359918)
			(layers "*.Cu" "*.Mask")
			(remove_unused_layers no)
			(net "GND")
			(clearance 0.1651)
			(thermal_gap 0.1651)
		)
		(pad "GND93" thru_hole circle
			(at 46.800008 6.100064 270)
			(size 0.762 0.762)
			(drill 0.359918)
			(layers "*.Cu" "*.Mask")
			(remove_unused_layers no)
			(net "GND")
			(clearance 0.1651)
			(thermal_gap 0.1651)
		)
		(pad "GND94" thru_hole circle
			(at 46.800008 9.700006 270)
			(size 0.762 0.762)
			(drill 0.359918)
			(layers "*.Cu" "*.Mask")
			(remove_unused_layers no)
			(net "GND")
			(clearance 0.1651)
			(thermal_gap 0.1651)
		)
		(pad "GND95" thru_hole circle
			(at 48.600106 -0.100076 270)
			(size 0.762 0.762)
			(drill 0.359918)
			(layers "*.Cu" "*.Mask")
			(remove_unused_layers no)
			(net "GND")
			(clearance 0.1651)
			(thermal_gap 0.1651)
		)
		(pad "GND96" thru_hole circle
			(at 48.600106 3.50012 270)
			(size 0.762 0.762)
			(drill 0.359918)
			(layers "*.Cu" "*.Mask")
			(remove_unused_layers no)
			(net "GND")
			(clearance 0.1651)
			(thermal_gap 0.1651)
		)
		(pad "GND97" thru_hole circle
			(at 48.600106 7.100062 270)
			(size 0.762 0.762)
			(drill 0.359918)
			(layers "*.Cu" "*.Mask")
			(remove_unused_layers no)
			(net "GND")
			(clearance 0.1651)
			(thermal_gap 0.1651)
		)
		(pad "GND98" thru_hole circle
			(at 48.600106 10.700004 270)
			(size 0.762 0.762)
			(drill 0.359918)
			(layers "*.Cu" "*.Mask")
			(remove_unused_layers no)
			(net "GND")
			(clearance 0.1651)
			(thermal_gap 0.1651)
		)
		(pad "GND99" thru_hole circle
			(at 50.39995 2.500122 270)
			(size 0.762 0.762)
			(drill 0.359918)
			(layers "*.Cu" "*.Mask")
			(remove_unused_layers no)
			(net "GND")
			(clearance 0.1651)
			(thermal_gap 0.1651)
		)
		(pad "GND100" thru_hole circle
			(at 50.39995 6.100064 270)
			(size 0.762 0.762)
			(drill 0.359918)
			(layers "*.Cu" "*.Mask")
			(remove_unused_layers no)
			(net "GND")
			(clearance 0.1651)
			(thermal_gap 0.1651)
		)
		(pad "GND101" thru_hole circle
			(at 50.39995 9.700006 270)
			(size 0.762 0.762)
			(drill 0.359918)
			(layers "*.Cu" "*.Mask")
			(remove_unused_layers no)
			(net "GND")
			(clearance 0.1651)
			(thermal_gap 0.1651)
		)
		(pad "GND102" thru_hole circle
			(at 52.200048 -0.100076 270)
			(size 0.762 0.762)
			(drill 0.359918)
			(layers "*.Cu" "*.Mask")
			(remove_unused_layers no)
			(net "GND")
			(clearance 0.1651)
			(thermal_gap 0.1651)
		)
		(pad "GND103" thru_hole circle
			(at 52.200048 3.50012 270)
			(size 0.762 0.762)
			(drill 0.359918)
			(layers "*.Cu" "*.Mask")
			(remove_unused_layers no)
			(net "GND")
			(clearance 0.1651)
			(thermal_gap 0.1651)
		)
		(pad "GND104" thru_hole circle
			(at 52.200048 7.100062 270)
			(size 0.762 0.762)
			(drill 0.359918)
			(layers "*.Cu" "*.Mask")
			(remove_unused_layers no)
			(net "GND")
			(clearance 0.1651)
			(thermal_gap 0.1651)
		)
		(pad "GND105" thru_hole circle
			(at 52.200048 10.700004 270)
			(size 0.762 0.762)
			(drill 0.359918)
			(layers "*.Cu" "*.Mask")
			(remove_unused_layers no)
			(net "GND")
			(clearance 0.1651)
			(thermal_gap 0.1651)
		)
		(pad "GND106" thru_hole circle
			(at 53.999892 2.500122 270)
			(size 0.762 0.762)
			(drill 0.359918)
			(layers "*.Cu" "*.Mask")
			(remove_unused_layers no)
			(net "GND")
			(clearance 0.1651)
			(thermal_gap 0.1651)
		)
		(pad "GND107" thru_hole circle
			(at 53.999892 6.100064 270)
			(size 0.762 0.762)
			(drill 0.359918)
			(layers "*.Cu" "*.Mask")
			(remove_unused_layers no)
			(net "GND")
			(clearance 0.1651)
			(thermal_gap 0.1651)
		)
		(pad "GND108" thru_hole circle
			(at 53.999892 9.700006 270)
			(size 0.762 0.762)
			(drill 0.359918)
			(layers "*.Cu" "*.Mask")
			(remove_unused_layers no)
			(net "GND")
			(clearance 0.1651)
			(thermal_gap 0.1651)
		)
		(pad "GND109" thru_hole circle
			(at 55.79999 -0.100076 270)
			(size 0.762 0.762)
			(drill 0.359918)
			(layers "*.Cu" "*.Mask")
			(remove_unused_layers no)
			(net "GND")
			(clearance 0.1651)
			(thermal_gap 0.1651)
		)
		(pad "GND110" thru_hole circle
			(at 55.79999 3.50012 270)
			(size 0.762 0.762)
			(drill 0.359918)
			(layers "*.Cu" "*.Mask")
			(remove_unused_layers no)
			(net "GND")
			(clearance 0.1651)
			(thermal_gap 0.1651)
		)
		(pad "GND111" thru_hole circle
			(at 55.79999 7.100062 270)
			(size 0.762 0.762)
			(drill 0.359918)
			(layers "*.Cu" "*.Mask")
			(remove_unused_layers no)
			(net "GND")
			(clearance 0.1651)
			(thermal_gap 0.1651)
		)
		(pad "GND112" thru_hole circle
			(at 55.79999 10.700004 270)
			(size 0.762 0.762)
			(drill 0.359918)
			(layers "*.Cu" "*.Mask")
			(remove_unused_layers no)
			(net "GND")
			(clearance 0.1651)
			(thermal_gap 0.1651)
		)
		(pad "GND113" thru_hole circle
			(at 57.600088 2.500122 270)
			(size 0.762 0.762)
			(drill 0.359918)
			(layers "*.Cu" "*.Mask")
			(remove_unused_layers no)
			(net "GND")
			(clearance 0.1651)
			(thermal_gap 0.1651)
		)
		(pad "GND114" thru_hole circle
			(at 57.600088 6.100064 270)
			(size 0.762 0.762)
			(drill 0.359918)
			(layers "*.Cu" "*.Mask")
			(remove_unused_layers no)
			(net "GND")
			(clearance 0.1651)
			(thermal_gap 0.1651)
		)
		(pad "GND115" thru_hole circle
			(at 57.600088 9.700006 270)
			(size 0.762 0.762)
			(drill 0.359918)
			(layers "*.Cu" "*.Mask")
			(remove_unused_layers no)
			(net "GND")
			(clearance 0.1651)
			(thermal_gap 0.1651)
		)
		(pad "GND116" thru_hole circle
			(at 59.399932 -0.100076 270)
			(size 0.762 0.762)
			(drill 0.359918)
			(layers "*.Cu" "*.Mask")
			(remove_unused_layers no)
			(net "GND")
			(clearance 0.1651)
			(thermal_gap 0.1651)
		)
		(pad "GND117" thru_hole circle
			(at 59.399932 3.50012 270)
			(size 0.762 0.762)
			(drill 0.359918)
			(layers "*.Cu" "*.Mask")
			(remove_unused_layers no)
			(net "GND")
			(clearance 0.1651)
			(thermal_gap 0.1651)
		)
		(pad "GND118" thru_hole circle
			(at 59.399932 7.100062 270)
			(size 0.762 0.762)
			(drill 0.359918)
			(layers "*.Cu" "*.Mask")
			(remove_unused_layers no)
			(net "GND")
			(clearance 0.1651)
			(thermal_gap 0.1651)
		)
		(pad "GND119" thru_hole circle
			(at 59.399932 10.700004 270)
			(size 0.762 0.762)
			(drill 0.359918)
			(layers "*.Cu" "*.Mask")
			(remove_unused_layers no)
			(net "GND")
			(clearance 0.1651)
			(thermal_gap 0.1651)
		)
		(pad "GND120" thru_hole circle
			(at 61.20003 2.500122 270)
			(size 0.762 0.762)
			(drill 0.359918)
			(layers "*.Cu" "*.Mask")
			(remove_unused_layers no)
			(net "GND")
			(clearance 0.1651)
			(thermal_gap 0.1651)
		)
		(pad "GND121" thru_hole circle
			(at 61.20003 6.100064 270)
			(size 0.762 0.762)
			(drill 0.359918)
			(layers "*.Cu" "*.Mask")
			(remove_unused_layers no)
			(net "GND")
			(clearance 0.1651)
			(thermal_gap 0.1651)
		)
		(pad "GND122" thru_hole circle
			(at 61.20003 9.700006 270)
			(size 0.762 0.762)
			(drill 0.359918)
			(layers "*.Cu" "*.Mask")
			(remove_unused_layers no)
			(net "GND")
			(clearance 0.1651)
			(thermal_gap 0.1651)
		)
		(pad "GND123" thru_hole circle
			(at 62.999874 -0.100076 270)
			(size 0.762 0.762)
			(drill 0.359918)
			(layers "*.Cu" "*.Mask")
			(remove_unused_layers no)
			(net "GND")
			(clearance 0.1651)
			(thermal_gap 0.1651)
		)
		(pad "GND124" thru_hole circle
			(at 62.999874 3.50012 270)
			(size 0.762 0.762)
			(drill 0.359918)
			(layers "*.Cu" "*.Mask")
			(remove_unused_layers no)
			(net "GND")
			(clearance 0.1651)
			(thermal_gap 0.1651)
		)
		(pad "GND125" thru_hole circle
			(at 62.999874 7.100062 270)
			(size 0.762 0.762)
			(drill 0.359918)
			(layers "*.Cu" "*.Mask")
			(remove_unused_layers no)
			(net "GND")
			(clearance 0.1651)
			(thermal_gap 0.1651)
		)
		(pad "GND126" thru_hole circle
			(at 62.999874 10.700004 270)
			(size 0.762 0.762)
			(drill 0.359918)
			(layers "*.Cu" "*.Mask")
			(remove_unused_layers no)
			(net "GND")
			(clearance 0.1651)
			(thermal_gap 0.1651)
		)
	)
	(footprint ""
		(layer "F.Cu")
		(at 96.324928 -92.799916)
		(property "Reference" ""
			(at 0 0 0)
			(layer "F.SilkS")
			(hide yes)
			(effects
				(font
					(size 1.27 1.27)
				)
			)
		)
		(property "Value" "*"
			(at -8.398764 -8.057642 0)
			(unlocked yes)
			(layer "F.Fab")
			(hide yes)
			(effects
				(font
					(size 1.016 1.016)
					(thickness 0.1524)
				)
			)
		)
		(duplicate_pad_numbers_are_jumpers no)
		(fp_poly
			(pts
				(arc
					(start 7.3152 0)
					(mid 0 7.3152)
					(end -7.3152 0)
				)
				(arc
					(start -7.3152 -5.9944)
					(mid 0 -13.3096)
					(end 7.3152 -5.9944)
				)
			)
			(stroke
				(width 0)
				(type default)
			)
			(fill no)
			(layer "B.CrtYd")
		)
		(fp_poly
			(pts
				(arc
					(start 7.3152 0)
					(mid 0 7.3152)
					(end -7.3152 0)
				)
				(arc
					(start -7.3152 -5.9944)
					(mid 0 -13.3096)
					(end 7.3152 -5.9944)
				)
			)
			(stroke
				(width 0)
				(type default)
			)
			(fill no)
			(layer "F.CrtYd")
		)
		(fp_poly
			(pts
				(arc
					(start 7.3152 0)
					(mid 0 7.3152)
					(end -7.3152 0)
				)
				(arc
					(start -7.3152 -5.9944)
					(mid 0 -13.3096)
					(end 7.3152 -5.9944)
				)
			)
			(stroke
				(width 0)
				(type default)
			)
			(fill no)
			(layer "B.Fab")
		)
		(fp_poly
			(pts
				(arc
					(start 7.3152 0)
					(mid 0 7.3152)
					(end -7.3152 0)
				)
				(arc
					(start -7.3152 -5.9944)
					(mid 0 -13.3096)
					(end 7.3152 -5.9944)
				)
			)
			(stroke
				(width 0)
				(type default)
			)
			(fill no)
			(layer "F.Fab")
		)
		(pad "1" thru_hole oval
			(at 0 0)
			(size 14.0208 20.0152)
			(drill 0.0254
				(offset 0 -2.9972)
			)
			(layers "*.Cu" "*.Mask")
			(remove_unused_layers no)
			(net "Net_27")
			(clearance -1.002284)
			(thermal_gap 0.1524)
			(padstack
				(mode front_inner_back)
				(layer "Inner"
					(shape custom)
					(size 2.928012 2.928012)
					(options
						(anchor circle)
					)
					(primitives
						(gr_poly
							(pts
								(arc
									(start 4.571746 -2.084324)
									(mid 0.000333 7.430372)
									(end -4.571492 -2.084324)
								)
								(arc
									(start -4.571492 -2.084324)
									(mid -3.570296 -3.611977)
									(end -2.875026 -5.30098)
								)
								(arc
									(start -2.875026 -5.30098)
									(mid 0.000217 -7.43089)
									(end 2.87528 -5.30098)
								)
								(arc
									(start 2.87528 -5.30098)
									(mid 3.570511 -3.611956)
									(end 4.571746 -2.084324)
								)
							)
							(width 0)
							(fill yes)
						)
					)
					(clearance 0.1524)
				)
				(layer "B.Cu"
					(shape oval)
					(size 14.0208 20.0152)
					(offset 0 -2.9972)
					(clearance -1.002284)
				)
			)
		)
		(zone
			(layers "F.Cu" "B.Cu" "In1.Cu" "In2.Cu" "In3.Cu" "In4.Cu" "In5.Cu" "In6.Cu"
				"In7.Cu" "In8.Cu" "In9.Cu" "In10.Cu"
			)
			(hatch none 0.5)
			(connect_pads
				(clearance 0)
			)
			(min_thickness 0.25)
			(keepout
				(tracks not_allowed)
				(vias allowed)
				(pads allowed)
				(copperpour not_allowed)
				(footprints allowed)
			)
			(placement
				(enabled no)
				(sheetname "")
			)
			(fill
				(thermal_gap 0.5)
				(thermal_bridge_width 0.5)
				(island_removal_mode 0)
			)
			(polygon
				(pts
					(arc
						(start 89.314528 -98.794316)
						(mid 96.324928 -105.804716)
						(end 103.335328 -98.794316)
					)
					(arc
						(start 103.335328 -92.799916)
						(mid 96.324928 -85.789516)
						(end 89.314528 -92.799916)
					)
				)
			)
		)
	)
	(footprint ""
		(layer "F.Cu")
		(at 221.697042 -206.90332 90)
		(property "Reference" "R409"
			(at 0 0 90)
			(layer "F.SilkS")
			(hide yes)
			(effects
				(font
					(size 1.27 1.27)
				)
			)
		)
		(property "Value" "10KR2F-2-GP"
			(at 0.064008 -3.993896 90)
			(unlocked yes)
			(layer "F.Fab")
			(hide yes)
			(effects
				(font
					(size 1.016 1.016)
					(thickness 0.1524)
				)
			)
		)
		(property "Device Type" "R402H16"
			(at 0.064008 -5.517896 90)
			(unlocked yes)
			(layer "F.Fab")
			(hide yes)
			(effects
				(font
					(size 1.016 1.016)
					(thickness 0.1524)
				)
			)
		)
		(duplicate_pad_numbers_are_jumpers no)
		(fp_line
			(start 0.508 -0.9398)
			(end -0.508 -0.9398)
			(stroke
				(width 0.1524)
				(type default)
			)
			(layer "F.SilkS")
		)
		(fp_line
			(start -0.508 -0.9398)
			(end -0.508 0.9398)
			(stroke
				(width 0.1524)
				(type default)
			)
			(layer "F.SilkS")
		)
		(fp_rect
			(start -0.508 0.9398)
			(end 0.508 -0.9398)
			(stroke
				(width 0)
				(type default)
			)
			(fill no)
			(layer "F.CrtYd")
		)
		(fp_rect
			(start -0.508 0.9398)
			(end 0.508 -0.9398)
			(stroke
				(width 0)
				(type default)
			)
			(fill no)
			(layer "F.Fab")
		)
		(pad "1" smd custom
			(at 0 -0.4445 90)
			(size 0.1397 0.1397)
			(layers "F.Cu" "F.Mask" "F.Paste")
			(net "P3V3_STBY_A")
			(options
				(clearance outline)
				(anchor circle)
			)
			(primitives
				(gr_poly
					(pts
						(arc
							(start -0.1778 -0.2794)
							(mid -0.249642 -0.249642)
							(end -0.2794 -0.1778)
						)
						(arc
							(start -0.2794 0.1778)
							(mid -0.249642 0.249642)
							(end -0.1778 0.2794)
						)
						(arc
							(start 0.1778 0.2794)
							(mid 0.249642 0.249642)
							(end 0.2794 0.1778)
						)
						(arc
							(start 0.2794 -0.1778)
							(mid 0.249642 -0.249642)
							(end 0.1778 -0.2794)
						)
					)
					(width 0)
					(fill yes)
				)
			)
		)
		(pad "2" smd custom
			(at 0 0.4445 90)
			(size 0.1397 0.1397)
			(layers "F.Cu" "F.Mask" "F.Paste")
			(net "I2C_SCC_BUFF_EN")
			(options
				(clearance outline)
				(anchor circle)
			)
			(primitives
				(gr_poly
					(pts
						(arc
							(start -0.1778 -0.2794)
							(mid -0.249642 -0.249642)
							(end -0.2794 -0.1778)
						)
						(arc
							(start -0.2794 0.1778)
							(mid -0.249642 0.249642)
							(end -0.1778 0.2794)
						)
						(arc
							(start 0.1778 0.2794)
							(mid 0.249642 0.249642)
							(end 0.2794 0.1778)
						)
						(arc
							(start 0.2794 -0.1778)
							(mid 0.249642 -0.249642)
							(end 0.1778 -0.2794)
						)
					)
					(width 0)
					(fill yes)
				)
			)
		)
	)
	(footprint ""
		(layer "F.Cu")
		(at 413.004 -298.704)
		(property "Reference" "TP47"
			(at 0 0 0)
			(layer "F.SilkS")
			(hide yes)
			(effects
				(font
					(size 1.27 1.27)
				)
			)
		)
		(property "Value" "TPAD32-GP"
			(at -0.0508 -1.6764 0)
			(unlocked yes)
			(layer "F.Fab")
			(hide yes)
			(effects
				(font
					(size 1.016 1.016)
					(thickness 0.1524)
				)
			)
		)
		(property "Device Type" "TPAD32"
			(at -0.0508 -3.2004 0)
			(unlocked yes)
			(layer "F.Fab")
			(hide yes)
			(effects
				(font
					(size 1.016 1.016)
					(thickness 0.1524)
				)
			)
		)
		(duplicate_pad_numbers_are_jumpers no)
		(fp_poly
			(pts
				(arc
					(start 0.4064 0)
					(mid -0.4064 0)
					(end 0.4064 0)
				)
			)
			(stroke
				(width 0)
				(type default)
			)
			(fill no)
			(layer "F.CrtYd")
		)
		(fp_poly
			(pts
				(arc
					(start 0.7112 0)
					(mid -0.7112 0)
					(end 0.7112 0)
				)
			)
			(stroke
				(width 0)
				(type default)
			)
			(fill no)
			(layer "F.Fab")
		)
		(pad "1" smd circle
			(at 0 0)
			(size 0.8128 0.8128)
			(layers "F.Cu" "F.Mask" "F.Paste")
			(net "ACT_HDD_9")
		)
	)
	(footprint ""
		(layer "F.Cu")
		(at 14.842998 -168.482518 -90)
		(property "Reference" "R421"
			(at 0 0 270)
			(layer "F.SilkS")
			(hide yes)
			(effects
				(font
					(size 1.27 1.27)
				)
			)
		)
		(property "Value" "300KR2F-GP"
			(at 0.064008 -3.993896 270)
			(unlocked yes)
			(layer "F.Fab")
			(hide yes)
			(effects
				(font
					(size 1.016 1.016)
					(thickness 0.1524)
				)
			)
		)
		(property "Device Type" "R402H16"
			(at 0.064008 -5.517896 270)
			(unlocked yes)
			(layer "F.Fab")
			(hide yes)
			(effects
				(font
					(size 1.016 1.016)
					(thickness 0.1524)
				)
			)
		)
		(duplicate_pad_numbers_are_jumpers no)
		(fp_line
			(start -0.508 -0.9398)
			(end -0.508 0.9398)
			(stroke
				(width 0.1524)
				(type default)
			)
			(layer "F.SilkS")
		)
		(fp_line
			(start 0.508 -0.9398)
			(end -0.508 -0.9398)
			(stroke
				(width 0.1524)
				(type default)
			)
			(layer "F.SilkS")
		)
		(fp_rect
			(start -0.508 0.9398)
			(end 0.508 -0.9398)
			(stroke
				(width 0)
				(type default)
			)
			(fill no)
			(layer "F.CrtYd")
		)
		(fp_rect
			(start -0.508 0.9398)
			(end 0.508 -0.9398)
			(stroke
				(width 0)
				(type default)
			)
			(fill no)
			(layer "F.Fab")
		)
		(pad "1" smd custom
			(at 0 -0.4445 270)
			(size 0.1397 0.1397)
			(layers "F.Cu" "F.Mask" "F.Paste")
			(net "SW_HDD_N12")
			(options
				(clearance outline)
				(anchor circle)
			)
			(primitives
				(gr_poly
					(pts
						(arc
							(start -0.1778 -0.2794)
							(mid -0.249642 -0.249642)
							(end -0.2794 -0.1778)
						)
						(arc
							(start -0.2794 0.1778)
							(mid -0.249642 0.249642)
							(end -0.1778 0.2794)
						)
						(arc
							(start 0.1778 0.2794)
							(mid 0.249642 0.249642)
							(end 0.2794 0.1778)
						)
						(arc
							(start 0.2794 -0.1778)
							(mid 0.249642 -0.249642)
							(end 0.1778 -0.2794)
						)
					)
					(width 0)
					(fill yes)
				)
			)
		)
		(pad "2" smd custom
			(at 0 0.4445 270)
			(size 0.1397 0.1397)
			(layers "F.Cu" "F.Mask" "F.Paste")
			(net "P12V_A")
			(options
				(clearance outline)
				(anchor circle)
			)
			(primitives
				(gr_poly
					(pts
						(arc
							(start -0.1778 -0.2794)
							(mid -0.249642 -0.249642)
							(end -0.2794 -0.1778)
						)
						(arc
							(start -0.2794 0.1778)
							(mid -0.249642 0.249642)
							(end -0.1778 0.2794)
						)
						(arc
							(start 0.1778 0.2794)
							(mid 0.249642 0.249642)
							(end 0.2794 0.1778)
						)
						(arc
							(start 0.2794 -0.1778)
							(mid 0.249642 -0.249642)
							(end 0.1778 -0.2794)
						)
					)
					(width 0)
					(fill yes)
				)
			)
		)
	)
	(footprint ""
		(layer "F.Cu")
		(at 67.347846 -61.127894 90)
		(property "Reference" "C371"
			(at 0 0 90)
			(layer "F.SilkS")
			(hide yes)
			(effects
				(font
					(size 1.27 1.27)
				)
			)
		)
		(property "Value" "SCD01U50V2KX-1GP"
			(at 1.1811 -2.7051 90)
			(unlocked yes)
			(layer "F.Fab")
			(hide yes)
			(effects
				(font
					(size 1.016 1.016)
					(thickness 0.1524)
				)
			)
		)
		(property "Device Type" "C402H22"
			(at 1.1811 -4.2291 90)
			(unlocked yes)
			(layer "F.Fab")
			(hide yes)
			(effects
				(font
					(size 1.016 1.016)
					(thickness 0.1524)
				)
			)
		)
		(duplicate_pad_numbers_are_jumpers no)
		(fp_rect
			(start -0.4318 0.9525)
			(end 0.4318 -0.9525)
			(stroke
				(width 0)
				(type default)
			)
			(fill no)
			(layer "F.CrtYd")
		)
		(fp_rect
			(start -0.4318 0.9525)
			(end 0.4318 -0.9525)
			(stroke
				(width 0)
				(type default)
			)
			(fill no)
			(layer "F.Fab")
		)
		(pad "1" smd custom
			(at 0 -0.4445 90)
			(size 0.1524 0.1524)
			(layers "F.Cu" "F.Mask" "F.Paste")
			(net "HDD_PRSNT_25")
			(options
				(clearance outline)
				(anchor circle)
			)
			(primitives
				(gr_poly
					(pts
						(arc
							(start 0.3048 -0.2032)
							(mid 0.275042 -0.275042)
							(end 0.2032 -0.3048)
						)
						(arc
							(start -0.2032 -0.3048)
							(mid -0.275042 -0.275042)
							(end -0.3048 -0.2032)
						)
						(arc
							(start -0.3048 0.2032)
							(mid -0.275042 0.275042)
							(end -0.2032 0.3048)
						)
						(arc
							(start 0.2032 0.3048)
							(mid 0.275042 0.275042)
							(end 0.3048 0.2032)
						)
					)
					(width 0)
					(fill yes)
				)
			)
		)
		(pad "2" smd custom
			(at 0 0.4445 90)
			(size 0.1524 0.1524)
			(layers "F.Cu" "F.Mask" "F.Paste")
			(net "GND")
			(options
				(clearance outline)
				(anchor circle)
			)
			(primitives
				(gr_poly
					(pts
						(arc
							(start 0.3048 -0.2032)
							(mid 0.275042 -0.275042)
							(end 0.2032 -0.3048)
						)
						(arc
							(start -0.2032 -0.3048)
							(mid -0.275042 -0.275042)
							(end -0.3048 -0.2032)
						)
						(arc
							(start -0.3048 0.2032)
							(mid -0.275042 0.275042)
							(end -0.2032 0.3048)
						)
						(arc
							(start 0.2032 0.3048)
							(mid 0.275042 0.275042)
							(end 0.3048 0.2032)
						)
					)
					(width 0)
					(fill yes)
				)
			)
		)
	)
	(footprint ""
		(layer "F.Cu")
		(at 237.998 -395.9098 180)
		(property "Reference" "C592"
			(at 0 0 180)
			(layer "F.SilkS")
			(hide yes)
			(effects
				(font
					(size 1.27 1.27)
				)
			)
		)
		(property "Value" "SCD1U25V2KX-2-GP"
			(at 1.1811 -2.7051 180)
			(unlocked yes)
			(layer "F.Fab")
			(hide yes)
			(effects
				(font
					(size 1.016 1.016)
					(thickness 0.1524)
				)
			)
		)
		(property "Device Type" "C402H22"
			(at 1.1811 -4.2291 180)
			(unlocked yes)
			(layer "F.Fab")
			(hide yes)
			(effects
				(font
					(size 1.016 1.016)
					(thickness 0.1524)
				)
			)
		)
		(duplicate_pad_numbers_are_jumpers no)
		(fp_rect
			(start -0.4318 0.9525)
			(end 0.4318 -0.9525)
			(stroke
				(width 0)
				(type default)
			)
			(fill no)
			(layer "F.CrtYd")
		)
		(fp_rect
			(start -0.4318 0.9525)
			(end 0.4318 -0.9525)
			(stroke
				(width 0)
				(type default)
			)
			(fill no)
			(layer "F.Fab")
		)
		(pad "1" smd custom
			(at 0 -0.4445 180)
			(size 0.1524 0.1524)
			(layers "F.Cu" "F.Mask" "F.Paste")
			(net "MB3_ISTART_R")
			(options
				(clearance outline)
				(anchor circle)
			)
			(primitives
				(gr_poly
					(pts
						(arc
							(start 0.3048 -0.2032)
							(mid 0.275042 -0.275042)
							(end 0.2032 -0.3048)
						)
						(arc
							(start -0.2032 -0.3048)
							(mid -0.275042 -0.275042)
							(end -0.3048 -0.2032)
						)
						(arc
							(start -0.3048 0.2032)
							(mid -0.275042 0.275042)
							(end -0.2032 0.3048)
						)
						(arc
							(start 0.2032 0.3048)
							(mid 0.275042 0.275042)
							(end 0.3048 0.2032)
						)
					)
					(width 0)
					(fill yes)
				)
			)
		)
		(pad "2" smd custom
			(at 0 0.4445 180)
			(size 0.1524 0.1524)
			(layers "F.Cu" "F.Mask" "F.Paste")
			(net "AGND_CURRENT_DPB")
			(options
				(clearance outline)
				(anchor circle)
			)
			(primitives
				(gr_poly
					(pts
						(arc
							(start 0.3048 -0.2032)
							(mid 0.275042 -0.275042)
							(end 0.2032 -0.3048)
						)
						(arc
							(start -0.2032 -0.3048)
							(mid -0.275042 -0.275042)
							(end -0.3048 -0.2032)
						)
						(arc
							(start -0.3048 0.2032)
							(mid -0.275042 0.275042)
							(end -0.2032 0.3048)
						)
						(arc
							(start 0.2032 0.3048)
							(mid 0.275042 0.275042)
							(end 0.3048 0.2032)
						)
					)
					(width 0)
					(fill yes)
				)
			)
		)
	)
	(footprint ""
		(layer "F.Cu")
		(at 32.463486 -159.219392 90)
		(property "Reference" "C194"
			(at 0 0 90)
			(layer "F.SilkS")
			(hide yes)
			(effects
				(font
					(size 1.27 1.27)
				)
			)
		)
		(property "Value" "SCD01U16V1KX-GP"
			(at -2.8321 -1.7399 90)
			(unlocked yes)
			(layer "F.Fab")
			(hide yes)
			(effects
				(font
					(size 1.016 1.016)
					(thickness 0.1524)
				)
			)
		)
		(property "Device Type" "C0201H13"
			(at -2.8321 -3.2639 90)
			(unlocked yes)
			(layer "F.Fab")
			(hide yes)
			(effects
				(font
					(size 1.016 1.016)
					(thickness 0.1524)
				)
			)
		)
		(duplicate_pad_numbers_are_jumpers no)
		(fp_rect
			(start -0.2794 0.6477)
			(end 0.2794 -0.6477)
			(stroke
				(width 0)
				(type default)
			)
			(fill no)
			(layer "F.CrtYd")
		)
		(fp_rect
			(start -0.2794 0.6477)
			(end 0.2794 -0.6477)
			(stroke
				(width 0)
				(type default)
			)
			(fill no)
			(layer "F.Fab")
		)
		(pad "1" smd custom
			(at 0 -0.2794 90)
			(size 0.0762 0.0762)
			(layers "F.Cu" "F.Mask" "F.Paste")
			(net "SAS_HDD_RX_N12")
			(options
				(clearance outline)
				(anchor circle)
			)
			(primitives
				(gr_poly
					(pts
						(arc
							(start 0.1524 -0.127)
							(mid 0.137521 -0.162921)
							(end 0.1016 -0.1778)
						)
						(arc
							(start -0.1016 -0.1778)
							(mid -0.137521 -0.162921)
							(end -0.1524 -0.127)
						)
						(arc
							(start -0.1524 0.127)
							(mid -0.137521 0.162921)
							(end -0.1016 0.1778)
						)
						(arc
							(start 0.1016 0.1778)
							(mid 0.137521 0.162921)
							(end 0.1524 0.127)
						)
					)
					(width 0)
					(fill yes)
				)
			)
		)
		(pad "2" smd custom
			(at 0 0.2794 90)
			(size 0.0762 0.0762)
			(layers "F.Cu" "F.Mask" "F.Paste")
			(net "PHY_SCC_A_TO_DRV_A_12_DN")
			(options
				(clearance outline)
				(anchor circle)
			)
			(primitives
				(gr_poly
					(pts
						(arc
							(start 0.1524 -0.127)
							(mid 0.137521 -0.162921)
							(end 0.1016 -0.1778)
						)
						(arc
							(start -0.1016 -0.1778)
							(mid -0.137521 -0.162921)
							(end -0.1524 -0.127)
						)
						(arc
							(start -0.1524 0.127)
							(mid -0.137521 0.162921)
							(end -0.1016 0.1778)
						)
						(arc
							(start 0.1016 0.1778)
							(mid 0.137521 0.162921)
							(end 0.1524 0.127)
						)
					)
					(width 0)
					(fill yes)
				)
			)
		)
	)
	(footprint ""
		(layer "F.Cu")
		(at 272.542 -314.505086 180)
		(property "Reference" "VIA59"
			(at 0 0 180)
			(layer "F.SilkS")
			(hide yes)
			(effects
				(font
					(size 1.27 1.27)
				)
			)
		)
		(property "Value" "100OHM-8L-1D6MM-L18L16-GP"
			(at -3.7211 -4.5085 180)
			(unlocked yes)
			(layer "F.Fab")
			(hide yes)
			(effects
				(font
					(size 1.016 1.016)
					(thickness 0.1524)
				)
			)
		)
		(property "Device Type" "VIA-PCIE-4P-394076"
			(at -3.7211 -6.0325 180)
			(unlocked yes)
			(layer "F.Fab")
			(hide yes)
			(effects
				(font
					(size 1.016 1.016)
					(thickness 0.1524)
				)
			)
		)
		(duplicate_pad_numbers_are_jumpers no)
		(fp_rect
			(start -1.9685 0.381)
			(end 1.9685 -0.381)
			(stroke
				(width 0)
				(type default)
			)
			(fill no)
			(layer "F.CrtYd")
		)
		(fp_rect
			(start -1.9685 0.381)
			(end 1.9685 -0.381)
			(stroke
				(width 0)
				(type default)
			)
			(fill no)
			(layer "F.Fab")
		)
		(pad "1" thru_hole circle
			(at -1.5875 0 180)
			(size 0.508 0.508)
			(drill 0.254)
			(layers "*.Cu" "*.Mask")
			(remove_unused_layers no)
			(net "GND")
			(clearance 0.127)
			(thermal_gap 0.127)
		)
		(pad "2" thru_hole circle
			(at -0.5715 0 180)
			(size 0.508 0.508)
			(drill 0.254)
			(layers "*.Cu" "*.Mask")
			(remove_unused_layers no)
			(net "PHY_SCC_A_TO_DRV_A_25_DP")
			(clearance 0.127)
			(thermal_gap 0.127)
		)
		(pad "3" thru_hole circle
			(at 0.5715 0 180)
			(size 0.508 0.508)
			(drill 0.254)
			(layers "*.Cu" "*.Mask")
			(remove_unused_layers no)
			(net "PHY_SCC_A_TO_DRV_A_25_DN")
			(clearance 0.127)
			(thermal_gap 0.127)
		)
		(pad "4" thru_hole circle
			(at 1.5875 0 180)
			(size 0.508 0.508)
			(drill 0.254)
			(layers "*.Cu" "*.Mask")
			(remove_unused_layers no)
			(net "GND")
			(clearance 0.127)
			(thermal_gap 0.127)
		)
	)
	(footprint ""
		(layer "F.Cu")
		(at 109.492796 -53.482494 -90)
		(property "Reference" "R766"
			(at 0 0 270)
			(layer "F.SilkS")
			(hide yes)
			(effects
				(font
					(size 1.27 1.27)
				)
			)
		)
		(property "Value" "300KR2F-GP"
			(at 0.064008 -3.993896 270)
			(unlocked yes)
			(layer "F.Fab")
			(hide yes)
			(effects
				(font
					(size 1.016 1.016)
					(thickness 0.1524)
				)
			)
		)
		(property "Device Type" "R402H16"
			(at 0.064008 -5.517896 270)
			(unlocked yes)
			(layer "F.Fab")
			(hide yes)
			(effects
				(font
					(size 1.016 1.016)
					(thickness 0.1524)
				)
			)
		)
		(duplicate_pad_numbers_are_jumpers no)
		(fp_line
			(start -0.508 -0.9398)
			(end -0.508 0.9398)
			(stroke
				(width 0.1524)
				(type default)
			)
			(layer "F.SilkS")
		)
		(fp_line
			(start 0.508 -0.9398)
			(end -0.508 -0.9398)
			(stroke
				(width 0.1524)
				(type default)
			)
			(layer "F.SilkS")
		)
		(fp_rect
			(start -0.508 0.9398)
			(end 0.508 -0.9398)
			(stroke
				(width 0)
				(type default)
			)
			(fill no)
			(layer "F.CrtYd")
		)
		(fp_rect
			(start -0.508 0.9398)
			(end 0.508 -0.9398)
			(stroke
				(width 0)
				(type default)
			)
			(fill no)
			(layer "F.Fab")
		)
		(pad "1" smd custom
			(at 0 -0.4445 270)
			(size 0.1397 0.1397)
			(layers "F.Cu" "F.Mask" "F.Paste")
			(net "SW_HDD_N27")
			(options
				(clearance outline)
				(anchor circle)
			)
			(primitives
				(gr_poly
					(pts
						(arc
							(start -0.1778 -0.2794)
							(mid -0.249642 -0.249642)
							(end -0.2794 -0.1778)
						)
						(arc
							(start -0.2794 0.1778)
							(mid -0.249642 0.249642)
							(end -0.1778 0.2794)
						)
						(arc
							(start 0.1778 0.2794)
							(mid 0.249642 0.249642)
							(end 0.2794 0.1778)
						)
						(arc
							(start 0.2794 -0.1778)
							(mid 0.249642 -0.249642)
							(end 0.1778 -0.2794)
						)
					)
					(width 0)
					(fill yes)
				)
			)
		)
		(pad "2" smd custom
			(at 0 0.4445 270)
			(size 0.1397 0.1397)
			(layers "F.Cu" "F.Mask" "F.Paste")
			(net "P12V_A")
			(options
				(clearance outline)
				(anchor circle)
			)
			(primitives
				(gr_poly
					(pts
						(arc
							(start -0.1778 -0.2794)
							(mid -0.249642 -0.249642)
							(end -0.2794 -0.1778)
						)
						(arc
							(start -0.2794 0.1778)
							(mid -0.249642 0.249642)
							(end -0.1778 0.2794)
						)
						(arc
							(start 0.1778 0.2794)
							(mid 0.249642 0.249642)
							(end 0.2794 0.1778)
						)
						(arc
							(start 0.2794 -0.1778)
							(mid 0.249642 -0.249642)
							(end 0.1778 -0.2794)
						)
					)
					(width 0)
					(fill yes)
				)
			)
		)
	)
	(footprint ""
		(layer "F.Cu")
		(at 32.04337 -252.151642 -90)
		(property "Reference" "R1213"
			(at 0 0 270)
			(layer "F.SilkS")
			(hide yes)
			(effects
				(font
					(size 1.27 1.27)
				)
			)
		)
		(property "Value" "15KR2F-GP"
			(at 0.064008 -3.993896 270)
			(unlocked yes)
			(layer "F.Fab")
			(hide yes)
			(effects
				(font
					(size 1.016 1.016)
					(thickness 0.1524)
				)
			)
		)
		(property "Device Type" "R402H16"
			(at 0.064008 -5.517896 270)
			(unlocked yes)
			(layer "F.Fab")
			(hide yes)
			(effects
				(font
					(size 1.016 1.016)
					(thickness 0.1524)
				)
			)
		)
		(duplicate_pad_numbers_are_jumpers no)
		(fp_line
			(start -0.508 -0.9398)
			(end -0.508 0.9398)
			(stroke
				(width 0.1524)
				(type default)
			)
			(layer "F.SilkS")
		)
		(fp_line
			(start 0.508 -0.9398)
			(end -0.508 -0.9398)
			(stroke
				(width 0.1524)
				(type default)
			)
			(layer "F.SilkS")
		)
		(fp_rect
			(start -0.508 0.9398)
			(end 0.508 -0.9398)
			(stroke
				(width 0)
				(type default)
			)
			(fill no)
			(layer "F.CrtYd")
		)
		(fp_rect
			(start -0.508 0.9398)
			(end 0.508 -0.9398)
			(stroke
				(width 0)
				(type default)
			)
			(fill no)
			(layer "F.Fab")
		)
		(pad "1" smd custom
			(at 0 -0.4445 270)
			(size 0.1397 0.1397)
			(layers "F.Cu" "F.Mask" "F.Paste")
			(net "P5V_A_1_PGOOD")
			(options
				(clearance outline)
				(anchor circle)
			)
			(primitives
				(gr_poly
					(pts
						(arc
							(start -0.1778 -0.2794)
							(mid -0.249642 -0.249642)
							(end -0.2794 -0.1778)
						)
						(arc
							(start -0.2794 0.1778)
							(mid -0.249642 0.249642)
							(end -0.1778 0.2794)
						)
						(arc
							(start 0.1778 0.2794)
							(mid 0.249642 0.249642)
							(end 0.2794 0.1778)
						)
						(arc
							(start 0.2794 -0.1778)
							(mid 0.249642 -0.249642)
							(end 0.1778 -0.2794)
						)
					)
					(width 0)
					(fill yes)
				)
			)
		)
		(pad "2" smd custom
			(at 0 0.4445 270)
			(size 0.1397 0.1397)
			(layers "F.Cu" "F.Mask" "F.Paste")
			(net "GND")
			(options
				(clearance outline)
				(anchor circle)
			)
			(primitives
				(gr_poly
					(pts
						(arc
							(start -0.1778 -0.2794)
							(mid -0.249642 -0.249642)
							(end -0.2794 -0.1778)
						)
						(arc
							(start -0.2794 0.1778)
							(mid -0.249642 0.249642)
							(end -0.1778 0.2794)
						)
						(arc
							(start 0.1778 0.2794)
							(mid 0.249642 0.249642)
							(end 0.2794 0.1778)
						)
						(arc
							(start 0.2794 -0.1778)
							(mid 0.249642 -0.249642)
							(end 0.1778 -0.2794)
						)
					)
					(width 0)
					(fill yes)
				)
			)
		)
	)
	(footprint ""
		(layer "F.Cu")
		(at 396.60195 -303.954942 180)
		(property "Reference" "C148"
			(at 0 0 180)
			(layer "F.SilkS")
			(hide yes)
			(effects
				(font
					(size 1.27 1.27)
				)
			)
		)
		(property "Value" "SC4D7U25V5KX-1-GP"
			(at -0.0762 -6.1214 180)
			(unlocked yes)
			(layer "F.Fab")
			(hide yes)
			(effects
				(font
					(size 1.016 1.016)
					(thickness 0.1524)
				)
			)
		)
		(property "Device Type" "C805H58"
			(at -0.0762 -8.1534 180)
			(unlocked yes)
			(layer "F.Fab")
			(hide yes)
			(effects
				(font
					(size 1.016 1.016)
					(thickness 0.1524)
				)
			)
		)
		(duplicate_pad_numbers_are_jumpers no)
		(fp_line
			(start 0.635 0)
			(end -0.635 0)
			(stroke
				(width 0.508)
				(type default)
			)
			(layer "F.SilkS")
		)
		(fp_rect
			(start -0.9652 1.778)
			(end 0.9652 -1.778)
			(stroke
				(width 0)
				(type default)
			)
			(fill no)
			(layer "F.CrtYd")
		)
		(fp_poly
			(pts
				(xy -0.9652 -1.778) (xy 0.9652 -1.778) (xy 0.9652 1.778) (xy -0.9652 1.778)
			)
			(stroke
				(width 0)
				(type default)
			)
			(fill no)
			(layer "F.Fab")
		)
		(pad "1" smd rect
			(at 0 -0.9652 180)
			(size 1.397 1.143)
			(layers "F.Cu" "F.Mask" "F.Paste")
			(net "P12V_HDD8")
		)
		(pad "2" smd rect
			(at 0 0.9652 180)
			(size 1.397 1.143)
			(layers "F.Cu" "F.Mask" "F.Paste")
			(net "GND")
		)
	)
	(footprint ""
		(layer "F.Cu")
		(at 479.384614 -44.219368 -90)
		(property "Reference" "C493"
			(at 0 0 270)
			(layer "F.SilkS")
			(hide yes)
			(effects
				(font
					(size 1.27 1.27)
				)
			)
		)
		(property "Value" "SCD01U16V1KX-GP"
			(at -2.8321 -1.7399 270)
			(unlocked yes)
			(layer "F.Fab")
			(hide yes)
			(effects
				(font
					(size 1.016 1.016)
					(thickness 0.1524)
				)
			)
		)
		(property "Device Type" "C0201H13"
			(at -2.8321 -3.2639 270)
			(unlocked yes)
			(layer "F.Fab")
			(hide yes)
			(effects
				(font
					(size 1.016 1.016)
					(thickness 0.1524)
				)
			)
		)
		(duplicate_pad_numbers_are_jumpers no)
		(fp_rect
			(start -0.2794 0.6477)
			(end 0.2794 -0.6477)
			(stroke
				(width 0)
				(type default)
			)
			(fill no)
			(layer "F.CrtYd")
		)
		(fp_rect
			(start -0.2794 0.6477)
			(end 0.2794 -0.6477)
			(stroke
				(width 0)
				(type default)
			)
			(fill no)
			(layer "F.Fab")
		)
		(pad "1" smd custom
			(at 0 -0.2794 270)
			(size 0.0762 0.0762)
			(layers "F.Cu" "F.Mask" "F.Paste")
			(net "SAS_HDD_RX_N35")
			(options
				(clearance outline)
				(anchor circle)
			)
			(primitives
				(gr_poly
					(pts
						(arc
							(start 0.1524 -0.127)
							(mid 0.137521 -0.162921)
							(end 0.1016 -0.1778)
						)
						(arc
							(start -0.1016 -0.1778)
							(mid -0.137521 -0.162921)
							(end -0.1524 -0.127)
						)
						(arc
							(start -0.1524 0.127)
							(mid -0.137521 0.162921)
							(end -0.1016 0.1778)
						)
						(arc
							(start 0.1016 0.1778)
							(mid 0.137521 0.162921)
							(end 0.1524 0.127)
						)
					)
					(width 0)
					(fill yes)
				)
			)
		)
		(pad "2" smd custom
			(at 0 0.2794 270)
			(size 0.0762 0.0762)
			(layers "F.Cu" "F.Mask" "F.Paste")
			(net "PHY_SCC_A_TO_DRV_A_35_DN")
			(options
				(clearance outline)
				(anchor circle)
			)
			(primitives
				(gr_poly
					(pts
						(arc
							(start 0.1524 -0.127)
							(mid 0.137521 -0.162921)
							(end 0.1016 -0.1778)
						)
						(arc
							(start -0.1016 -0.1778)
							(mid -0.137521 -0.162921)
							(end -0.1524 -0.127)
						)
						(arc
							(start -0.1524 0.127)
							(mid -0.137521 0.162921)
							(end -0.1016 0.1778)
						)
						(arc
							(start 0.1016 0.1778)
							(mid 0.137521 0.162921)
							(end 0.1524 0.127)
						)
					)
					(width 0)
					(fill yes)
				)
			)
		)
	)
	(footprint ""
		(layer "F.Cu")
		(at 149.196298 -48.554894 90)
		(property "Reference" "R787"
			(at 0 0 90)
			(layer "F.SilkS")
			(hide yes)
			(effects
				(font
					(size 1.27 1.27)
				)
			)
		)
		(property "Value" "4K7R2J-2-GP"
			(at 0.064008 -3.993896 90)
			(unlocked yes)
			(layer "F.Fab")
			(hide yes)
			(effects
				(font
					(size 1.016 1.016)
					(thickness 0.1524)
				)
			)
		)
		(property "Device Type" "R402H16"
			(at 0.064008 -5.517896 90)
			(unlocked yes)
			(layer "F.Fab")
			(hide yes)
			(effects
				(font
					(size 1.016 1.016)
					(thickness 0.1524)
				)
			)
		)
		(duplicate_pad_numbers_are_jumpers no)
		(fp_line
			(start 0.508 -0.9398)
			(end -0.508 -0.9398)
			(stroke
				(width 0.1524)
				(type default)
			)
			(layer "F.SilkS")
		)
		(fp_line
			(start -0.508 -0.9398)
			(end -0.508 0.9398)
			(stroke
				(width 0.1524)
				(type default)
			)
			(layer "F.SilkS")
		)
		(fp_rect
			(start -0.508 0.9398)
			(end 0.508 -0.9398)
			(stroke
				(width 0)
				(type default)
			)
			(fill no)
			(layer "F.CrtYd")
		)
		(fp_rect
			(start -0.508 0.9398)
			(end 0.508 -0.9398)
			(stroke
				(width 0)
				(type default)
			)
			(fill no)
			(layer "F.Fab")
		)
		(pad "1" smd custom
			(at 0 -0.4445 90)
			(size 0.1397 0.1397)
			(layers "F.Cu" "F.Mask" "F.Paste")
			(net "SW_PWR_R_HDD28")
			(options
				(clearance outline)
				(anchor circle)
			)
			(primitives
				(gr_poly
					(pts
						(arc
							(start -0.1778 -0.2794)
							(mid -0.249642 -0.249642)
							(end -0.2794 -0.1778)
						)
						(arc
							(start -0.2794 0.1778)
							(mid -0.249642 0.249642)
							(end -0.1778 0.2794)
						)
						(arc
							(start 0.1778 0.2794)
							(mid 0.249642 0.249642)
							(end 0.2794 0.1778)
						)
						(arc
							(start 0.2794 -0.1778)
							(mid 0.249642 -0.249642)
							(end 0.1778 -0.2794)
						)
					)
					(width 0)
					(fill yes)
				)
			)
		)
		(pad "2" smd custom
			(at 0 0.4445 90)
			(size 0.1397 0.1397)
			(layers "F.Cu" "F.Mask" "F.Paste")
			(net "GND")
			(options
				(clearance outline)
				(anchor circle)
			)
			(primitives
				(gr_poly
					(pts
						(arc
							(start -0.1778 -0.2794)
							(mid -0.249642 -0.249642)
							(end -0.2794 -0.1778)
						)
						(arc
							(start -0.2794 0.1778)
							(mid -0.249642 0.249642)
							(end -0.1778 0.2794)
						)
						(arc
							(start 0.1778 0.2794)
							(mid 0.249642 0.249642)
							(end 0.2794 0.1778)
						)
						(arc
							(start 0.2794 -0.1778)
							(mid 0.249642 -0.249642)
							(end 0.1778 -0.2794)
						)
					)
					(width 0)
					(fill yes)
				)
			)
		)
	)
	(footprint ""
		(layer "F.Cu")
		(at 363.3978 -137.1854 90)
		(property "Reference" "R1073"
			(at 0 0 90)
			(layer "F.SilkS")
			(hide yes)
			(effects
				(font
					(size 1.27 1.27)
				)
			)
		)
		(property "Value" "10R2F-L-GP"
			(at 0.064008 -3.993896 90)
			(unlocked yes)
			(layer "F.Fab")
			(hide yes)
			(effects
				(font
					(size 1.016 1.016)
					(thickness 0.1524)
				)
			)
		)
		(property "Device Type" "R402H14"
			(at 0.064008 -5.517896 90)
			(unlocked yes)
			(layer "F.Fab")
			(hide yes)
			(effects
				(font
					(size 1.016 1.016)
					(thickness 0.1524)
				)
			)
		)
		(duplicate_pad_numbers_are_jumpers no)
		(fp_line
			(start 0.508 -0.9398)
			(end -0.508 -0.9398)
			(stroke
				(width 0.1524)
				(type default)
			)
			(layer "F.SilkS")
		)
		(fp_line
			(start -0.508 -0.9398)
			(end -0.508 0.9398)
			(stroke
				(width 0.1524)
				(type default)
			)
			(layer "F.SilkS")
		)
		(fp_rect
			(start -0.508 0.9398)
			(end 0.508 -0.9398)
			(stroke
				(width 0)
				(type default)
			)
			(fill no)
			(layer "F.CrtYd")
		)
		(fp_rect
			(start -0.508 0.9398)
			(end 0.508 -0.9398)
			(stroke
				(width 0)
				(type default)
			)
			(fill no)
			(layer "F.Fab")
		)
		(pad "1" smd custom
			(at 0 -0.4445 90)
			(size 0.1397 0.1397)
			(layers "F.Cu" "F.Mask" "F.Paste")
			(net "P12V_B")
			(options
				(clearance outline)
				(anchor circle)
			)
			(primitives
				(gr_poly
					(pts
						(arc
							(start -0.1778 -0.2794)
							(mid -0.249642 -0.249642)
							(end -0.2794 -0.1778)
						)
						(arc
							(start -0.2794 0.1778)
							(mid -0.249642 0.249642)
							(end -0.1778 0.2794)
						)
						(arc
							(start 0.1778 0.2794)
							(mid 0.249642 0.249642)
							(end 0.2794 0.1778)
						)
						(arc
							(start 0.2794 -0.1778)
							(mid 0.249642 -0.249642)
							(end 0.1778 -0.2794)
						)
					)
					(width 0)
					(fill yes)
				)
			)
		)
		(pad "2" smd custom
			(at 0 0.4445 90)
			(size 0.1397 0.1397)
			(layers "F.Cu" "F.Mask" "F.Paste")
			(net "MB1_P12V_HS")
			(options
				(clearance outline)
				(anchor circle)
			)
			(primitives
				(gr_poly
					(pts
						(arc
							(start -0.1778 -0.2794)
							(mid -0.249642 -0.249642)
							(end -0.2794 -0.1778)
						)
						(arc
							(start -0.2794 0.1778)
							(mid -0.249642 0.249642)
							(end -0.1778 0.2794)
						)
						(arc
							(start 0.1778 0.2794)
							(mid 0.249642 0.249642)
							(end 0.2794 0.1778)
						)
						(arc
							(start 0.2794 -0.1778)
							(mid 0.249642 -0.249642)
							(end 0.1778 -0.2794)
						)
					)
					(width 0)
					(fill yes)
				)
			)
		)
	)
	(footprint ""
		(layer "F.Cu")
		(at 138.007852 -140.962126 180)
		(property "Reference" "C27"
			(at 0 0 180)
			(layer "F.SilkS")
			(hide yes)
			(effects
				(font
					(size 1.27 1.27)
				)
			)
		)
		(property "Value" "SCD1U16V2KX-3GP"
			(at 1.1811 -2.7051 180)
			(unlocked yes)
			(layer "F.Fab")
			(hide yes)
			(effects
				(font
					(size 1.016 1.016)
					(thickness 0.1524)
				)
			)
		)
		(property "Device Type" "C402H22"
			(at 1.1811 -4.2291 180)
			(unlocked yes)
			(layer "F.Fab")
			(hide yes)
			(effects
				(font
					(size 1.016 1.016)
					(thickness 0.1524)
				)
			)
		)
		(duplicate_pad_numbers_are_jumpers no)
		(fp_rect
			(start -0.4318 0.9525)
			(end 0.4318 -0.9525)
			(stroke
				(width 0)
				(type default)
			)
			(fill no)
			(layer "F.CrtYd")
		)
		(fp_rect
			(start -0.4318 0.9525)
			(end 0.4318 -0.9525)
			(stroke
				(width 0)
				(type default)
			)
			(fill no)
			(layer "F.Fab")
		)
		(pad "1" smd custom
			(at 0 -0.4445 180)
			(size 0.1524 0.1524)
			(layers "F.Cu" "F.Mask" "F.Paste")
			(net "P3V3_A_BIAS")
			(options
				(clearance outline)
				(anchor circle)
			)
			(primitives
				(gr_poly
					(pts
						(arc
							(start 0.3048 -0.2032)
							(mid 0.275042 -0.275042)
							(end 0.2032 -0.3048)
						)
						(arc
							(start -0.2032 -0.3048)
							(mid -0.275042 -0.275042)
							(end -0.3048 -0.2032)
						)
						(arc
							(start -0.3048 0.2032)
							(mid -0.275042 0.275042)
							(end -0.2032 0.3048)
						)
						(arc
							(start 0.2032 0.3048)
							(mid 0.275042 0.275042)
							(end 0.3048 0.2032)
						)
					)
					(width 0)
					(fill yes)
				)
			)
		)
		(pad "2" smd custom
			(at 0 0.4445 180)
			(size 0.1524 0.1524)
			(layers "F.Cu" "F.Mask" "F.Paste")
			(net "GND")
			(options
				(clearance outline)
				(anchor circle)
			)
			(primitives
				(gr_poly
					(pts
						(arc
							(start 0.3048 -0.2032)
							(mid 0.275042 -0.275042)
							(end 0.2032 -0.3048)
						)
						(arc
							(start -0.2032 -0.3048)
							(mid -0.275042 -0.275042)
							(end -0.3048 -0.2032)
						)
						(arc
							(start -0.3048 0.2032)
							(mid -0.275042 0.275042)
							(end -0.2032 0.3048)
						)
						(arc
							(start 0.2032 0.3048)
							(mid 0.275042 0.275042)
							(end 0.3048 0.2032)
						)
					)
					(width 0)
					(fill yes)
				)
			)
		)
	)
	(footprint ""
		(layer "F.Cu")
		(at 463.0039 -292.016942)
		(property "Reference" "Q62"
			(at 0 0 0)
			(layer "F.SilkS")
			(hide yes)
			(effects
				(font
					(size 1.27 1.27)
				)
			)
		)
		(property "Value" "AO4407AL-GP"
			(at -3.707384 -1.5367 0)
			(unlocked yes)
			(layer "F.Fab")
			(hide yes)
			(effects
				(font
					(size 1.016 1.016)
					(thickness 0.1524)
				)
			)
		)
		(property "Device Type" "SOIC8H69"
			(at -3.707384 -3.0607 0)
			(unlocked yes)
			(layer "F.Fab")
			(hide yes)
			(effects
				(font
					(size 1.016 1.016)
					(thickness 0.1524)
				)
			)
		)
		(duplicate_pad_numbers_are_jumpers no)
		(fp_line
			(start -2.7432 -1.4224)
			(end -2.7432 1.4224)
			(stroke
				(width 0.1524)
				(type default)
			)
			(layer "F.SilkS")
		)
		(fp_line
			(start -2.7432 1.4224)
			(end -2.6416 1.4224)
			(stroke
				(width 0.1524)
				(type default)
			)
			(layer "F.SilkS")
		)
		(fp_line
			(start -2.7432 1.4224)
			(end 2.1336 1.4224)
			(stroke
				(width 0.1524)
				(type default)
			)
			(layer "F.SilkS")
		)
		(fp_line
			(start -2.7178 -0.508)
			(end -2.1844 -0.0508)
			(stroke
				(width 0.1524)
				(type default)
			)
			(layer "F.SilkS")
		)
		(fp_line
			(start -2.6289 3.4417)
			(end -2.6289 1.4732)
			(stroke
				(width 0.381)
				(type default)
			)
			(layer "F.SilkS")
		)
		(fp_line
			(start -2.1844 -0.0508)
			(end -2.7178 0.508)
			(stroke
				(width 0.1524)
				(type default)
			)
			(layer "F.SilkS")
		)
		(fp_line
			(start 2.1336 -1.4224)
			(end -2.7432 -1.4224)
			(stroke
				(width 0.1524)
				(type default)
			)
			(layer "F.SilkS")
		)
		(fp_line
			(start 2.1336 1.4224)
			(end 2.1336 -1.4224)
			(stroke
				(width 0.1524)
				(type default)
			)
			(layer "F.SilkS")
		)
		(fp_poly
			(pts
				(xy -2.2098 -1.4224) (xy -2.2098 1.4224) (xy 2.2098 1.4224) (xy 2.2098 -1.4224)
			)
			(stroke
				(width 0)
				(type default)
			)
			(fill yes)
			(layer "F.SilkS")
		)
		(fp_rect
			(start -2.450084 2.999994)
			(end 2.450084 -2.999994)
			(stroke
				(width 0)
				(type default)
			)
			(fill no)
			(layer "F.CrtYd")
		)
		(fp_poly
			(pts
				(xy -2.8194 3.6322) (xy -2.8194 -3.6322) (xy 2.8194 -3.6322) (xy 2.8194 1.18364) (xy 2.450084 1.18364)
				(xy 2.450084 -2.999994) (xy -2.450084 -2.999994) (xy -2.450084 2.999994) (xy 2.450084 2.999994)
				(xy 2.450084 1.18618) (xy 2.8194 1.18618) (xy 2.8194 3.6322)
			)
			(stroke
				(width 0)
				(type default)
			)
			(fill no)
			(layer "F.CrtYd")
		)
		(fp_rect
			(start -2.8194 3.6322)
			(end 2.8194 -3.6322)
			(stroke
				(width 0)
				(type default)
			)
			(fill no)
			(layer "F.Fab")
		)
		(pad "1" smd rect
			(at -1.905 2.54)
			(size 0.635 1.651)
			(layers "F.Cu" "F.Mask" "F.Paste")
			(net "P12V_A")
		)
		(pad "2" smd rect
			(at -0.635 2.54)
			(size 0.635 1.651)
			(layers "F.Cu" "F.Mask" "F.Paste")
			(net "P12V_A")
		)
		(pad "3" smd rect
			(at 0.635 2.54)
			(size 0.635 1.651)
			(layers "F.Cu" "F.Mask" "F.Paste")
			(net "P12V_A")
		)
		(pad "4" smd rect
			(at 1.905 2.54)
			(size 0.635 1.651)
			(layers "F.Cu" "F.Mask" "F.Paste")
			(net "SW_HDD_N10")
		)
		(pad "5" smd rect
			(at 1.905 -2.54)
			(size 0.635 1.651)
			(layers "F.Cu" "F.Mask" "F.Paste")
			(net "P12V_HDD10")
		)
		(pad "6" smd rect
			(at 0.635 -2.54)
			(size 0.635 1.651)
			(layers "F.Cu" "F.Mask" "F.Paste")
			(net "P12V_HDD10")
		)
		(pad "7" smd rect
			(at -0.635 -2.54)
			(size 0.635 1.651)
			(layers "F.Cu" "F.Mask" "F.Paste")
			(net "P12V_HDD10")
		)
		(pad "8" smd rect
			(at -1.905 -2.54)
			(size 0.635 1.651)
			(layers "F.Cu" "F.Mask" "F.Paste")
			(net "P12V_HDD10")
		)
	)
	(footprint ""
		(layer "F.Cu")
		(at 351.208086 -62.186566 -90)
		(property "Reference" "R843"
			(at 0 0 270)
			(layer "F.SilkS")
			(hide yes)
			(effects
				(font
					(size 1.27 1.27)
				)
			)
		)
		(property "Value" "10KR2F-2-GP"
			(at 0.064008 -3.993896 270)
			(unlocked yes)
			(layer "F.Fab")
			(hide yes)
			(effects
				(font
					(size 1.016 1.016)
					(thickness 0.1524)
				)
			)
		)
		(property "Device Type" "R402H16"
			(at 0.064008 -5.517896 270)
			(unlocked yes)
			(layer "F.Fab")
			(hide yes)
			(effects
				(font
					(size 1.016 1.016)
					(thickness 0.1524)
				)
			)
		)
		(duplicate_pad_numbers_are_jumpers no)
		(fp_line
			(start -0.508 -0.9398)
			(end -0.508 0.9398)
			(stroke
				(width 0.1524)
				(type default)
			)
			(layer "F.SilkS")
		)
		(fp_line
			(start 0.508 -0.9398)
			(end -0.508 -0.9398)
			(stroke
				(width 0.1524)
				(type default)
			)
			(layer "F.SilkS")
		)
		(fp_rect
			(start -0.508 0.9398)
			(end 0.508 -0.9398)
			(stroke
				(width 0)
				(type default)
			)
			(fill no)
			(layer "F.CrtYd")
		)
		(fp_rect
			(start -0.508 0.9398)
			(end 0.508 -0.9398)
			(stroke
				(width 0)
				(type default)
			)
			(fill no)
			(layer "F.Fab")
		)
		(pad "1" smd custom
			(at 0 -0.4445 270)
			(size 0.1397 0.1397)
			(layers "F.Cu" "F.Mask" "F.Paste")
			(net "P3V3_STBY_A")
			(options
				(clearance outline)
				(anchor circle)
			)
			(primitives
				(gr_poly
					(pts
						(arc
							(start -0.1778 -0.2794)
							(mid -0.249642 -0.249642)
							(end -0.2794 -0.1778)
						)
						(arc
							(start -0.2794 0.1778)
							(mid -0.249642 0.249642)
							(end -0.1778 0.2794)
						)
						(arc
							(start 0.1778 0.2794)
							(mid 0.249642 0.249642)
							(end 0.2794 0.1778)
						)
						(arc
							(start 0.2794 -0.1778)
							(mid 0.249642 -0.249642)
							(end 0.1778 -0.2794)
						)
					)
					(width 0)
					(fill yes)
				)
			)
		)
		(pad "2" smd custom
			(at 0 0.4445 270)
			(size 0.1397 0.1397)
			(layers "F.Cu" "F.Mask" "F.Paste")
			(net "HDD_PRSNT_31")
			(options
				(clearance outline)
				(anchor circle)
			)
			(primitives
				(gr_poly
					(pts
						(arc
							(start -0.1778 -0.2794)
							(mid -0.249642 -0.249642)
							(end -0.2794 -0.1778)
						)
						(arc
							(start -0.2794 0.1778)
							(mid -0.249642 0.249642)
							(end -0.1778 0.2794)
						)
						(arc
							(start 0.1778 0.2794)
							(mid 0.249642 0.249642)
							(end 0.2794 0.1778)
						)
						(arc
							(start 0.2794 -0.1778)
							(mid 0.249642 -0.249642)
							(end 0.1778 -0.2794)
						)
					)
					(width 0)
					(fill yes)
				)
			)
		)
	)
	(footprint ""
		(layer "F.Cu")
		(at 82.006948 -64.683894 90)
		(property "Reference" "R729"
			(at 0 0 90)
			(layer "F.SilkS")
			(hide yes)
			(effects
				(font
					(size 1.27 1.27)
				)
			)
		)
		(property "Value" "2R6F-GP"
			(at -0.0508 -4.8514 90)
			(unlocked yes)
			(layer "F.Fab")
			(hide yes)
			(effects
				(font
					(size 1.016 1.016)
					(thickness 0.1524)
				)
			)
		)
		(property "Device Type" "R1206H26"
			(at 0 -6.3754 90)
			(unlocked yes)
			(layer "F.Fab")
			(hide yes)
			(effects
				(font
					(size 1.016 1.016)
					(thickness 0.1524)
				)
			)
		)
		(duplicate_pad_numbers_are_jumpers no)
		(fp_line
			(start 1.016 -2.2352)
			(end 1.016 2.2352)
			(stroke
				(width 0.1524)
				(type default)
			)
			(layer "F.SilkS")
		)
		(fp_line
			(start -1.016 -2.2352)
			(end 1.016 -2.2352)
			(stroke
				(width 0.1524)
				(type default)
			)
			(layer "F.SilkS")
		)
		(fp_line
			(start 1.016 2.2352)
			(end -1.016 2.2352)
			(stroke
				(width 0.1524)
				(type default)
			)
			(layer "F.SilkS")
		)
		(fp_line
			(start -1.016 2.2352)
			(end -1.016 -2.2352)
			(stroke
				(width 0.1524)
				(type default)
			)
			(layer "F.SilkS")
		)
		(fp_rect
			(start -1.0922 2.3114)
			(end 1.0922 -2.3114)
			(stroke
				(width 0)
				(type default)
			)
			(fill no)
			(layer "F.CrtYd")
		)
		(fp_poly
			(pts
				(xy -1.0922 -2.3114) (xy 1.0922 -2.3114) (xy 1.0922 2.3114) (xy -1.0922 2.3114)
			)
			(stroke
				(width 0)
				(type default)
			)
			(fill no)
			(layer "F.Fab")
		)
		(pad "1" smd rect
			(at 0 -1.397 90)
			(size 1.651 1.27)
			(layers "F.Cu" "F.Mask" "F.Paste")
			(net "P12V_HDD26")
		)
		(pad "2" smd rect
			(at 0 1.397 90)
			(size 1.651 1.27)
			(layers "F.Cu" "F.Mask" "F.Paste")
			(net "12V_PRE_26")
		)
	)
	(footprint ""
		(layer "F.Cu")
		(at 239.268 -382.1938)
		(property "Reference" "R1176"
			(at 0 0 0)
			(layer "F.SilkS")
			(hide yes)
			(effects
				(font
					(size 1.27 1.27)
				)
			)
		)
		(property "Value" "1KR2F-3-GP"
			(at 0.064008 -3.993896 0)
			(unlocked yes)
			(layer "F.Fab")
			(hide yes)
			(effects
				(font
					(size 1.016 1.016)
					(thickness 0.1524)
				)
			)
		)
		(property "Device Type" "R402H16"
			(at 0.064008 -5.517896 0)
			(unlocked yes)
			(layer "F.Fab")
			(hide yes)
			(effects
				(font
					(size 1.016 1.016)
					(thickness 0.1524)
				)
			)
		)
		(duplicate_pad_numbers_are_jumpers no)
		(fp_line
			(start -0.508 -0.9398)
			(end -0.508 0.9398)
			(stroke
				(width 0.1524)
				(type default)
			)
			(layer "F.SilkS")
		)
		(fp_line
			(start 0.508 -0.9398)
			(end -0.508 -0.9398)
			(stroke
				(width 0.1524)
				(type default)
			)
			(layer "F.SilkS")
		)
		(fp_rect
			(start -0.508 0.9398)
			(end 0.508 -0.9398)
			(stroke
				(width 0)
				(type default)
			)
			(fill no)
			(layer "F.CrtYd")
		)
		(fp_rect
			(start -0.508 0.9398)
			(end 0.508 -0.9398)
			(stroke
				(width 0)
				(type default)
			)
			(fill no)
			(layer "F.Fab")
		)
		(pad "1" smd custom
			(at 0 -0.4445)
			(size 0.1397 0.1397)
			(layers "F.Cu" "F.Mask" "F.Paste")
			(net "MB3_CM_VOUT_R")
			(options
				(clearance outline)
				(anchor circle)
			)
			(primitives
				(gr_poly
					(pts
						(arc
							(start -0.1778 -0.2794)
							(mid -0.249642 -0.249642)
							(end -0.2794 -0.1778)
						)
						(arc
							(start -0.2794 0.1778)
							(mid -0.249642 0.249642)
							(end -0.1778 0.2794)
						)
						(arc
							(start 0.1778 0.2794)
							(mid 0.249642 0.249642)
							(end 0.2794 0.1778)
						)
						(arc
							(start 0.2794 -0.1778)
							(mid 0.249642 -0.249642)
							(end 0.1778 -0.2794)
						)
					)
					(width 0)
					(fill yes)
				)
			)
		)
		(pad "2" smd custom
			(at 0 0.4445)
			(size 0.1397 0.1397)
			(layers "F.Cu" "F.Mask" "F.Paste")
			(net "P12V_A")
			(options
				(clearance outline)
				(anchor circle)
			)
			(primitives
				(gr_poly
					(pts
						(arc
							(start -0.1778 -0.2794)
							(mid -0.249642 -0.249642)
							(end -0.2794 -0.1778)
						)
						(arc
							(start -0.2794 0.1778)
							(mid -0.249642 0.249642)
							(end -0.1778 0.2794)
						)
						(arc
							(start 0.1778 0.2794)
							(mid 0.249642 0.249642)
							(end 0.2794 0.1778)
						)
						(arc
							(start 0.2794 -0.1778)
							(mid 0.249642 -0.249642)
							(end 0.1778 -0.2794)
						)
					)
					(width 0)
					(fill yes)
				)
			)
		)
	)
	(footprint ""
		(layer "F.Cu")
		(at 144.700498 -160.633918)
		(property "Reference" "R515"
			(at 0 0 0)
			(layer "F.SilkS")
			(hide yes)
			(effects
				(font
					(size 1.27 1.27)
				)
			)
		)
		(property "Value" "0R2J-2-GP"
			(at 0.064008 -3.993896 0)
			(unlocked yes)
			(layer "F.Fab")
			(hide yes)
			(effects
				(font
					(size 1.016 1.016)
					(thickness 0.1524)
				)
			)
		)
		(property "Device Type" "R402H16"
			(at 0.064008 -5.517896 0)
			(unlocked yes)
			(layer "F.Fab")
			(hide yes)
			(effects
				(font
					(size 1.016 1.016)
					(thickness 0.1524)
				)
			)
		)
		(duplicate_pad_numbers_are_jumpers no)
		(fp_line
			(start -0.508 -0.9398)
			(end -0.508 0.9398)
			(stroke
				(width 0.1524)
				(type default)
			)
			(layer "F.SilkS")
		)
		(fp_line
			(start 0.508 -0.9398)
			(end -0.508 -0.9398)
			(stroke
				(width 0.1524)
				(type default)
			)
			(layer "F.SilkS")
		)
		(fp_rect
			(start -0.508 0.9398)
			(end 0.508 -0.9398)
			(stroke
				(width 0)
				(type default)
			)
			(fill no)
			(layer "F.CrtYd")
		)
		(fp_rect
			(start -0.508 0.9398)
			(end 0.508 -0.9398)
			(stroke
				(width 0)
				(type default)
			)
			(fill no)
			(layer "F.Fab")
		)
		(pad "1" smd custom
			(at 0 -0.4445)
			(size 0.1397 0.1397)
			(layers "F.Cu" "F.Mask" "F.Paste")
			(net "SW_HDD_G16")
			(options
				(clearance outline)
				(anchor circle)
			)
			(primitives
				(gr_poly
					(pts
						(arc
							(start -0.1778 -0.2794)
							(mid -0.249642 -0.249642)
							(end -0.2794 -0.1778)
						)
						(arc
							(start -0.2794 0.1778)
							(mid -0.249642 0.249642)
							(end -0.1778 0.2794)
						)
						(arc
							(start 0.1778 0.2794)
							(mid 0.249642 0.249642)
							(end 0.2794 0.1778)
						)
						(arc
							(start 0.2794 -0.1778)
							(mid 0.249642 -0.249642)
							(end 0.1778 -0.2794)
						)
					)
					(width 0)
					(fill yes)
				)
			)
		)
		(pad "2" smd custom
			(at 0 0.4445)
			(size 0.1397 0.1397)
			(layers "F.Cu" "F.Mask" "F.Paste")
			(net "SW_HDD_R16")
			(options
				(clearance outline)
				(anchor circle)
			)
			(primitives
				(gr_poly
					(pts
						(arc
							(start -0.1778 -0.2794)
							(mid -0.249642 -0.249642)
							(end -0.2794 -0.1778)
						)
						(arc
							(start -0.2794 0.1778)
							(mid -0.249642 0.249642)
							(end -0.1778 0.2794)
						)
						(arc
							(start 0.1778 0.2794)
							(mid 0.249642 0.249642)
							(end 0.2794 0.1778)
						)
						(arc
							(start 0.2794 -0.1778)
							(mid 0.249642 -0.249642)
							(end 0.1778 -0.2794)
						)
					)
					(width 0)
					(fill yes)
				)
			)
		)
	)
	(footprint ""
		(layer "F.Cu")
		(at 398.88795 -42.585894 180)
		(property "Reference" "R876"
			(at 0 0 180)
			(layer "F.SilkS")
			(hide yes)
			(effects
				(font
					(size 1.27 1.27)
				)
			)
		)
		(property "Value" "0R2J-2-GP"
			(at 0.064008 -3.993896 180)
			(unlocked yes)
			(layer "F.Fab")
			(hide yes)
			(effects
				(font
					(size 1.016 1.016)
					(thickness 0.1524)
				)
			)
		)
		(property "Device Type" "R402H16"
			(at 0.064008 -5.517896 180)
			(unlocked yes)
			(layer "F.Fab")
			(hide yes)
			(effects
				(font
					(size 1.016 1.016)
					(thickness 0.1524)
				)
			)
		)
		(duplicate_pad_numbers_are_jumpers no)
		(fp_line
			(start 0.508 -0.9398)
			(end -0.508 -0.9398)
			(stroke
				(width 0.1524)
				(type default)
			)
			(layer "F.SilkS")
		)
		(fp_line
			(start -0.508 -0.9398)
			(end -0.508 0.9398)
			(stroke
				(width 0.1524)
				(type default)
			)
			(layer "F.SilkS")
		)
		(fp_rect
			(start -0.508 0.9398)
			(end 0.508 -0.9398)
			(stroke
				(width 0)
				(type default)
			)
			(fill no)
			(layer "F.CrtYd")
		)
		(fp_rect
			(start -0.508 0.9398)
			(end 0.508 -0.9398)
			(stroke
				(width 0)
				(type default)
			)
			(fill no)
			(layer "F.Fab")
		)
		(pad "1" smd custom
			(at 0 -0.4445 180)
			(size 0.1397 0.1397)
			(layers "F.Cu" "F.Mask" "F.Paste")
			(net "DRIVE_A_32_PWR")
			(options
				(clearance outline)
				(anchor circle)
			)
			(primitives
				(gr_poly
					(pts
						(arc
							(start -0.1778 -0.2794)
							(mid -0.249642 -0.249642)
							(end -0.2794 -0.1778)
						)
						(arc
							(start -0.2794 0.1778)
							(mid -0.249642 0.249642)
							(end -0.1778 0.2794)
						)
						(arc
							(start 0.1778 0.2794)
							(mid 0.249642 0.249642)
							(end 0.2794 0.1778)
						)
						(arc
							(start 0.2794 -0.1778)
							(mid 0.249642 -0.249642)
							(end 0.1778 -0.2794)
						)
					)
					(width 0)
					(fill yes)
				)
			)
		)
		(pad "2" smd custom
			(at 0 0.4445 180)
			(size 0.1397 0.1397)
			(layers "F.Cu" "F.Mask" "F.Paste")
			(net "SW_PWR_R_HDD32")
			(options
				(clearance outline)
				(anchor circle)
			)
			(primitives
				(gr_poly
					(pts
						(arc
							(start -0.1778 -0.2794)
							(mid -0.249642 -0.249642)
							(end -0.2794 -0.1778)
						)
						(arc
							(start -0.2794 0.1778)
							(mid -0.249642 0.249642)
							(end -0.1778 0.2794)
						)
						(arc
							(start 0.1778 0.2794)
							(mid 0.249642 0.249642)
							(end 0.2794 0.1778)
						)
						(arc
							(start 0.2794 -0.1778)
							(mid 0.249642 -0.249642)
							(end 0.1778 -0.2794)
						)
					)
					(width 0)
					(fill yes)
				)
			)
		)
	)
	(footprint ""
		(layer "F.Cu")
		(at 260.84149 -230.785162 -90)
		(property "Reference" "R95"
			(at 0 0 270)
			(layer "F.SilkS")
			(hide yes)
			(effects
				(font
					(size 1.27 1.27)
				)
			)
		)
		(property "Value" "0R2J-2-GP"
			(at 0.064008 -3.993896 270)
			(unlocked yes)
			(layer "F.Fab")
			(hide yes)
			(effects
				(font
					(size 1.016 1.016)
					(thickness 0.1524)
				)
			)
		)
		(property "Device Type" "R402H16"
			(at 0.064008 -5.517896 270)
			(unlocked yes)
			(layer "F.Fab")
			(hide yes)
			(effects
				(font
					(size 1.016 1.016)
					(thickness 0.1524)
				)
			)
		)
		(duplicate_pad_numbers_are_jumpers no)
		(fp_line
			(start -0.508 -0.9398)
			(end -0.508 0.9398)
			(stroke
				(width 0.1524)
				(type default)
			)
			(layer "F.SilkS")
		)
		(fp_line
			(start 0.508 -0.9398)
			(end -0.508 -0.9398)
			(stroke
				(width 0.1524)
				(type default)
			)
			(layer "F.SilkS")
		)
		(fp_rect
			(start -0.508 0.9398)
			(end 0.508 -0.9398)
			(stroke
				(width 0)
				(type default)
			)
			(fill no)
			(layer "F.CrtYd")
		)
		(fp_rect
			(start -0.508 0.9398)
			(end 0.508 -0.9398)
			(stroke
				(width 0)
				(type default)
			)
			(fill no)
			(layer "F.Fab")
		)
		(pad "1" smd custom
			(at 0 -0.4445 270)
			(size 0.1397 0.1397)
			(layers "F.Cu" "F.Mask" "F.Paste")
			(net "IO_EXP3_SDA")
			(options
				(clearance outline)
				(anchor circle)
			)
			(primitives
				(gr_poly
					(pts
						(arc
							(start -0.1778 -0.2794)
							(mid -0.249642 -0.249642)
							(end -0.2794 -0.1778)
						)
						(arc
							(start -0.2794 0.1778)
							(mid -0.249642 0.249642)
							(end -0.1778 0.2794)
						)
						(arc
							(start 0.1778 0.2794)
							(mid 0.249642 0.249642)
							(end 0.2794 0.1778)
						)
						(arc
							(start 0.2794 -0.1778)
							(mid 0.249642 -0.249642)
							(end 0.1778 -0.2794)
						)
					)
					(width 0)
					(fill yes)
				)
			)
		)
		(pad "2" smd custom
			(at 0 0.4445 270)
			(size 0.1397 0.1397)
			(layers "F.Cu" "F.Mask" "F.Paste")
			(net "I2C_DRIVE_A_PWR_SDA")
			(options
				(clearance outline)
				(anchor circle)
			)
			(primitives
				(gr_poly
					(pts
						(arc
							(start -0.1778 -0.2794)
							(mid -0.249642 -0.249642)
							(end -0.2794 -0.1778)
						)
						(arc
							(start -0.2794 0.1778)
							(mid -0.249642 0.249642)
							(end -0.1778 0.2794)
						)
						(arc
							(start 0.1778 0.2794)
							(mid 0.249642 0.249642)
							(end 0.2794 0.1778)
						)
						(arc
							(start 0.2794 -0.1778)
							(mid 0.249642 -0.249642)
							(end 0.1778 -0.2794)
						)
					)
					(width 0)
					(fill yes)
				)
			)
		)
	)
	(footprint ""
		(layer "F.Cu")
		(at 271.526 -272.288)
		(property "Reference" "R113"
			(at 0 0 0)
			(layer "F.SilkS")
			(hide yes)
			(effects
				(font
					(size 1.27 1.27)
				)
			)
		)
		(property "Value" "4K7R2F-GP"
			(at 0.064008 -3.993896 0)
			(unlocked yes)
			(layer "F.Fab")
			(hide yes)
			(effects
				(font
					(size 1.016 1.016)
					(thickness 0.1524)
				)
			)
		)
		(property "Device Type" "R402H16"
			(at 0.064008 -5.517896 0)
			(unlocked yes)
			(layer "F.Fab")
			(hide yes)
			(effects
				(font
					(size 1.016 1.016)
					(thickness 0.1524)
				)
			)
		)
		(duplicate_pad_numbers_are_jumpers no)
		(fp_line
			(start -0.508 -0.9398)
			(end -0.508 0.9398)
			(stroke
				(width 0.1524)
				(type default)
			)
			(layer "F.SilkS")
		)
		(fp_line
			(start 0.508 -0.9398)
			(end -0.508 -0.9398)
			(stroke
				(width 0.1524)
				(type default)
			)
			(layer "F.SilkS")
		)
		(fp_rect
			(start -0.508 0.9398)
			(end 0.508 -0.9398)
			(stroke
				(width 0)
				(type default)
			)
			(fill no)
			(layer "F.CrtYd")
		)
		(fp_rect
			(start -0.508 0.9398)
			(end 0.508 -0.9398)
			(stroke
				(width 0)
				(type default)
			)
			(fill no)
			(layer "F.Fab")
		)
		(pad "1" smd custom
			(at 0 -0.4445)
			(size 0.1397 0.1397)
			(layers "F.Cu" "F.Mask" "F.Paste")
			(net "IO_EXP1_HDD_FAULT_INT_N")
			(options
				(clearance outline)
				(anchor circle)
			)
			(primitives
				(gr_poly
					(pts
						(arc
							(start -0.1778 -0.2794)
							(mid -0.249642 -0.249642)
							(end -0.2794 -0.1778)
						)
						(arc
							(start -0.2794 0.1778)
							(mid -0.249642 0.249642)
							(end -0.1778 0.2794)
						)
						(arc
							(start 0.1778 0.2794)
							(mid 0.249642 0.249642)
							(end 0.2794 0.1778)
						)
						(arc
							(start 0.2794 -0.1778)
							(mid 0.249642 -0.249642)
							(end 0.1778 -0.2794)
						)
					)
					(width 0)
					(fill yes)
				)
			)
		)
		(pad "2" smd custom
			(at 0 0.4445)
			(size 0.1397 0.1397)
			(layers "F.Cu" "F.Mask" "F.Paste")
			(net "P3V3_STBY_A")
			(options
				(clearance outline)
				(anchor circle)
			)
			(primitives
				(gr_poly
					(pts
						(arc
							(start -0.1778 -0.2794)
							(mid -0.249642 -0.249642)
							(end -0.2794 -0.1778)
						)
						(arc
							(start -0.2794 0.1778)
							(mid -0.249642 0.249642)
							(end -0.1778 0.2794)
						)
						(arc
							(start 0.1778 0.2794)
							(mid 0.249642 0.249642)
							(end 0.2794 0.1778)
						)
						(arc
							(start 0.2794 -0.1778)
							(mid 0.249642 -0.249642)
							(end 0.1778 -0.2794)
						)
					)
					(width 0)
					(fill yes)
				)
			)
		)
	)
	(footprint ""
		(layer "F.Cu")
		(at 86.096348 -161.040318 -90)
		(property "Reference" "R460"
			(at 0 0 270)
			(layer "F.SilkS")
			(hide yes)
			(effects
				(font
					(size 1.27 1.27)
				)
			)
		)
		(property "Value" "1KR2F-3-GP"
			(at 0.064008 -3.993896 270)
			(unlocked yes)
			(layer "F.Fab")
			(hide yes)
			(effects
				(font
					(size 1.016 1.016)
					(thickness 0.1524)
				)
			)
		)
		(property "Device Type" "R402H16"
			(at 0.064008 -5.517896 270)
			(unlocked yes)
			(layer "F.Fab")
			(hide yes)
			(effects
				(font
					(size 1.016 1.016)
					(thickness 0.1524)
				)
			)
		)
		(duplicate_pad_numbers_are_jumpers no)
		(fp_line
			(start -0.508 -0.9398)
			(end -0.508 0.9398)
			(stroke
				(width 0.1524)
				(type default)
			)
			(layer "F.SilkS")
		)
		(fp_line
			(start 0.508 -0.9398)
			(end -0.508 -0.9398)
			(stroke
				(width 0.1524)
				(type default)
			)
			(layer "F.SilkS")
		)
		(fp_rect
			(start -0.508 0.9398)
			(end 0.508 -0.9398)
			(stroke
				(width 0)
				(type default)
			)
			(fill no)
			(layer "F.CrtYd")
		)
		(fp_rect
			(start -0.508 0.9398)
			(end 0.508 -0.9398)
			(stroke
				(width 0)
				(type default)
			)
			(fill no)
			(layer "F.Fab")
		)
		(pad "1" smd custom
			(at 0 -0.4445 270)
			(size 0.1397 0.1397)
			(layers "F.Cu" "F.Mask" "F.Paste")
			(net "P3V3_STBY_A")
			(options
				(clearance outline)
				(anchor circle)
			)
			(primitives
				(gr_poly
					(pts
						(arc
							(start -0.1778 -0.2794)
							(mid -0.249642 -0.249642)
							(end -0.2794 -0.1778)
						)
						(arc
							(start -0.2794 0.1778)
							(mid -0.249642 0.249642)
							(end -0.1778 0.2794)
						)
						(arc
							(start 0.1778 0.2794)
							(mid 0.249642 0.249642)
							(end 0.2794 0.1778)
						)
						(arc
							(start 0.2794 -0.1778)
							(mid 0.249642 -0.249642)
							(end 0.1778 -0.2794)
						)
					)
					(width 0)
					(fill yes)
				)
			)
		)
		(pad "2" smd custom
			(at 0 0.4445 270)
			(size 0.1397 0.1397)
			(layers "F.Cu" "F.Mask" "F.Paste")
			(net "SW_PWR_R_HDD14")
			(options
				(clearance outline)
				(anchor circle)
			)
			(primitives
				(gr_poly
					(pts
						(arc
							(start -0.1778 -0.2794)
							(mid -0.249642 -0.249642)
							(end -0.2794 -0.1778)
						)
						(arc
							(start -0.2794 0.1778)
							(mid -0.249642 0.249642)
							(end -0.1778 0.2794)
						)
						(arc
							(start 0.1778 0.2794)
							(mid 0.249642 0.249642)
							(end 0.2794 0.1778)
						)
						(arc
							(start 0.2794 -0.1778)
							(mid 0.249642 -0.249642)
							(end 0.1778 -0.2794)
						)
					)
					(width 0)
					(fill yes)
				)
			)
		)
	)
	(footprint ""
		(layer "F.Cu")
		(at 401.17395 -49.443894 90)
		(property "Reference" "R882"
			(at 0 0 90)
			(layer "F.SilkS")
			(hide yes)
			(effects
				(font
					(size 1.27 1.27)
				)
			)
		)
		(property "Value" "200KR2F-L-GP"
			(at 0.064008 -3.993896 90)
			(unlocked yes)
			(layer "F.Fab")
			(hide yes)
			(effects
				(font
					(size 1.016 1.016)
					(thickness 0.1524)
				)
			)
		)
		(property "Device Type" "R402H16"
			(at 0.064008 -5.517896 90)
			(unlocked yes)
			(layer "F.Fab")
			(hide yes)
			(effects
				(font
					(size 1.016 1.016)
					(thickness 0.1524)
				)
			)
		)
		(duplicate_pad_numbers_are_jumpers no)
		(fp_line
			(start 0.508 -0.9398)
			(end -0.508 -0.9398)
			(stroke
				(width 0.1524)
				(type default)
			)
			(layer "F.SilkS")
		)
		(fp_line
			(start -0.508 -0.9398)
			(end -0.508 0.9398)
			(stroke
				(width 0.1524)
				(type default)
			)
			(layer "F.SilkS")
		)
		(fp_rect
			(start -0.508 0.9398)
			(end 0.508 -0.9398)
			(stroke
				(width 0)
				(type default)
			)
			(fill no)
			(layer "F.CrtYd")
		)
		(fp_rect
			(start -0.508 0.9398)
			(end 0.508 -0.9398)
			(stroke
				(width 0)
				(type default)
			)
			(fill no)
			(layer "F.Fab")
		)
		(pad "1" smd custom
			(at 0 -0.4445 90)
			(size 0.1397 0.1397)
			(layers "F.Cu" "F.Mask" "F.Paste")
			(net "SW_HDD_R32")
			(options
				(clearance outline)
				(anchor circle)
			)
			(primitives
				(gr_poly
					(pts
						(arc
							(start -0.1778 -0.2794)
							(mid -0.249642 -0.249642)
							(end -0.2794 -0.1778)
						)
						(arc
							(start -0.2794 0.1778)
							(mid -0.249642 0.249642)
							(end -0.1778 0.2794)
						)
						(arc
							(start 0.1778 0.2794)
							(mid 0.249642 0.249642)
							(end 0.2794 0.1778)
						)
						(arc
							(start 0.2794 -0.1778)
							(mid 0.249642 -0.249642)
							(end 0.1778 -0.2794)
						)
					)
					(width 0)
					(fill yes)
				)
			)
		)
		(pad "2" smd custom
			(at 0 0.4445 90)
			(size 0.1397 0.1397)
			(layers "F.Cu" "F.Mask" "F.Paste")
			(net "SW_HDD_N32")
			(options
				(clearance outline)
				(anchor circle)
			)
			(primitives
				(gr_poly
					(pts
						(arc
							(start -0.1778 -0.2794)
							(mid -0.249642 -0.249642)
							(end -0.2794 -0.1778)
						)
						(arc
							(start -0.2794 0.1778)
							(mid -0.249642 0.249642)
							(end -0.1778 0.2794)
						)
						(arc
							(start 0.1778 0.2794)
							(mid 0.249642 0.249642)
							(end 0.2794 0.1778)
						)
						(arc
							(start 0.2794 -0.1778)
							(mid 0.249642 -0.249642)
							(end 0.1778 -0.2794)
						)
					)
					(width 0)
					(fill yes)
				)
			)
		)
	)
	(footprint ""
		(layer "F.Cu")
		(at 272.542 -350.505014 180)
		(property "Reference" "VIA43"
			(at 0 0 180)
			(layer "F.SilkS")
			(hide yes)
			(effects
				(font
					(size 1.27 1.27)
				)
			)
		)
		(property "Value" "100OHM-8L-1D6MM-L18L16-GP"
			(at -3.7211 -4.5085 180)
			(unlocked yes)
			(layer "F.Fab")
			(hide yes)
			(effects
				(font
					(size 1.016 1.016)
					(thickness 0.1524)
				)
			)
		)
		(property "Device Type" "VIA-PCIE-4P-394076"
			(at -3.7211 -6.0325 180)
			(unlocked yes)
			(layer "F.Fab")
			(hide yes)
			(effects
				(font
					(size 1.016 1.016)
					(thickness 0.1524)
				)
			)
		)
		(duplicate_pad_numbers_are_jumpers no)
		(fp_rect
			(start -1.9685 0.381)
			(end 1.9685 -0.381)
			(stroke
				(width 0)
				(type default)
			)
			(fill no)
			(layer "F.CrtYd")
		)
		(fp_rect
			(start -1.9685 0.381)
			(end 1.9685 -0.381)
			(stroke
				(width 0)
				(type default)
			)
			(fill no)
			(layer "F.Fab")
		)
		(pad "1" thru_hole circle
			(at -1.5875 0 180)
			(size 0.508 0.508)
			(drill 0.254)
			(layers "*.Cu" "*.Mask")
			(remove_unused_layers no)
			(net "GND")
			(clearance 0.127)
			(thermal_gap 0.127)
		)
		(pad "2" thru_hole circle
			(at -0.5715 0 180)
			(size 0.508 0.508)
			(drill 0.254)
			(layers "*.Cu" "*.Mask")
			(remove_unused_layers no)
			(net "PHY_SCC_A_TO_DRV_A_5_DP")
			(clearance 0.127)
			(thermal_gap 0.127)
		)
		(pad "3" thru_hole circle
			(at 0.5715 0 180)
			(size 0.508 0.508)
			(drill 0.254)
			(layers "*.Cu" "*.Mask")
			(remove_unused_layers no)
			(net "PHY_SCC_A_TO_DRV_A_5_DN")
			(clearance 0.127)
			(thermal_gap 0.127)
		)
		(pad "4" thru_hole circle
			(at 1.5875 0 180)
			(size 0.508 0.508)
			(drill 0.254)
			(layers "*.Cu" "*.Mask")
			(remove_unused_layers no)
			(net "GND")
			(clearance 0.127)
			(thermal_gap 0.127)
		)
	)
	(footprint ""
		(layer "F.Cu")
		(at 144.700498 -275.633942)
		(property "Reference" "R239"
			(at 0 0 0)
			(layer "F.SilkS")
			(hide yes)
			(effects
				(font
					(size 1.27 1.27)
				)
			)
		)
		(property "Value" "0R2J-2-GP"
			(at 0.064008 -3.993896 0)
			(unlocked yes)
			(layer "F.Fab")
			(hide yes)
			(effects
				(font
					(size 1.016 1.016)
					(thickness 0.1524)
				)
			)
		)
		(property "Device Type" "R402H16"
			(at 0.064008 -5.517896 0)
			(unlocked yes)
			(layer "F.Fab")
			(hide yes)
			(effects
				(font
					(size 1.016 1.016)
					(thickness 0.1524)
				)
			)
		)
		(duplicate_pad_numbers_are_jumpers no)
		(fp_line
			(start -0.508 -0.9398)
			(end -0.508 0.9398)
			(stroke
				(width 0.1524)
				(type default)
			)
			(layer "F.SilkS")
		)
		(fp_line
			(start 0.508 -0.9398)
			(end -0.508 -0.9398)
			(stroke
				(width 0.1524)
				(type default)
			)
			(layer "F.SilkS")
		)
		(fp_rect
			(start -0.508 0.9398)
			(end 0.508 -0.9398)
			(stroke
				(width 0)
				(type default)
			)
			(fill no)
			(layer "F.CrtYd")
		)
		(fp_rect
			(start -0.508 0.9398)
			(end 0.508 -0.9398)
			(stroke
				(width 0)
				(type default)
			)
			(fill no)
			(layer "F.Fab")
		)
		(pad "1" smd custom
			(at 0 -0.4445)
			(size 0.1397 0.1397)
			(layers "F.Cu" "F.Mask" "F.Paste")
			(net "SW_HDD_G4")
			(options
				(clearance outline)
				(anchor circle)
			)
			(primitives
				(gr_poly
					(pts
						(arc
							(start -0.1778 -0.2794)
							(mid -0.249642 -0.249642)
							(end -0.2794 -0.1778)
						)
						(arc
							(start -0.2794 0.1778)
							(mid -0.249642 0.249642)
							(end -0.1778 0.2794)
						)
						(arc
							(start 0.1778 0.2794)
							(mid 0.249642 0.249642)
							(end 0.2794 0.1778)
						)
						(arc
							(start 0.2794 -0.1778)
							(mid 0.249642 -0.249642)
							(end 0.1778 -0.2794)
						)
					)
					(width 0)
					(fill yes)
				)
			)
		)
		(pad "2" smd custom
			(at 0 0.4445)
			(size 0.1397 0.1397)
			(layers "F.Cu" "F.Mask" "F.Paste")
			(net "SW_HDD_R4")
			(options
				(clearance outline)
				(anchor circle)
			)
			(primitives
				(gr_poly
					(pts
						(arc
							(start -0.1778 -0.2794)
							(mid -0.249642 -0.249642)
							(end -0.2794 -0.1778)
						)
						(arc
							(start -0.2794 0.1778)
							(mid -0.249642 0.249642)
							(end -0.1778 0.2794)
						)
						(arc
							(start 0.1778 0.2794)
							(mid 0.249642 0.249642)
							(end 0.2794 0.1778)
						)
						(arc
							(start 0.2794 -0.1778)
							(mid 0.249642 -0.249642)
							(end 0.1778 -0.2794)
						)
					)
					(width 0)
					(fill yes)
				)
			)
		)
	)
	(footprint ""
		(layer "F.Cu")
		(at 91.300046 -57.909968 -90)
		(property "Reference" "HDDSAS26"
			(at 0 0 270)
			(layer "F.SilkS")
			(hide yes)
			(effects
				(font
					(size 1.27 1.27)
				)
			)
		)
		(property "Value" "SKT-SAS15P-14P-45-GP"
			(at -20.7645 -8.9789 270)
			(unlocked yes)
			(layer "F.Fab")
			(hide yes)
			(effects
				(font
					(size 1.016 1.016)
					(thickness 0.1524)
				)
			)
		)
		(property "Device Type" "10120818-001C-TRLF"
			(at -20.7645 -10.5029 270)
			(unlocked yes)
			(layer "F.Fab")
			(hide yes)
			(effects
				(font
					(size 1.016 1.016)
					(thickness 0.1524)
				)
			)
		)
		(duplicate_pad_numbers_are_jumpers no)
		(fp_line
			(start 1.651 4.2926)
			(end 1.651 3.0099)
			(stroke
				(width 0.1524)
				(type default)
			)
			(layer "F.SilkS")
		)
		(fp_line
			(start 8.509 4.2926)
			(end 1.651 4.2926)
			(stroke
				(width 0.1524)
				(type default)
			)
			(layer "F.SilkS")
		)
		(fp_line
			(start -23.4188 3.0099)
			(end -23.4188 -3.2512)
			(stroke
				(width 0.1524)
				(type default)
			)
			(layer "F.SilkS")
		)
		(fp_line
			(start 1.651 3.0099)
			(end -23.4188 3.0099)
			(stroke
				(width 0.1524)
				(type default)
			)
			(layer "F.SilkS")
		)
		(fp_line
			(start 8.509 3.0099)
			(end 8.509 4.2926)
			(stroke
				(width 0.1524)
				(type default)
			)
			(layer "F.SilkS")
		)
		(fp_line
			(start 23.4188 3.0099)
			(end 8.509 3.0099)
			(stroke
				(width 0.1524)
				(type default)
			)
			(layer "F.SilkS")
		)
		(fp_line
			(start -23.4188 -3.2512)
			(end 23.4188 -3.2512)
			(stroke
				(width 0.1524)
				(type default)
			)
			(layer "F.SilkS")
		)
		(fp_line
			(start 23.4188 -3.2512)
			(end 23.4188 3.0099)
			(stroke
				(width 0.1524)
				(type default)
			)
			(layer "F.SilkS")
		)
		(fp_line
			(start 15.5067 -3.3401)
			(end 16.2687 -3.3401)
			(stroke
				(width 0.3302)
				(type default)
			)
			(layer "F.SilkS")
		)
		(fp_poly
			(pts
				(xy 15.868904 -3.230372) (xy 16.503904 -3.865372) (xy 15.233904 -3.865372)
			)
			(stroke
				(width 0)
				(type default)
			)
			(fill yes)
			(layer "F.SilkS")
		)
		(fp_poly
			(pts
				(xy -22.8727 -2.7559) (xy 22.8727 -2.7559) (xy 22.8727 2.7559) (xy 8.255 2.7559) (xy 8.255 3.5179)
				(xy 1.905 3.5179) (xy 1.905 2.7559) (xy -22.8727 2.7559)
			)
			(stroke
				(width 0)
				(type default)
			)
			(fill no)
			(layer "F.CrtYd")
		)
		(fp_poly
			(pts
				(xy 1.397 4.5466) (xy 1.397 3.2639) (xy -23.6728 3.2639) (xy -23.6728 -3.5052) (xy 23.6728 -3.5052)
				(xy 23.6728 -0.00635) (xy 22.8727 -0.00635) (xy 22.8727 -2.7559) (xy -22.8727 -2.7559) (xy -22.8727 2.7559)
				(xy 1.905 2.7559) (xy 1.905 3.5179) (xy 8.255 3.5179) (xy 8.255 2.7559) (xy 22.8727 2.7559) (xy 22.8727 0.00635)
				(xy 23.6728 0.00635) (xy 23.6728 3.2639) (xy 8.763 3.2639) (xy 8.763 4.5466)
			)
			(stroke
				(width 0)
				(type default)
			)
			(fill no)
			(layer "F.CrtYd")
		)
		(fp_poly
			(pts
				(xy 1.397 4.5466) (xy 1.397 3.2639) (xy -23.6728 3.2639) (xy -23.6728 -3.5052) (xy 23.6728 -3.5052)
				(xy 23.6728 3.2639) (xy 8.763 3.2639) (xy 8.763 4.5466)
			)
			(stroke
				(width 0)
				(type default)
			)
			(fill no)
			(layer "F.Fab")
		)
		(pad "" np_thru_hole circle
			(at -18.874994 0 270)
			(size 0.254 0.254)
			(drill 1.3462)
			(layers "*.Cu" "*.Mask")
			(clearance 0.9017)
			(thermal_gap 0.9017)
		)
		(pad "" np_thru_hole circle
			(at 18.874994 0 270)
			(size 0.254 0.254)
			(drill 0.9398)
			(layers "*.Cu" "*.Mask")
			(clearance 0.6985)
			(thermal_gap 0.6985)
		)
		(pad "G1" smd rect
			(at 21.874988 0 270)
			(size 2.5908 2.5908)
			(layers "F.Cu" "F.Mask" "F.Paste")
			(net "GND")
		)
		(pad "G2" smd rect
			(at -21.874988 0 270)
			(size 2.5908 2.5908)
			(layers "F.Cu" "F.Mask" "F.Paste")
			(net "GND")
		)
		(pad "P1" smd rect
			(at 1.905 -1.82499 270)
			(size 0.6096 2.3622)
			(layers "F.Cu" "F.Mask" "F.Paste")
			(net "Net_2081")
		)
		(pad "P2" smd rect
			(at 0.635 -1.82499 270)
			(size 0.6096 2.3622)
			(layers "F.Cu" "F.Mask" "F.Paste")
			(net "Net_2082")
		)
		(pad "P3" smd rect
			(at -0.635 -1.82499 270)
			(size 0.6096 2.3622)
			(layers "F.Cu" "F.Mask" "F.Paste")
			(net "Net_2083")
		)
		(pad "P4" smd rect
			(at -1.905 -1.82499 270)
			(size 0.6096 2.3622)
			(layers "F.Cu" "F.Mask" "F.Paste")
			(net "GND")
		)
		(pad "P5" smd rect
			(at -3.175 -1.82499 270)
			(size 0.6096 2.3622)
			(layers "F.Cu" "F.Mask" "F.Paste")
			(net "HDD_PRSNT_26")
		)
		(pad "P6" smd rect
			(at -4.445 -1.82499 270)
			(size 0.6096 2.3622)
			(layers "F.Cu" "F.Mask" "F.Paste")
			(net "GND")
		)
		(pad "P7" smd rect
			(at -5.715 -1.82499 270)
			(size 0.6096 2.3622)
			(layers "F.Cu" "F.Mask" "F.Paste")
			(net "5V_PRE_26")
		)
		(pad "P8" smd rect
			(at -6.985 -1.82499 270)
			(size 0.6096 2.3622)
			(layers "F.Cu" "F.Mask" "F.Paste")
			(net "P5V_HDD26")
		)
		(pad "P9" smd rect
			(at -8.255 -1.82499 270)
			(size 0.6096 2.3622)
			(layers "F.Cu" "F.Mask" "F.Paste")
			(net "P5V_HDD26")
		)
		(pad "P10" smd rect
			(at -9.525 -1.82499 270)
			(size 0.6096 2.3622)
			(layers "F.Cu" "F.Mask" "F.Paste")
			(net "GND")
		)
		(pad "P11" smd rect
			(at -10.795 -1.82499 270)
			(size 0.6096 2.3622)
			(layers "F.Cu" "F.Mask" "F.Paste")
			(net "ACT_HDD_26")
		)
		(pad "P12" smd rect
			(at -12.065 -1.82499 270)
			(size 0.6096 2.3622)
			(layers "F.Cu" "F.Mask" "F.Paste")
			(net "GND")
		)
		(pad "P13" smd rect
			(at -13.335 -1.82499 270)
			(size 0.6096 2.3622)
			(layers "F.Cu" "F.Mask" "F.Paste")
			(net "12V_PRE_26")
		)
		(pad "P14" smd rect
			(at -14.605 -1.82499 270)
			(size 0.6096 2.3622)
			(layers "F.Cu" "F.Mask" "F.Paste")
			(net "P12V_HDD26")
		)
		(pad "P15" smd rect
			(at -15.875 -1.82499 270)
			(size 0.6096 2.3622)
			(layers "F.Cu" "F.Mask" "F.Paste")
			(net "P12V_HDD26")
		)
		(pad "S1" smd rect
			(at 15.875 -1.82499 270)
			(size 0.6096 2.3622)
			(layers "F.Cu" "F.Mask" "F.Paste")
			(net "GND")
		)
		(pad "S2" smd rect
			(at 14.605 -1.82499 270)
			(size 0.6096 2.3622)
			(layers "F.Cu" "F.Mask" "F.Paste")
			(net "SAS_HDD_RX_P26")
		)
		(pad "S3" smd rect
			(at 13.335 -1.82499 270)
			(size 0.6096 2.3622)
			(layers "F.Cu" "F.Mask" "F.Paste")
			(net "SAS_HDD_RX_N26")
		)
		(pad "S4" smd rect
			(at 12.065 -1.82499 270)
			(size 0.6096 2.3622)
			(layers "F.Cu" "F.Mask" "F.Paste")
			(net "GND")
		)
		(pad "S5" smd rect
			(at 10.795 -1.82499 270)
			(size 0.6096 2.3622)
			(layers "F.Cu" "F.Mask" "F.Paste")
			(net "PHY_DRV_A_TO_SCC_A_26_DN")
		)
		(pad "S6" smd rect
			(at 9.525 -1.82499 270)
			(size 0.6096 2.3622)
			(layers "F.Cu" "F.Mask" "F.Paste")
			(net "PHY_DRV_A_TO_SCC_A_26_DP")
		)
		(pad "S7" smd rect
			(at 8.255 -1.82499 270)
			(size 0.6096 2.3622)
			(layers "F.Cu" "F.Mask" "F.Paste")
			(net "GND")
		)
		(pad "S8" smd rect
			(at 7.480046 2.845054 270)
			(size 0.508 2.3622)
			(layers "F.Cu" "F.Mask" "F.Paste")
			(net "GND")
		)
		(pad "S9" smd rect
			(at 6.679946 2.845054 270)
			(size 0.508 2.3622)
			(layers "F.Cu" "F.Mask" "F.Paste")
			(net "Net_464")
		)
		(pad "S10" smd rect
			(at 5.8801 2.845054 270)
			(size 0.508 2.3622)
			(layers "F.Cu" "F.Mask" "F.Paste")
			(net "Net_356")
		)
		(pad "S11" smd rect
			(at 5.08 2.845054 270)
			(size 0.508 2.3622)
			(layers "F.Cu" "F.Mask" "F.Paste")
			(net "GND")
		)
		(pad "S12" smd rect
			(at 4.2799 2.845054 270)
			(size 0.508 2.3622)
			(layers "F.Cu" "F.Mask" "F.Paste")
			(net "Net_392")
		)
		(pad "S13" smd rect
			(at 3.480054 2.845054 270)
			(size 0.508 2.3622)
			(layers "F.Cu" "F.Mask" "F.Paste")
			(net "Net_428")
		)
		(pad "S14" smd rect
			(at 2.679954 2.845054 270)
			(size 0.508 2.3622)
			(layers "F.Cu" "F.Mask" "F.Paste")
			(net "GND")
		)
		(zone
			(layer "F.Cu")
			(hatch none 0.5)
			(connect_pads
				(clearance 0)
			)
			(min_thickness 0.25)
			(keepout
				(tracks not_allowed)
				(vias allowed)
				(pads allowed)
				(copperpour not_allowed)
				(footprints allowed)
			)
			(placement
				(enabled no)
				(sheetname "")
			)
			(fill
				(thermal_gap 0.5)
				(thermal_bridge_width 0.5)
				(island_removal_mode 0)
			)
			(polygon
				(pts
					(xy 94.957646 -74.648568) (xy 87.883746 -74.648568) (xy 87.883746 -81.582768) (xy 88.988646 -81.582768)
					(xy 88.988646 -77.467968) (xy 93.611446 -77.467968) (xy 93.611446 -81.582768) (xy 94.957646 -81.582768)
				)
			)
		)
		(zone
			(layer "F.Cu")
			(hatch none 0.5)
			(connect_pads
				(clearance 0)
			)
			(min_thickness 0.25)
			(keepout
				(tracks allowed)
				(vias not_allowed)
				(pads allowed)
				(copperpour not_allowed)
				(footprints allowed)
			)
			(placement
				(enabled no)
				(sheetname "")
			)
			(fill
				(thermal_gap 0.5)
				(thermal_bridge_width 0.5)
				(island_removal_mode 0)
			)
			(polygon
				(pts
					(xy 94.957646 -74.648568) (xy 87.883746 -74.648568) (xy 87.883746 -81.582768) (xy 88.988646 -81.582768)
					(xy 88.988646 -77.467968) (xy 93.611446 -77.467968) (xy 93.611446 -81.582768) (xy 94.957646 -81.582768)
				)
			)
		)
		(zone
			(layer "F.Cu")
			(hatch none 0.5)
			(connect_pads
				(clearance 0)
			)
			(min_thickness 0.25)
			(keepout
				(tracks not_allowed)
				(vias allowed)
				(pads allowed)
				(copperpour not_allowed)
				(footprints allowed)
			)
			(placement
				(enabled no)
				(sheetname "")
			)
			(fill
				(thermal_gap 0.5)
				(thermal_bridge_width 0.5)
				(island_removal_mode 0)
			)
			(polygon
				(pts
					(xy 94.957646 -41.171368) (xy 87.883746 -41.171368) (xy 87.883746 -34.237168) (xy 88.988646 -34.237168)
					(xy 88.988646 -38.351968) (xy 93.611446 -38.351968) (xy 93.611446 -34.237168) (xy 94.957646 -34.237168)
				)
			)
		)
		(zone
			(layer "F.Cu")
			(hatch none 0.5)
			(connect_pads
				(clearance 0)
			)
			(min_thickness 0.25)
			(keepout
				(tracks allowed)
				(vias not_allowed)
				(pads allowed)
				(copperpour not_allowed)
				(footprints allowed)
			)
			(placement
				(enabled no)
				(sheetname "")
			)
			(fill
				(thermal_gap 0.5)
				(thermal_bridge_width 0.5)
				(island_removal_mode 0)
			)
			(polygon
				(pts
					(xy 94.957646 -41.171368) (xy 87.883746 -41.171368) (xy 87.883746 -34.237168) (xy 88.988646 -34.237168)
					(xy 88.988646 -38.351968) (xy 93.611446 -38.351968) (xy 93.611446 -34.237168) (xy 94.957646 -34.237168)
				)
			)
		)
		(zone
			(layers "F.Cu" "B.Cu" "In1.Cu" "In2.Cu" "In3.Cu" "In4.Cu" "In5.Cu" "In6.Cu"
				"In7.Cu" "In8.Cu" "In9.Cu" "In10.Cu"
			)
			(hatch none 0.5)
			(connect_pads
				(clearance 0)
			)
			(min_thickness 0.25)
			(keepout
				(tracks not_allowed)
				(vias allowed)
				(pads allowed)
				(copperpour not_allowed)
				(footprints allowed)
			)
			(placement
				(enabled no)
				(sheetname "")
			)
			(fill
				(thermal_gap 0.5)
				(thermal_bridge_width 0.5)
				(island_removal_mode 0)
			)
			(polygon
				(pts
					(arc
						(start 92.074746 -39.034974)
						(mid 90.525346 -39.034974)
						(end 92.074746 -39.034974)
					)
				)
			)
		)
		(zone
			(layers "F.Cu" "B.Cu" "In1.Cu" "In2.Cu" "In3.Cu" "In4.Cu" "In5.Cu" "In6.Cu"
				"In7.Cu" "In8.Cu" "In9.Cu" "In10.Cu"
			)
			(hatch none 0.5)
			(connect_pads
				(clearance 0)
			)
			(min_thickness 0.25)
			(keepout
				(tracks not_allowed)
				(vias allowed)
				(pads allowed)
				(copperpour not_allowed)
				(footprints allowed)
			)
			(placement
				(enabled no)
				(sheetname "")
			)
			(fill
				(thermal_gap 0.5)
				(thermal_bridge_width 0.5)
				(island_removal_mode 0)
			)
			(polygon
				(pts
					(arc
						(start 92.277946 -76.784962)
						(mid 90.322146 -76.784962)
						(end 92.277946 -76.784962)
					)
				)
			)
		)
	)
	(footprint ""
		(layer "F.Cu")
		(at 86.121748 -278.580342 90)
		(property "Reference" "R189"
			(at 0 0 90)
			(layer "F.SilkS")
			(hide yes)
			(effects
				(font
					(size 1.27 1.27)
				)
			)
		)
		(property "Value" "4K7R2J-2-GP"
			(at 0.064008 -3.993896 90)
			(unlocked yes)
			(layer "F.Fab")
			(hide yes)
			(effects
				(font
					(size 1.016 1.016)
					(thickness 0.1524)
				)
			)
		)
		(property "Device Type" "R402H16"
			(at 0.064008 -5.517896 90)
			(unlocked yes)
			(layer "F.Fab")
			(hide yes)
			(effects
				(font
					(size 1.016 1.016)
					(thickness 0.1524)
				)
			)
		)
		(duplicate_pad_numbers_are_jumpers no)
		(fp_line
			(start 0.508 -0.9398)
			(end -0.508 -0.9398)
			(stroke
				(width 0.1524)
				(type default)
			)
			(layer "F.SilkS")
		)
		(fp_line
			(start -0.508 -0.9398)
			(end -0.508 0.9398)
			(stroke
				(width 0.1524)
				(type default)
			)
			(layer "F.SilkS")
		)
		(fp_rect
			(start -0.508 0.9398)
			(end 0.508 -0.9398)
			(stroke
				(width 0)
				(type default)
			)
			(fill no)
			(layer "F.CrtYd")
		)
		(fp_rect
			(start -0.508 0.9398)
			(end 0.508 -0.9398)
			(stroke
				(width 0)
				(type default)
			)
			(fill no)
			(layer "F.Fab")
		)
		(pad "1" smd custom
			(at 0 -0.4445 90)
			(size 0.1397 0.1397)
			(layers "F.Cu" "F.Mask" "F.Paste")
			(net "SW_PWR_R_HDD2")
			(options
				(clearance outline)
				(anchor circle)
			)
			(primitives
				(gr_poly
					(pts
						(arc
							(start -0.1778 -0.2794)
							(mid -0.249642 -0.249642)
							(end -0.2794 -0.1778)
						)
						(arc
							(start -0.2794 0.1778)
							(mid -0.249642 0.249642)
							(end -0.1778 0.2794)
						)
						(arc
							(start 0.1778 0.2794)
							(mid 0.249642 0.249642)
							(end 0.2794 0.1778)
						)
						(arc
							(start 0.2794 -0.1778)
							(mid 0.249642 -0.249642)
							(end 0.1778 -0.2794)
						)
					)
					(width 0)
					(fill yes)
				)
			)
		)
		(pad "2" smd custom
			(at 0 0.4445 90)
			(size 0.1397 0.1397)
			(layers "F.Cu" "F.Mask" "F.Paste")
			(net "GND")
			(options
				(clearance outline)
				(anchor circle)
			)
			(primitives
				(gr_poly
					(pts
						(arc
							(start -0.1778 -0.2794)
							(mid -0.249642 -0.249642)
							(end -0.2794 -0.1778)
						)
						(arc
							(start -0.2794 0.1778)
							(mid -0.249642 0.249642)
							(end -0.1778 0.2794)
						)
						(arc
							(start 0.1778 0.2794)
							(mid 0.249642 0.249642)
							(end 0.2794 0.1778)
						)
						(arc
							(start 0.2794 -0.1778)
							(mid 0.249642 -0.249642)
							(end 0.1778 -0.2794)
						)
					)
					(width 0)
					(fill yes)
				)
			)
		)
	)
	(footprint ""
		(layer "F.Cu")
		(at 476.200978 -179.64912)
		(property "Reference" "TP117"
			(at 0 0 0)
			(layer "F.SilkS")
			(hide yes)
			(effects
				(font
					(size 1.27 1.27)
				)
			)
		)
		(property "Value" "TPAD32-GP"
			(at -0.0508 -1.6764 0)
			(unlocked yes)
			(layer "F.Fab")
			(hide yes)
			(effects
				(font
					(size 1.016 1.016)
					(thickness 0.1524)
				)
			)
		)
		(property "Device Type" "TPAD32"
			(at -0.0508 -3.2004 0)
			(unlocked yes)
			(layer "F.Fab")
			(hide yes)
			(effects
				(font
					(size 1.016 1.016)
					(thickness 0.1524)
				)
			)
		)
		(duplicate_pad_numbers_are_jumpers no)
		(fp_poly
			(pts
				(arc
					(start 0.4064 0)
					(mid -0.4064 0)
					(end 0.4064 0)
				)
			)
			(stroke
				(width 0)
				(type default)
			)
			(fill no)
			(layer "F.CrtYd")
		)
		(fp_poly
			(pts
				(arc
					(start 0.7112 0)
					(mid -0.7112 0)
					(end 0.7112 0)
				)
			)
			(stroke
				(width 0)
				(type default)
			)
			(fill no)
			(layer "F.Fab")
		)
		(pad "1" smd circle
			(at 0 0)
			(size 0.8128 0.8128)
			(layers "F.Cu" "F.Mask" "F.Paste")
			(net "ACT_HDD_23")
		)
	)
	(footprint ""
		(layer "F.Cu")
		(at 160.608264 -304.310796 180)
		(property "Reference" "R257"
			(at 0 0 180)
			(layer "F.SilkS")
			(hide yes)
			(effects
				(font
					(size 1.27 1.27)
				)
			)
		)
		(property "Value" "91R3F-1-GP"
			(at -0.0254 -2.5146 180)
			(unlocked yes)
			(layer "F.Fab")
			(hide yes)
			(effects
				(font
					(size 1.016 1.016)
					(thickness 0.1524)
				)
			)
		)
		(property "Device Type" "R603H22"
			(at -0.0254 -4.0386 180)
			(unlocked yes)
			(layer "F.Fab")
			(hide yes)
			(effects
				(font
					(size 1.016 1.016)
					(thickness 0.1524)
				)
			)
		)
		(duplicate_pad_numbers_are_jumpers no)
		(fp_line
			(start 0.2032 0)
			(end 0.4826 0)
			(stroke
				(width 0.2032)
				(type default)
			)
			(layer "F.SilkS")
		)
		(fp_line
			(start -0.4826 0)
			(end -0.2032 0)
			(stroke
				(width 0.2032)
				(type default)
			)
			(layer "F.SilkS")
		)
		(fp_rect
			(start -0.5842 1.3335)
			(end 0.5842 -1.3335)
			(stroke
				(width 0)
				(type default)
			)
			(fill no)
			(layer "F.CrtYd")
		)
		(fp_rect
			(start -0.5842 1.3335)
			(end 0.5842 -1.3335)
			(stroke
				(width 0)
				(type default)
			)
			(fill no)
			(layer "F.Fab")
		)
		(pad "1" smd custom
			(at 0 -0.762 180)
			(size 0.2159 0.2159)
			(layers "F.Cu" "F.Mask" "F.Paste")
			(net "P5V_B")
			(options
				(clearance outline)
				(anchor circle)
			)
			(primitives
				(gr_poly
					(pts
						(arc
							(start -0.3302 -0.4318)
							(mid -0.402042 -0.402042)
							(end -0.4318 -0.3302)
						)
						(arc
							(start -0.4318 0.3302)
							(mid -0.402042 0.402042)
							(end -0.3302 0.4318)
						)
						(arc
							(start 0.3302 0.4318)
							(mid 0.402042 0.402042)
							(end 0.4318 0.3302)
						)
						(arc
							(start 0.4318 -0.3302)
							(mid 0.402042 -0.402042)
							(end 0.3302 -0.4318)
						)
					)
					(width 0)
					(fill yes)
				)
			)
		)
		(pad "2" smd custom
			(at 0 0.762 180)
			(size 0.2159 0.2159)
			(layers "F.Cu" "F.Mask" "F.Paste")
			(net "DRV_ACT_29")
			(options
				(clearance outline)
				(anchor circle)
			)
			(primitives
				(gr_poly
					(pts
						(arc
							(start -0.3302 -0.4318)
							(mid -0.402042 -0.402042)
							(end -0.4318 -0.3302)
						)
						(arc
							(start -0.4318 0.3302)
							(mid -0.402042 0.402042)
							(end -0.3302 0.4318)
						)
						(arc
							(start 0.3302 0.4318)
							(mid 0.402042 0.402042)
							(end 0.4318 0.3302)
						)
						(arc
							(start 0.4318 -0.3302)
							(mid 0.402042 -0.402042)
							(end 0.3302 -0.4318)
						)
					)
					(width 0)
					(fill yes)
				)
			)
		)
	)
	(footprint ""
		(layer "F.Cu")
		(at 447.167 -184.912 180)
		(property "Reference" "R640"
			(at 0 0 180)
			(layer "F.SilkS")
			(hide yes)
			(effects
				(font
					(size 1.27 1.27)
				)
			)
		)
		(property "Value" "220R3F-1-GP"
			(at -0.0254 -2.5146 180)
			(unlocked yes)
			(layer "F.Fab")
			(hide yes)
			(effects
				(font
					(size 1.016 1.016)
					(thickness 0.1524)
				)
			)
		)
		(property "Device Type" "R603H22"
			(at -0.0254 -4.0386 180)
			(unlocked yes)
			(layer "F.Fab")
			(hide yes)
			(effects
				(font
					(size 1.016 1.016)
					(thickness 0.1524)
				)
			)
		)
		(duplicate_pad_numbers_are_jumpers no)
		(fp_line
			(start 0.2032 0)
			(end 0.4826 0)
			(stroke
				(width 0.2032)
				(type default)
			)
			(layer "F.SilkS")
		)
		(fp_line
			(start -0.4826 0)
			(end -0.2032 0)
			(stroke
				(width 0.2032)
				(type default)
			)
			(layer "F.SilkS")
		)
		(fp_rect
			(start -0.5842 1.3335)
			(end 0.5842 -1.3335)
			(stroke
				(width 0)
				(type default)
			)
			(fill no)
			(layer "F.CrtYd")
		)
		(fp_rect
			(start -0.5842 1.3335)
			(end 0.5842 -1.3335)
			(stroke
				(width 0)
				(type default)
			)
			(fill no)
			(layer "F.Fab")
		)
		(pad "1" smd custom
			(at 0 -0.762 180)
			(size 0.2159 0.2159)
			(layers "F.Cu" "F.Mask" "F.Paste")
			(net "HDD_PRSNT_22")
			(options
				(clearance outline)
				(anchor circle)
			)
			(primitives
				(gr_poly
					(pts
						(arc
							(start -0.3302 -0.4318)
							(mid -0.402042 -0.402042)
							(end -0.4318 -0.3302)
						)
						(arc
							(start -0.4318 0.3302)
							(mid -0.402042 0.402042)
							(end -0.3302 0.4318)
						)
						(arc
							(start 0.3302 0.4318)
							(mid 0.402042 0.402042)
							(end 0.4318 0.3302)
						)
						(arc
							(start 0.4318 -0.3302)
							(mid 0.402042 -0.402042)
							(end 0.3302 -0.4318)
						)
					)
					(width 0)
					(fill yes)
				)
			)
		)
		(pad "2" smd custom
			(at 0 0.762 180)
			(size 0.2159 0.2159)
			(layers "F.Cu" "F.Mask" "F.Paste")
			(net "DRIVE_A_22_INS")
			(options
				(clearance outline)
				(anchor circle)
			)
			(primitives
				(gr_poly
					(pts
						(arc
							(start -0.3302 -0.4318)
							(mid -0.402042 -0.402042)
							(end -0.4318 -0.3302)
						)
						(arc
							(start -0.4318 0.3302)
							(mid -0.402042 0.402042)
							(end -0.3302 0.4318)
						)
						(arc
							(start 0.3302 0.4318)
							(mid 0.402042 0.402042)
							(end 0.4318 0.3302)
						)
						(arc
							(start 0.4318 -0.3302)
							(mid 0.402042 -0.402042)
							(end 0.3302 -0.4318)
						)
					)
					(width 0)
					(fill yes)
				)
			)
		)
	)
	(footprint ""
		(layer "F.Cu")
		(at 204.004418 -162.9918)
		(property "Reference" "TC15"
			(at 0 0 0)
			(layer "F.SilkS")
			(hide yes)
			(effects
				(font
					(size 1.27 1.27)
				)
			)
		)
		(property "Value" "SE270U16VM-8-GP"
			(at -4.5974 -2.54 0)
			(unlocked yes)
			(layer "F.Fab")
			(hide yes)
			(effects
				(font
					(size 1.016 1.016)
					(thickness 0.1524)
				)
			)
		)
		(property "Device Type" "SE361416H394"
			(at -4.5974 -4.064 0)
			(unlocked yes)
			(layer "F.Fab")
			(hide yes)
			(effects
				(font
					(size 1.016 1.016)
					(thickness 0.1524)
				)
			)
		)
		(duplicate_pad_numbers_are_jumpers no)
		(fp_line
			(start -3.556 -3.4163)
			(end -2.3622 -4.6101)
			(stroke
				(width 0.1524)
				(type default)
			)
			(layer "F.SilkS")
		)
		(fp_line
			(start -3.556 4.6101)
			(end -3.556 -3.4163)
			(stroke
				(width 0.1524)
				(type default)
			)
			(layer "F.SilkS")
		)
		(fp_line
			(start -2.3622 -4.6101)
			(end 2.3622 -4.6101)
			(stroke
				(width 0.1524)
				(type default)
			)
			(layer "F.SilkS")
		)
		(fp_line
			(start 2.3622 -4.6101)
			(end 3.556 -3.4163)
			(stroke
				(width 0.1524)
				(type default)
			)
			(layer "F.SilkS")
		)
		(fp_line
			(start 3.556 -3.4163)
			(end 3.556 4.6101)
			(stroke
				(width 0.1524)
				(type default)
			)
			(layer "F.SilkS")
		)
		(fp_line
			(start 3.556 4.6101)
			(end -3.556 4.6101)
			(stroke
				(width 0.1524)
				(type default)
			)
			(layer "F.SilkS")
		)
		(fp_rect
			(start -3.302 3.6449)
			(end 3.302 -3.6449)
			(stroke
				(width 0)
				(type default)
			)
			(fill no)
			(layer "F.CrtYd")
		)
		(fp_poly
			(pts
				(xy 3.81 4.6863) (xy 3.81 -3.4925) (xy 3.302 -3.4925) (xy 3.302 3.6449) (xy -3.302 3.6449) (xy -3.302 -3.6449)
				(xy 3.302 -3.6449) (xy 3.302 -3.5052) (xy 3.81 -3.5052) (xy 3.81 -4.6863) (xy -3.81 -4.6863) (xy -3.81 4.6863)
			)
			(stroke
				(width 0)
				(type default)
			)
			(fill no)
			(layer "F.CrtYd")
		)
		(fp_rect
			(start -3.81 4.6863)
			(end 3.81 -4.6863)
			(stroke
				(width 0)
				(type default)
			)
			(fill no)
			(layer "F.Fab")
		)
		(pad "1" smd rect
			(at 0 -2.574036)
			(size 1.4224 3.556)
			(layers "F.Cu" "F.Mask" "F.Paste")
			(net "P12V_A")
		)
		(pad "2" smd rect
			(at 0 2.574036)
			(size 1.4224 3.556)
			(layers "F.Cu" "F.Mask" "F.Paste")
			(net "GND")
		)
	)
	(footprint ""
		(layer "F.Cu")
		(at 141.423898 -47.157894 180)
		(property "Reference" "R790"
			(at 0 0 180)
			(layer "F.SilkS")
			(hide yes)
			(effects
				(font
					(size 1.27 1.27)
				)
			)
		)
		(property "Value" "200KR2F-L-GP"
			(at 0.064008 -3.993896 180)
			(unlocked yes)
			(layer "F.Fab")
			(hide yes)
			(effects
				(font
					(size 1.016 1.016)
					(thickness 0.1524)
				)
			)
		)
		(property "Device Type" "R402H16"
			(at 0.064008 -5.517896 180)
			(unlocked yes)
			(layer "F.Fab")
			(hide yes)
			(effects
				(font
					(size 1.016 1.016)
					(thickness 0.1524)
				)
			)
		)
		(duplicate_pad_numbers_are_jumpers no)
		(fp_line
			(start 0.508 -0.9398)
			(end -0.508 -0.9398)
			(stroke
				(width 0.1524)
				(type default)
			)
			(layer "F.SilkS")
		)
		(fp_line
			(start -0.508 -0.9398)
			(end -0.508 0.9398)
			(stroke
				(width 0.1524)
				(type default)
			)
			(layer "F.SilkS")
		)
		(fp_rect
			(start -0.508 0.9398)
			(end 0.508 -0.9398)
			(stroke
				(width 0)
				(type default)
			)
			(fill no)
			(layer "F.CrtYd")
		)
		(fp_rect
			(start -0.508 0.9398)
			(end 0.508 -0.9398)
			(stroke
				(width 0)
				(type default)
			)
			(fill no)
			(layer "F.Fab")
		)
		(pad "1" smd custom
			(at 0 -0.4445 180)
			(size 0.1397 0.1397)
			(layers "F.Cu" "F.Mask" "F.Paste")
			(net "SW_HDD_R28")
			(options
				(clearance outline)
				(anchor circle)
			)
			(primitives
				(gr_poly
					(pts
						(arc
							(start -0.1778 -0.2794)
							(mid -0.249642 -0.249642)
							(end -0.2794 -0.1778)
						)
						(arc
							(start -0.2794 0.1778)
							(mid -0.249642 0.249642)
							(end -0.1778 0.2794)
						)
						(arc
							(start 0.1778 0.2794)
							(mid 0.249642 0.249642)
							(end 0.2794 0.1778)
						)
						(arc
							(start 0.2794 -0.1778)
							(mid 0.249642 -0.249642)
							(end 0.1778 -0.2794)
						)
					)
					(width 0)
					(fill yes)
				)
			)
		)
		(pad "2" smd custom
			(at 0 0.4445 180)
			(size 0.1397 0.1397)
			(layers "F.Cu" "F.Mask" "F.Paste")
			(net "SW_HDD_N28")
			(options
				(clearance outline)
				(anchor circle)
			)
			(primitives
				(gr_poly
					(pts
						(arc
							(start -0.1778 -0.2794)
							(mid -0.249642 -0.249642)
							(end -0.2794 -0.1778)
						)
						(arc
							(start -0.2794 0.1778)
							(mid -0.249642 0.249642)
							(end -0.1778 0.2794)
						)
						(arc
							(start 0.1778 0.2794)
							(mid 0.249642 0.249642)
							(end 0.2794 0.1778)
						)
						(arc
							(start 0.2794 -0.1778)
							(mid 0.249642 -0.249642)
							(end 0.1778 -0.2794)
						)
					)
					(width 0)
					(fill yes)
				)
			)
		)
	)
	(footprint ""
		(layer "F.Cu")
		(at 77.917548 -160.633918 90)
		(property "Reference" "R466"
			(at 0 0 90)
			(layer "F.SilkS")
			(hide yes)
			(effects
				(font
					(size 1.27 1.27)
				)
			)
		)
		(property "Value" "4K7R2J-2-GP"
			(at 0.064008 -3.993896 90)
			(unlocked yes)
			(layer "F.Fab")
			(hide yes)
			(effects
				(font
					(size 1.016 1.016)
					(thickness 0.1524)
				)
			)
		)
		(property "Device Type" "R402H16"
			(at 0.064008 -5.517896 90)
			(unlocked yes)
			(layer "F.Fab")
			(hide yes)
			(effects
				(font
					(size 1.016 1.016)
					(thickness 0.1524)
				)
			)
		)
		(duplicate_pad_numbers_are_jumpers no)
		(fp_line
			(start 0.508 -0.9398)
			(end -0.508 -0.9398)
			(stroke
				(width 0.1524)
				(type default)
			)
			(layer "F.SilkS")
		)
		(fp_line
			(start -0.508 -0.9398)
			(end -0.508 0.9398)
			(stroke
				(width 0.1524)
				(type default)
			)
			(layer "F.SilkS")
		)
		(fp_rect
			(start -0.508 0.9398)
			(end 0.508 -0.9398)
			(stroke
				(width 0)
				(type default)
			)
			(fill no)
			(layer "F.CrtYd")
		)
		(fp_rect
			(start -0.508 0.9398)
			(end 0.508 -0.9398)
			(stroke
				(width 0)
				(type default)
			)
			(fill no)
			(layer "F.Fab")
		)
		(pad "1" smd custom
			(at 0 -0.4445 90)
			(size 0.1397 0.1397)
			(layers "F.Cu" "F.Mask" "F.Paste")
			(net "P12V_A")
			(options
				(clearance outline)
				(anchor circle)
			)
			(primitives
				(gr_poly
					(pts
						(arc
							(start -0.1778 -0.2794)
							(mid -0.249642 -0.249642)
							(end -0.2794 -0.1778)
						)
						(arc
							(start -0.2794 0.1778)
							(mid -0.249642 0.249642)
							(end -0.1778 0.2794)
						)
						(arc
							(start 0.1778 0.2794)
							(mid 0.249642 0.249642)
							(end 0.2794 0.1778)
						)
						(arc
							(start 0.2794 -0.1778)
							(mid 0.249642 -0.249642)
							(end 0.1778 -0.2794)
						)
					)
					(width 0)
					(fill yes)
				)
			)
		)
		(pad "2" smd custom
			(at 0 0.4445 90)
			(size 0.1397 0.1397)
			(layers "F.Cu" "F.Mask" "F.Paste")
			(net "SW_HDD_R14")
			(options
				(clearance outline)
				(anchor circle)
			)
			(primitives
				(gr_poly
					(pts
						(arc
							(start -0.1778 -0.2794)
							(mid -0.249642 -0.249642)
							(end -0.2794 -0.1778)
						)
						(arc
							(start -0.2794 0.1778)
							(mid -0.249642 0.249642)
							(end -0.1778 0.2794)
						)
						(arc
							(start 0.1778 0.2794)
							(mid 0.249642 0.249642)
							(end 0.2794 0.1778)
						)
						(arc
							(start 0.2794 -0.1778)
							(mid 0.249642 -0.249642)
							(end 0.1778 -0.2794)
						)
					)
					(width 0)
					(fill yes)
				)
			)
		)
	)
	(footprint ""
		(layer "F.Cu")
		(at 256.970276 -254.97536)
		(property "Reference" "U6"
			(at 0 0 0)
			(layer "F.SilkS")
			(hide yes)
			(effects
				(font
					(size 1.27 1.27)
				)
			)
		)
		(property "Value" "TCA9555PWR-GP"
			(at 0 -6.9342 0)
			(unlocked yes)
			(layer "F.Fab")
			(hide yes)
			(effects
				(font
					(size 1.016 1.016)
					(thickness 0.1524)
				)
			)
		)
		(property "Device Type" "TSOIC24H48"
			(at 0 -8.5852 0)
			(unlocked yes)
			(layer "F.Fab")
			(hide yes)
			(effects
				(font
					(size 1.016 1.016)
					(thickness 0.1524)
				)
			)
		)
		(duplicate_pad_numbers_are_jumpers no)
		(fp_line
			(start -4.2291 -1.397)
			(end 3.81 -1.397)
			(stroke
				(width 0.1524)
				(type default)
			)
			(layer "F.SilkS")
		)
		(fp_line
			(start -4.2291 -0.8001)
			(end -3.429 0)
			(stroke
				(width 0.1524)
				(type default)
			)
			(layer "F.SilkS")
		)
		(fp_line
			(start -4.2291 3.937)
			(end -4.2291 -1.397)
			(stroke
				(width 0.1524)
				(type default)
			)
			(layer "F.SilkS")
		)
		(fp_line
			(start -4.22656 3.81)
			(end -4.2291 1.397)
			(stroke
				(width 0.508)
				(type default)
			)
			(layer "F.SilkS")
		)
		(fp_line
			(start -3.429 0)
			(end -4.2291 0.8001)
			(stroke
				(width 0.1524)
				(type default)
			)
			(layer "F.SilkS")
		)
		(fp_line
			(start 3.81 -1.397)
			(end 3.81 1.397)
			(stroke
				(width 0.1524)
				(type default)
			)
			(layer "F.SilkS")
		)
		(fp_line
			(start 3.81 1.397)
			(end -4.2291 1.397)
			(stroke
				(width 0.1524)
				(type default)
			)
			(layer "F.SilkS")
		)
		(fp_poly
			(pts
				(xy -3.90652 -1.8542) (xy 3.90652 -1.8542) (xy 3.90652 1.8542) (xy -3.90652 1.8542)
			)
			(stroke
				(width 0)
				(type default)
			)
			(fill yes)
			(layer "F.SilkS")
		)
		(fp_poly
			(pts
				(xy -4.2164 3.81) (xy 4.2164 3.81) (xy 4.22656 -3.81) (xy -4.2164 -3.81)
			)
			(stroke
				(width 0)
				(type default)
			)
			(fill no)
			(layer "F.CrtYd")
		)
		(fp_poly
			(pts
				(xy -4.22656 -3.81) (xy 4.22656 -3.81) (xy 4.22656 3.81) (xy -4.22656 3.81)
			)
			(stroke
				(width 0)
				(type default)
			)
			(fill no)
			(layer "F.Fab")
		)
		(pad "1" smd rect
			(at -3.57632 2.8194)
			(size 0.3556 1.524)
			(layers "F.Cu" "F.Mask" "F.Paste")
			(net "IO_EXP6_INT_N")
		)
		(pad "2" smd rect
			(at -2.92608 2.8194)
			(size 0.3556 1.524)
			(layers "F.Cu" "F.Mask" "F.Paste")
			(net "IO_EXP6_A1")
		)
		(pad "3" smd rect
			(at -2.27584 2.8194)
			(size 0.3556 1.524)
			(layers "F.Cu" "F.Mask" "F.Paste")
			(net "IO_EXP6_A2")
		)
		(pad "4" smd rect
			(at -1.6256 2.8194)
			(size 0.3556 1.524)
			(layers "F.Cu" "F.Mask" "F.Paste")
			(net "DRIVE_A_32_INS")
		)
		(pad "5" smd rect
			(at -0.97536 2.8194)
			(size 0.3556 1.524)
			(layers "F.Cu" "F.Mask" "F.Paste")
			(net "DRIVE_A_33_INS")
		)
		(pad "6" smd rect
			(at -0.32512 2.8194)
			(size 0.3556 1.524)
			(layers "F.Cu" "F.Mask" "F.Paste")
			(net "DRIVE_A_34_INS")
		)
		(pad "7" smd rect
			(at 0.32512 2.8194)
			(size 0.3556 1.524)
			(layers "F.Cu" "F.Mask" "F.Paste")
			(net "DRIVE_A_35_INS")
		)
		(pad "8" smd rect
			(at 0.97536 2.8194)
			(size 0.3556 1.524)
			(layers "F.Cu" "F.Mask" "F.Paste")
			(net "Net_332")
		)
		(pad "9" smd rect
			(at 1.6256 2.8194)
			(size 0.3556 1.524)
			(layers "F.Cu" "F.Mask" "F.Paste")
			(net "Net_331")
		)
		(pad "10" smd rect
			(at 2.27584 2.8194)
			(size 0.3556 1.524)
			(layers "F.Cu" "F.Mask" "F.Paste")
			(net "Net_330")
		)
		(pad "11" smd rect
			(at 2.92608 2.8194)
			(size 0.3556 1.524)
			(layers "F.Cu" "F.Mask" "F.Paste")
			(net "Net_329")
		)
		(pad "12" smd rect
			(at 3.57632 2.8194)
			(size 0.3556 1.524)
			(layers "F.Cu" "F.Mask" "F.Paste")
			(net "GND")
		)
		(pad "13" smd rect
			(at 3.57632 -2.8194)
			(size 0.3556 1.524)
			(layers "F.Cu" "F.Mask" "F.Paste")
			(net "DRAWER_CLOSED_N")
		)
		(pad "14" smd rect
			(at 2.92608 -2.8194)
			(size 0.3556 1.524)
			(layers "F.Cu" "F.Mask" "F.Paste")
			(net "FAN_0_INS_N")
		)
		(pad "15" smd rect
			(at 2.27584 -2.8194)
			(size 0.3556 1.524)
			(layers "F.Cu" "F.Mask" "F.Paste")
			(net "FAN_1_INS_N")
		)
		(pad "16" smd rect
			(at 1.6256 -2.8194)
			(size 0.3556 1.524)
			(layers "F.Cu" "F.Mask" "F.Paste")
			(net "FAN_2_INS_N")
		)
		(pad "17" smd rect
			(at 0.97536 -2.8194)
			(size 0.3556 1.524)
			(layers "F.Cu" "F.Mask" "F.Paste")
			(net "FAN_3_INS_N")
		)
		(pad "18" smd rect
			(at 0.32512 -2.8194)
			(size 0.3556 1.524)
			(layers "F.Cu" "F.Mask" "F.Paste")
			(net "IOM_A_INS_N")
		)
		(pad "19" smd rect
			(at -0.32512 -2.8194)
			(size 0.3556 1.524)
			(layers "F.Cu" "F.Mask" "F.Paste")
			(net "IOM_B_INS_N")
		)
		(pad "20" smd rect
			(at -0.97536 -2.8194)
			(size 0.3556 1.524)
			(layers "F.Cu" "F.Mask" "F.Paste")
			(net "SCC_B_INS_N")
		)
		(pad "21" smd rect
			(at -1.6256 -2.8194)
			(size 0.3556 1.524)
			(layers "F.Cu" "F.Mask" "F.Paste")
			(net "IO_EXP6_A0")
		)
		(pad "22" smd rect
			(at -2.27584 -2.8194)
			(size 0.3556 1.524)
			(layers "F.Cu" "F.Mask" "F.Paste")
			(net "IO_EXP6_SCL")
		)
		(pad "23" smd rect
			(at -2.92608 -2.8194)
			(size 0.3556 1.524)
			(layers "F.Cu" "F.Mask" "F.Paste")
			(net "IO_EXP6_SDA")
		)
		(pad "24" smd rect
			(at -3.57632 -2.8194)
			(size 0.3556 1.524)
			(layers "F.Cu" "F.Mask" "F.Paste")
			(net "P3V3_STBY_A")
		)
	)
	(footprint ""
		(layer "F.Cu")
		(at 59.749944 -287.910016 -90)
		(property "Reference" "HDDSAS1"
			(at 0 0 270)
			(layer "F.SilkS")
			(hide yes)
			(effects
				(font
					(size 1.27 1.27)
				)
			)
		)
		(property "Value" "SKT-SAS15P-14P-45-GP"
			(at -20.7645 -8.9789 270)
			(unlocked yes)
			(layer "F.Fab")
			(hide yes)
			(effects
				(font
					(size 1.016 1.016)
					(thickness 0.1524)
				)
			)
		)
		(property "Device Type" "10120818-001C-TRLF"
			(at -20.7645 -10.5029 270)
			(unlocked yes)
			(layer "F.Fab")
			(hide yes)
			(effects
				(font
					(size 1.016 1.016)
					(thickness 0.1524)
				)
			)
		)
		(duplicate_pad_numbers_are_jumpers no)
		(fp_line
			(start 1.651 4.2926)
			(end 1.651 3.0099)
			(stroke
				(width 0.1524)
				(type default)
			)
			(layer "F.SilkS")
		)
		(fp_line
			(start 8.509 4.2926)
			(end 1.651 4.2926)
			(stroke
				(width 0.1524)
				(type default)
			)
			(layer "F.SilkS")
		)
		(fp_line
			(start -23.4188 3.0099)
			(end -23.4188 -3.2512)
			(stroke
				(width 0.1524)
				(type default)
			)
			(layer "F.SilkS")
		)
		(fp_line
			(start 1.651 3.0099)
			(end -23.4188 3.0099)
			(stroke
				(width 0.1524)
				(type default)
			)
			(layer "F.SilkS")
		)
		(fp_line
			(start 8.509 3.0099)
			(end 8.509 4.2926)
			(stroke
				(width 0.1524)
				(type default)
			)
			(layer "F.SilkS")
		)
		(fp_line
			(start 23.4188 3.0099)
			(end 8.509 3.0099)
			(stroke
				(width 0.1524)
				(type default)
			)
			(layer "F.SilkS")
		)
		(fp_line
			(start -23.4188 -3.2512)
			(end 23.4188 -3.2512)
			(stroke
				(width 0.1524)
				(type default)
			)
			(layer "F.SilkS")
		)
		(fp_line
			(start 23.4188 -3.2512)
			(end 23.4188 3.0099)
			(stroke
				(width 0.1524)
				(type default)
			)
			(layer "F.SilkS")
		)
		(fp_line
			(start 15.5067 -3.3401)
			(end 16.2687 -3.3401)
			(stroke
				(width 0.3302)
				(type default)
			)
			(layer "F.SilkS")
		)
		(fp_poly
			(pts
				(xy 15.868904 -3.230372) (xy 16.503904 -3.865372) (xy 15.233904 -3.865372)
			)
			(stroke
				(width 0)
				(type default)
			)
			(fill yes)
			(layer "F.SilkS")
		)
		(fp_poly
			(pts
				(xy -22.8727 -2.7559) (xy 22.8727 -2.7559) (xy 22.8727 2.7559) (xy 8.255 2.7559) (xy 8.255 3.5179)
				(xy 1.905 3.5179) (xy 1.905 2.7559) (xy -22.8727 2.7559)
			)
			(stroke
				(width 0)
				(type default)
			)
			(fill no)
			(layer "F.CrtYd")
		)
		(fp_poly
			(pts
				(xy 1.397 4.5466) (xy 1.397 3.2639) (xy -23.6728 3.2639) (xy -23.6728 -3.5052) (xy 23.6728 -3.5052)
				(xy 23.6728 -0.00635) (xy 22.8727 -0.00635) (xy 22.8727 -2.7559) (xy -22.8727 -2.7559) (xy -22.8727 2.7559)
				(xy 1.905 2.7559) (xy 1.905 3.5179) (xy 8.255 3.5179) (xy 8.255 2.7559) (xy 22.8727 2.7559) (xy 22.8727 0.00635)
				(xy 23.6728 0.00635) (xy 23.6728 3.2639) (xy 8.763 3.2639) (xy 8.763 4.5466)
			)
			(stroke
				(width 0)
				(type default)
			)
			(fill no)
			(layer "F.CrtYd")
		)
		(fp_poly
			(pts
				(xy 1.397 4.5466) (xy 1.397 3.2639) (xy -23.6728 3.2639) (xy -23.6728 -3.5052) (xy 23.6728 -3.5052)
				(xy 23.6728 3.2639) (xy 8.763 3.2639) (xy 8.763 4.5466)
			)
			(stroke
				(width 0)
				(type default)
			)
			(fill no)
			(layer "F.Fab")
		)
		(pad "" np_thru_hole circle
			(at -18.874994 0 270)
			(size 0.254 0.254)
			(drill 1.3462)
			(layers "*.Cu" "*.Mask")
			(clearance 0.9017)
			(thermal_gap 0.9017)
		)
		(pad "" np_thru_hole circle
			(at 18.874994 0 270)
			(size 0.254 0.254)
			(drill 0.9398)
			(layers "*.Cu" "*.Mask")
			(clearance 0.6985)
			(thermal_gap 0.6985)
		)
		(pad "G1" smd rect
			(at 21.874988 0 270)
			(size 2.5908 2.5908)
			(layers "F.Cu" "F.Mask" "F.Paste")
			(net "GND")
		)
		(pad "G2" smd rect
			(at -21.874988 0 270)
			(size 2.5908 2.5908)
			(layers "F.Cu" "F.Mask" "F.Paste")
			(net "GND")
		)
		(pad "P1" smd rect
			(at 1.905 -1.82499 270)
			(size 0.6096 2.3622)
			(layers "F.Cu" "F.Mask" "F.Paste")
			(net "Net_2121")
		)
		(pad "P2" smd rect
			(at 0.635 -1.82499 270)
			(size 0.6096 2.3622)
			(layers "F.Cu" "F.Mask" "F.Paste")
			(net "Net_2122")
		)
		(pad "P3" smd rect
			(at -0.635 -1.82499 270)
			(size 0.6096 2.3622)
			(layers "F.Cu" "F.Mask" "F.Paste")
			(net "Net_2123")
		)
		(pad "P4" smd rect
			(at -1.905 -1.82499 270)
			(size 0.6096 2.3622)
			(layers "F.Cu" "F.Mask" "F.Paste")
			(net "GND")
		)
		(pad "P5" smd rect
			(at -3.175 -1.82499 270)
			(size 0.6096 2.3622)
			(layers "F.Cu" "F.Mask" "F.Paste")
			(net "HDD_PRSNT_1")
		)
		(pad "P6" smd rect
			(at -4.445 -1.82499 270)
			(size 0.6096 2.3622)
			(layers "F.Cu" "F.Mask" "F.Paste")
			(net "GND")
		)
		(pad "P7" smd rect
			(at -5.715 -1.82499 270)
			(size 0.6096 2.3622)
			(layers "F.Cu" "F.Mask" "F.Paste")
			(net "5V_PRE_1")
		)
		(pad "P8" smd rect
			(at -6.985 -1.82499 270)
			(size 0.6096 2.3622)
			(layers "F.Cu" "F.Mask" "F.Paste")
			(net "P5V_HDD1")
		)
		(pad "P9" smd rect
			(at -8.255 -1.82499 270)
			(size 0.6096 2.3622)
			(layers "F.Cu" "F.Mask" "F.Paste")
			(net "P5V_HDD1")
		)
		(pad "P10" smd rect
			(at -9.525 -1.82499 270)
			(size 0.6096 2.3622)
			(layers "F.Cu" "F.Mask" "F.Paste")
			(net "GND")
		)
		(pad "P11" smd rect
			(at -10.795 -1.82499 270)
			(size 0.6096 2.3622)
			(layers "F.Cu" "F.Mask" "F.Paste")
			(net "ACT_HDD_1")
		)
		(pad "P12" smd rect
			(at -12.065 -1.82499 270)
			(size 0.6096 2.3622)
			(layers "F.Cu" "F.Mask" "F.Paste")
			(net "GND")
		)
		(pad "P13" smd rect
			(at -13.335 -1.82499 270)
			(size 0.6096 2.3622)
			(layers "F.Cu" "F.Mask" "F.Paste")
			(net "12V_PRE_1")
		)
		(pad "P14" smd rect
			(at -14.605 -1.82499 270)
			(size 0.6096 2.3622)
			(layers "F.Cu" "F.Mask" "F.Paste")
			(net "P12V_HDD1")
		)
		(pad "P15" smd rect
			(at -15.875 -1.82499 270)
			(size 0.6096 2.3622)
			(layers "F.Cu" "F.Mask" "F.Paste")
			(net "P12V_HDD1")
		)
		(pad "S1" smd rect
			(at 15.875 -1.82499 270)
			(size 0.6096 2.3622)
			(layers "F.Cu" "F.Mask" "F.Paste")
			(net "GND")
		)
		(pad "S2" smd rect
			(at 14.605 -1.82499 270)
			(size 0.6096 2.3622)
			(layers "F.Cu" "F.Mask" "F.Paste")
			(net "SAS_HDD_RX_P1")
		)
		(pad "S3" smd rect
			(at 13.335 -1.82499 270)
			(size 0.6096 2.3622)
			(layers "F.Cu" "F.Mask" "F.Paste")
			(net "SAS_HDD_RX_N1")
		)
		(pad "S4" smd rect
			(at 12.065 -1.82499 270)
			(size 0.6096 2.3622)
			(layers "F.Cu" "F.Mask" "F.Paste")
			(net "GND")
		)
		(pad "S5" smd rect
			(at 10.795 -1.82499 270)
			(size 0.6096 2.3622)
			(layers "F.Cu" "F.Mask" "F.Paste")
			(net "PHY_DRV_A_TO_SCC_A_1_DN")
		)
		(pad "S6" smd rect
			(at 9.525 -1.82499 270)
			(size 0.6096 2.3622)
			(layers "F.Cu" "F.Mask" "F.Paste")
			(net "PHY_DRV_A_TO_SCC_A_1_DP")
		)
		(pad "S7" smd rect
			(at 8.255 -1.82499 270)
			(size 0.6096 2.3622)
			(layers "F.Cu" "F.Mask" "F.Paste")
			(net "GND")
		)
		(pad "S8" smd rect
			(at 7.480046 2.845054 270)
			(size 0.508 2.3622)
			(layers "F.Cu" "F.Mask" "F.Paste")
			(net "GND")
		)
		(pad "S9" smd rect
			(at 6.679946 2.845054 270)
			(size 0.508 2.3622)
			(layers "F.Cu" "F.Mask" "F.Paste")
			(net "Net_456")
		)
		(pad "S10" smd rect
			(at 5.8801 2.845054 270)
			(size 0.508 2.3622)
			(layers "F.Cu" "F.Mask" "F.Paste")
			(net "Net_348")
		)
		(pad "S11" smd rect
			(at 5.08 2.845054 270)
			(size 0.508 2.3622)
			(layers "F.Cu" "F.Mask" "F.Paste")
			(net "GND")
		)
		(pad "S12" smd rect
			(at 4.2799 2.845054 270)
			(size 0.508 2.3622)
			(layers "F.Cu" "F.Mask" "F.Paste")
			(net "Net_384")
		)
		(pad "S13" smd rect
			(at 3.480054 2.845054 270)
			(size 0.508 2.3622)
			(layers "F.Cu" "F.Mask" "F.Paste")
			(net "Net_420")
		)
		(pad "S14" smd rect
			(at 2.679954 2.845054 270)
			(size 0.508 2.3622)
			(layers "F.Cu" "F.Mask" "F.Paste")
			(net "GND")
		)
		(zone
			(layer "F.Cu")
			(hatch none 0.5)
			(connect_pads
				(clearance 0)
			)
			(min_thickness 0.25)
			(keepout
				(tracks allowed)
				(vias not_allowed)
				(pads allowed)
				(copperpour not_allowed)
				(footprints allowed)
			)
			(placement
				(enabled no)
				(sheetname "")
			)
			(fill
				(thermal_gap 0.5)
				(thermal_bridge_width 0.5)
				(island_removal_mode 0)
			)
			(polygon
				(pts
					(xy 63.407544 -304.648616) (xy 56.333644 -304.648616) (xy 56.333644 -311.582816) (xy 57.438544 -311.582816)
					(xy 57.438544 -307.468016) (xy 62.061344 -307.468016) (xy 62.061344 -311.582816) (xy 63.407544 -311.582816)
				)
			)
		)
		(zone
			(layer "F.Cu")
			(hatch none 0.5)
			(connect_pads
				(clearance 0)
			)
			(min_thickness 0.25)
			(keepout
				(tracks not_allowed)
				(vias allowed)
				(pads allowed)
				(copperpour not_allowed)
				(footprints allowed)
			)
			(placement
				(enabled no)
				(sheetname "")
			)
			(fill
				(thermal_gap 0.5)
				(thermal_bridge_width 0.5)
				(island_removal_mode 0)
			)
			(polygon
				(pts
					(xy 63.407544 -304.648616) (xy 56.333644 -304.648616) (xy 56.333644 -311.582816) (xy 57.438544 -311.582816)
					(xy 57.438544 -307.468016) (xy 62.061344 -307.468016) (xy 62.061344 -311.582816) (xy 63.407544 -311.582816)
				)
			)
		)
		(zone
			(layer "F.Cu")
			(hatch none 0.5)
			(connect_pads
				(clearance 0)
			)
			(min_thickness 0.25)
			(keepout
				(tracks not_allowed)
				(vias allowed)
				(pads allowed)
				(copperpour not_allowed)
				(footprints allowed)
			)
			(placement
				(enabled no)
				(sheetname "")
			)
			(fill
				(thermal_gap 0.5)
				(thermal_bridge_width 0.5)
				(island_removal_mode 0)
			)
			(polygon
				(pts
					(xy 63.407544 -271.171416) (xy 56.333644 -271.171416) (xy 56.333644 -264.237216) (xy 57.438544 -264.237216)
					(xy 57.438544 -268.352016) (xy 62.061344 -268.352016) (xy 62.061344 -264.237216) (xy 63.407544 -264.237216)
				)
			)
		)
		(zone
			(layer "F.Cu")
			(hatch none 0.5)
			(connect_pads
				(clearance 0)
			)
			(min_thickness 0.25)
			(keepout
				(tracks allowed)
				(vias not_allowed)
				(pads allowed)
				(copperpour not_allowed)
				(footprints allowed)
			)
			(placement
				(enabled no)
				(sheetname "")
			)
			(fill
				(thermal_gap 0.5)
				(thermal_bridge_width 0.5)
				(island_removal_mode 0)
			)
			(polygon
				(pts
					(xy 63.407544 -271.171416) (xy 56.333644 -271.171416) (xy 56.333644 -264.237216) (xy 57.438544 -264.237216)
					(xy 57.438544 -268.352016) (xy 62.061344 -268.352016) (xy 62.061344 -264.237216) (xy 63.407544 -264.237216)
				)
			)
		)
		(zone
			(layers "F.Cu" "B.Cu" "In1.Cu" "In2.Cu" "In3.Cu" "In4.Cu" "In5.Cu" "In6.Cu"
				"In7.Cu" "In8.Cu" "In9.Cu" "In10.Cu"
			)
			(hatch none 0.5)
			(connect_pads
				(clearance 0)
			)
			(min_thickness 0.25)
			(keepout
				(tracks not_allowed)
				(vias allowed)
				(pads allowed)
				(copperpour not_allowed)
				(footprints allowed)
			)
			(placement
				(enabled no)
				(sheetname "")
			)
			(fill
				(thermal_gap 0.5)
				(thermal_bridge_width 0.5)
				(island_removal_mode 0)
			)
			(polygon
				(pts
					(arc
						(start 60.524644 -269.035022)
						(mid 58.975244 -269.035022)
						(end 60.524644 -269.035022)
					)
				)
			)
		)
		(zone
			(layers "F.Cu" "B.Cu" "In1.Cu" "In2.Cu" "In3.Cu" "In4.Cu" "In5.Cu" "In6.Cu"
				"In7.Cu" "In8.Cu" "In9.Cu" "In10.Cu"
			)
			(hatch none 0.5)
			(connect_pads
				(clearance 0)
			)
			(min_thickness 0.25)
			(keepout
				(tracks not_allowed)
				(vias allowed)
				(pads allowed)
				(copperpour not_allowed)
				(footprints allowed)
			)
			(placement
				(enabled no)
				(sheetname "")
			)
			(fill
				(thermal_gap 0.5)
				(thermal_bridge_width 0.5)
				(island_removal_mode 0)
			)
			(polygon
				(pts
					(arc
						(start 60.727844 -306.78501)
						(mid 58.772044 -306.78501)
						(end 60.727844 -306.78501)
					)
				)
			)
		)
	)
	(footprint ""
		(layer "F.Cu")
		(at 162.378898 -65.064894 90)
		(property "Reference" "R778"
			(at 0 0 90)
			(layer "F.SilkS")
			(hide yes)
			(effects
				(font
					(size 1.27 1.27)
				)
			)
		)
		(property "Value" "220R3F-1-GP"
			(at -0.0254 -2.5146 90)
			(unlocked yes)
			(layer "F.Fab")
			(hide yes)
			(effects
				(font
					(size 1.016 1.016)
					(thickness 0.1524)
				)
			)
		)
		(property "Device Type" "R603H22"
			(at -0.0254 -4.0386 90)
			(unlocked yes)
			(layer "F.Fab")
			(hide yes)
			(effects
				(font
					(size 1.016 1.016)
					(thickness 0.1524)
				)
			)
		)
		(duplicate_pad_numbers_are_jumpers no)
		(fp_line
			(start 0.2032 0)
			(end 0.4826 0)
			(stroke
				(width 0.2032)
				(type default)
			)
			(layer "F.SilkS")
		)
		(fp_line
			(start -0.4826 0)
			(end -0.2032 0)
			(stroke
				(width 0.2032)
				(type default)
			)
			(layer "F.SilkS")
		)
		(fp_rect
			(start -0.5842 1.3335)
			(end 0.5842 -1.3335)
			(stroke
				(width 0)
				(type default)
			)
			(fill no)
			(layer "F.CrtYd")
		)
		(fp_rect
			(start -0.5842 1.3335)
			(end 0.5842 -1.3335)
			(stroke
				(width 0)
				(type default)
			)
			(fill no)
			(layer "F.Fab")
		)
		(pad "1" smd custom
			(at 0 -0.762 90)
			(size 0.2159 0.2159)
			(layers "F.Cu" "F.Mask" "F.Paste")
			(net "HDD_PRSNT_28")
			(options
				(clearance outline)
				(anchor circle)
			)
			(primitives
				(gr_poly
					(pts
						(arc
							(start -0.3302 -0.4318)
							(mid -0.402042 -0.402042)
							(end -0.4318 -0.3302)
						)
						(arc
							(start -0.4318 0.3302)
							(mid -0.402042 0.402042)
							(end -0.3302 0.4318)
						)
						(arc
							(start 0.3302 0.4318)
							(mid 0.402042 0.402042)
							(end 0.4318 0.3302)
						)
						(arc
							(start 0.4318 -0.3302)
							(mid 0.402042 -0.402042)
							(end 0.3302 -0.4318)
						)
					)
					(width 0)
					(fill yes)
				)
			)
		)
		(pad "2" smd custom
			(at 0 0.762 90)
			(size 0.2159 0.2159)
			(layers "F.Cu" "F.Mask" "F.Paste")
			(net "DRIVE_A_28_INS")
			(options
				(clearance outline)
				(anchor circle)
			)
			(primitives
				(gr_poly
					(pts
						(arc
							(start -0.3302 -0.4318)
							(mid -0.402042 -0.402042)
							(end -0.4318 -0.3302)
						)
						(arc
							(start -0.4318 0.3302)
							(mid -0.402042 0.402042)
							(end -0.3302 0.4318)
						)
						(arc
							(start 0.3302 0.4318)
							(mid 0.402042 0.402042)
							(end 0.4318 0.3302)
						)
						(arc
							(start 0.4318 -0.3302)
							(mid 0.402042 -0.402042)
							(end 0.3302 -0.4318)
						)
					)
					(width 0)
					(fill yes)
				)
			)
		)
	)
	(footprint ""
		(layer "F.Cu")
		(at 332.6384 -272.585942 180)
		(property "Reference" "R276"
			(at 0 0 180)
			(layer "F.SilkS")
			(hide yes)
			(effects
				(font
					(size 1.27 1.27)
				)
			)
		)
		(property "Value" "1KR2F-3-GP"
			(at 0.064008 -3.993896 180)
			(unlocked yes)
			(layer "F.Fab")
			(hide yes)
			(effects
				(font
					(size 1.016 1.016)
					(thickness 0.1524)
				)
			)
		)
		(property "Device Type" "R402H16"
			(at 0.064008 -5.517896 180)
			(unlocked yes)
			(layer "F.Fab")
			(hide yes)
			(effects
				(font
					(size 1.016 1.016)
					(thickness 0.1524)
				)
			)
		)
		(duplicate_pad_numbers_are_jumpers no)
		(fp_line
			(start 0.508 -0.9398)
			(end -0.508 -0.9398)
			(stroke
				(width 0.1524)
				(type default)
			)
			(layer "F.SilkS")
		)
		(fp_line
			(start -0.508 -0.9398)
			(end -0.508 0.9398)
			(stroke
				(width 0.1524)
				(type default)
			)
			(layer "F.SilkS")
		)
		(fp_rect
			(start -0.508 0.9398)
			(end 0.508 -0.9398)
			(stroke
				(width 0)
				(type default)
			)
			(fill no)
			(layer "F.CrtYd")
		)
		(fp_rect
			(start -0.508 0.9398)
			(end 0.508 -0.9398)
			(stroke
				(width 0)
				(type default)
			)
			(fill no)
			(layer "F.Fab")
		)
		(pad "1" smd custom
			(at 0 -0.4445 180)
			(size 0.1397 0.1397)
			(layers "F.Cu" "F.Mask" "F.Paste")
			(net "P3V3_STBY_A")
			(options
				(clearance outline)
				(anchor circle)
			)
			(primitives
				(gr_poly
					(pts
						(arc
							(start -0.1778 -0.2794)
							(mid -0.249642 -0.249642)
							(end -0.2794 -0.1778)
						)
						(arc
							(start -0.2794 0.1778)
							(mid -0.249642 0.249642)
							(end -0.1778 0.2794)
						)
						(arc
							(start 0.1778 0.2794)
							(mid 0.249642 0.249642)
							(end 0.2794 0.1778)
						)
						(arc
							(start 0.2794 -0.1778)
							(mid 0.249642 -0.249642)
							(end 0.1778 -0.2794)
						)
					)
					(width 0)
					(fill yes)
				)
			)
		)
		(pad "2" smd custom
			(at 0 0.4445 180)
			(size 0.1397 0.1397)
			(layers "F.Cu" "F.Mask" "F.Paste")
			(net "SW_PWR_R_HDD6")
			(options
				(clearance outline)
				(anchor circle)
			)
			(primitives
				(gr_poly
					(pts
						(arc
							(start -0.1778 -0.2794)
							(mid -0.249642 -0.249642)
							(end -0.2794 -0.1778)
						)
						(arc
							(start -0.2794 0.1778)
							(mid -0.249642 0.249642)
							(end -0.1778 0.2794)
						)
						(arc
							(start 0.1778 0.2794)
							(mid 0.249642 0.249642)
							(end 0.2794 0.1778)
						)
						(arc
							(start 0.2794 -0.1778)
							(mid 0.249642 -0.249642)
							(end 0.1778 -0.2794)
						)
					)
					(width 0)
					(fill yes)
				)
			)
		)
	)
	(footprint ""
		(layer "F.Cu")
		(at 403.48535 -277.843742 90)
		(property "Reference" "R330"
			(at 0 0 90)
			(layer "F.SilkS")
			(hide yes)
			(effects
				(font
					(size 1.27 1.27)
				)
			)
		)
		(property "Value" "200KR2F-L-GP"
			(at 0.064008 -3.993896 90)
			(unlocked yes)
			(layer "F.Fab")
			(hide yes)
			(effects
				(font
					(size 1.016 1.016)
					(thickness 0.1524)
				)
			)
		)
		(property "Device Type" "R402H16"
			(at 0.064008 -5.517896 90)
			(unlocked yes)
			(layer "F.Fab")
			(hide yes)
			(effects
				(font
					(size 1.016 1.016)
					(thickness 0.1524)
				)
			)
		)
		(duplicate_pad_numbers_are_jumpers no)
		(fp_line
			(start 0.508 -0.9398)
			(end -0.508 -0.9398)
			(stroke
				(width 0.1524)
				(type default)
			)
			(layer "F.SilkS")
		)
		(fp_line
			(start -0.508 -0.9398)
			(end -0.508 0.9398)
			(stroke
				(width 0.1524)
				(type default)
			)
			(layer "F.SilkS")
		)
		(fp_rect
			(start -0.508 0.9398)
			(end 0.508 -0.9398)
			(stroke
				(width 0)
				(type default)
			)
			(fill no)
			(layer "F.CrtYd")
		)
		(fp_rect
			(start -0.508 0.9398)
			(end 0.508 -0.9398)
			(stroke
				(width 0)
				(type default)
			)
			(fill no)
			(layer "F.Fab")
		)
		(pad "1" smd custom
			(at 0 -0.4445 90)
			(size 0.1397 0.1397)
			(layers "F.Cu" "F.Mask" "F.Paste")
			(net "SW_HDD_R8")
			(options
				(clearance outline)
				(anchor circle)
			)
			(primitives
				(gr_poly
					(pts
						(arc
							(start -0.1778 -0.2794)
							(mid -0.249642 -0.249642)
							(end -0.2794 -0.1778)
						)
						(arc
							(start -0.2794 0.1778)
							(mid -0.249642 0.249642)
							(end -0.1778 0.2794)
						)
						(arc
							(start 0.1778 0.2794)
							(mid 0.249642 0.249642)
							(end 0.2794 0.1778)
						)
						(arc
							(start 0.2794 -0.1778)
							(mid 0.249642 -0.249642)
							(end 0.1778 -0.2794)
						)
					)
					(width 0)
					(fill yes)
				)
			)
		)
		(pad "2" smd custom
			(at 0 0.4445 90)
			(size 0.1397 0.1397)
			(layers "F.Cu" "F.Mask" "F.Paste")
			(net "SW_HDD_N8")
			(options
				(clearance outline)
				(anchor circle)
			)
			(primitives
				(gr_poly
					(pts
						(arc
							(start -0.1778 -0.2794)
							(mid -0.249642 -0.249642)
							(end -0.2794 -0.1778)
						)
						(arc
							(start -0.2794 0.1778)
							(mid -0.249642 0.249642)
							(end -0.1778 0.2794)
						)
						(arc
							(start 0.1778 0.2794)
							(mid 0.249642 0.249642)
							(end 0.2794 0.1778)
						)
						(arc
							(start 0.2794 -0.1778)
							(mid 0.249642 -0.249642)
							(end 0.1778 -0.2794)
						)
					)
					(width 0)
					(fill yes)
				)
			)
		)
	)
	(footprint ""
		(layer "F.Cu")
		(at 248.466102 -393.538964 -90)
		(property "Reference" "R1168"
			(at 0 0 270)
			(layer "F.SilkS")
			(hide yes)
			(effects
				(font
					(size 1.27 1.27)
				)
			)
		)
		(property "Value" "49K9R2F-L-GP"
			(at 0.064008 -3.993896 270)
			(unlocked yes)
			(layer "F.Fab")
			(hide yes)
			(effects
				(font
					(size 1.016 1.016)
					(thickness 0.1524)
				)
			)
		)
		(property "Device Type" "R402H16"
			(at 0.064008 -5.517896 270)
			(unlocked yes)
			(layer "F.Fab")
			(hide yes)
			(effects
				(font
					(size 1.016 1.016)
					(thickness 0.1524)
				)
			)
		)
		(duplicate_pad_numbers_are_jumpers no)
		(fp_line
			(start -0.508 -0.9398)
			(end -0.508 0.9398)
			(stroke
				(width 0.1524)
				(type default)
			)
			(layer "F.SilkS")
		)
		(fp_line
			(start 0.508 -0.9398)
			(end -0.508 -0.9398)
			(stroke
				(width 0.1524)
				(type default)
			)
			(layer "F.SilkS")
		)
		(fp_rect
			(start -0.508 0.9398)
			(end 0.508 -0.9398)
			(stroke
				(width 0)
				(type default)
			)
			(fill no)
			(layer "F.CrtYd")
		)
		(fp_rect
			(start -0.508 0.9398)
			(end 0.508 -0.9398)
			(stroke
				(width 0)
				(type default)
			)
			(fill no)
			(layer "F.Fab")
		)
		(pad "1" smd custom
			(at 0 -0.4445 270)
			(size 0.1397 0.1397)
			(layers "F.Cu" "F.Mask" "F.Paste")
			(net "P12V_IN")
			(options
				(clearance outline)
				(anchor circle)
			)
			(primitives
				(gr_poly
					(pts
						(arc
							(start -0.1778 -0.2794)
							(mid -0.249642 -0.249642)
							(end -0.2794 -0.1778)
						)
						(arc
							(start -0.2794 0.1778)
							(mid -0.249642 0.249642)
							(end -0.1778 0.2794)
						)
						(arc
							(start 0.1778 0.2794)
							(mid 0.249642 0.249642)
							(end 0.2794 0.1778)
						)
						(arc
							(start 0.2794 -0.1778)
							(mid 0.249642 -0.249642)
							(end 0.1778 -0.2794)
						)
					)
					(width 0)
					(fill yes)
				)
			)
		)
		(pad "2" smd custom
			(at 0 0.4445 270)
			(size 0.1397 0.1397)
			(layers "F.Cu" "F.Mask" "F.Paste")
			(net "MB3_CM_UV_R")
			(options
				(clearance outline)
				(anchor circle)
			)
			(primitives
				(gr_poly
					(pts
						(arc
							(start -0.1778 -0.2794)
							(mid -0.249642 -0.249642)
							(end -0.2794 -0.1778)
						)
						(arc
							(start -0.2794 0.1778)
							(mid -0.249642 0.249642)
							(end -0.1778 0.2794)
						)
						(arc
							(start 0.1778 0.2794)
							(mid 0.249642 0.249642)
							(end 0.2794 0.1778)
						)
						(arc
							(start 0.2794 -0.1778)
							(mid 0.249642 -0.249642)
							(end 0.1778 -0.2794)
						)
					)
					(width 0)
					(fill yes)
				)
			)
		)
	)
	(footprint ""
		(layer "F.Cu")
		(at 262.308848 17.959832 90)
		(property "Reference" "C47"
			(at 0 0 90)
			(layer "F.SilkS")
			(hide yes)
			(effects
				(font
					(size 1.27 1.27)
				)
			)
		)
		(property "Value" "SCD1U16V2KX-3GP"
			(at 1.1811 -2.7051 90)
			(unlocked yes)
			(layer "F.Fab")
			(hide yes)
			(effects
				(font
					(size 1.016 1.016)
					(thickness 0.1524)
				)
			)
		)
		(property "Device Type" "C402H22"
			(at 1.1811 -4.2291 90)
			(unlocked yes)
			(layer "F.Fab")
			(hide yes)
			(effects
				(font
					(size 1.016 1.016)
					(thickness 0.1524)
				)
			)
		)
		(duplicate_pad_numbers_are_jumpers no)
		(fp_rect
			(start -0.4318 0.9525)
			(end 0.4318 -0.9525)
			(stroke
				(width 0)
				(type default)
			)
			(fill no)
			(layer "F.CrtYd")
		)
		(fp_rect
			(start -0.4318 0.9525)
			(end 0.4318 -0.9525)
			(stroke
				(width 0)
				(type default)
			)
			(fill no)
			(layer "F.Fab")
		)
		(pad "1" smd custom
			(at 0 -0.4445 90)
			(size 0.1524 0.1524)
			(layers "F.Cu" "F.Mask" "F.Paste")
			(net "P5V_USB_A")
			(options
				(clearance outline)
				(anchor circle)
			)
			(primitives
				(gr_poly
					(pts
						(arc
							(start 0.3048 -0.2032)
							(mid 0.275042 -0.275042)
							(end 0.2032 -0.3048)
						)
						(arc
							(start -0.2032 -0.3048)
							(mid -0.275042 -0.275042)
							(end -0.3048 -0.2032)
						)
						(arc
							(start -0.3048 0.2032)
							(mid -0.275042 0.275042)
							(end -0.2032 0.3048)
						)
						(arc
							(start 0.2032 0.3048)
							(mid 0.275042 0.275042)
							(end 0.3048 0.2032)
						)
					)
					(width 0)
					(fill yes)
				)
			)
		)
		(pad "2" smd custom
			(at 0 0.4445 90)
			(size 0.1524 0.1524)
			(layers "F.Cu" "F.Mask" "F.Paste")
			(net "GND")
			(options
				(clearance outline)
				(anchor circle)
			)
			(primitives
				(gr_poly
					(pts
						(arc
							(start 0.3048 -0.2032)
							(mid 0.275042 -0.275042)
							(end 0.2032 -0.3048)
						)
						(arc
							(start -0.2032 -0.3048)
							(mid -0.275042 -0.275042)
							(end -0.3048 -0.2032)
						)
						(arc
							(start -0.3048 0.2032)
							(mid -0.275042 0.275042)
							(end -0.2032 0.3048)
						)
						(arc
							(start 0.2032 0.3048)
							(mid 0.275042 0.275042)
							(end 0.3048 0.2032)
						)
					)
					(width 0)
					(fill yes)
				)
			)
		)
	)
	(footprint ""
		(layer "F.Cu")
		(at 112.450118 -324.39991)
		(property "Reference" "RLED28"
			(at 0 0 0)
			(layer "F.SilkS")
			(hide yes)
			(effects
				(font
					(size 1.27 1.27)
				)
			)
		)
		(property "Value" "LED-BY-19-GP"
			(at -2.132076 1.414018 0)
			(unlocked yes)
			(layer "F.Fab")
			(hide yes)
			(effects
				(font
					(size 1.016 1.016)
					(thickness 0.1524)
				)
			)
		)
		(property "Device Type" "LED-1615-4PH26"
			(at -2.132076 -0.109982 0)
			(unlocked yes)
			(layer "F.Fab")
			(hide yes)
			(effects
				(font
					(size 1.016 1.016)
					(thickness 0.1524)
				)
			)
		)
		(duplicate_pad_numbers_are_jumpers no)
		(fp_line
			(start -1.2954 0.254)
			(end -1.2954 1.6002)
			(stroke
				(width 0.508)
				(type default)
			)
			(layer "F.SilkS")
		)
		(fp_line
			(start -1.2954 1.6002)
			(end 1.2954 1.6002)
			(stroke
				(width 0.508)
				(type default)
			)
			(layer "F.SilkS")
		)
		(fp_line
			(start -1.1176 -1.4224)
			(end 1.1176 -1.4224)
			(stroke
				(width 0.1524)
				(type default)
			)
			(layer "F.SilkS")
		)
		(fp_line
			(start -1.1176 1.4224)
			(end -1.1176 -1.4224)
			(stroke
				(width 0.1524)
				(type default)
			)
			(layer "F.SilkS")
		)
		(fp_line
			(start 1.1176 -1.4224)
			(end 1.1176 1.4224)
			(stroke
				(width 0.1524)
				(type default)
			)
			(layer "F.SilkS")
		)
		(fp_line
			(start 1.1176 1.4224)
			(end -1.1176 1.4224)
			(stroke
				(width 0.1524)
				(type default)
			)
			(layer "F.SilkS")
		)
		(fp_line
			(start 1.2954 1.6002)
			(end 1.2954 0.254)
			(stroke
				(width 0.508)
				(type default)
			)
			(layer "F.SilkS")
		)
		(fp_rect
			(start -0.7493 0.8001)
			(end 0.7493 -0.8001)
			(stroke
				(width 0)
				(type default)
			)
			(fill no)
			(layer "F.CrtYd")
		)
		(fp_poly
			(pts
				(xy -1.3716 1.6764) (xy -1.3716 -1.6764) (xy 1.3716 -1.6764) (xy 1.3716 0.0635) (xy 0.7493 0.0635)
				(xy 0.7493 -0.8001) (xy -0.7493 -0.8001) (xy -0.7493 0.8001) (xy 0.7493 0.8001) (xy 0.7493 0.0762)
				(xy 1.3716 0.0762) (xy 1.3716 1.6764)
			)
			(stroke
				(width 0)
				(type default)
			)
			(fill no)
			(layer "F.CrtYd")
		)
		(fp_rect
			(start -1.3716 1.6764)
			(end 1.3716 -1.6764)
			(stroke
				(width 0)
				(type default)
			)
			(fill no)
			(layer "F.Fab")
		)
		(pad "1" smd rect
			(at 0.50038 -0.73025)
			(size 0.7112 0.8636)
			(layers "F.Cu" "F.Mask" "F.Paste")
			(net "DRV_ACT_27")
		)
		(pad "2" smd rect
			(at -0.50038 -0.73025)
			(size 0.7112 0.8636)
			(layers "F.Cu" "F.Mask" "F.Paste")
			(net "FLT_HDD27")
		)
		(pad "3" smd rect
			(at 0.50038 0.73025)
			(size 0.7112 0.8636)
			(layers "F.Cu" "F.Mask" "F.Paste")
			(net "DRV_ACT_27_N")
		)
		(pad "4" smd rect
			(at -0.50038 0.73025)
			(size 0.7112 0.8636)
			(layers "F.Cu" "F.Mask" "F.Paste")
			(net "FLT_HDD27_N")
		)
	)
	(footprint ""
		(layer "F.Cu")
		(at 381.38735 -61.102494 -90)
		(property "Reference" "C458"
			(at 0 0 270)
			(layer "F.SilkS")
			(hide yes)
			(effects
				(font
					(size 1.27 1.27)
				)
			)
		)
		(property "Value" "SCD01U50V2KX-1GP"
			(at 1.1811 -2.7051 270)
			(unlocked yes)
			(layer "F.Fab")
			(hide yes)
			(effects
				(font
					(size 1.016 1.016)
					(thickness 0.1524)
				)
			)
		)
		(property "Device Type" "C402H22"
			(at 1.1811 -4.2291 270)
			(unlocked yes)
			(layer "F.Fab")
			(hide yes)
			(effects
				(font
					(size 1.016 1.016)
					(thickness 0.1524)
				)
			)
		)
		(duplicate_pad_numbers_are_jumpers no)
		(fp_rect
			(start -0.4318 0.9525)
			(end 0.4318 -0.9525)
			(stroke
				(width 0)
				(type default)
			)
			(fill no)
			(layer "F.CrtYd")
		)
		(fp_rect
			(start -0.4318 0.9525)
			(end 0.4318 -0.9525)
			(stroke
				(width 0)
				(type default)
			)
			(fill no)
			(layer "F.Fab")
		)
		(pad "1" smd custom
			(at 0 -0.4445 270)
			(size 0.1524 0.1524)
			(layers "F.Cu" "F.Mask" "F.Paste")
			(net "HDD_PRSNT_32")
			(options
				(clearance outline)
				(anchor circle)
			)
			(primitives
				(gr_poly
					(pts
						(arc
							(start 0.3048 -0.2032)
							(mid 0.275042 -0.275042)
							(end 0.2032 -0.3048)
						)
						(arc
							(start -0.2032 -0.3048)
							(mid -0.275042 -0.275042)
							(end -0.3048 -0.2032)
						)
						(arc
							(start -0.3048 0.2032)
							(mid -0.275042 0.275042)
							(end -0.2032 0.3048)
						)
						(arc
							(start 0.2032 0.3048)
							(mid 0.275042 0.275042)
							(end 0.3048 0.2032)
						)
					)
					(width 0)
					(fill yes)
				)
			)
		)
		(pad "2" smd custom
			(at 0 0.4445 270)
			(size 0.1524 0.1524)
			(layers "F.Cu" "F.Mask" "F.Paste")
			(net "GND")
			(options
				(clearance outline)
				(anchor circle)
			)
			(primitives
				(gr_poly
					(pts
						(arc
							(start 0.3048 -0.2032)
							(mid 0.275042 -0.275042)
							(end 0.2032 -0.3048)
						)
						(arc
							(start -0.2032 -0.3048)
							(mid -0.275042 -0.275042)
							(end -0.3048 -0.2032)
						)
						(arc
							(start -0.3048 0.2032)
							(mid -0.275042 0.275042)
							(end -0.2032 0.3048)
						)
						(arc
							(start 0.2032 0.3048)
							(mid 0.275042 0.275042)
							(end 0.3048 0.2032)
						)
					)
					(width 0)
					(fill yes)
				)
			)
		)
	)
	(footprint ""
		(layer "F.Cu")
		(at 35.667188 -304.428398 180)
		(property "Reference" "R209"
			(at 0 0 180)
			(layer "F.SilkS")
			(hide yes)
			(effects
				(font
					(size 1.27 1.27)
				)
			)
		)
		(property "Value" "130R3F-GP"
			(at -0.0254 -2.5146 180)
			(unlocked yes)
			(layer "F.Fab")
			(hide yes)
			(effects
				(font
					(size 1.016 1.016)
					(thickness 0.1524)
				)
			)
		)
		(property "Device Type" "R603H22"
			(at -0.0254 -4.0386 180)
			(unlocked yes)
			(layer "F.Fab")
			(hide yes)
			(effects
				(font
					(size 1.016 1.016)
					(thickness 0.1524)
				)
			)
		)
		(duplicate_pad_numbers_are_jumpers no)
		(fp_line
			(start 0.2032 0)
			(end 0.4826 0)
			(stroke
				(width 0.2032)
				(type default)
			)
			(layer "F.SilkS")
		)
		(fp_line
			(start -0.4826 0)
			(end -0.2032 0)
			(stroke
				(width 0.2032)
				(type default)
			)
			(layer "F.SilkS")
		)
		(fp_rect
			(start -0.5842 1.3335)
			(end 0.5842 -1.3335)
			(stroke
				(width 0)
				(type default)
			)
			(fill no)
			(layer "F.CrtYd")
		)
		(fp_rect
			(start -0.5842 1.3335)
			(end 0.5842 -1.3335)
			(stroke
				(width 0)
				(type default)
			)
			(fill no)
			(layer "F.Fab")
		)
		(pad "1" smd custom
			(at 0 -0.762 180)
			(size 0.2159 0.2159)
			(layers "F.Cu" "F.Mask" "F.Paste")
			(net "P5V_B")
			(options
				(clearance outline)
				(anchor circle)
			)
			(primitives
				(gr_poly
					(pts
						(arc
							(start -0.3302 -0.4318)
							(mid -0.402042 -0.402042)
							(end -0.4318 -0.3302)
						)
						(arc
							(start -0.4318 0.3302)
							(mid -0.402042 0.402042)
							(end -0.3302 0.4318)
						)
						(arc
							(start 0.3302 0.4318)
							(mid 0.402042 0.402042)
							(end 0.4318 0.3302)
						)
						(arc
							(start 0.4318 -0.3302)
							(mid 0.402042 -0.402042)
							(end 0.3302 -0.4318)
						)
					)
					(width 0)
					(fill yes)
				)
			)
		)
		(pad "2" smd custom
			(at 0 0.762 180)
			(size 0.2159 0.2159)
			(layers "F.Cu" "F.Mask" "F.Paste")
			(net "FLT_HDD25")
			(options
				(clearance outline)
				(anchor circle)
			)
			(primitives
				(gr_poly
					(pts
						(arc
							(start -0.3302 -0.4318)
							(mid -0.402042 -0.402042)
							(end -0.4318 -0.3302)
						)
						(arc
							(start -0.4318 0.3302)
							(mid -0.402042 0.402042)
							(end -0.3302 0.4318)
						)
						(arc
							(start 0.3302 0.4318)
							(mid 0.402042 0.402042)
							(end 0.4318 0.3302)
						)
						(arc
							(start 0.4318 -0.3302)
							(mid 0.402042 -0.402042)
							(end 0.3302 -0.4318)
						)
					)
					(width 0)
					(fill yes)
				)
			)
		)
	)
	(footprint ""
		(layer "F.Cu")
		(at 115.4684 -289.6108)
		(property "Reference" "Q20"
			(at 0 0 0)
			(layer "F.SilkS")
			(hide yes)
			(effects
				(font
					(size 1.27 1.27)
				)
			)
		)
		(property "Value" "AO4407AL-GP"
			(at -3.707384 -1.5367 0)
			(unlocked yes)
			(layer "F.Fab")
			(hide yes)
			(effects
				(font
					(size 1.016 1.016)
					(thickness 0.1524)
				)
			)
		)
		(property "Device Type" "SOIC8H69"
			(at -3.707384 -3.0607 0)
			(unlocked yes)
			(layer "F.Fab")
			(hide yes)
			(effects
				(font
					(size 1.016 1.016)
					(thickness 0.1524)
				)
			)
		)
		(duplicate_pad_numbers_are_jumpers no)
		(fp_line
			(start -2.7432 -1.4224)
			(end -2.7432 1.4224)
			(stroke
				(width 0.1524)
				(type default)
			)
			(layer "F.SilkS")
		)
		(fp_line
			(start -2.7432 1.4224)
			(end -2.6416 1.4224)
			(stroke
				(width 0.1524)
				(type default)
			)
			(layer "F.SilkS")
		)
		(fp_line
			(start -2.7432 1.4224)
			(end 2.1336 1.4224)
			(stroke
				(width 0.1524)
				(type default)
			)
			(layer "F.SilkS")
		)
		(fp_line
			(start -2.7178 -0.508)
			(end -2.1844 -0.0508)
			(stroke
				(width 0.1524)
				(type default)
			)
			(layer "F.SilkS")
		)
		(fp_line
			(start -2.6289 3.4417)
			(end -2.6289 1.4732)
			(stroke
				(width 0.381)
				(type default)
			)
			(layer "F.SilkS")
		)
		(fp_line
			(start -2.1844 -0.0508)
			(end -2.7178 0.508)
			(stroke
				(width 0.1524)
				(type default)
			)
			(layer "F.SilkS")
		)
		(fp_line
			(start 2.1336 -1.4224)
			(end -2.7432 -1.4224)
			(stroke
				(width 0.1524)
				(type default)
			)
			(layer "F.SilkS")
		)
		(fp_line
			(start 2.1336 1.4224)
			(end 2.1336 -1.4224)
			(stroke
				(width 0.1524)
				(type default)
			)
			(layer "F.SilkS")
		)
		(fp_poly
			(pts
				(xy -2.2098 -1.4224) (xy -2.2098 1.4224) (xy 2.2098 1.4224) (xy 2.2098 -1.4224)
			)
			(stroke
				(width 0)
				(type default)
			)
			(fill yes)
			(layer "F.SilkS")
		)
		(fp_rect
			(start -2.450084 2.999994)
			(end 2.450084 -2.999994)
			(stroke
				(width 0)
				(type default)
			)
			(fill no)
			(layer "F.CrtYd")
		)
		(fp_poly
			(pts
				(xy -2.8194 3.6322) (xy -2.8194 -3.6322) (xy 2.8194 -3.6322) (xy 2.8194 1.18364) (xy 2.450084 1.18364)
				(xy 2.450084 -2.999994) (xy -2.450084 -2.999994) (xy -2.450084 2.999994) (xy 2.450084 2.999994)
				(xy 2.450084 1.18618) (xy 2.8194 1.18618) (xy 2.8194 3.6322)
			)
			(stroke
				(width 0)
				(type default)
			)
			(fill no)
			(layer "F.CrtYd")
		)
		(fp_rect
			(start -2.8194 3.6322)
			(end 2.8194 -3.6322)
			(stroke
				(width 0)
				(type default)
			)
			(fill no)
			(layer "F.Fab")
		)
		(pad "1" smd rect
			(at -1.905 2.54)
			(size 0.635 1.651)
			(layers "F.Cu" "F.Mask" "F.Paste")
			(net "P12V_A")
		)
		(pad "2" smd rect
			(at -0.635 2.54)
			(size 0.635 1.651)
			(layers "F.Cu" "F.Mask" "F.Paste")
			(net "P12V_A")
		)
		(pad "3" smd rect
			(at 0.635 2.54)
			(size 0.635 1.651)
			(layers "F.Cu" "F.Mask" "F.Paste")
			(net "P12V_A")
		)
		(pad "4" smd rect
			(at 1.905 2.54)
			(size 0.635 1.651)
			(layers "F.Cu" "F.Mask" "F.Paste")
			(net "SW_HDD_N3")
		)
		(pad "5" smd rect
			(at 1.905 -2.54)
			(size 0.635 1.651)
			(layers "F.Cu" "F.Mask" "F.Paste")
			(net "P12V_HDD3")
		)
		(pad "6" smd rect
			(at 0.635 -2.54)
			(size 0.635 1.651)
			(layers "F.Cu" "F.Mask" "F.Paste")
			(net "P12V_HDD3")
		)
		(pad "7" smd rect
			(at -0.635 -2.54)
			(size 0.635 1.651)
			(layers "F.Cu" "F.Mask" "F.Paste")
			(net "P12V_HDD3")
		)
		(pad "8" smd rect
			(at -1.905 -2.54)
			(size 0.635 1.651)
			(layers "F.Cu" "F.Mask" "F.Paste")
			(net "P12V_HDD3")
		)
	)
	(footprint ""
		(layer "F.Cu")
		(at 469.942926 -169.523918 90)
		(property "Reference" "C348"
			(at 0 0 90)
			(layer "F.SilkS")
			(hide yes)
			(effects
				(font
					(size 1.27 1.27)
				)
			)
		)
		(property "Value" "SCD033U25V2KX-GP"
			(at 1.1811 -2.7051 90)
			(unlocked yes)
			(layer "F.Fab")
			(hide yes)
			(effects
				(font
					(size 1.016 1.016)
					(thickness 0.1524)
				)
			)
		)
		(property "Device Type" "C402H22"
			(at 1.1811 -4.2291 90)
			(unlocked yes)
			(layer "F.Fab")
			(hide yes)
			(effects
				(font
					(size 1.016 1.016)
					(thickness 0.1524)
				)
			)
		)
		(duplicate_pad_numbers_are_jumpers no)
		(fp_rect
			(start -0.4318 0.9525)
			(end 0.4318 -0.9525)
			(stroke
				(width 0)
				(type default)
			)
			(fill no)
			(layer "F.CrtYd")
		)
		(fp_rect
			(start -0.4318 0.9525)
			(end 0.4318 -0.9525)
			(stroke
				(width 0)
				(type default)
			)
			(fill no)
			(layer "F.Fab")
		)
		(pad "1" smd custom
			(at 0 -0.4445 90)
			(size 0.1524 0.1524)
			(layers "F.Cu" "F.Mask" "F.Paste")
			(net "P12V_A")
			(options
				(clearance outline)
				(anchor circle)
			)
			(primitives
				(gr_poly
					(pts
						(arc
							(start 0.3048 -0.2032)
							(mid 0.275042 -0.275042)
							(end 0.2032 -0.3048)
						)
						(arc
							(start -0.2032 -0.3048)
							(mid -0.275042 -0.275042)
							(end -0.3048 -0.2032)
						)
						(arc
							(start -0.3048 0.2032)
							(mid -0.275042 0.275042)
							(end -0.2032 0.3048)
						)
						(arc
							(start 0.2032 0.3048)
							(mid 0.275042 0.275042)
							(end 0.3048 0.2032)
						)
					)
					(width 0)
					(fill yes)
				)
			)
		)
		(pad "2" smd custom
			(at 0 0.4445 90)
			(size 0.1524 0.1524)
			(layers "F.Cu" "F.Mask" "F.Paste")
			(net "SW_HDD_N23")
			(options
				(clearance outline)
				(anchor circle)
			)
			(primitives
				(gr_poly
					(pts
						(arc
							(start 0.3048 -0.2032)
							(mid 0.275042 -0.275042)
							(end 0.2032 -0.3048)
						)
						(arc
							(start -0.2032 -0.3048)
							(mid -0.275042 -0.275042)
							(end -0.3048 -0.2032)
						)
						(arc
							(start -0.3048 0.2032)
							(mid -0.275042 0.275042)
							(end -0.2032 0.3048)
						)
						(arc
							(start 0.2032 0.3048)
							(mid 0.275042 0.275042)
							(end 0.3048 0.2032)
						)
					)
					(width 0)
					(fill yes)
				)
			)
		)
	)
	(footprint ""
		(layer "F.Cu")
		(at 395.45895 -180.826918 180)
		(property "Reference" "C301"
			(at 0 0 180)
			(layer "F.SilkS")
			(hide yes)
			(effects
				(font
					(size 1.27 1.27)
				)
			)
		)
		(property "Value" "SC10U16V6KX-2GP"
			(at -0.0762 -5.1308 180)
			(unlocked yes)
			(layer "F.Fab")
			(hide yes)
			(effects
				(font
					(size 1.016 1.016)
					(thickness 0.1524)
				)
			)
		)
		(property "Device Type" "C1206H71"
			(at -0.127 -6.6548 180)
			(unlocked yes)
			(layer "F.Fab")
			(hide yes)
			(effects
				(font
					(size 1.016 1.016)
					(thickness 0.1524)
				)
			)
		)
		(duplicate_pad_numbers_are_jumpers no)
		(fp_line
			(start 1.016 2.2352)
			(end -1.016 2.2352)
			(stroke
				(width 0.1524)
				(type default)
			)
			(layer "F.SilkS")
		)
		(fp_line
			(start 1.016 0.8382)
			(end 1.016 2.2352)
			(stroke
				(width 0.1524)
				(type default)
			)
			(layer "F.SilkS")
		)
		(fp_line
			(start 1.016 -2.2352)
			(end 1.016 -0.8382)
			(stroke
				(width 0.1524)
				(type default)
			)
			(layer "F.SilkS")
		)
		(fp_line
			(start -1.016 2.2352)
			(end -1.016 0.8382)
			(stroke
				(width 0.1524)
				(type default)
			)
			(layer "F.SilkS")
		)
		(fp_line
			(start -1.016 -0.8382)
			(end -1.016 -2.2352)
			(stroke
				(width 0.1524)
				(type default)
			)
			(layer "F.SilkS")
		)
		(fp_line
			(start -1.016 -2.2352)
			(end 1.016 -2.2352)
			(stroke
				(width 0.1524)
				(type default)
			)
			(layer "F.SilkS")
		)
		(fp_rect
			(start -1.0922 2.3114)
			(end 1.0922 -2.3114)
			(stroke
				(width 0)
				(type default)
			)
			(fill no)
			(layer "F.CrtYd")
		)
		(fp_poly
			(pts
				(xy 1.0922 -2.3114) (xy 1.0922 2.3114) (xy -1.0922 2.3114) (xy -1.0922 -2.3114)
			)
			(stroke
				(width 0)
				(type default)
			)
			(fill no)
			(layer "F.Fab")
		)
		(pad "1" smd rect
			(at 0 -1.397 180)
			(size 1.651 1.27)
			(layers "F.Cu" "F.Mask" "F.Paste")
			(net "P5V_HDD20")
		)
		(pad "2" smd rect
			(at 0 1.397 180)
			(size 1.651 1.27)
			(layers "F.Cu" "F.Mask" "F.Paste")
			(net "GND")
		)
	)
	(footprint ""
		(layer "F.Cu")
		(at 162.378898 -180.064918 90)
		(property "Reference" "R502"
			(at 0 0 90)
			(layer "F.SilkS")
			(hide yes)
			(effects
				(font
					(size 1.27 1.27)
				)
			)
		)
		(property "Value" "220R3F-1-GP"
			(at -0.0254 -2.5146 90)
			(unlocked yes)
			(layer "F.Fab")
			(hide yes)
			(effects
				(font
					(size 1.016 1.016)
					(thickness 0.1524)
				)
			)
		)
		(property "Device Type" "R603H22"
			(at -0.0254 -4.0386 90)
			(unlocked yes)
			(layer "F.Fab")
			(hide yes)
			(effects
				(font
					(size 1.016 1.016)
					(thickness 0.1524)
				)
			)
		)
		(duplicate_pad_numbers_are_jumpers no)
		(fp_line
			(start 0.2032 0)
			(end 0.4826 0)
			(stroke
				(width 0.2032)
				(type default)
			)
			(layer "F.SilkS")
		)
		(fp_line
			(start -0.4826 0)
			(end -0.2032 0)
			(stroke
				(width 0.2032)
				(type default)
			)
			(layer "F.SilkS")
		)
		(fp_rect
			(start -0.5842 1.3335)
			(end 0.5842 -1.3335)
			(stroke
				(width 0)
				(type default)
			)
			(fill no)
			(layer "F.CrtYd")
		)
		(fp_rect
			(start -0.5842 1.3335)
			(end 0.5842 -1.3335)
			(stroke
				(width 0)
				(type default)
			)
			(fill no)
			(layer "F.Fab")
		)
		(pad "1" smd custom
			(at 0 -0.762 90)
			(size 0.2159 0.2159)
			(layers "F.Cu" "F.Mask" "F.Paste")
			(net "HDD_PRSNT_16")
			(options
				(clearance outline)
				(anchor circle)
			)
			(primitives
				(gr_poly
					(pts
						(arc
							(start -0.3302 -0.4318)
							(mid -0.402042 -0.402042)
							(end -0.4318 -0.3302)
						)
						(arc
							(start -0.4318 0.3302)
							(mid -0.402042 0.402042)
							(end -0.3302 0.4318)
						)
						(arc
							(start 0.3302 0.4318)
							(mid 0.402042 0.402042)
							(end 0.4318 0.3302)
						)
						(arc
							(start 0.4318 -0.3302)
							(mid 0.402042 -0.402042)
							(end 0.3302 -0.4318)
						)
					)
					(width 0)
					(fill yes)
				)
			)
		)
		(pad "2" smd custom
			(at 0 0.762 90)
			(size 0.2159 0.2159)
			(layers "F.Cu" "F.Mask" "F.Paste")
			(net "DRIVE_A_16_INS")
			(options
				(clearance outline)
				(anchor circle)
			)
			(primitives
				(gr_poly
					(pts
						(arc
							(start -0.3302 -0.4318)
							(mid -0.402042 -0.402042)
							(end -0.4318 -0.3302)
						)
						(arc
							(start -0.4318 0.3302)
							(mid -0.402042 0.402042)
							(end -0.3302 0.4318)
						)
						(arc
							(start 0.3302 0.4318)
							(mid 0.402042 0.402042)
							(end 0.4318 0.3302)
						)
						(arc
							(start 0.4318 -0.3302)
							(mid 0.402042 -0.402042)
							(end 0.3302 -0.4318)
						)
					)
					(width 0)
					(fill yes)
				)
			)
		)
	)
	(footprint ""
		(layer "F.Cu")
		(at 144.215866 -145.372074 180)
		(property "Reference" "C550"
			(at 0 0 180)
			(layer "F.SilkS")
			(hide yes)
			(effects
				(font
					(size 1.27 1.27)
				)
			)
		)
		(property "Value" "SCD1U25V2KX-2-GP"
			(at 1.1811 -2.7051 180)
			(unlocked yes)
			(layer "F.Fab")
			(hide yes)
			(effects
				(font
					(size 1.016 1.016)
					(thickness 0.1524)
				)
			)
		)
		(property "Device Type" "C402H22"
			(at 1.1811 -4.2291 180)
			(unlocked yes)
			(layer "F.Fab")
			(hide yes)
			(effects
				(font
					(size 1.016 1.016)
					(thickness 0.1524)
				)
			)
		)
		(duplicate_pad_numbers_are_jumpers no)
		(fp_rect
			(start -0.4318 0.9525)
			(end 0.4318 -0.9525)
			(stroke
				(width 0)
				(type default)
			)
			(fill no)
			(layer "F.CrtYd")
		)
		(fp_rect
			(start -0.4318 0.9525)
			(end 0.4318 -0.9525)
			(stroke
				(width 0)
				(type default)
			)
			(fill no)
			(layer "F.Fab")
		)
		(pad "1" smd custom
			(at 0 -0.4445 180)
			(size 0.1524 0.1524)
			(layers "F.Cu" "F.Mask" "F.Paste")
			(net "MB0_ISTART_R")
			(options
				(clearance outline)
				(anchor circle)
			)
			(primitives
				(gr_poly
					(pts
						(arc
							(start 0.3048 -0.2032)
							(mid 0.275042 -0.275042)
							(end 0.2032 -0.3048)
						)
						(arc
							(start -0.2032 -0.3048)
							(mid -0.275042 -0.275042)
							(end -0.3048 -0.2032)
						)
						(arc
							(start -0.3048 0.2032)
							(mid -0.275042 0.275042)
							(end -0.2032 0.3048)
						)
						(arc
							(start 0.2032 0.3048)
							(mid 0.275042 0.275042)
							(end 0.3048 0.2032)
						)
					)
					(width 0)
					(fill yes)
				)
			)
		)
		(pad "2" smd custom
			(at 0 0.4445 180)
			(size 0.1524 0.1524)
			(layers "F.Cu" "F.Mask" "F.Paste")
			(net "AGND_CURRENT_MONOA")
			(options
				(clearance outline)
				(anchor circle)
			)
			(primitives
				(gr_poly
					(pts
						(arc
							(start 0.3048 -0.2032)
							(mid 0.275042 -0.275042)
							(end 0.2032 -0.3048)
						)
						(arc
							(start -0.2032 -0.3048)
							(mid -0.275042 -0.275042)
							(end -0.3048 -0.2032)
						)
						(arc
							(start -0.3048 0.2032)
							(mid -0.275042 0.275042)
							(end -0.2032 0.3048)
						)
						(arc
							(start 0.2032 0.3048)
							(mid 0.275042 0.275042)
							(end 0.3048 0.2032)
						)
					)
					(width 0)
					(fill yes)
				)
			)
		)
	)
	(footprint ""
		(layer "F.Cu")
		(at 393.674854 -92.799916)
		(property "Reference" ""
			(at 0 0 0)
			(layer "F.SilkS")
			(hide yes)
			(effects
				(font
					(size 1.27 1.27)
				)
			)
		)
		(property "Value" "*"
			(at -8.398764 -8.057642 0)
			(unlocked yes)
			(layer "F.Fab")
			(hide yes)
			(effects
				(font
					(size 1.016 1.016)
					(thickness 0.1524)
				)
			)
		)
		(duplicate_pad_numbers_are_jumpers no)
		(fp_poly
			(pts
				(arc
					(start 7.3152 0)
					(mid 0 7.3152)
					(end -7.3152 0)
				)
				(arc
					(start -7.3152 -5.9944)
					(mid 0 -13.3096)
					(end 7.3152 -5.9944)
				)
			)
			(stroke
				(width 0)
				(type default)
			)
			(fill no)
			(layer "B.CrtYd")
		)
		(fp_poly
			(pts
				(arc
					(start 7.3152 0)
					(mid 0 7.3152)
					(end -7.3152 0)
				)
				(arc
					(start -7.3152 -5.9944)
					(mid 0 -13.3096)
					(end 7.3152 -5.9944)
				)
			)
			(stroke
				(width 0)
				(type default)
			)
			(fill no)
			(layer "F.CrtYd")
		)
		(fp_poly
			(pts
				(arc
					(start 7.3152 0)
					(mid 0 7.3152)
					(end -7.3152 0)
				)
				(arc
					(start -7.3152 -5.9944)
					(mid 0 -13.3096)
					(end 7.3152 -5.9944)
				)
			)
			(stroke
				(width 0)
				(type default)
			)
			(fill no)
			(layer "B.Fab")
		)
		(fp_poly
			(pts
				(arc
					(start 7.3152 0)
					(mid 0 7.3152)
					(end -7.3152 0)
				)
				(arc
					(start -7.3152 -5.9944)
					(mid 0 -13.3096)
					(end 7.3152 -5.9944)
				)
			)
			(stroke
				(width 0)
				(type default)
			)
			(fill no)
			(layer "F.Fab")
		)
		(pad "1" thru_hole oval
			(at 0 0)
			(size 14.0208 20.0152)
			(drill 0.0254
				(offset 0 -2.9972)
			)
			(layers "*.Cu" "*.Mask")
			(remove_unused_layers no)
			(net "Net_101")
			(clearance -1.002284)
			(thermal_gap 0.1524)
			(padstack
				(mode front_inner_back)
				(layer "Inner"
					(shape custom)
					(size 2.928012 2.928012)
					(options
						(anchor circle)
					)
					(primitives
						(gr_poly
							(pts
								(arc
									(start 4.571746 -2.084324)
									(mid 0.000333 7.430372)
									(end -4.571492 -2.084324)
								)
								(arc
									(start -4.571492 -2.084324)
									(mid -3.570296 -3.611977)
									(end -2.875026 -5.30098)
								)
								(arc
									(start -2.875026 -5.30098)
									(mid 0.000217 -7.43089)
									(end 2.87528 -5.30098)
								)
								(arc
									(start 2.87528 -5.30098)
									(mid 3.570511 -3.611956)
									(end 4.571746 -2.084324)
								)
							)
							(width 0)
							(fill yes)
						)
					)
					(clearance 0.1524)
				)
				(layer "B.Cu"
					(shape oval)
					(size 14.0208 20.0152)
					(offset 0 -2.9972)
					(clearance -1.002284)
				)
			)
		)
		(zone
			(layers "F.Cu" "B.Cu" "In1.Cu" "In2.Cu" "In3.Cu" "In4.Cu" "In5.Cu" "In6.Cu"
				"In7.Cu" "In8.Cu" "In9.Cu" "In10.Cu"
			)
			(hatch none 0.5)
			(connect_pads
				(clearance 0)
			)
			(min_thickness 0.25)
			(keepout
				(tracks not_allowed)
				(vias allowed)
				(pads allowed)
				(copperpour not_allowed)
				(footprints allowed)
			)
			(placement
				(enabled no)
				(sheetname "")
			)
			(fill
				(thermal_gap 0.5)
				(thermal_bridge_width 0.5)
				(island_removal_mode 0)
			)
			(polygon
				(pts
					(arc
						(start 386.664454 -98.794316)
						(mid 393.674854 -105.804716)
						(end 400.685254 -98.794316)
					)
					(arc
						(start 400.685254 -92.799916)
						(mid 393.674854 -85.789516)
						(end 386.664454 -92.799916)
					)
				)
			)
		)
	)
	(footprint ""
		(layer "F.Cu")
		(at 365.5568 -132.1054)
		(property "Reference" "C561"
			(at 0 0 0)
			(layer "F.SilkS")
			(hide yes)
			(effects
				(font
					(size 1.27 1.27)
				)
			)
		)
		(property "Value" "SCD1U25V2KX-2-GP"
			(at 1.1811 -2.7051 0)
			(unlocked yes)
			(layer "F.Fab")
			(hide yes)
			(effects
				(font
					(size 1.016 1.016)
					(thickness 0.1524)
				)
			)
		)
		(property "Device Type" "C402H22"
			(at 1.1811 -4.2291 0)
			(unlocked yes)
			(layer "F.Fab")
			(hide yes)
			(effects
				(font
					(size 1.016 1.016)
					(thickness 0.1524)
				)
			)
		)
		(duplicate_pad_numbers_are_jumpers no)
		(fp_rect
			(start -0.4318 0.9525)
			(end 0.4318 -0.9525)
			(stroke
				(width 0)
				(type default)
			)
			(fill no)
			(layer "F.CrtYd")
		)
		(fp_rect
			(start -0.4318 0.9525)
			(end 0.4318 -0.9525)
			(stroke
				(width 0)
				(type default)
			)
			(fill no)
			(layer "F.Fab")
		)
		(pad "1" smd custom
			(at 0 -0.4445)
			(size 0.1524 0.1524)
			(layers "F.Cu" "F.Mask" "F.Paste")
			(net "MB1_PSET_R")
			(options
				(clearance outline)
				(anchor circle)
			)
			(primitives
				(gr_poly
					(pts
						(arc
							(start 0.3048 -0.2032)
							(mid 0.275042 -0.275042)
							(end 0.2032 -0.3048)
						)
						(arc
							(start -0.2032 -0.3048)
							(mid -0.275042 -0.275042)
							(end -0.3048 -0.2032)
						)
						(arc
							(start -0.3048 0.2032)
							(mid -0.275042 0.275042)
							(end -0.2032 0.3048)
						)
						(arc
							(start 0.2032 0.3048)
							(mid 0.275042 0.275042)
							(end 0.3048 0.2032)
						)
					)
					(width 0)
					(fill yes)
				)
			)
		)
		(pad "2" smd custom
			(at 0 0.4445)
			(size 0.1524 0.1524)
			(layers "F.Cu" "F.Mask" "F.Paste")
			(net "AGND_CURRENT_MONOB")
			(options
				(clearance outline)
				(anchor circle)
			)
			(primitives
				(gr_poly
					(pts
						(arc
							(start 0.3048 -0.2032)
							(mid 0.275042 -0.275042)
							(end 0.2032 -0.3048)
						)
						(arc
							(start -0.2032 -0.3048)
							(mid -0.275042 -0.275042)
							(end -0.3048 -0.2032)
						)
						(arc
							(start -0.3048 0.2032)
							(mid -0.275042 0.275042)
							(end -0.2032 0.3048)
						)
						(arc
							(start 0.2032 0.3048)
							(mid 0.275042 0.275042)
							(end 0.3048 0.2032)
						)
					)
					(width 0)
					(fill yes)
				)
			)
		)
	)
	(footprint ""
		(layer "F.Cu")
		(at 143.999966 -324.39991)
		(property "Reference" "RLED29"
			(at 0 0 0)
			(layer "F.SilkS")
			(hide yes)
			(effects
				(font
					(size 1.27 1.27)
				)
			)
		)
		(property "Value" "LED-BY-19-GP"
			(at -2.132076 1.414018 0)
			(unlocked yes)
			(layer "F.Fab")
			(hide yes)
			(effects
				(font
					(size 1.016 1.016)
					(thickness 0.1524)
				)
			)
		)
		(property "Device Type" "LED-1615-4PH26"
			(at -2.132076 -0.109982 0)
			(unlocked yes)
			(layer "F.Fab")
			(hide yes)
			(effects
				(font
					(size 1.016 1.016)
					(thickness 0.1524)
				)
			)
		)
		(duplicate_pad_numbers_are_jumpers no)
		(fp_line
			(start -1.2954 0.254)
			(end -1.2954 1.6002)
			(stroke
				(width 0.508)
				(type default)
			)
			(layer "F.SilkS")
		)
		(fp_line
			(start -1.2954 1.6002)
			(end 1.2954 1.6002)
			(stroke
				(width 0.508)
				(type default)
			)
			(layer "F.SilkS")
		)
		(fp_line
			(start -1.1176 -1.4224)
			(end 1.1176 -1.4224)
			(stroke
				(width 0.1524)
				(type default)
			)
			(layer "F.SilkS")
		)
		(fp_line
			(start -1.1176 1.4224)
			(end -1.1176 -1.4224)
			(stroke
				(width 0.1524)
				(type default)
			)
			(layer "F.SilkS")
		)
		(fp_line
			(start 1.1176 -1.4224)
			(end 1.1176 1.4224)
			(stroke
				(width 0.1524)
				(type default)
			)
			(layer "F.SilkS")
		)
		(fp_line
			(start 1.1176 1.4224)
			(end -1.1176 1.4224)
			(stroke
				(width 0.1524)
				(type default)
			)
			(layer "F.SilkS")
		)
		(fp_line
			(start 1.2954 1.6002)
			(end 1.2954 0.254)
			(stroke
				(width 0.508)
				(type default)
			)
			(layer "F.SilkS")
		)
		(fp_rect
			(start -0.7493 0.8001)
			(end 0.7493 -0.8001)
			(stroke
				(width 0)
				(type default)
			)
			(fill no)
			(layer "F.CrtYd")
		)
		(fp_poly
			(pts
				(xy -1.3716 1.6764) (xy -1.3716 -1.6764) (xy 1.3716 -1.6764) (xy 1.3716 0.0635) (xy 0.7493 0.0635)
				(xy 0.7493 -0.8001) (xy -0.7493 -0.8001) (xy -0.7493 0.8001) (xy 0.7493 0.8001) (xy 0.7493 0.0762)
				(xy 1.3716 0.0762) (xy 1.3716 1.6764)
			)
			(stroke
				(width 0)
				(type default)
			)
			(fill no)
			(layer "F.CrtYd")
		)
		(fp_rect
			(start -1.3716 1.6764)
			(end 1.3716 -1.6764)
			(stroke
				(width 0)
				(type default)
			)
			(fill no)
			(layer "F.Fab")
		)
		(pad "1" smd rect
			(at 0.50038 -0.73025)
			(size 0.7112 0.8636)
			(layers "F.Cu" "F.Mask" "F.Paste")
			(net "DRV_ACT_28")
		)
		(pad "2" smd rect
			(at -0.50038 -0.73025)
			(size 0.7112 0.8636)
			(layers "F.Cu" "F.Mask" "F.Paste")
			(net "FLT_HDD28")
		)
		(pad "3" smd rect
			(at 0.50038 0.73025)
			(size 0.7112 0.8636)
			(layers "F.Cu" "F.Mask" "F.Paste")
			(net "DRV_ACT_28_N")
		)
		(pad "4" smd rect
			(at -0.50038 0.73025)
			(size 0.7112 0.8636)
			(layers "F.Cu" "F.Mask" "F.Paste")
			(net "FLT_HDD28_N")
		)
	)
	(footprint ""
		(layer "F.Cu")
		(at 6.812788 -172.385482)
		(property "Reference" "Q263"
			(at 0 0 0)
			(layer "F.SilkS")
			(hide yes)
			(effects
				(font
					(size 1.27 1.27)
				)
			)
		)
		(property "Value" "SSM3K324R-GP"
			(at 0.127 -8.9662 0)
			(unlocked yes)
			(layer "F.Fab")
			(hide yes)
			(effects
				(font
					(size 1.016 1.016)
					(thickness 0.1524)
				)
			)
		)
		(property "Device Type" "SOT23DGS2D4H35"
			(at 0.127 -10.4902 0)
			(unlocked yes)
			(layer "F.Fab")
			(hide yes)
			(effects
				(font
					(size 1.016 1.016)
					(thickness 0.1524)
				)
			)
		)
		(duplicate_pad_numbers_are_jumpers no)
		(fp_line
			(start -1.651 -1.778)
			(end -1.651 1.778)
			(stroke
				(width 0.1524)
				(type default)
			)
			(layer "F.SilkS")
		)
		(fp_line
			(start -1.651 1.778)
			(end 1.651 1.778)
			(stroke
				(width 0.1524)
				(type default)
			)
			(layer "F.SilkS")
		)
		(fp_line
			(start 1.651 -1.778)
			(end -1.651 -1.778)
			(stroke
				(width 0.1524)
				(type default)
			)
			(layer "F.SilkS")
		)
		(fp_line
			(start 1.651 1.778)
			(end 1.651 -1.778)
			(stroke
				(width 0.1524)
				(type default)
			)
			(layer "F.SilkS")
		)
		(fp_poly
			(pts
				(xy -1.778 1.8796) (xy -1.778 -1.8796) (xy 1.778 -1.8796) (xy 1.778 1.8796)
			)
			(stroke
				(width 0)
				(type default)
			)
			(fill no)
			(layer "F.CrtYd")
		)
		(fp_poly
			(pts
				(xy -1.778 1.8796) (xy -1.778 -1.8796) (xy 1.778 -1.8796) (xy 1.778 1.8796)
			)
			(stroke
				(width 0)
				(type default)
			)
			(fill no)
			(layer "F.Fab")
		)
		(pad "D" smd custom
			(at 0 -0.9525)
			(size 0.1905 0.1905)
			(layers "F.Cu" "F.Mask" "F.Paste")
			(net "DRV_ACT_0_N")
			(options
				(clearance outline)
				(anchor circle)
			)
			(primitives
				(gr_poly
					(pts
						(arc
							(start -0.1778 0.5715)
							(mid -0.321484 0.511984)
							(end -0.381 0.3683)
						)
						(arc
							(start -0.381 -0.3683)
							(mid -0.321484 -0.511984)
							(end -0.1778 -0.5715)
						)
						(arc
							(start 0.1778 -0.5715)
							(mid 0.321484 -0.511984)
							(end 0.381 -0.3683)
						)
						(arc
							(start 0.381 0.3683)
							(mid 0.321484 0.511984)
							(end 0.1778 0.5715)
						)
					)
					(width 0)
					(fill yes)
				)
			)
		)
		(pad "G" smd custom
			(at -0.98425 0.9525)
			(size 0.1905 0.1905)
			(layers "F.Cu" "F.Mask" "F.Paste")
			(net "DRIVE_A_0_ACT")
			(options
				(clearance outline)
				(anchor circle)
			)
			(primitives
				(gr_poly
					(pts
						(arc
							(start -0.1778 0.5715)
							(mid -0.321484 0.511984)
							(end -0.381 0.3683)
						)
						(arc
							(start -0.381 -0.3683)
							(mid -0.321484 -0.511984)
							(end -0.1778 -0.5715)
						)
						(arc
							(start 0.1778 -0.5715)
							(mid 0.321484 -0.511984)
							(end 0.381 -0.3683)
						)
						(arc
							(start 0.381 0.3683)
							(mid 0.321484 0.511984)
							(end 0.1778 0.5715)
						)
					)
					(width 0)
					(fill yes)
				)
			)
		)
		(pad "S" smd custom
			(at 0.98425 0.9525)
			(size 0.1905 0.1905)
			(layers "F.Cu" "F.Mask" "F.Paste")
			(net "GND")
			(options
				(clearance outline)
				(anchor circle)
			)
			(primitives
				(gr_poly
					(pts
						(arc
							(start -0.1778 0.5715)
							(mid -0.321484 0.511984)
							(end -0.381 0.3683)
						)
						(arc
							(start -0.381 -0.3683)
							(mid -0.321484 -0.511984)
							(end -0.1778 -0.5715)
						)
						(arc
							(start 0.1778 -0.5715)
							(mid 0.321484 -0.511984)
							(end 0.381 -0.3683)
						)
						(arc
							(start 0.381 0.3683)
							(mid 0.321484 0.511984)
							(end 0.1778 0.5715)
						)
					)
					(width 0)
					(fill yes)
				)
			)
		)
	)
	(footprint ""
		(layer "F.Cu")
		(at 70.313804 -294.191182 90)
		(property "Reference" "R557"
			(at 0 0 90)
			(layer "F.SilkS")
			(hide yes)
			(effects
				(font
					(size 1.27 1.27)
				)
			)
		)
		(property "Value" "4K7R2J-2-GP"
			(at 0.064008 -3.993896 90)
			(unlocked yes)
			(layer "F.Fab")
			(hide yes)
			(effects
				(font
					(size 1.016 1.016)
					(thickness 0.1524)
				)
			)
		)
		(property "Device Type" "R402H16"
			(at 0.064008 -5.517896 90)
			(unlocked yes)
			(layer "F.Fab")
			(hide yes)
			(effects
				(font
					(size 1.016 1.016)
					(thickness 0.1524)
				)
			)
		)
		(duplicate_pad_numbers_are_jumpers no)
		(fp_line
			(start 0.508 -0.9398)
			(end -0.508 -0.9398)
			(stroke
				(width 0.1524)
				(type default)
			)
			(layer "F.SilkS")
		)
		(fp_line
			(start -0.508 -0.9398)
			(end -0.508 0.9398)
			(stroke
				(width 0.1524)
				(type default)
			)
			(layer "F.SilkS")
		)
		(fp_rect
			(start -0.508 0.9398)
			(end 0.508 -0.9398)
			(stroke
				(width 0)
				(type default)
			)
			(fill no)
			(layer "F.CrtYd")
		)
		(fp_rect
			(start -0.508 0.9398)
			(end 0.508 -0.9398)
			(stroke
				(width 0)
				(type default)
			)
			(fill no)
			(layer "F.Fab")
		)
		(pad "1" smd custom
			(at 0 -0.4445 90)
			(size 0.1397 0.1397)
			(layers "F.Cu" "F.Mask" "F.Paste")
			(net "DRIVE_B_26_ACT")
			(options
				(clearance outline)
				(anchor circle)
			)
			(primitives
				(gr_poly
					(pts
						(arc
							(start -0.1778 -0.2794)
							(mid -0.249642 -0.249642)
							(end -0.2794 -0.1778)
						)
						(arc
							(start -0.2794 0.1778)
							(mid -0.249642 0.249642)
							(end -0.1778 0.2794)
						)
						(arc
							(start 0.1778 0.2794)
							(mid 0.249642 0.249642)
							(end 0.2794 0.1778)
						)
						(arc
							(start 0.2794 -0.1778)
							(mid 0.249642 -0.249642)
							(end 0.1778 -0.2794)
						)
					)
					(width 0)
					(fill yes)
				)
			)
		)
		(pad "2" smd custom
			(at 0 0.4445 90)
			(size 0.1397 0.1397)
			(layers "F.Cu" "F.Mask" "F.Paste")
			(net "GND")
			(options
				(clearance outline)
				(anchor circle)
			)
			(primitives
				(gr_poly
					(pts
						(arc
							(start -0.1778 -0.2794)
							(mid -0.249642 -0.249642)
							(end -0.2794 -0.1778)
						)
						(arc
							(start -0.2794 0.1778)
							(mid -0.249642 0.249642)
							(end -0.1778 0.2794)
						)
						(arc
							(start 0.1778 0.2794)
							(mid 0.249642 0.249642)
							(end 0.2794 0.1778)
						)
						(arc
							(start 0.2794 -0.1778)
							(mid 0.249642 -0.249642)
							(end 0.1778 -0.2794)
						)
					)
					(width 0)
					(fill yes)
				)
			)
		)
	)
	(footprint ""
		(layer "F.Cu")
		(at 190.213488 -273.660616 90)
		(property "Reference" "C104"
			(at 0 0 90)
			(layer "F.SilkS")
			(hide yes)
			(effects
				(font
					(size 1.27 1.27)
				)
			)
		)
		(property "Value" "SCD01U16V1KX-GP"
			(at -2.8321 -1.7399 90)
			(unlocked yes)
			(layer "F.Fab")
			(hide yes)
			(effects
				(font
					(size 1.016 1.016)
					(thickness 0.1524)
				)
			)
		)
		(property "Device Type" "C0201H13"
			(at -2.8321 -3.2639 90)
			(unlocked yes)
			(layer "F.Fab")
			(hide yes)
			(effects
				(font
					(size 1.016 1.016)
					(thickness 0.1524)
				)
			)
		)
		(duplicate_pad_numbers_are_jumpers no)
		(fp_rect
			(start -0.2794 0.6477)
			(end 0.2794 -0.6477)
			(stroke
				(width 0)
				(type default)
			)
			(fill no)
			(layer "F.CrtYd")
		)
		(fp_rect
			(start -0.2794 0.6477)
			(end 0.2794 -0.6477)
			(stroke
				(width 0)
				(type default)
			)
			(fill no)
			(layer "F.Fab")
		)
		(pad "1" smd custom
			(at 0 -0.2794 90)
			(size 0.0762 0.0762)
			(layers "F.Cu" "F.Mask" "F.Paste")
			(net "SAS_HDD_RX_P5")
			(options
				(clearance outline)
				(anchor circle)
			)
			(primitives
				(gr_poly
					(pts
						(arc
							(start 0.1524 -0.127)
							(mid 0.137521 -0.162921)
							(end 0.1016 -0.1778)
						)
						(arc
							(start -0.1016 -0.1778)
							(mid -0.137521 -0.162921)
							(end -0.1524 -0.127)
						)
						(arc
							(start -0.1524 0.127)
							(mid -0.137521 0.162921)
							(end -0.1016 0.1778)
						)
						(arc
							(start 0.1016 0.1778)
							(mid 0.137521 0.162921)
							(end 0.1524 0.127)
						)
					)
					(width 0)
					(fill yes)
				)
			)
		)
		(pad "2" smd custom
			(at 0 0.2794 90)
			(size 0.0762 0.0762)
			(layers "F.Cu" "F.Mask" "F.Paste")
			(net "PHY_SCC_A_TO_DRV_A_5_DP")
			(options
				(clearance outline)
				(anchor circle)
			)
			(primitives
				(gr_poly
					(pts
						(arc
							(start 0.1524 -0.127)
							(mid 0.137521 -0.162921)
							(end 0.1016 -0.1778)
						)
						(arc
							(start -0.1016 -0.1778)
							(mid -0.137521 -0.162921)
							(end -0.1524 -0.127)
						)
						(arc
							(start -0.1524 0.127)
							(mid -0.137521 0.162921)
							(end -0.1016 0.1778)
						)
						(arc
							(start 0.1016 0.1778)
							(mid 0.137521 0.162921)
							(end 0.1524 0.127)
						)
					)
					(width 0)
					(fill yes)
				)
			)
		)
	)
	(footprint ""
		(layer "F.Cu")
		(at 261.9756 -284.4292 180)
		(property "Reference" "R101"
			(at 0 0 180)
			(layer "F.SilkS")
			(hide yes)
			(effects
				(font
					(size 1.27 1.27)
				)
			)
		)
		(property "Value" "4K7R2F-GP"
			(at 0.064008 -3.993896 180)
			(unlocked yes)
			(layer "F.Fab")
			(hide yes)
			(effects
				(font
					(size 1.016 1.016)
					(thickness 0.1524)
				)
			)
		)
		(property "Device Type" "R402H16"
			(at 0.064008 -5.517896 180)
			(unlocked yes)
			(layer "F.Fab")
			(hide yes)
			(effects
				(font
					(size 1.016 1.016)
					(thickness 0.1524)
				)
			)
		)
		(duplicate_pad_numbers_are_jumpers no)
		(fp_line
			(start 0.508 -0.9398)
			(end -0.508 -0.9398)
			(stroke
				(width 0.1524)
				(type default)
			)
			(layer "F.SilkS")
		)
		(fp_line
			(start -0.508 -0.9398)
			(end -0.508 0.9398)
			(stroke
				(width 0.1524)
				(type default)
			)
			(layer "F.SilkS")
		)
		(fp_rect
			(start -0.508 0.9398)
			(end 0.508 -0.9398)
			(stroke
				(width 0)
				(type default)
			)
			(fill no)
			(layer "F.CrtYd")
		)
		(fp_rect
			(start -0.508 0.9398)
			(end 0.508 -0.9398)
			(stroke
				(width 0)
				(type default)
			)
			(fill no)
			(layer "F.Fab")
		)
		(pad "1" smd custom
			(at 0 -0.4445 180)
			(size 0.1397 0.1397)
			(layers "F.Cu" "F.Mask" "F.Paste")
			(net "IO_EXP0_HDD_FAULT_A0")
			(options
				(clearance outline)
				(anchor circle)
			)
			(primitives
				(gr_poly
					(pts
						(arc
							(start -0.1778 -0.2794)
							(mid -0.249642 -0.249642)
							(end -0.2794 -0.1778)
						)
						(arc
							(start -0.2794 0.1778)
							(mid -0.249642 0.249642)
							(end -0.1778 0.2794)
						)
						(arc
							(start 0.1778 0.2794)
							(mid 0.249642 0.249642)
							(end 0.2794 0.1778)
						)
						(arc
							(start 0.2794 -0.1778)
							(mid 0.249642 -0.249642)
							(end 0.1778 -0.2794)
						)
					)
					(width 0)
					(fill yes)
				)
			)
		)
		(pad "2" smd custom
			(at 0 0.4445 180)
			(size 0.1397 0.1397)
			(layers "F.Cu" "F.Mask" "F.Paste")
			(net "GND")
			(options
				(clearance outline)
				(anchor circle)
			)
			(primitives
				(gr_poly
					(pts
						(arc
							(start -0.1778 -0.2794)
							(mid -0.249642 -0.249642)
							(end -0.2794 -0.1778)
						)
						(arc
							(start -0.2794 0.1778)
							(mid -0.249642 0.249642)
							(end -0.1778 0.2794)
						)
						(arc
							(start 0.1778 0.2794)
							(mid 0.249642 0.249642)
							(end 0.2794 0.1778)
						)
						(arc
							(start 0.2794 -0.1778)
							(mid 0.249642 -0.249642)
							(end 0.1778 -0.2794)
						)
					)
					(width 0)
					(fill yes)
				)
			)
		)
	)
	(footprint ""
		(layer "F.Cu")
		(at 117.646196 -46.014894 -90)
		(property "Reference" "R759"
			(at 0 0 270)
			(layer "F.SilkS")
			(hide yes)
			(effects
				(font
					(size 1.27 1.27)
				)
			)
		)
		(property "Value" "1KR2F-3-GP"
			(at 0.064008 -3.993896 270)
			(unlocked yes)
			(layer "F.Fab")
			(hide yes)
			(effects
				(font
					(size 1.016 1.016)
					(thickness 0.1524)
				)
			)
		)
		(property "Device Type" "R402H16"
			(at 0.064008 -5.517896 270)
			(unlocked yes)
			(layer "F.Fab")
			(hide yes)
			(effects
				(font
					(size 1.016 1.016)
					(thickness 0.1524)
				)
			)
		)
		(duplicate_pad_numbers_are_jumpers no)
		(fp_line
			(start -0.508 -0.9398)
			(end -0.508 0.9398)
			(stroke
				(width 0.1524)
				(type default)
			)
			(layer "F.SilkS")
		)
		(fp_line
			(start 0.508 -0.9398)
			(end -0.508 -0.9398)
			(stroke
				(width 0.1524)
				(type default)
			)
			(layer "F.SilkS")
		)
		(fp_rect
			(start -0.508 0.9398)
			(end 0.508 -0.9398)
			(stroke
				(width 0)
				(type default)
			)
			(fill no)
			(layer "F.CrtYd")
		)
		(fp_rect
			(start -0.508 0.9398)
			(end 0.508 -0.9398)
			(stroke
				(width 0)
				(type default)
			)
			(fill no)
			(layer "F.Fab")
		)
		(pad "1" smd custom
			(at 0 -0.4445 270)
			(size 0.1397 0.1397)
			(layers "F.Cu" "F.Mask" "F.Paste")
			(net "P3V3_STBY_A")
			(options
				(clearance outline)
				(anchor circle)
			)
			(primitives
				(gr_poly
					(pts
						(arc
							(start -0.1778 -0.2794)
							(mid -0.249642 -0.249642)
							(end -0.2794 -0.1778)
						)
						(arc
							(start -0.2794 0.1778)
							(mid -0.249642 0.249642)
							(end -0.1778 0.2794)
						)
						(arc
							(start 0.1778 0.2794)
							(mid 0.249642 0.249642)
							(end 0.2794 0.1778)
						)
						(arc
							(start 0.2794 -0.1778)
							(mid 0.249642 -0.249642)
							(end 0.1778 -0.2794)
						)
					)
					(width 0)
					(fill yes)
				)
			)
		)
		(pad "2" smd custom
			(at 0 0.4445 270)
			(size 0.1397 0.1397)
			(layers "F.Cu" "F.Mask" "F.Paste")
			(net "SW_PWR_R_HDD27")
			(options
				(clearance outline)
				(anchor circle)
			)
			(primitives
				(gr_poly
					(pts
						(arc
							(start -0.1778 -0.2794)
							(mid -0.249642 -0.249642)
							(end -0.2794 -0.1778)
						)
						(arc
							(start -0.2794 0.1778)
							(mid -0.249642 0.249642)
							(end -0.1778 0.2794)
						)
						(arc
							(start 0.1778 0.2794)
							(mid 0.249642 0.249642)
							(end 0.2794 0.1778)
						)
						(arc
							(start 0.2794 -0.1778)
							(mid 0.249642 -0.249642)
							(end 0.1778 -0.2794)
						)
					)
					(width 0)
					(fill yes)
				)
			)
		)
	)
	(footprint ""
		(layer "F.Cu")
		(at 14.715998 -179.683918 -90)
		(property "Reference" "C201"
			(at 0 0 270)
			(layer "F.SilkS")
			(hide yes)
			(effects
				(font
					(size 1.27 1.27)
				)
			)
		)
		(property "Value" "SC4D7U25V5KX-1-GP"
			(at -0.0762 -6.1214 270)
			(unlocked yes)
			(layer "F.Fab")
			(hide yes)
			(effects
				(font
					(size 1.016 1.016)
					(thickness 0.1524)
				)
			)
		)
		(property "Device Type" "C805H58"
			(at -0.0762 -8.1534 270)
			(unlocked yes)
			(layer "F.Fab")
			(hide yes)
			(effects
				(font
					(size 1.016 1.016)
					(thickness 0.1524)
				)
			)
		)
		(duplicate_pad_numbers_are_jumpers no)
		(fp_line
			(start 0.635 0)
			(end -0.635 0)
			(stroke
				(width 0.508)
				(type default)
			)
			(layer "F.SilkS")
		)
		(fp_rect
			(start -0.9652 1.778)
			(end 0.9652 -1.778)
			(stroke
				(width 0)
				(type default)
			)
			(fill no)
			(layer "F.CrtYd")
		)
		(fp_poly
			(pts
				(xy -0.9652 -1.778) (xy 0.9652 -1.778) (xy 0.9652 1.778) (xy -0.9652 1.778)
			)
			(stroke
				(width 0)
				(type default)
			)
			(fill no)
			(layer "F.Fab")
		)
		(pad "1" smd rect
			(at 0 -0.9652 270)
			(size 1.397 1.143)
			(layers "F.Cu" "F.Mask" "F.Paste")
			(net "P12V_HDD12")
		)
		(pad "2" smd rect
			(at 0 0.9652 270)
			(size 1.397 1.143)
			(layers "F.Cu" "F.Mask" "F.Paste")
			(net "GND")
		)
	)
	(footprint ""
		(layer "F.Cu")
		(at 67.347846 -176.127918 90)
		(property "Reference" "C215"
			(at 0 0 90)
			(layer "F.SilkS")
			(hide yes)
			(effects
				(font
					(size 1.27 1.27)
				)
			)
		)
		(property "Value" "SCD01U50V2KX-1GP"
			(at 1.1811 -2.7051 90)
			(unlocked yes)
			(layer "F.Fab")
			(hide yes)
			(effects
				(font
					(size 1.016 1.016)
					(thickness 0.1524)
				)
			)
		)
		(property "Device Type" "C402H22"
			(at 1.1811 -4.2291 90)
			(unlocked yes)
			(layer "F.Fab")
			(hide yes)
			(effects
				(font
					(size 1.016 1.016)
					(thickness 0.1524)
				)
			)
		)
		(duplicate_pad_numbers_are_jumpers no)
		(fp_rect
			(start -0.4318 0.9525)
			(end 0.4318 -0.9525)
			(stroke
				(width 0)
				(type default)
			)
			(fill no)
			(layer "F.CrtYd")
		)
		(fp_rect
			(start -0.4318 0.9525)
			(end 0.4318 -0.9525)
			(stroke
				(width 0)
				(type default)
			)
			(fill no)
			(layer "F.Fab")
		)
		(pad "1" smd custom
			(at 0 -0.4445 90)
			(size 0.1524 0.1524)
			(layers "F.Cu" "F.Mask" "F.Paste")
			(net "HDD_PRSNT_13")
			(options
				(clearance outline)
				(anchor circle)
			)
			(primitives
				(gr_poly
					(pts
						(arc
							(start 0.3048 -0.2032)
							(mid 0.275042 -0.275042)
							(end 0.2032 -0.3048)
						)
						(arc
							(start -0.2032 -0.3048)
							(mid -0.275042 -0.275042)
							(end -0.3048 -0.2032)
						)
						(arc
							(start -0.3048 0.2032)
							(mid -0.275042 0.275042)
							(end -0.2032 0.3048)
						)
						(arc
							(start 0.2032 0.3048)
							(mid 0.275042 0.275042)
							(end 0.3048 0.2032)
						)
					)
					(width 0)
					(fill yes)
				)
			)
		)
		(pad "2" smd custom
			(at 0 0.4445 90)
			(size 0.1524 0.1524)
			(layers "F.Cu" "F.Mask" "F.Paste")
			(net "GND")
			(options
				(clearance outline)
				(anchor circle)
			)
			(primitives
				(gr_poly
					(pts
						(arc
							(start 0.3048 -0.2032)
							(mid 0.275042 -0.275042)
							(end 0.2032 -0.3048)
						)
						(arc
							(start -0.2032 -0.3048)
							(mid -0.275042 -0.275042)
							(end -0.3048 -0.2032)
						)
						(arc
							(start -0.3048 0.2032)
							(mid -0.275042 0.275042)
							(end -0.2032 0.3048)
						)
						(arc
							(start 0.2032 0.3048)
							(mid 0.275042 0.275042)
							(end 0.3048 0.2032)
						)
					)
					(width 0)
					(fill yes)
				)
			)
		)
	)
	(footprint ""
		(layer "F.Cu")
		(at 335.228438 -33.550352 180)
		(property "Reference" "R100"
			(at 0 0 180)
			(layer "F.SilkS")
			(hide yes)
			(effects
				(font
					(size 1.27 1.27)
				)
			)
		)
		(property "Value" "0R2J-2-GP"
			(at 0.064008 -3.993896 180)
			(unlocked yes)
			(layer "F.Fab")
			(hide yes)
			(effects
				(font
					(size 1.016 1.016)
					(thickness 0.1524)
				)
			)
		)
		(property "Device Type" "R402H16"
			(at 0.064008 -5.517896 180)
			(unlocked yes)
			(layer "F.Fab")
			(hide yes)
			(effects
				(font
					(size 1.016 1.016)
					(thickness 0.1524)
				)
			)
		)
		(duplicate_pad_numbers_are_jumpers no)
		(fp_line
			(start 0.508 -0.9398)
			(end -0.508 -0.9398)
			(stroke
				(width 0.1524)
				(type default)
			)
			(layer "F.SilkS")
		)
		(fp_line
			(start -0.508 -0.9398)
			(end -0.508 0.9398)
			(stroke
				(width 0.1524)
				(type default)
			)
			(layer "F.SilkS")
		)
		(fp_rect
			(start -0.508 0.9398)
			(end 0.508 -0.9398)
			(stroke
				(width 0)
				(type default)
			)
			(fill no)
			(layer "F.CrtYd")
		)
		(fp_rect
			(start -0.508 0.9398)
			(end 0.508 -0.9398)
			(stroke
				(width 0)
				(type default)
			)
			(fill no)
			(layer "F.Fab")
		)
		(pad "1" smd custom
			(at 0 -0.4445 180)
			(size 0.1397 0.1397)
			(layers "F.Cu" "F.Mask" "F.Paste")
			(net "IO_EXP11_SDA")
			(options
				(clearance outline)
				(anchor circle)
			)
			(primitives
				(gr_poly
					(pts
						(arc
							(start -0.1778 -0.2794)
							(mid -0.249642 -0.249642)
							(end -0.2794 -0.1778)
						)
						(arc
							(start -0.2794 0.1778)
							(mid -0.249642 0.249642)
							(end -0.1778 0.2794)
						)
						(arc
							(start 0.1778 0.2794)
							(mid 0.249642 0.249642)
							(end 0.2794 0.1778)
						)
						(arc
							(start 0.2794 -0.1778)
							(mid 0.249642 -0.249642)
							(end 0.1778 -0.2794)
						)
					)
					(width 0)
					(fill yes)
				)
			)
		)
		(pad "2" smd custom
			(at 0 0.4445 180)
			(size 0.1397 0.1397)
			(layers "F.Cu" "F.Mask" "F.Paste")
			(net "I2C_BMC_B_MISC_SDA")
			(options
				(clearance outline)
				(anchor circle)
			)
			(primitives
				(gr_poly
					(pts
						(arc
							(start -0.1778 -0.2794)
							(mid -0.249642 -0.249642)
							(end -0.2794 -0.1778)
						)
						(arc
							(start -0.2794 0.1778)
							(mid -0.249642 0.249642)
							(end -0.1778 0.2794)
						)
						(arc
							(start 0.1778 0.2794)
							(mid 0.249642 0.249642)
							(end 0.2794 0.1778)
						)
						(arc
							(start 0.2794 -0.1778)
							(mid 0.249642 -0.249642)
							(end 0.1778 -0.2794)
						)
					)
					(width 0)
					(fill yes)
				)
			)
		)
	)
	(footprint ""
		(layer "F.Cu")
		(at 146.249898 -61.000894 -90)
		(property "Reference" "C405"
			(at 0 0 270)
			(layer "F.SilkS")
			(hide yes)
			(effects
				(font
					(size 1.27 1.27)
				)
			)
		)
		(property "Value" "SC10U16V6KX-2GP"
			(at -0.0762 -5.1308 270)
			(unlocked yes)
			(layer "F.Fab")
			(hide yes)
			(effects
				(font
					(size 1.016 1.016)
					(thickness 0.1524)
				)
			)
		)
		(property "Device Type" "C1206H71"
			(at -0.127 -6.6548 270)
			(unlocked yes)
			(layer "F.Fab")
			(hide yes)
			(effects
				(font
					(size 1.016 1.016)
					(thickness 0.1524)
				)
			)
		)
		(duplicate_pad_numbers_are_jumpers no)
		(fp_line
			(start -1.016 2.2352)
			(end -1.016 0.8382)
			(stroke
				(width 0.1524)
				(type default)
			)
			(layer "F.SilkS")
		)
		(fp_line
			(start 1.016 2.2352)
			(end -1.016 2.2352)
			(stroke
				(width 0.1524)
				(type default)
			)
			(layer "F.SilkS")
		)
		(fp_line
			(start 1.016 0.8382)
			(end 1.016 2.2352)
			(stroke
				(width 0.1524)
				(type default)
			)
			(layer "F.SilkS")
		)
		(fp_line
			(start -1.016 -0.8382)
			(end -1.016 -2.2352)
			(stroke
				(width 0.1524)
				(type default)
			)
			(layer "F.SilkS")
		)
		(fp_line
			(start -1.016 -2.2352)
			(end 1.016 -2.2352)
			(stroke
				(width 0.1524)
				(type default)
			)
			(layer "F.SilkS")
		)
		(fp_line
			(start 1.016 -2.2352)
			(end 1.016 -0.8382)
			(stroke
				(width 0.1524)
				(type default)
			)
			(layer "F.SilkS")
		)
		(fp_rect
			(start -1.0922 2.3114)
			(end 1.0922 -2.3114)
			(stroke
				(width 0)
				(type default)
			)
			(fill no)
			(layer "F.CrtYd")
		)
		(fp_poly
			(pts
				(xy 1.0922 -2.3114) (xy 1.0922 2.3114) (xy -1.0922 2.3114) (xy -1.0922 -2.3114)
			)
			(stroke
				(width 0)
				(type default)
			)
			(fill no)
			(layer "F.Fab")
		)
		(pad "1" smd rect
			(at 0 -1.397 270)
			(size 1.651 1.27)
			(layers "F.Cu" "F.Mask" "F.Paste")
			(net "P5V_HDD28")
		)
		(pad "2" smd rect
			(at 0 1.397 270)
			(size 1.651 1.27)
			(layers "F.Cu" "F.Mask" "F.Paste")
			(net "GND")
		)
	)
	(footprint ""
		(layer "F.Cu")
		(at 83.530948 -177.778918 -90)
		(property "Reference" "C222"
			(at 0 0 270)
			(layer "F.SilkS")
			(hide yes)
			(effects
				(font
					(size 1.27 1.27)
				)
			)
		)
		(property "Value" "SC1U16V3KX-5GP"
			(at 0 -2.8194 270)
			(unlocked yes)
			(layer "F.Fab")
			(hide yes)
			(effects
				(font
					(size 1.016 1.016)
					(thickness 0.1524)
				)
			)
		)
		(property "Device Type" "C603H36"
			(at 0 -4.3434 270)
			(unlocked yes)
			(layer "F.Fab")
			(hide yes)
			(effects
				(font
					(size 1.016 1.016)
					(thickness 0.1524)
				)
			)
		)
		(duplicate_pad_numbers_are_jumpers no)
		(fp_line
			(start 0.508 0)
			(end -0.508 0)
			(stroke
				(width 0.2032)
				(type default)
			)
			(layer "F.SilkS")
		)
		(fp_rect
			(start -0.5842 1.3335)
			(end 0.5842 -1.3335)
			(stroke
				(width 0)
				(type default)
			)
			(fill no)
			(layer "F.CrtYd")
		)
		(fp_rect
			(start -0.5842 1.3335)
			(end 0.5842 -1.3335)
			(stroke
				(width 0)
				(type default)
			)
			(fill no)
			(layer "F.Fab")
		)
		(pad "1" smd custom
			(at 0 -0.762 270)
			(size 0.2159 0.2159)
			(layers "F.Cu" "F.Mask" "F.Paste")
			(net "P5V_HDD14")
			(options
				(clearance outline)
				(anchor circle)
			)
			(primitives
				(gr_poly
					(pts
						(arc
							(start -0.3302 -0.4318)
							(mid -0.402042 -0.402042)
							(end -0.4318 -0.3302)
						)
						(arc
							(start -0.4318 0.3302)
							(mid -0.402042 0.402042)
							(end -0.3302 0.4318)
						)
						(arc
							(start 0.3302 0.4318)
							(mid 0.402042 0.402042)
							(end 0.4318 0.3302)
						)
						(arc
							(start 0.4318 -0.3302)
							(mid 0.402042 -0.402042)
							(end 0.3302 -0.4318)
						)
					)
					(width 0)
					(fill yes)
				)
			)
		)
		(pad "2" smd custom
			(at 0 0.762 270)
			(size 0.2159 0.2159)
			(layers "F.Cu" "F.Mask" "F.Paste")
			(net "GND")
			(options
				(clearance outline)
				(anchor circle)
			)
			(primitives
				(gr_poly
					(pts
						(arc
							(start -0.3302 -0.4318)
							(mid -0.402042 -0.402042)
							(end -0.4318 -0.3302)
						)
						(arc
							(start -0.4318 0.3302)
							(mid -0.402042 0.402042)
							(end -0.3302 0.4318)
						)
						(arc
							(start 0.3302 0.4318)
							(mid 0.402042 0.402042)
							(end 0.4318 0.3302)
						)
						(arc
							(start 0.4318 -0.3302)
							(mid 0.402042 -0.402042)
							(end 0.3302 -0.4318)
						)
					)
					(width 0)
					(fill yes)
				)
			)
		)
	)
	(footprint ""
		(layer "F.Cu")
		(at 236.871256 -343.309448)
		(property "Reference" "R185"
			(at 0 0 0)
			(layer "F.SilkS")
			(hide yes)
			(effects
				(font
					(size 1.27 1.27)
				)
			)
		)
		(property "Value" "10KR2F-2-GP"
			(at 0.064008 -3.993896 0)
			(unlocked yes)
			(layer "F.Fab")
			(hide yes)
			(effects
				(font
					(size 1.016 1.016)
					(thickness 0.1524)
				)
			)
		)
		(property "Device Type" "R402H16"
			(at 0.064008 -5.517896 0)
			(unlocked yes)
			(layer "F.Fab")
			(hide yes)
			(effects
				(font
					(size 1.016 1.016)
					(thickness 0.1524)
				)
			)
		)
		(duplicate_pad_numbers_are_jumpers no)
		(fp_line
			(start -0.508 -0.9398)
			(end -0.508 0.9398)
			(stroke
				(width 0.1524)
				(type default)
			)
			(layer "F.SilkS")
		)
		(fp_line
			(start 0.508 -0.9398)
			(end -0.508 -0.9398)
			(stroke
				(width 0.1524)
				(type default)
			)
			(layer "F.SilkS")
		)
		(fp_rect
			(start -0.508 0.9398)
			(end 0.508 -0.9398)
			(stroke
				(width 0)
				(type default)
			)
			(fill no)
			(layer "F.CrtYd")
		)
		(fp_rect
			(start -0.508 0.9398)
			(end 0.508 -0.9398)
			(stroke
				(width 0)
				(type default)
			)
			(fill no)
			(layer "F.Fab")
		)
		(pad "1" smd custom
			(at 0 -0.4445)
			(size 0.1397 0.1397)
			(layers "F.Cu" "F.Mask" "F.Paste")
			(net "P5V_A_4_SENSE")
			(options
				(clearance outline)
				(anchor circle)
			)
			(primitives
				(gr_poly
					(pts
						(arc
							(start -0.1778 -0.2794)
							(mid -0.249642 -0.249642)
							(end -0.2794 -0.1778)
						)
						(arc
							(start -0.2794 0.1778)
							(mid -0.249642 0.249642)
							(end -0.1778 0.2794)
						)
						(arc
							(start 0.1778 0.2794)
							(mid 0.249642 0.249642)
							(end 0.2794 0.1778)
						)
						(arc
							(start 0.2794 -0.1778)
							(mid 0.249642 -0.249642)
							(end 0.1778 -0.2794)
						)
					)
					(width 0)
					(fill yes)
				)
			)
		)
		(pad "2" smd custom
			(at 0 0.4445)
			(size 0.1397 0.1397)
			(layers "F.Cu" "F.Mask" "F.Paste")
			(net "GND")
			(options
				(clearance outline)
				(anchor circle)
			)
			(primitives
				(gr_poly
					(pts
						(arc
							(start -0.1778 -0.2794)
							(mid -0.249642 -0.249642)
							(end -0.2794 -0.1778)
						)
						(arc
							(start -0.2794 0.1778)
							(mid -0.249642 0.249642)
							(end -0.1778 0.2794)
						)
						(arc
							(start 0.1778 0.2794)
							(mid 0.249642 0.249642)
							(end 0.2794 0.1778)
						)
						(arc
							(start 0.2794 -0.1778)
							(mid 0.249642 -0.249642)
							(end 0.1778 -0.2794)
						)
					)
					(width 0)
					(fill yes)
				)
			)
		)
	)
	(footprint ""
		(layer "F.Cu")
		(at 475.529148 -269.348204 180)
		(property "Reference" "R394"
			(at 0 0 180)
			(layer "F.SilkS")
			(hide yes)
			(effects
				(font
					(size 1.27 1.27)
				)
			)
		)
		(property "Value" "0R2J-2-GP"
			(at 0.064008 -3.993896 180)
			(unlocked yes)
			(layer "F.Fab")
			(hide yes)
			(effects
				(font
					(size 1.016 1.016)
					(thickness 0.1524)
				)
			)
		)
		(property "Device Type" "R402H16"
			(at 0.064008 -5.517896 180)
			(unlocked yes)
			(layer "F.Fab")
			(hide yes)
			(effects
				(font
					(size 1.016 1.016)
					(thickness 0.1524)
				)
			)
		)
		(duplicate_pad_numbers_are_jumpers no)
		(fp_line
			(start 0.508 -0.9398)
			(end -0.508 -0.9398)
			(stroke
				(width 0.1524)
				(type default)
			)
			(layer "F.SilkS")
		)
		(fp_line
			(start -0.508 -0.9398)
			(end -0.508 0.9398)
			(stroke
				(width 0.1524)
				(type default)
			)
			(layer "F.SilkS")
		)
		(fp_rect
			(start -0.508 0.9398)
			(end 0.508 -0.9398)
			(stroke
				(width 0)
				(type default)
			)
			(fill no)
			(layer "F.CrtYd")
		)
		(fp_rect
			(start -0.508 0.9398)
			(end 0.508 -0.9398)
			(stroke
				(width 0)
				(type default)
			)
			(fill no)
			(layer "F.Fab")
		)
		(pad "1" smd custom
			(at 0 -0.4445 180)
			(size 0.1397 0.1397)
			(layers "F.Cu" "F.Mask" "F.Paste")
			(net "DRIVE_A_11_PWR")
			(options
				(clearance outline)
				(anchor circle)
			)
			(primitives
				(gr_poly
					(pts
						(arc
							(start -0.1778 -0.2794)
							(mid -0.249642 -0.249642)
							(end -0.2794 -0.1778)
						)
						(arc
							(start -0.2794 0.1778)
							(mid -0.249642 0.249642)
							(end -0.1778 0.2794)
						)
						(arc
							(start 0.1778 0.2794)
							(mid 0.249642 0.249642)
							(end 0.2794 0.1778)
						)
						(arc
							(start 0.2794 -0.1778)
							(mid 0.249642 -0.249642)
							(end 0.1778 -0.2794)
						)
					)
					(width 0)
					(fill yes)
				)
			)
		)
		(pad "2" smd custom
			(at 0 0.4445 180)
			(size 0.1397 0.1397)
			(layers "F.Cu" "F.Mask" "F.Paste")
			(net "SW_PWR_R_HDD11")
			(options
				(clearance outline)
				(anchor circle)
			)
			(primitives
				(gr_poly
					(pts
						(arc
							(start -0.1778 -0.2794)
							(mid -0.249642 -0.249642)
							(end -0.2794 -0.1778)
						)
						(arc
							(start -0.2794 0.1778)
							(mid -0.249642 0.249642)
							(end -0.1778 0.2794)
						)
						(arc
							(start 0.1778 0.2794)
							(mid 0.249642 0.249642)
							(end 0.2794 0.1778)
						)
						(arc
							(start 0.2794 -0.1778)
							(mid 0.249642 -0.249642)
							(end 0.1778 -0.2794)
						)
					)
					(width 0)
					(fill yes)
				)
			)
		)
	)
	(footprint ""
		(layer "F.Cu")
		(at 475.246192 -286.120332 -90)
		(property "Reference" "C184"
			(at 0 0 270)
			(layer "F.SilkS")
			(hide yes)
			(effects
				(font
					(size 1.27 1.27)
				)
			)
		)
		(property "Value" "SC10U16V6KX-2GP"
			(at -0.0762 -5.1308 270)
			(unlocked yes)
			(layer "F.Fab")
			(hide yes)
			(effects
				(font
					(size 1.016 1.016)
					(thickness 0.1524)
				)
			)
		)
		(property "Device Type" "C1206H71"
			(at -0.127 -6.6548 270)
			(unlocked yes)
			(layer "F.Fab")
			(hide yes)
			(effects
				(font
					(size 1.016 1.016)
					(thickness 0.1524)
				)
			)
		)
		(duplicate_pad_numbers_are_jumpers no)
		(fp_line
			(start -1.016 2.2352)
			(end -1.016 0.8382)
			(stroke
				(width 0.1524)
				(type default)
			)
			(layer "F.SilkS")
		)
		(fp_line
			(start 1.016 2.2352)
			(end -1.016 2.2352)
			(stroke
				(width 0.1524)
				(type default)
			)
			(layer "F.SilkS")
		)
		(fp_line
			(start 1.016 0.8382)
			(end 1.016 2.2352)
			(stroke
				(width 0.1524)
				(type default)
			)
			(layer "F.SilkS")
		)
		(fp_line
			(start -1.016 -0.8382)
			(end -1.016 -2.2352)
			(stroke
				(width 0.1524)
				(type default)
			)
			(layer "F.SilkS")
		)
		(fp_line
			(start -1.016 -2.2352)
			(end 1.016 -2.2352)
			(stroke
				(width 0.1524)
				(type default)
			)
			(layer "F.SilkS")
		)
		(fp_line
			(start 1.016 -2.2352)
			(end 1.016 -0.8382)
			(stroke
				(width 0.1524)
				(type default)
			)
			(layer "F.SilkS")
		)
		(fp_rect
			(start -1.0922 2.3114)
			(end 1.0922 -2.3114)
			(stroke
				(width 0)
				(type default)
			)
			(fill no)
			(layer "F.CrtYd")
		)
		(fp_poly
			(pts
				(xy 1.0922 -2.3114) (xy 1.0922 2.3114) (xy -1.0922 2.3114) (xy -1.0922 -2.3114)
			)
			(stroke
				(width 0)
				(type default)
			)
			(fill no)
			(layer "F.Fab")
		)
		(pad "1" smd rect
			(at 0 -1.397 270)
			(size 1.651 1.27)
			(layers "F.Cu" "F.Mask" "F.Paste")
			(net "P5V_HDD11")
		)
		(pad "2" smd rect
			(at 0 1.397 270)
			(size 1.651 1.27)
			(layers "F.Cu" "F.Mask" "F.Paste")
			(net "GND")
		)
	)
	(footprint ""
		(layer "F.Cu")
		(at 52.202588 -148.6535 -90)
		(property "Reference" "R1229"
			(at 0 0 270)
			(layer "F.SilkS")
			(hide yes)
			(effects
				(font
					(size 1.27 1.27)
				)
			)
		)
		(property "Value" "10KR2F-2-GP"
			(at 0.064008 -3.993896 270)
			(unlocked yes)
			(layer "F.Fab")
			(hide yes)
			(effects
				(font
					(size 1.016 1.016)
					(thickness 0.1524)
				)
			)
		)
		(property "Device Type" "R402H16"
			(at 0.064008 -5.517896 270)
			(unlocked yes)
			(layer "F.Fab")
			(hide yes)
			(effects
				(font
					(size 1.016 1.016)
					(thickness 0.1524)
				)
			)
		)
		(duplicate_pad_numbers_are_jumpers no)
		(fp_line
			(start -0.508 -0.9398)
			(end -0.508 0.9398)
			(stroke
				(width 0.1524)
				(type default)
			)
			(layer "F.SilkS")
		)
		(fp_line
			(start 0.508 -0.9398)
			(end -0.508 -0.9398)
			(stroke
				(width 0.1524)
				(type default)
			)
			(layer "F.SilkS")
		)
		(fp_rect
			(start -0.508 0.9398)
			(end 0.508 -0.9398)
			(stroke
				(width 0)
				(type default)
			)
			(fill no)
			(layer "F.CrtYd")
		)
		(fp_rect
			(start -0.508 0.9398)
			(end 0.508 -0.9398)
			(stroke
				(width 0)
				(type default)
			)
			(fill no)
			(layer "F.Fab")
		)
		(pad "1" smd custom
			(at 0 -0.4445 270)
			(size 0.1397 0.1397)
			(layers "F.Cu" "F.Mask" "F.Paste")
			(net "P5V_A_2")
			(options
				(clearance outline)
				(anchor circle)
			)
			(primitives
				(gr_poly
					(pts
						(arc
							(start -0.1778 -0.2794)
							(mid -0.249642 -0.249642)
							(end -0.2794 -0.1778)
						)
						(arc
							(start -0.2794 0.1778)
							(mid -0.249642 0.249642)
							(end -0.1778 0.2794)
						)
						(arc
							(start 0.1778 0.2794)
							(mid 0.249642 0.249642)
							(end 0.2794 0.1778)
						)
						(arc
							(start 0.2794 -0.1778)
							(mid 0.249642 -0.249642)
							(end 0.1778 -0.2794)
						)
					)
					(width 0)
					(fill yes)
				)
			)
		)
		(pad "2" smd custom
			(at 0 0.4445 270)
			(size 0.1397 0.1397)
			(layers "F.Cu" "F.Mask" "F.Paste")
			(net "P5V_A_2_PGOOD")
			(options
				(clearance outline)
				(anchor circle)
			)
			(primitives
				(gr_poly
					(pts
						(arc
							(start -0.1778 -0.2794)
							(mid -0.249642 -0.249642)
							(end -0.2794 -0.1778)
						)
						(arc
							(start -0.2794 0.1778)
							(mid -0.249642 0.249642)
							(end -0.1778 0.2794)
						)
						(arc
							(start 0.1778 0.2794)
							(mid 0.249642 0.249642)
							(end 0.2794 0.1778)
						)
						(arc
							(start 0.2794 -0.1778)
							(mid 0.249642 -0.249642)
							(end 0.1778 -0.2794)
						)
					)
					(width 0)
					(fill yes)
				)
			)
		)
	)
	(footprint ""
		(layer "F.Cu")
		(at 263.398 -272.288)
		(property "Reference" "R103"
			(at 0 0 0)
			(layer "F.SilkS")
			(hide yes)
			(effects
				(font
					(size 1.27 1.27)
				)
			)
		)
		(property "Value" "4K7R2F-GP"
			(at 0.064008 -3.993896 0)
			(unlocked yes)
			(layer "F.Fab")
			(hide yes)
			(effects
				(font
					(size 1.016 1.016)
					(thickness 0.1524)
				)
			)
		)
		(property "Device Type" "R402H16"
			(at 0.064008 -5.517896 0)
			(unlocked yes)
			(layer "F.Fab")
			(hide yes)
			(effects
				(font
					(size 1.016 1.016)
					(thickness 0.1524)
				)
			)
		)
		(duplicate_pad_numbers_are_jumpers no)
		(fp_line
			(start -0.508 -0.9398)
			(end -0.508 0.9398)
			(stroke
				(width 0.1524)
				(type default)
			)
			(layer "F.SilkS")
		)
		(fp_line
			(start 0.508 -0.9398)
			(end -0.508 -0.9398)
			(stroke
				(width 0.1524)
				(type default)
			)
			(layer "F.SilkS")
		)
		(fp_rect
			(start -0.508 0.9398)
			(end 0.508 -0.9398)
			(stroke
				(width 0)
				(type default)
			)
			(fill no)
			(layer "F.CrtYd")
		)
		(fp_rect
			(start -0.508 0.9398)
			(end 0.508 -0.9398)
			(stroke
				(width 0)
				(type default)
			)
			(fill no)
			(layer "F.Fab")
		)
		(pad "1" smd custom
			(at 0 -0.4445)
			(size 0.1397 0.1397)
			(layers "F.Cu" "F.Mask" "F.Paste")
			(net "IO_EXP0_HDD_FAULT_A2")
			(options
				(clearance outline)
				(anchor circle)
			)
			(primitives
				(gr_poly
					(pts
						(arc
							(start -0.1778 -0.2794)
							(mid -0.249642 -0.249642)
							(end -0.2794 -0.1778)
						)
						(arc
							(start -0.2794 0.1778)
							(mid -0.249642 0.249642)
							(end -0.1778 0.2794)
						)
						(arc
							(start 0.1778 0.2794)
							(mid 0.249642 0.249642)
							(end 0.2794 0.1778)
						)
						(arc
							(start 0.2794 -0.1778)
							(mid 0.249642 -0.249642)
							(end 0.1778 -0.2794)
						)
					)
					(width 0)
					(fill yes)
				)
			)
		)
		(pad "2" smd custom
			(at 0 0.4445)
			(size 0.1397 0.1397)
			(layers "F.Cu" "F.Mask" "F.Paste")
			(net "GND")
			(options
				(clearance outline)
				(anchor circle)
			)
			(primitives
				(gr_poly
					(pts
						(arc
							(start -0.1778 -0.2794)
							(mid -0.249642 -0.249642)
							(end -0.2794 -0.1778)
						)
						(arc
							(start -0.2794 0.1778)
							(mid -0.249642 0.249642)
							(end -0.1778 0.2794)
						)
						(arc
							(start 0.1778 0.2794)
							(mid 0.249642 0.249642)
							(end 0.2794 0.1778)
						)
						(arc
							(start 0.2794 -0.1778)
							(mid 0.249642 -0.249642)
							(end 0.1778 -0.2794)
						)
					)
					(width 0)
					(fill yes)
				)
			)
		)
	)
	(footprint ""
		(layer "F.Cu")
		(at 275.17217 -284.734762 180)
		(property "Reference" "R438"
			(at 0 0 180)
			(layer "F.SilkS")
			(hide yes)
			(effects
				(font
					(size 1.27 1.27)
				)
			)
		)
		(property "Value" "1KR2F-3-GP"
			(at 0.064008 -3.993896 180)
			(unlocked yes)
			(layer "F.Fab")
			(hide yes)
			(effects
				(font
					(size 1.016 1.016)
					(thickness 0.1524)
				)
			)
		)
		(property "Device Type" "R402H16"
			(at 0.064008 -5.517896 180)
			(unlocked yes)
			(layer "F.Fab")
			(hide yes)
			(effects
				(font
					(size 1.016 1.016)
					(thickness 0.1524)
				)
			)
		)
		(duplicate_pad_numbers_are_jumpers no)
		(fp_line
			(start 0.508 -0.9398)
			(end -0.508 -0.9398)
			(stroke
				(width 0.1524)
				(type default)
			)
			(layer "F.SilkS")
		)
		(fp_line
			(start -0.508 -0.9398)
			(end -0.508 0.9398)
			(stroke
				(width 0.1524)
				(type default)
			)
			(layer "F.SilkS")
		)
		(fp_rect
			(start -0.508 0.9398)
			(end 0.508 -0.9398)
			(stroke
				(width 0)
				(type default)
			)
			(fill no)
			(layer "F.CrtYd")
		)
		(fp_rect
			(start -0.508 0.9398)
			(end 0.508 -0.9398)
			(stroke
				(width 0)
				(type default)
			)
			(fill no)
			(layer "F.Fab")
		)
		(pad "1" smd custom
			(at 0 -0.4445 180)
			(size 0.1397 0.1397)
			(layers "F.Cu" "F.Mask" "F.Paste")
			(net "P3V3_STBY_A")
			(options
				(clearance outline)
				(anchor circle)
			)
			(primitives
				(gr_poly
					(pts
						(arc
							(start -0.1778 -0.2794)
							(mid -0.249642 -0.249642)
							(end -0.2794 -0.1778)
						)
						(arc
							(start -0.2794 0.1778)
							(mid -0.249642 0.249642)
							(end -0.1778 0.2794)
						)
						(arc
							(start 0.1778 0.2794)
							(mid 0.249642 0.249642)
							(end 0.2794 0.1778)
						)
						(arc
							(start 0.2794 -0.1778)
							(mid 0.249642 -0.249642)
							(end 0.1778 -0.2794)
						)
					)
					(width 0)
					(fill yes)
				)
			)
		)
		(pad "2" smd custom
			(at 0 0.4445 180)
			(size 0.1397 0.1397)
			(layers "F.Cu" "F.Mask" "F.Paste")
			(net "I2C_DRIVE_A_FLT_LED_SCL")
			(options
				(clearance outline)
				(anchor circle)
			)
			(primitives
				(gr_poly
					(pts
						(arc
							(start -0.1778 -0.2794)
							(mid -0.249642 -0.249642)
							(end -0.2794 -0.1778)
						)
						(arc
							(start -0.2794 0.1778)
							(mid -0.249642 0.249642)
							(end -0.1778 0.2794)
						)
						(arc
							(start 0.1778 0.2794)
							(mid 0.249642 0.249642)
							(end 0.2794 0.1778)
						)
						(arc
							(start 0.2794 -0.1778)
							(mid 0.249642 -0.249642)
							(end 0.1778 -0.2794)
						)
					)
					(width 0)
					(fill yes)
				)
			)
		)
	)
	(footprint ""
		(layer "F.Cu")
		(at 92.751148 -21.07438 180)
		(property "Reference" "R984"
			(at 0 0 180)
			(layer "F.SilkS")
			(hide yes)
			(effects
				(font
					(size 1.27 1.27)
				)
			)
		)
		(property "Value" "0R2J-2-GP"
			(at 0.064008 -3.993896 180)
			(unlocked yes)
			(layer "F.Fab")
			(hide yes)
			(effects
				(font
					(size 1.016 1.016)
					(thickness 0.1524)
				)
			)
		)
		(property "Device Type" "R402H16"
			(at 0.064008 -5.517896 180)
			(unlocked yes)
			(layer "F.Fab")
			(hide yes)
			(effects
				(font
					(size 1.016 1.016)
					(thickness 0.1524)
				)
			)
		)
		(duplicate_pad_numbers_are_jumpers no)
		(fp_line
			(start 0.508 -0.9398)
			(end -0.508 -0.9398)
			(stroke
				(width 0.1524)
				(type default)
			)
			(layer "F.SilkS")
		)
		(fp_line
			(start -0.508 -0.9398)
			(end -0.508 0.9398)
			(stroke
				(width 0.1524)
				(type default)
			)
			(layer "F.SilkS")
		)
		(fp_rect
			(start -0.508 0.9398)
			(end 0.508 -0.9398)
			(stroke
				(width 0)
				(type default)
			)
			(fill no)
			(layer "F.CrtYd")
		)
		(fp_rect
			(start -0.508 0.9398)
			(end 0.508 -0.9398)
			(stroke
				(width 0)
				(type default)
			)
			(fill no)
			(layer "F.Fab")
		)
		(pad "1" smd custom
			(at 0 -0.4445 180)
			(size 0.1397 0.1397)
			(layers "F.Cu" "F.Mask" "F.Paste")
			(net "GND")
			(options
				(clearance outline)
				(anchor circle)
			)
			(primitives
				(gr_poly
					(pts
						(arc
							(start -0.1778 -0.2794)
							(mid -0.249642 -0.249642)
							(end -0.2794 -0.1778)
						)
						(arc
							(start -0.2794 0.1778)
							(mid -0.249642 0.249642)
							(end -0.1778 0.2794)
						)
						(arc
							(start 0.1778 0.2794)
							(mid 0.249642 0.249642)
							(end 0.2794 0.1778)
						)
						(arc
							(start 0.2794 -0.1778)
							(mid 0.249642 -0.249642)
							(end 0.1778 -0.2794)
						)
					)
					(width 0)
					(fill yes)
				)
			)
		)
		(pad "2" smd custom
			(at 0 0.4445 180)
			(size 0.1397 0.1397)
			(layers "F.Cu" "F.Mask" "F.Paste")
			(net "IOM_A_SLOT_ID_0")
			(options
				(clearance outline)
				(anchor circle)
			)
			(primitives
				(gr_poly
					(pts
						(arc
							(start -0.1778 -0.2794)
							(mid -0.249642 -0.249642)
							(end -0.2794 -0.1778)
						)
						(arc
							(start -0.2794 0.1778)
							(mid -0.249642 0.249642)
							(end -0.1778 0.2794)
						)
						(arc
							(start 0.1778 0.2794)
							(mid 0.249642 0.249642)
							(end 0.2794 0.1778)
						)
						(arc
							(start 0.2794 -0.1778)
							(mid 0.249642 -0.249642)
							(end 0.1778 -0.2794)
						)
					)
					(width 0)
					(fill yes)
				)
			)
		)
	)
	(footprint ""
		(layer "F.Cu")
		(at 141.423898 -162.157918 180)
		(property "Reference" "R514"
			(at 0 0 180)
			(layer "F.SilkS")
			(hide yes)
			(effects
				(font
					(size 1.27 1.27)
				)
			)
		)
		(property "Value" "200KR2F-L-GP"
			(at 0.064008 -3.993896 180)
			(unlocked yes)
			(layer "F.Fab")
			(hide yes)
			(effects
				(font
					(size 1.016 1.016)
					(thickness 0.1524)
				)
			)
		)
		(property "Device Type" "R402H16"
			(at 0.064008 -5.517896 180)
			(unlocked yes)
			(layer "F.Fab")
			(hide yes)
			(effects
				(font
					(size 1.016 1.016)
					(thickness 0.1524)
				)
			)
		)
		(duplicate_pad_numbers_are_jumpers no)
		(fp_line
			(start 0.508 -0.9398)
			(end -0.508 -0.9398)
			(stroke
				(width 0.1524)
				(type default)
			)
			(layer "F.SilkS")
		)
		(fp_line
			(start -0.508 -0.9398)
			(end -0.508 0.9398)
			(stroke
				(width 0.1524)
				(type default)
			)
			(layer "F.SilkS")
		)
		(fp_rect
			(start -0.508 0.9398)
			(end 0.508 -0.9398)
			(stroke
				(width 0)
				(type default)
			)
			(fill no)
			(layer "F.CrtYd")
		)
		(fp_rect
			(start -0.508 0.9398)
			(end 0.508 -0.9398)
			(stroke
				(width 0)
				(type default)
			)
			(fill no)
			(layer "F.Fab")
		)
		(pad "1" smd custom
			(at 0 -0.4445 180)
			(size 0.1397 0.1397)
			(layers "F.Cu" "F.Mask" "F.Paste")
			(net "SW_HDD_R16")
			(options
				(clearance outline)
				(anchor circle)
			)
			(primitives
				(gr_poly
					(pts
						(arc
							(start -0.1778 -0.2794)
							(mid -0.249642 -0.249642)
							(end -0.2794 -0.1778)
						)
						(arc
							(start -0.2794 0.1778)
							(mid -0.249642 0.249642)
							(end -0.1778 0.2794)
						)
						(arc
							(start 0.1778 0.2794)
							(mid 0.249642 0.249642)
							(end 0.2794 0.1778)
						)
						(arc
							(start 0.2794 -0.1778)
							(mid 0.249642 -0.249642)
							(end 0.1778 -0.2794)
						)
					)
					(width 0)
					(fill yes)
				)
			)
		)
		(pad "2" smd custom
			(at 0 0.4445 180)
			(size 0.1397 0.1397)
			(layers "F.Cu" "F.Mask" "F.Paste")
			(net "SW_HDD_N16")
			(options
				(clearance outline)
				(anchor circle)
			)
			(primitives
				(gr_poly
					(pts
						(arc
							(start -0.1778 -0.2794)
							(mid -0.249642 -0.249642)
							(end -0.2794 -0.1778)
						)
						(arc
							(start -0.2794 0.1778)
							(mid -0.249642 0.249642)
							(end -0.1778 0.2794)
						)
						(arc
							(start 0.1778 0.2794)
							(mid 0.249642 0.249642)
							(end 0.2794 0.1778)
						)
						(arc
							(start 0.2794 -0.1778)
							(mid 0.249642 -0.249642)
							(end 0.1778 -0.2794)
						)
					)
					(width 0)
					(fill yes)
				)
			)
		)
	)
	(footprint ""
		(layer "F.Cu")
		(at 472.899994 -324.39991)
		(property "Reference" "RLED36"
			(at 0 0 0)
			(layer "F.SilkS")
			(hide yes)
			(effects
				(font
					(size 1.27 1.27)
				)
			)
		)
		(property "Value" "LED-BY-19-GP"
			(at -2.132076 1.414018 0)
			(unlocked yes)
			(layer "F.Fab")
			(hide yes)
			(effects
				(font
					(size 1.016 1.016)
					(thickness 0.1524)
				)
			)
		)
		(property "Device Type" "LED-1615-4PH26"
			(at -2.132076 -0.109982 0)
			(unlocked yes)
			(layer "F.Fab")
			(hide yes)
			(effects
				(font
					(size 1.016 1.016)
					(thickness 0.1524)
				)
			)
		)
		(duplicate_pad_numbers_are_jumpers no)
		(fp_line
			(start -1.2954 0.254)
			(end -1.2954 1.6002)
			(stroke
				(width 0.508)
				(type default)
			)
			(layer "F.SilkS")
		)
		(fp_line
			(start -1.2954 1.6002)
			(end 1.2954 1.6002)
			(stroke
				(width 0.508)
				(type default)
			)
			(layer "F.SilkS")
		)
		(fp_line
			(start -1.1176 -1.4224)
			(end 1.1176 -1.4224)
			(stroke
				(width 0.1524)
				(type default)
			)
			(layer "F.SilkS")
		)
		(fp_line
			(start -1.1176 1.4224)
			(end -1.1176 -1.4224)
			(stroke
				(width 0.1524)
				(type default)
			)
			(layer "F.SilkS")
		)
		(fp_line
			(start 1.1176 -1.4224)
			(end 1.1176 1.4224)
			(stroke
				(width 0.1524)
				(type default)
			)
			(layer "F.SilkS")
		)
		(fp_line
			(start 1.1176 1.4224)
			(end -1.1176 1.4224)
			(stroke
				(width 0.1524)
				(type default)
			)
			(layer "F.SilkS")
		)
		(fp_line
			(start 1.2954 1.6002)
			(end 1.2954 0.254)
			(stroke
				(width 0.508)
				(type default)
			)
			(layer "F.SilkS")
		)
		(fp_rect
			(start -0.7493 0.8001)
			(end 0.7493 -0.8001)
			(stroke
				(width 0)
				(type default)
			)
			(fill no)
			(layer "F.CrtYd")
		)
		(fp_poly
			(pts
				(xy -1.3716 1.6764) (xy -1.3716 -1.6764) (xy 1.3716 -1.6764) (xy 1.3716 0.0635) (xy 0.7493 0.0635)
				(xy 0.7493 -0.8001) (xy -0.7493 -0.8001) (xy -0.7493 0.8001) (xy 0.7493 0.8001) (xy 0.7493 0.0762)
				(xy 1.3716 0.0762) (xy 1.3716 1.6764)
			)
			(stroke
				(width 0)
				(type default)
			)
			(fill no)
			(layer "F.CrtYd")
		)
		(fp_rect
			(start -1.3716 1.6764)
			(end 1.3716 -1.6764)
			(stroke
				(width 0)
				(type default)
			)
			(fill no)
			(layer "F.Fab")
		)
		(pad "1" smd rect
			(at 0.50038 -0.73025)
			(size 0.7112 0.8636)
			(layers "F.Cu" "F.Mask" "F.Paste")
			(net "DRV_ACT_35")
		)
		(pad "2" smd rect
			(at -0.50038 -0.73025)
			(size 0.7112 0.8636)
			(layers "F.Cu" "F.Mask" "F.Paste")
			(net "FLT_HDD35")
		)
		(pad "3" smd rect
			(at 0.50038 0.73025)
			(size 0.7112 0.8636)
			(layers "F.Cu" "F.Mask" "F.Paste")
			(net "DRV_ACT_35_N")
		)
		(pad "4" smd rect
			(at -0.50038 0.73025)
			(size 0.7112 0.8636)
			(layers "F.Cu" "F.Mask" "F.Paste")
			(net "FLT_HDD35_N")
		)
	)
	(footprint ""
		(layer "F.Cu")
		(at 236.3724 -248.9708)
		(property "Reference" "R35"
			(at 0 0 0)
			(layer "F.SilkS")
			(hide yes)
			(effects
				(font
					(size 1.27 1.27)
				)
			)
		)
		(property "Value" "0R2J-2-GP"
			(at 0.064008 -3.993896 0)
			(unlocked yes)
			(layer "F.Fab")
			(hide yes)
			(effects
				(font
					(size 1.016 1.016)
					(thickness 0.1524)
				)
			)
		)
		(property "Device Type" "R402H16"
			(at 0.064008 -5.517896 0)
			(unlocked yes)
			(layer "F.Fab")
			(hide yes)
			(effects
				(font
					(size 1.016 1.016)
					(thickness 0.1524)
				)
			)
		)
		(duplicate_pad_numbers_are_jumpers no)
		(fp_line
			(start -0.508 -0.9398)
			(end -0.508 0.9398)
			(stroke
				(width 0.1524)
				(type default)
			)
			(layer "F.SilkS")
		)
		(fp_line
			(start 0.508 -0.9398)
			(end -0.508 -0.9398)
			(stroke
				(width 0.1524)
				(type default)
			)
			(layer "F.SilkS")
		)
		(fp_rect
			(start -0.508 0.9398)
			(end 0.508 -0.9398)
			(stroke
				(width 0)
				(type default)
			)
			(fill no)
			(layer "F.CrtYd")
		)
		(fp_rect
			(start -0.508 0.9398)
			(end 0.508 -0.9398)
			(stroke
				(width 0)
				(type default)
			)
			(fill no)
			(layer "F.Fab")
		)
		(pad "1" smd custom
			(at 0 -0.4445)
			(size 0.1397 0.1397)
			(layers "F.Cu" "F.Mask" "F.Paste")
			(net "IO_EXP4_SDA")
			(options
				(clearance outline)
				(anchor circle)
			)
			(primitives
				(gr_poly
					(pts
						(arc
							(start -0.1778 -0.2794)
							(mid -0.249642 -0.249642)
							(end -0.2794 -0.1778)
						)
						(arc
							(start -0.2794 0.1778)
							(mid -0.249642 0.249642)
							(end -0.1778 0.2794)
						)
						(arc
							(start 0.1778 0.2794)
							(mid 0.249642 0.249642)
							(end 0.2794 0.1778)
						)
						(arc
							(start 0.2794 -0.1778)
							(mid 0.249642 -0.249642)
							(end 0.1778 -0.2794)
						)
					)
					(width 0)
					(fill yes)
				)
			)
		)
		(pad "2" smd custom
			(at 0 0.4445)
			(size 0.1397 0.1397)
			(layers "F.Cu" "F.Mask" "F.Paste")
			(net "I2C_DRIVE_A_INS_SDA")
			(options
				(clearance outline)
				(anchor circle)
			)
			(primitives
				(gr_poly
					(pts
						(arc
							(start -0.1778 -0.2794)
							(mid -0.249642 -0.249642)
							(end -0.2794 -0.1778)
						)
						(arc
							(start -0.2794 0.1778)
							(mid -0.249642 0.249642)
							(end -0.1778 0.2794)
						)
						(arc
							(start 0.1778 0.2794)
							(mid 0.249642 0.249642)
							(end 0.2794 0.1778)
						)
						(arc
							(start 0.2794 -0.1778)
							(mid 0.249642 -0.249642)
							(end 0.1778 -0.2794)
						)
					)
					(width 0)
					(fill yes)
				)
			)
		)
	)
	(footprint ""
		(layer "F.Cu")
		(at 86.121748 -274.846542 -90)
		(property "Reference" "R187"
			(at 0 0 270)
			(layer "F.SilkS")
			(hide yes)
			(effects
				(font
					(size 1.27 1.27)
				)
			)
		)
		(property "Value" "0R2J-2-GP"
			(at 0.064008 -3.993896 270)
			(unlocked yes)
			(layer "F.Fab")
			(hide yes)
			(effects
				(font
					(size 1.016 1.016)
					(thickness 0.1524)
				)
			)
		)
		(property "Device Type" "R402H16"
			(at 0.064008 -5.517896 270)
			(unlocked yes)
			(layer "F.Fab")
			(hide yes)
			(effects
				(font
					(size 1.016 1.016)
					(thickness 0.1524)
				)
			)
		)
		(duplicate_pad_numbers_are_jumpers no)
		(fp_line
			(start -0.508 -0.9398)
			(end -0.508 0.9398)
			(stroke
				(width 0.1524)
				(type default)
			)
			(layer "F.SilkS")
		)
		(fp_line
			(start 0.508 -0.9398)
			(end -0.508 -0.9398)
			(stroke
				(width 0.1524)
				(type default)
			)
			(layer "F.SilkS")
		)
		(fp_rect
			(start -0.508 0.9398)
			(end 0.508 -0.9398)
			(stroke
				(width 0)
				(type default)
			)
			(fill no)
			(layer "F.CrtYd")
		)
		(fp_rect
			(start -0.508 0.9398)
			(end 0.508 -0.9398)
			(stroke
				(width 0)
				(type default)
			)
			(fill no)
			(layer "F.Fab")
		)
		(pad "1" smd custom
			(at 0 -0.4445 270)
			(size 0.1397 0.1397)
			(layers "F.Cu" "F.Mask" "F.Paste")
			(net "DRIVE_A_2_PWR")
			(options
				(clearance outline)
				(anchor circle)
			)
			(primitives
				(gr_poly
					(pts
						(arc
							(start -0.1778 -0.2794)
							(mid -0.249642 -0.249642)
							(end -0.2794 -0.1778)
						)
						(arc
							(start -0.2794 0.1778)
							(mid -0.249642 0.249642)
							(end -0.1778 0.2794)
						)
						(arc
							(start 0.1778 0.2794)
							(mid 0.249642 0.249642)
							(end 0.2794 0.1778)
						)
						(arc
							(start 0.2794 -0.1778)
							(mid 0.249642 -0.249642)
							(end 0.1778 -0.2794)
						)
					)
					(width 0)
					(fill yes)
				)
			)
		)
		(pad "2" smd custom
			(at 0 0.4445 270)
			(size 0.1397 0.1397)
			(layers "F.Cu" "F.Mask" "F.Paste")
			(net "SW_PWR_R_HDD2")
			(options
				(clearance outline)
				(anchor circle)
			)
			(primitives
				(gr_poly
					(pts
						(arc
							(start -0.1778 -0.2794)
							(mid -0.249642 -0.249642)
							(end -0.2794 -0.1778)
						)
						(arc
							(start -0.2794 0.1778)
							(mid -0.249642 0.249642)
							(end -0.1778 0.2794)
						)
						(arc
							(start 0.1778 0.2794)
							(mid 0.249642 0.249642)
							(end 0.2794 0.1778)
						)
						(arc
							(start 0.2794 -0.1778)
							(mid 0.249642 -0.249642)
							(end 0.1778 -0.2794)
						)
					)
					(width 0)
					(fill yes)
				)
			)
		)
	)
	(footprint ""
		(layer "F.Cu")
		(at 475.530926 -177.778918 -90)
		(property "Reference" "C339"
			(at 0 0 270)
			(layer "F.SilkS")
			(hide yes)
			(effects
				(font
					(size 1.27 1.27)
				)
			)
		)
		(property "Value" "SC1U16V3KX-5GP"
			(at 0 -2.8194 270)
			(unlocked yes)
			(layer "F.Fab")
			(hide yes)
			(effects
				(font
					(size 1.016 1.016)
					(thickness 0.1524)
				)
			)
		)
		(property "Device Type" "C603H36"
			(at 0 -4.3434 270)
			(unlocked yes)
			(layer "F.Fab")
			(hide yes)
			(effects
				(font
					(size 1.016 1.016)
					(thickness 0.1524)
				)
			)
		)
		(duplicate_pad_numbers_are_jumpers no)
		(fp_line
			(start 0.508 0)
			(end -0.508 0)
			(stroke
				(width 0.2032)
				(type default)
			)
			(layer "F.SilkS")
		)
		(fp_rect
			(start -0.5842 1.3335)
			(end 0.5842 -1.3335)
			(stroke
				(width 0)
				(type default)
			)
			(fill no)
			(layer "F.CrtYd")
		)
		(fp_rect
			(start -0.5842 1.3335)
			(end 0.5842 -1.3335)
			(stroke
				(width 0)
				(type default)
			)
			(fill no)
			(layer "F.Fab")
		)
		(pad "1" smd custom
			(at 0 -0.762 270)
			(size 0.2159 0.2159)
			(layers "F.Cu" "F.Mask" "F.Paste")
			(net "P5V_HDD23")
			(options
				(clearance outline)
				(anchor circle)
			)
			(primitives
				(gr_poly
					(pts
						(arc
							(start -0.3302 -0.4318)
							(mid -0.402042 -0.402042)
							(end -0.4318 -0.3302)
						)
						(arc
							(start -0.4318 0.3302)
							(mid -0.402042 0.402042)
							(end -0.3302 0.4318)
						)
						(arc
							(start 0.3302 0.4318)
							(mid 0.402042 0.402042)
							(end 0.4318 0.3302)
						)
						(arc
							(start 0.4318 -0.3302)
							(mid 0.402042 -0.402042)
							(end 0.3302 -0.4318)
						)
					)
					(width 0)
					(fill yes)
				)
			)
		)
		(pad "2" smd custom
			(at 0 0.762 270)
			(size 0.2159 0.2159)
			(layers "F.Cu" "F.Mask" "F.Paste")
			(net "GND")
			(options
				(clearance outline)
				(anchor circle)
			)
			(primitives
				(gr_poly
					(pts
						(arc
							(start -0.3302 -0.4318)
							(mid -0.402042 -0.402042)
							(end -0.4318 -0.3302)
						)
						(arc
							(start -0.4318 0.3302)
							(mid -0.402042 0.402042)
							(end -0.3302 0.4318)
						)
						(arc
							(start 0.3302 0.4318)
							(mid 0.402042 0.402042)
							(end 0.4318 0.3302)
						)
						(arc
							(start 0.4318 -0.3302)
							(mid 0.402042 -0.402042)
							(end 0.3302 -0.4318)
						)
					)
					(width 0)
					(fill yes)
				)
			)
		)
	)
	(footprint ""
		(layer "F.Cu")
		(at 395.45895 -295.826942 180)
		(property "Reference" "C145"
			(at 0 0 180)
			(layer "F.SilkS")
			(hide yes)
			(effects
				(font
					(size 1.27 1.27)
				)
			)
		)
		(property "Value" "SC10U16V6KX-2GP"
			(at -0.0762 -5.1308 180)
			(unlocked yes)
			(layer "F.Fab")
			(hide yes)
			(effects
				(font
					(size 1.016 1.016)
					(thickness 0.1524)
				)
			)
		)
		(property "Device Type" "C1206H71"
			(at -0.127 -6.6548 180)
			(unlocked yes)
			(layer "F.Fab")
			(hide yes)
			(effects
				(font
					(size 1.016 1.016)
					(thickness 0.1524)
				)
			)
		)
		(duplicate_pad_numbers_are_jumpers no)
		(fp_line
			(start 1.016 2.2352)
			(end -1.016 2.2352)
			(stroke
				(width 0.1524)
				(type default)
			)
			(layer "F.SilkS")
		)
		(fp_line
			(start 1.016 0.8382)
			(end 1.016 2.2352)
			(stroke
				(width 0.1524)
				(type default)
			)
			(layer "F.SilkS")
		)
		(fp_line
			(start 1.016 -2.2352)
			(end 1.016 -0.8382)
			(stroke
				(width 0.1524)
				(type default)
			)
			(layer "F.SilkS")
		)
		(fp_line
			(start -1.016 2.2352)
			(end -1.016 0.8382)
			(stroke
				(width 0.1524)
				(type default)
			)
			(layer "F.SilkS")
		)
		(fp_line
			(start -1.016 -0.8382)
			(end -1.016 -2.2352)
			(stroke
				(width 0.1524)
				(type default)
			)
			(layer "F.SilkS")
		)
		(fp_line
			(start -1.016 -2.2352)
			(end 1.016 -2.2352)
			(stroke
				(width 0.1524)
				(type default)
			)
			(layer "F.SilkS")
		)
		(fp_rect
			(start -1.0922 2.3114)
			(end 1.0922 -2.3114)
			(stroke
				(width 0)
				(type default)
			)
			(fill no)
			(layer "F.CrtYd")
		)
		(fp_poly
			(pts
				(xy 1.0922 -2.3114) (xy 1.0922 2.3114) (xy -1.0922 2.3114) (xy -1.0922 -2.3114)
			)
			(stroke
				(width 0)
				(type default)
			)
			(fill no)
			(layer "F.Fab")
		)
		(pad "1" smd rect
			(at 0 -1.397 180)
			(size 1.651 1.27)
			(layers "F.Cu" "F.Mask" "F.Paste")
			(net "P5V_HDD8")
		)
		(pad "2" smd rect
			(at 0 1.397 180)
			(size 1.651 1.27)
			(layers "F.Cu" "F.Mask" "F.Paste")
			(net "GND")
		)
	)
	(footprint ""
		(layer "F.Cu")
		(at 267.18641 -133.312662 -90)
		(property "Reference" "TP186"
			(at 0 0 270)
			(layer "F.SilkS")
			(hide yes)
			(effects
				(font
					(size 1.27 1.27)
				)
			)
		)
		(property "Value" "TPAD32-GP"
			(at -0.0508 -1.6764 270)
			(unlocked yes)
			(layer "F.Fab")
			(hide yes)
			(effects
				(font
					(size 1.016 1.016)
					(thickness 0.1524)
				)
			)
		)
		(property "Device Type" "TPAD32"
			(at -0.0508 -3.2004 270)
			(unlocked yes)
			(layer "F.Fab")
			(hide yes)
			(effects
				(font
					(size 1.016 1.016)
					(thickness 0.1524)
				)
			)
		)
		(duplicate_pad_numbers_are_jumpers no)
		(fp_poly
			(pts
				(arc
					(start 0 -0.4064)
					(mid 0 0.4064)
					(end 0 -0.4064)
				)
			)
			(stroke
				(width 0)
				(type default)
			)
			(fill no)
			(layer "F.CrtYd")
		)
		(fp_poly
			(pts
				(arc
					(start 0 -0.7112)
					(mid 0 0.7112)
					(end 0 -0.7112)
				)
			)
			(stroke
				(width 0)
				(type default)
			)
			(fill no)
			(layer "F.Fab")
		)
		(pad "1" smd circle
			(at 0 0 270)
			(size 0.8128 0.8128)
			(layers "F.Cu" "F.Mask" "F.Paste")
			(net "TP_COMP_B_SATA_P0_RX_DN")
		)
	)
	(footprint ""
		(layer "F.Cu")
		(at 456.0189 -66.842894 180)
		(property "Reference" "C482"
			(at 0 0 180)
			(layer "F.SilkS")
			(hide yes)
			(effects
				(font
					(size 1.27 1.27)
				)
			)
		)
		(property "Value" "SC1U16V3KX-5GP"
			(at 0 -2.8194 180)
			(unlocked yes)
			(layer "F.Fab")
			(hide yes)
			(effects
				(font
					(size 1.016 1.016)
					(thickness 0.1524)
				)
			)
		)
		(property "Device Type" "C603H36"
			(at 0 -4.3434 180)
			(unlocked yes)
			(layer "F.Fab")
			(hide yes)
			(effects
				(font
					(size 1.016 1.016)
					(thickness 0.1524)
				)
			)
		)
		(duplicate_pad_numbers_are_jumpers no)
		(fp_line
			(start 0.508 0)
			(end -0.508 0)
			(stroke
				(width 0.2032)
				(type default)
			)
			(layer "F.SilkS")
		)
		(fp_rect
			(start -0.5842 1.3335)
			(end 0.5842 -1.3335)
			(stroke
				(width 0)
				(type default)
			)
			(fill no)
			(layer "F.CrtYd")
		)
		(fp_rect
			(start -0.5842 1.3335)
			(end 0.5842 -1.3335)
			(stroke
				(width 0)
				(type default)
			)
			(fill no)
			(layer "F.Fab")
		)
		(pad "1" smd custom
			(at 0 -0.762 180)
			(size 0.2159 0.2159)
			(layers "F.Cu" "F.Mask" "F.Paste")
			(net "P5V_HDD34")
			(options
				(clearance outline)
				(anchor circle)
			)
			(primitives
				(gr_poly
					(pts
						(arc
							(start -0.3302 -0.4318)
							(mid -0.402042 -0.402042)
							(end -0.4318 -0.3302)
						)
						(arc
							(start -0.4318 0.3302)
							(mid -0.402042 0.402042)
							(end -0.3302 0.4318)
						)
						(arc
							(start 0.3302 0.4318)
							(mid 0.402042 0.402042)
							(end 0.4318 0.3302)
						)
						(arc
							(start 0.4318 -0.3302)
							(mid 0.402042 -0.402042)
							(end 0.3302 -0.4318)
						)
					)
					(width 0)
					(fill yes)
				)
			)
		)
		(pad "2" smd custom
			(at 0 0.762 180)
			(size 0.2159 0.2159)
			(layers "F.Cu" "F.Mask" "F.Paste")
			(net "GND")
			(options
				(clearance outline)
				(anchor circle)
			)
			(primitives
				(gr_poly
					(pts
						(arc
							(start -0.3302 -0.4318)
							(mid -0.402042 -0.402042)
							(end -0.4318 -0.3302)
						)
						(arc
							(start -0.4318 0.3302)
							(mid -0.402042 0.402042)
							(end -0.3302 0.4318)
						)
						(arc
							(start 0.3302 0.4318)
							(mid 0.402042 0.402042)
							(end 0.4318 0.3302)
						)
						(arc
							(start 0.4318 -0.3302)
							(mid 0.402042 -0.402042)
							(end 0.3302 -0.4318)
						)
					)
					(width 0)
					(fill yes)
				)
			)
		)
	)
	(footprint ""
		(layer "F.Cu")
		(at 18.906998 -64.683894 90)
		(property "Reference" "R683"
			(at 0 0 90)
			(layer "F.SilkS")
			(hide yes)
			(effects
				(font
					(size 1.27 1.27)
				)
			)
		)
		(property "Value" "2R6F-GP"
			(at -0.0508 -4.8514 90)
			(unlocked yes)
			(layer "F.Fab")
			(hide yes)
			(effects
				(font
					(size 1.016 1.016)
					(thickness 0.1524)
				)
			)
		)
		(property "Device Type" "R1206H26"
			(at 0 -6.3754 90)
			(unlocked yes)
			(layer "F.Fab")
			(hide yes)
			(effects
				(font
					(size 1.016 1.016)
					(thickness 0.1524)
				)
			)
		)
		(duplicate_pad_numbers_are_jumpers no)
		(fp_line
			(start 1.016 -2.2352)
			(end 1.016 2.2352)
			(stroke
				(width 0.1524)
				(type default)
			)
			(layer "F.SilkS")
		)
		(fp_line
			(start -1.016 -2.2352)
			(end 1.016 -2.2352)
			(stroke
				(width 0.1524)
				(type default)
			)
			(layer "F.SilkS")
		)
		(fp_line
			(start 1.016 2.2352)
			(end -1.016 2.2352)
			(stroke
				(width 0.1524)
				(type default)
			)
			(layer "F.SilkS")
		)
		(fp_line
			(start -1.016 2.2352)
			(end -1.016 -2.2352)
			(stroke
				(width 0.1524)
				(type default)
			)
			(layer "F.SilkS")
		)
		(fp_rect
			(start -1.0922 2.3114)
			(end 1.0922 -2.3114)
			(stroke
				(width 0)
				(type default)
			)
			(fill no)
			(layer "F.CrtYd")
		)
		(fp_poly
			(pts
				(xy -1.0922 -2.3114) (xy 1.0922 -2.3114) (xy 1.0922 2.3114) (xy -1.0922 2.3114)
			)
			(stroke
				(width 0)
				(type default)
			)
			(fill no)
			(layer "F.Fab")
		)
		(pad "1" smd rect
			(at 0 -1.397 90)
			(size 1.651 1.27)
			(layers "F.Cu" "F.Mask" "F.Paste")
			(net "P12V_HDD24")
		)
		(pad "2" smd rect
			(at 0 1.397 90)
			(size 1.651 1.27)
			(layers "F.Cu" "F.Mask" "F.Paste")
			(net "12V_PRE_24")
		)
	)
	(footprint ""
		(layer "F.Cu")
		(at 146.247866 -131.656074)
		(property "Reference" "R1054"
			(at 0 0 0)
			(layer "F.SilkS")
			(hide yes)
			(effects
				(font
					(size 1.27 1.27)
				)
			)
		)
		(property "Value" "11KR2F-L-GP"
			(at 0.064008 -3.993896 0)
			(unlocked yes)
			(layer "F.Fab")
			(hide yes)
			(effects
				(font
					(size 1.016 1.016)
					(thickness 0.1524)
				)
			)
		)
		(property "Device Type" "R402H16"
			(at 0.064008 -5.517896 0)
			(unlocked yes)
			(layer "F.Fab")
			(hide yes)
			(effects
				(font
					(size 1.016 1.016)
					(thickness 0.1524)
				)
			)
		)
		(duplicate_pad_numbers_are_jumpers no)
		(fp_line
			(start -0.508 -0.9398)
			(end -0.508 0.9398)
			(stroke
				(width 0.1524)
				(type default)
			)
			(layer "F.SilkS")
		)
		(fp_line
			(start 0.508 -0.9398)
			(end -0.508 -0.9398)
			(stroke
				(width 0.1524)
				(type default)
			)
			(layer "F.SilkS")
		)
		(fp_rect
			(start -0.508 0.9398)
			(end 0.508 -0.9398)
			(stroke
				(width 0)
				(type default)
			)
			(fill no)
			(layer "F.CrtYd")
		)
		(fp_rect
			(start -0.508 0.9398)
			(end 0.508 -0.9398)
			(stroke
				(width 0)
				(type default)
			)
			(fill no)
			(layer "F.Fab")
		)
		(pad "1" smd custom
			(at 0 -0.4445)
			(size 0.1397 0.1397)
			(layers "F.Cu" "F.Mask" "F.Paste")
			(net "MB0_P12V_PWGIN_R")
			(options
				(clearance outline)
				(anchor circle)
			)
			(primitives
				(gr_poly
					(pts
						(arc
							(start -0.1778 -0.2794)
							(mid -0.249642 -0.249642)
							(end -0.2794 -0.1778)
						)
						(arc
							(start -0.2794 0.1778)
							(mid -0.249642 0.249642)
							(end -0.1778 0.2794)
						)
						(arc
							(start 0.1778 0.2794)
							(mid 0.249642 0.249642)
							(end 0.2794 0.1778)
						)
						(arc
							(start 0.2794 -0.1778)
							(mid 0.249642 -0.249642)
							(end 0.1778 -0.2794)
						)
					)
					(width 0)
					(fill yes)
				)
			)
		)
		(pad "2" smd custom
			(at 0 0.4445)
			(size 0.1397 0.1397)
			(layers "F.Cu" "F.Mask" "F.Paste")
			(net "AGND_CURRENT_MONOA")
			(options
				(clearance outline)
				(anchor circle)
			)
			(primitives
				(gr_poly
					(pts
						(arc
							(start -0.1778 -0.2794)
							(mid -0.249642 -0.249642)
							(end -0.2794 -0.1778)
						)
						(arc
							(start -0.2794 0.1778)
							(mid -0.249642 0.249642)
							(end -0.1778 0.2794)
						)
						(arc
							(start 0.1778 0.2794)
							(mid 0.249642 0.249642)
							(end 0.2794 0.1778)
						)
						(arc
							(start 0.2794 -0.1778)
							(mid 0.249642 -0.249642)
							(end 0.1778 -0.2794)
						)
					)
					(width 0)
					(fill yes)
				)
			)
		)
	)
	(footprint ""
		(layer "F.Cu")
		(at 364.290102 -163.554918 -90)
		(property "Reference" "R574"
			(at 0 0 270)
			(layer "F.SilkS")
			(hide yes)
			(effects
				(font
					(size 1.27 1.27)
				)
			)
		)
		(property "Value" "4K7R2J-2-GP"
			(at 0.064008 -3.993896 270)
			(unlocked yes)
			(layer "F.Fab")
			(hide yes)
			(effects
				(font
					(size 1.016 1.016)
					(thickness 0.1524)
				)
			)
		)
		(property "Device Type" "R402H16"
			(at 0.064008 -5.517896 270)
			(unlocked yes)
			(layer "F.Fab")
			(hide yes)
			(effects
				(font
					(size 1.016 1.016)
					(thickness 0.1524)
				)
			)
		)
		(duplicate_pad_numbers_are_jumpers no)
		(fp_line
			(start -0.508 -0.9398)
			(end -0.508 0.9398)
			(stroke
				(width 0.1524)
				(type default)
			)
			(layer "F.SilkS")
		)
		(fp_line
			(start 0.508 -0.9398)
			(end -0.508 -0.9398)
			(stroke
				(width 0.1524)
				(type default)
			)
			(layer "F.SilkS")
		)
		(fp_rect
			(start -0.508 0.9398)
			(end 0.508 -0.9398)
			(stroke
				(width 0)
				(type default)
			)
			(fill no)
			(layer "F.CrtYd")
		)
		(fp_rect
			(start -0.508 0.9398)
			(end 0.508 -0.9398)
			(stroke
				(width 0)
				(type default)
			)
			(fill no)
			(layer "F.Fab")
		)
		(pad "1" smd custom
			(at 0 -0.4445 270)
			(size 0.1397 0.1397)
			(layers "F.Cu" "F.Mask" "F.Paste")
			(net "P12V_A")
			(options
				(clearance outline)
				(anchor circle)
			)
			(primitives
				(gr_poly
					(pts
						(arc
							(start -0.1778 -0.2794)
							(mid -0.249642 -0.249642)
							(end -0.2794 -0.1778)
						)
						(arc
							(start -0.2794 0.1778)
							(mid -0.249642 0.249642)
							(end -0.1778 0.2794)
						)
						(arc
							(start 0.1778 0.2794)
							(mid 0.249642 0.249642)
							(end 0.2794 0.1778)
						)
						(arc
							(start 0.2794 -0.1778)
							(mid 0.249642 -0.249642)
							(end 0.1778 -0.2794)
						)
					)
					(width 0)
					(fill yes)
				)
			)
		)
		(pad "2" smd custom
			(at 0 0.4445 270)
			(size 0.1397 0.1397)
			(layers "F.Cu" "F.Mask" "F.Paste")
			(net "SW_HDD_P19")
			(options
				(clearance outline)
				(anchor circle)
			)
			(primitives
				(gr_poly
					(pts
						(arc
							(start -0.1778 -0.2794)
							(mid -0.249642 -0.249642)
							(end -0.2794 -0.1778)
						)
						(arc
							(start -0.2794 0.1778)
							(mid -0.249642 0.249642)
							(end -0.1778 0.2794)
						)
						(arc
							(start 0.1778 0.2794)
							(mid 0.249642 0.249642)
							(end 0.2794 0.1778)
						)
						(arc
							(start 0.2794 -0.1778)
							(mid 0.249642 -0.249642)
							(end 0.1778 -0.2794)
						)
					)
					(width 0)
					(fill yes)
				)
			)
		)
	)
	(footprint ""
		(layer "F.Cu")
		(at 225.7044 -376.9995)
		(property "Reference" "R148"
			(at 0 0 0)
			(layer "F.SilkS")
			(hide yes)
			(effects
				(font
					(size 1.27 1.27)
				)
			)
		)
		(property "Value" "4K7R2F-GP"
			(at 0.064008 -3.993896 0)
			(unlocked yes)
			(layer "F.Fab")
			(hide yes)
			(effects
				(font
					(size 1.016 1.016)
					(thickness 0.1524)
				)
			)
		)
		(property "Device Type" "R402H16"
			(at 0.064008 -5.517896 0)
			(unlocked yes)
			(layer "F.Fab")
			(hide yes)
			(effects
				(font
					(size 1.016 1.016)
					(thickness 0.1524)
				)
			)
		)
		(duplicate_pad_numbers_are_jumpers no)
		(fp_line
			(start -0.508 -0.9398)
			(end -0.508 0.9398)
			(stroke
				(width 0.1524)
				(type default)
			)
			(layer "F.SilkS")
		)
		(fp_line
			(start 0.508 -0.9398)
			(end -0.508 -0.9398)
			(stroke
				(width 0.1524)
				(type default)
			)
			(layer "F.SilkS")
		)
		(fp_rect
			(start -0.508 0.9398)
			(end 0.508 -0.9398)
			(stroke
				(width 0)
				(type default)
			)
			(fill no)
			(layer "F.CrtYd")
		)
		(fp_rect
			(start -0.508 0.9398)
			(end 0.508 -0.9398)
			(stroke
				(width 0)
				(type default)
			)
			(fill no)
			(layer "F.Fab")
		)
		(pad "1" smd custom
			(at 0 -0.4445)
			(size 0.1397 0.1397)
			(layers "F.Cu" "F.Mask" "F.Paste")
			(net "P3V3_STBY_B")
			(options
				(clearance outline)
				(anchor circle)
			)
			(primitives
				(gr_poly
					(pts
						(arc
							(start -0.1778 -0.2794)
							(mid -0.249642 -0.249642)
							(end -0.2794 -0.1778)
						)
						(arc
							(start -0.2794 0.1778)
							(mid -0.249642 0.249642)
							(end -0.1778 0.2794)
						)
						(arc
							(start 0.1778 0.2794)
							(mid 0.249642 0.249642)
							(end 0.2794 0.1778)
						)
						(arc
							(start 0.2794 -0.1778)
							(mid 0.249642 -0.249642)
							(end 0.1778 -0.2794)
						)
					)
					(width 0)
					(fill yes)
				)
			)
		)
		(pad "2" smd custom
			(at 0 0.4445)
			(size 0.1397 0.1397)
			(layers "F.Cu" "F.Mask" "F.Paste")
			(net "IO_EXP3_HDD_FAULT_A0")
			(options
				(clearance outline)
				(anchor circle)
			)
			(primitives
				(gr_poly
					(pts
						(arc
							(start -0.1778 -0.2794)
							(mid -0.249642 -0.249642)
							(end -0.2794 -0.1778)
						)
						(arc
							(start -0.2794 0.1778)
							(mid -0.249642 0.249642)
							(end -0.1778 0.2794)
						)
						(arc
							(start 0.1778 0.2794)
							(mid 0.249642 0.249642)
							(end 0.2794 0.1778)
						)
						(arc
							(start 0.2794 -0.1778)
							(mid 0.249642 -0.249642)
							(end 0.1778 -0.2794)
						)
					)
					(width 0)
					(fill yes)
				)
			)
		)
	)
	(footprint ""
		(layer "F.Cu")
		(at 138.653266 -142.628874 -90)
		(property "Reference" "R1048"
			(at 0 0 270)
			(layer "F.SilkS")
			(hide yes)
			(effects
				(font
					(size 1.27 1.27)
				)
			)
		)
		(property "Value" "0R2J-2-GP"
			(at 0.064008 -3.993896 270)
			(unlocked yes)
			(layer "F.Fab")
			(hide yes)
			(effects
				(font
					(size 1.016 1.016)
					(thickness 0.1524)
				)
			)
		)
		(property "Device Type" "R402H16"
			(at 0.064008 -5.517896 270)
			(unlocked yes)
			(layer "F.Fab")
			(hide yes)
			(effects
				(font
					(size 1.016 1.016)
					(thickness 0.1524)
				)
			)
		)
		(duplicate_pad_numbers_are_jumpers no)
		(fp_line
			(start -0.508 -0.9398)
			(end -0.508 0.9398)
			(stroke
				(width 0.1524)
				(type default)
			)
			(layer "F.SilkS")
		)
		(fp_line
			(start 0.508 -0.9398)
			(end -0.508 -0.9398)
			(stroke
				(width 0.1524)
				(type default)
			)
			(layer "F.SilkS")
		)
		(fp_rect
			(start -0.508 0.9398)
			(end 0.508 -0.9398)
			(stroke
				(width 0)
				(type default)
			)
			(fill no)
			(layer "F.CrtYd")
		)
		(fp_rect
			(start -0.508 0.9398)
			(end 0.508 -0.9398)
			(stroke
				(width 0)
				(type default)
			)
			(fill no)
			(layer "F.Fab")
		)
		(pad "1" smd custom
			(at 0 -0.4445 270)
			(size 0.1397 0.1397)
			(layers "F.Cu" "F.Mask" "F.Paste")
			(net "MB0_SPISS_PD")
			(options
				(clearance outline)
				(anchor circle)
			)
			(primitives
				(gr_poly
					(pts
						(arc
							(start -0.1778 -0.2794)
							(mid -0.249642 -0.249642)
							(end -0.2794 -0.1778)
						)
						(arc
							(start -0.2794 0.1778)
							(mid -0.249642 0.249642)
							(end -0.1778 0.2794)
						)
						(arc
							(start 0.1778 0.2794)
							(mid 0.249642 0.249642)
							(end 0.2794 0.1778)
						)
						(arc
							(start 0.2794 -0.1778)
							(mid 0.249642 -0.249642)
							(end 0.1778 -0.2794)
						)
					)
					(width 0)
					(fill yes)
				)
			)
		)
		(pad "2" smd custom
			(at 0 0.4445 270)
			(size 0.1397 0.1397)
			(layers "F.Cu" "F.Mask" "F.Paste")
			(net "AGND_CURRENT_MONOA")
			(options
				(clearance outline)
				(anchor circle)
			)
			(primitives
				(gr_poly
					(pts
						(arc
							(start -0.1778 -0.2794)
							(mid -0.249642 -0.249642)
							(end -0.2794 -0.1778)
						)
						(arc
							(start -0.2794 0.1778)
							(mid -0.249642 0.249642)
							(end -0.1778 0.2794)
						)
						(arc
							(start 0.1778 0.2794)
							(mid 0.249642 0.249642)
							(end 0.2794 0.1778)
						)
						(arc
							(start 0.2794 -0.1778)
							(mid 0.249642 -0.249642)
							(end 0.1778 -0.2794)
						)
					)
					(width 0)
					(fill yes)
				)
			)
		)
	)
	(footprint ""
		(layer "F.Cu")
		(at 308.91607 -294.435276 180)
		(property "Reference" "R274"
			(at 0 0 180)
			(layer "F.SilkS")
			(hide yes)
			(effects
				(font
					(size 1.27 1.27)
				)
			)
		)
		(property "Value" "130R3F-GP"
			(at -0.0254 -2.5146 180)
			(unlocked yes)
			(layer "F.Fab")
			(hide yes)
			(effects
				(font
					(size 1.016 1.016)
					(thickness 0.1524)
				)
			)
		)
		(property "Device Type" "R603H22"
			(at -0.0254 -4.0386 180)
			(unlocked yes)
			(layer "F.Fab")
			(hide yes)
			(effects
				(font
					(size 1.016 1.016)
					(thickness 0.1524)
				)
			)
		)
		(duplicate_pad_numbers_are_jumpers no)
		(fp_line
			(start 0.2032 0)
			(end 0.4826 0)
			(stroke
				(width 0.2032)
				(type default)
			)
			(layer "F.SilkS")
		)
		(fp_line
			(start -0.4826 0)
			(end -0.2032 0)
			(stroke
				(width 0.2032)
				(type default)
			)
			(layer "F.SilkS")
		)
		(fp_rect
			(start -0.5842 1.3335)
			(end 0.5842 -1.3335)
			(stroke
				(width 0)
				(type default)
			)
			(fill no)
			(layer "F.CrtYd")
		)
		(fp_rect
			(start -0.5842 1.3335)
			(end 0.5842 -1.3335)
			(stroke
				(width 0)
				(type default)
			)
			(fill no)
			(layer "F.Fab")
		)
		(pad "1" smd custom
			(at 0 -0.762 180)
			(size 0.2159 0.2159)
			(layers "F.Cu" "F.Mask" "F.Paste")
			(net "P5V_B")
			(options
				(clearance outline)
				(anchor circle)
			)
			(primitives
				(gr_poly
					(pts
						(arc
							(start -0.3302 -0.4318)
							(mid -0.402042 -0.402042)
							(end -0.4318 -0.3302)
						)
						(arc
							(start -0.4318 0.3302)
							(mid -0.402042 0.402042)
							(end -0.3302 0.4318)
						)
						(arc
							(start 0.3302 0.4318)
							(mid 0.402042 0.402042)
							(end 0.4318 0.3302)
						)
						(arc
							(start 0.4318 -0.3302)
							(mid 0.402042 -0.402042)
							(end 0.3302 -0.4318)
						)
					)
					(width 0)
					(fill yes)
				)
			)
		)
		(pad "2" smd custom
			(at 0 0.762 180)
			(size 0.2159 0.2159)
			(layers "F.Cu" "F.Mask" "F.Paste")
			(net "FLT_HDD30")
			(options
				(clearance outline)
				(anchor circle)
			)
			(primitives
				(gr_poly
					(pts
						(arc
							(start -0.3302 -0.4318)
							(mid -0.402042 -0.402042)
							(end -0.4318 -0.3302)
						)
						(arc
							(start -0.4318 0.3302)
							(mid -0.402042 0.402042)
							(end -0.3302 0.4318)
						)
						(arc
							(start 0.3302 0.4318)
							(mid 0.402042 0.402042)
							(end 0.4318 0.3302)
						)
						(arc
							(start 0.4318 -0.3302)
							(mid 0.402042 -0.402042)
							(end 0.3302 -0.4318)
						)
					)
					(width 0)
					(fill yes)
				)
			)
		)
	)
	(footprint ""
		(layer "F.Cu")
		(at 483.300024 -172.909992 -90)
		(property "Reference" "HDDSAS23"
			(at 0 0 270)
			(layer "F.SilkS")
			(hide yes)
			(effects
				(font
					(size 1.27 1.27)
				)
			)
		)
		(property "Value" "SKT-SAS15P-14P-45-GP"
			(at -20.7645 -8.9789 270)
			(unlocked yes)
			(layer "F.Fab")
			(hide yes)
			(effects
				(font
					(size 1.016 1.016)
					(thickness 0.1524)
				)
			)
		)
		(property "Device Type" "10120818-001C-TRLF"
			(at -20.7645 -10.5029 270)
			(unlocked yes)
			(layer "F.Fab")
			(hide yes)
			(effects
				(font
					(size 1.016 1.016)
					(thickness 0.1524)
				)
			)
		)
		(duplicate_pad_numbers_are_jumpers no)
		(fp_line
			(start 1.651 4.2926)
			(end 1.651 3.0099)
			(stroke
				(width 0.1524)
				(type default)
			)
			(layer "F.SilkS")
		)
		(fp_line
			(start 8.509 4.2926)
			(end 1.651 4.2926)
			(stroke
				(width 0.1524)
				(type default)
			)
			(layer "F.SilkS")
		)
		(fp_line
			(start -23.4188 3.0099)
			(end -23.4188 -3.2512)
			(stroke
				(width 0.1524)
				(type default)
			)
			(layer "F.SilkS")
		)
		(fp_line
			(start 1.651 3.0099)
			(end -23.4188 3.0099)
			(stroke
				(width 0.1524)
				(type default)
			)
			(layer "F.SilkS")
		)
		(fp_line
			(start 8.509 3.0099)
			(end 8.509 4.2926)
			(stroke
				(width 0.1524)
				(type default)
			)
			(layer "F.SilkS")
		)
		(fp_line
			(start 23.4188 3.0099)
			(end 8.509 3.0099)
			(stroke
				(width 0.1524)
				(type default)
			)
			(layer "F.SilkS")
		)
		(fp_line
			(start -23.4188 -3.2512)
			(end 23.4188 -3.2512)
			(stroke
				(width 0.1524)
				(type default)
			)
			(layer "F.SilkS")
		)
		(fp_line
			(start 23.4188 -3.2512)
			(end 23.4188 3.0099)
			(stroke
				(width 0.1524)
				(type default)
			)
			(layer "F.SilkS")
		)
		(fp_line
			(start 15.5067 -3.3401)
			(end 16.2687 -3.3401)
			(stroke
				(width 0.3302)
				(type default)
			)
			(layer "F.SilkS")
		)
		(fp_poly
			(pts
				(xy 15.868904 -3.230372) (xy 16.503904 -3.865372) (xy 15.233904 -3.865372)
			)
			(stroke
				(width 0)
				(type default)
			)
			(fill yes)
			(layer "F.SilkS")
		)
		(fp_poly
			(pts
				(xy -22.8727 -2.7559) (xy 22.8727 -2.7559) (xy 22.8727 2.7559) (xy 8.255 2.7559) (xy 8.255 3.5179)
				(xy 1.905 3.5179) (xy 1.905 2.7559) (xy -22.8727 2.7559)
			)
			(stroke
				(width 0)
				(type default)
			)
			(fill no)
			(layer "F.CrtYd")
		)
		(fp_poly
			(pts
				(xy 1.397 4.5466) (xy 1.397 3.2639) (xy -23.6728 3.2639) (xy -23.6728 -3.5052) (xy 23.6728 -3.5052)
				(xy 23.6728 -0.00635) (xy 22.8727 -0.00635) (xy 22.8727 -2.7559) (xy -22.8727 -2.7559) (xy -22.8727 2.7559)
				(xy 1.905 2.7559) (xy 1.905 3.5179) (xy 8.255 3.5179) (xy 8.255 2.7559) (xy 22.8727 2.7559) (xy 22.8727 0.00635)
				(xy 23.6728 0.00635) (xy 23.6728 3.2639) (xy 8.763 3.2639) (xy 8.763 4.5466)
			)
			(stroke
				(width 0)
				(type default)
			)
			(fill no)
			(layer "F.CrtYd")
		)
		(fp_poly
			(pts
				(xy 1.397 4.5466) (xy 1.397 3.2639) (xy -23.6728 3.2639) (xy -23.6728 -3.5052) (xy 23.6728 -3.5052)
				(xy 23.6728 3.2639) (xy 8.763 3.2639) (xy 8.763 4.5466)
			)
			(stroke
				(width 0)
				(type default)
			)
			(fill no)
			(layer "F.Fab")
		)
		(pad "" np_thru_hole circle
			(at -18.874994 0 270)
			(size 0.254 0.254)
			(drill 1.3462)
			(layers "*.Cu" "*.Mask")
			(clearance 0.9017)
			(thermal_gap 0.9017)
		)
		(pad "" np_thru_hole circle
			(at 18.874994 0 270)
			(size 0.254 0.254)
			(drill 0.9398)
			(layers "*.Cu" "*.Mask")
			(clearance 0.6985)
			(thermal_gap 0.6985)
		)
		(pad "G1" smd rect
			(at 21.874988 0 270)
			(size 2.5908 2.5908)
			(layers "F.Cu" "F.Mask" "F.Paste")
			(net "GND")
		)
		(pad "G2" smd rect
			(at -21.874988 0 270)
			(size 2.5908 2.5908)
			(layers "F.Cu" "F.Mask" "F.Paste")
			(net "GND")
		)
		(pad "P1" smd rect
			(at 1.905 -1.82499 270)
			(size 0.6096 2.3622)
			(layers "F.Cu" "F.Mask" "F.Paste")
			(net "Net_2096")
		)
		(pad "P2" smd rect
			(at 0.635 -1.82499 270)
			(size 0.6096 2.3622)
			(layers "F.Cu" "F.Mask" "F.Paste")
			(net "Net_2097")
		)
		(pad "P3" smd rect
			(at -0.635 -1.82499 270)
			(size 0.6096 2.3622)
			(layers "F.Cu" "F.Mask" "F.Paste")
			(net "Net_2098")
		)
		(pad "P4" smd rect
			(at -1.905 -1.82499 270)
			(size 0.6096 2.3622)
			(layers "F.Cu" "F.Mask" "F.Paste")
			(net "GND")
		)
		(pad "P5" smd rect
			(at -3.175 -1.82499 270)
			(size 0.6096 2.3622)
			(layers "F.Cu" "F.Mask" "F.Paste")
			(net "HDD_PRSNT_23")
		)
		(pad "P6" smd rect
			(at -4.445 -1.82499 270)
			(size 0.6096 2.3622)
			(layers "F.Cu" "F.Mask" "F.Paste")
			(net "GND")
		)
		(pad "P7" smd rect
			(at -5.715 -1.82499 270)
			(size 0.6096 2.3622)
			(layers "F.Cu" "F.Mask" "F.Paste")
			(net "5V_PRE_23")
		)
		(pad "P8" smd rect
			(at -6.985 -1.82499 270)
			(size 0.6096 2.3622)
			(layers "F.Cu" "F.Mask" "F.Paste")
			(net "P5V_HDD23")
		)
		(pad "P9" smd rect
			(at -8.255 -1.82499 270)
			(size 0.6096 2.3622)
			(layers "F.Cu" "F.Mask" "F.Paste")
			(net "P5V_HDD23")
		)
		(pad "P10" smd rect
			(at -9.525 -1.82499 270)
			(size 0.6096 2.3622)
			(layers "F.Cu" "F.Mask" "F.Paste")
			(net "GND")
		)
		(pad "P11" smd rect
			(at -10.795 -1.82499 270)
			(size 0.6096 2.3622)
			(layers "F.Cu" "F.Mask" "F.Paste")
			(net "ACT_HDD_23")
		)
		(pad "P12" smd rect
			(at -12.065 -1.82499 270)
			(size 0.6096 2.3622)
			(layers "F.Cu" "F.Mask" "F.Paste")
			(net "GND")
		)
		(pad "P13" smd rect
			(at -13.335 -1.82499 270)
			(size 0.6096 2.3622)
			(layers "F.Cu" "F.Mask" "F.Paste")
			(net "12V_PRE_23")
		)
		(pad "P14" smd rect
			(at -14.605 -1.82499 270)
			(size 0.6096 2.3622)
			(layers "F.Cu" "F.Mask" "F.Paste")
			(net "P12V_HDD23")
		)
		(pad "P15" smd rect
			(at -15.875 -1.82499 270)
			(size 0.6096 2.3622)
			(layers "F.Cu" "F.Mask" "F.Paste")
			(net "P12V_HDD23")
		)
		(pad "S1" smd rect
			(at 15.875 -1.82499 270)
			(size 0.6096 2.3622)
			(layers "F.Cu" "F.Mask" "F.Paste")
			(net "GND")
		)
		(pad "S2" smd rect
			(at 14.605 -1.82499 270)
			(size 0.6096 2.3622)
			(layers "F.Cu" "F.Mask" "F.Paste")
			(net "SAS_HDD_RX_P23")
		)
		(pad "S3" smd rect
			(at 13.335 -1.82499 270)
			(size 0.6096 2.3622)
			(layers "F.Cu" "F.Mask" "F.Paste")
			(net "SAS_HDD_RX_N23")
		)
		(pad "S4" smd rect
			(at 12.065 -1.82499 270)
			(size 0.6096 2.3622)
			(layers "F.Cu" "F.Mask" "F.Paste")
			(net "GND")
		)
		(pad "S5" smd rect
			(at 10.795 -1.82499 270)
			(size 0.6096 2.3622)
			(layers "F.Cu" "F.Mask" "F.Paste")
			(net "PHY_DRV_A_TO_SCC_A_23_DN")
		)
		(pad "S6" smd rect
			(at 9.525 -1.82499 270)
			(size 0.6096 2.3622)
			(layers "F.Cu" "F.Mask" "F.Paste")
			(net "PHY_DRV_A_TO_SCC_A_23_DP")
		)
		(pad "S7" smd rect
			(at 8.255 -1.82499 270)
			(size 0.6096 2.3622)
			(layers "F.Cu" "F.Mask" "F.Paste")
			(net "GND")
		)
		(pad "S8" smd rect
			(at 7.480046 2.845054 270)
			(size 0.508 2.3622)
			(layers "F.Cu" "F.Mask" "F.Paste")
			(net "GND")
		)
		(pad "S9" smd rect
			(at 6.679946 2.845054 270)
			(size 0.508 2.3622)
			(layers "F.Cu" "F.Mask" "F.Paste")
			(net "Net_461")
		)
		(pad "S10" smd rect
			(at 5.8801 2.845054 270)
			(size 0.508 2.3622)
			(layers "F.Cu" "F.Mask" "F.Paste")
			(net "Net_353")
		)
		(pad "S11" smd rect
			(at 5.08 2.845054 270)
			(size 0.508 2.3622)
			(layers "F.Cu" "F.Mask" "F.Paste")
			(net "GND")
		)
		(pad "S12" smd rect
			(at 4.2799 2.845054 270)
			(size 0.508 2.3622)
			(layers "F.Cu" "F.Mask" "F.Paste")
			(net "Net_389")
		)
		(pad "S13" smd rect
			(at 3.480054 2.845054 270)
			(size 0.508 2.3622)
			(layers "F.Cu" "F.Mask" "F.Paste")
			(net "Net_425")
		)
		(pad "S14" smd rect
			(at 2.679954 2.845054 270)
			(size 0.508 2.3622)
			(layers "F.Cu" "F.Mask" "F.Paste")
			(net "GND")
		)
		(zone
			(layer "F.Cu")
			(hatch none 0.5)
			(connect_pads
				(clearance 0)
			)
			(min_thickness 0.25)
			(keepout
				(tracks not_allowed)
				(vias allowed)
				(pads allowed)
				(copperpour not_allowed)
				(footprints allowed)
			)
			(placement
				(enabled no)
				(sheetname "")
			)
			(fill
				(thermal_gap 0.5)
				(thermal_bridge_width 0.5)
				(island_removal_mode 0)
			)
			(polygon
				(pts
					(xy 486.957624 -189.648592) (xy 479.883724 -189.648592) (xy 479.883724 -196.582792) (xy 480.988624 -196.582792)
					(xy 480.988624 -192.467992) (xy 485.611424 -192.467992) (xy 485.611424 -196.582792) (xy 486.957624 -196.582792)
				)
			)
		)
		(zone
			(layer "F.Cu")
			(hatch none 0.5)
			(connect_pads
				(clearance 0)
			)
			(min_thickness 0.25)
			(keepout
				(tracks allowed)
				(vias not_allowed)
				(pads allowed)
				(copperpour not_allowed)
				(footprints allowed)
			)
			(placement
				(enabled no)
				(sheetname "")
			)
			(fill
				(thermal_gap 0.5)
				(thermal_bridge_width 0.5)
				(island_removal_mode 0)
			)
			(polygon
				(pts
					(xy 486.957624 -189.648592) (xy 479.883724 -189.648592) (xy 479.883724 -196.582792) (xy 480.988624 -196.582792)
					(xy 480.988624 -192.467992) (xy 485.611424 -192.467992) (xy 485.611424 -196.582792) (xy 486.957624 -196.582792)
				)
			)
		)
		(zone
			(layer "F.Cu")
			(hatch none 0.5)
			(connect_pads
				(clearance 0)
			)
			(min_thickness 0.25)
			(keepout
				(tracks not_allowed)
				(vias allowed)
				(pads allowed)
				(copperpour not_allowed)
				(footprints allowed)
			)
			(placement
				(enabled no)
				(sheetname "")
			)
			(fill
				(thermal_gap 0.5)
				(thermal_bridge_width 0.5)
				(island_removal_mode 0)
			)
			(polygon
				(pts
					(xy 486.957624 -156.171392) (xy 479.883724 -156.171392) (xy 479.883724 -149.237192) (xy 480.988624 -149.237192)
					(xy 480.988624 -153.351992) (xy 485.611424 -153.351992) (xy 485.611424 -149.237192) (xy 486.957624 -149.237192)
				)
			)
		)
		(zone
			(layer "F.Cu")
			(hatch none 0.5)
			(connect_pads
				(clearance 0)
			)
			(min_thickness 0.25)
			(keepout
				(tracks allowed)
				(vias not_allowed)
				(pads allowed)
				(copperpour not_allowed)
				(footprints allowed)
			)
			(placement
				(enabled no)
				(sheetname "")
			)
			(fill
				(thermal_gap 0.5)
				(thermal_bridge_width 0.5)
				(island_removal_mode 0)
			)
			(polygon
				(pts
					(xy 486.957624 -156.171392) (xy 479.883724 -156.171392) (xy 479.883724 -149.237192) (xy 480.988624 -149.237192)
					(xy 480.988624 -153.351992) (xy 485.611424 -153.351992) (xy 485.611424 -149.237192) (xy 486.957624 -149.237192)
				)
			)
		)
		(zone
			(layers "F.Cu" "B.Cu" "In1.Cu" "In2.Cu" "In3.Cu" "In4.Cu" "In5.Cu" "In6.Cu"
				"In7.Cu" "In8.Cu" "In9.Cu" "In10.Cu"
			)
			(hatch none 0.5)
			(connect_pads
				(clearance 0)
			)
			(min_thickness 0.25)
			(keepout
				(tracks not_allowed)
				(vias allowed)
				(pads allowed)
				(copperpour not_allowed)
				(footprints allowed)
			)
			(placement
				(enabled no)
				(sheetname "")
			)
			(fill
				(thermal_gap 0.5)
				(thermal_bridge_width 0.5)
				(island_removal_mode 0)
			)
			(polygon
				(pts
					(arc
						(start 484.074724 -154.034998)
						(mid 482.525324 -154.034998)
						(end 484.074724 -154.034998)
					)
				)
			)
		)
		(zone
			(layers "F.Cu" "B.Cu" "In1.Cu" "In2.Cu" "In3.Cu" "In4.Cu" "In5.Cu" "In6.Cu"
				"In7.Cu" "In8.Cu" "In9.Cu" "In10.Cu"
			)
			(hatch none 0.5)
			(connect_pads
				(clearance 0)
			)
			(min_thickness 0.25)
			(keepout
				(tracks not_allowed)
				(vias allowed)
				(pads allowed)
				(copperpour not_allowed)
				(footprints allowed)
			)
			(placement
				(enabled no)
				(sheetname "")
			)
			(fill
				(thermal_gap 0.5)
				(thermal_bridge_width 0.5)
				(island_removal_mode 0)
			)
			(polygon
				(pts
					(arc
						(start 484.277924 -191.784986)
						(mid 482.322124 -191.784986)
						(end 484.277924 -191.784986)
					)
				)
			)
		)
	)
	(footprint ""
		(layer "F.Cu")
		(at 174.382176 -150.260304 -90)
		(property "Reference" "R1062"
			(at 0 0 270)
			(layer "F.SilkS")
			(hide yes)
			(effects
				(font
					(size 1.27 1.27)
				)
			)
		)
		(property "Value" "D001FRL3115F-L-GP"
			(at 3.2766 1.3843 270)
			(unlocked yes)
			(layer "F.Fab")
			(hide yes)
			(effects
				(font
					(size 1.016 1.016)
					(thickness 0.1524)
				)
			)
		)
		(property "Device Type" "RL3115-4PH25"
			(at 3.2766 -0.1397 270)
			(unlocked yes)
			(layer "F.Fab")
			(hide yes)
			(effects
				(font
					(size 1.016 1.016)
					(thickness 0.1524)
				)
			)
		)
		(duplicate_pad_numbers_are_jumpers no)
		(fp_line
			(start -1.9685 1.651)
			(end -1.9685 -1.651)
			(stroke
				(width 0.1524)
				(type default)
			)
			(layer "F.SilkS")
		)
		(fp_line
			(start 1.9685 1.651)
			(end -1.9685 1.651)
			(stroke
				(width 0.1524)
				(type default)
			)
			(layer "F.SilkS")
		)
		(fp_line
			(start -1.9685 -1.651)
			(end 1.9685 -1.651)
			(stroke
				(width 0.1524)
				(type default)
			)
			(layer "F.SilkS")
		)
		(fp_line
			(start 1.9685 -1.651)
			(end 1.9685 1.651)
			(stroke
				(width 0.1524)
				(type default)
			)
			(layer "F.SilkS")
		)
		(fp_line
			(start -2.0828 -1.778)
			(end -2.0828 -0.4445)
			(stroke
				(width 0.3302)
				(type default)
			)
			(layer "F.SilkS")
		)
		(fp_line
			(start -0.5461 -1.778)
			(end -2.0828 -1.778)
			(stroke
				(width 0.3302)
				(type default)
			)
			(layer "F.SilkS")
		)
		(fp_poly
			(pts
				(xy -0.561594 -1.726946) (xy -0.053594 -2.234946) (xy -1.069594 -2.234946)
			)
			(stroke
				(width 0)
				(type default)
			)
			(fill yes)
			(layer "F.SilkS")
		)
		(fp_rect
			(start -1.524 0.7493)
			(end 1.524 -0.7493)
			(stroke
				(width 0)
				(type default)
			)
			(fill no)
			(layer "F.CrtYd")
		)
		(fp_poly
			(pts
				(xy -2.2225 1.905) (xy -2.2225 -1.905) (xy 2.2225 -1.905) (xy 2.2225 -0.7493) (xy -1.524 -0.7493)
				(xy -1.524 0.7493) (xy 1.524 0.7493) (xy 1.524 -0.7366) (xy 2.2225 -0.7366) (xy 2.2225 1.905)
			)
			(stroke
				(width 0)
				(type default)
			)
			(fill no)
			(layer "F.CrtYd")
		)
		(fp_rect
			(start -2.2225 1.905)
			(end 2.2225 -1.905)
			(stroke
				(width 0)
				(type default)
			)
			(fill no)
			(layer "F.Fab")
		)
		(pad "1" smd rect
			(at -0.5715 -0.813562 270)
			(size 2.286 1.143)
			(layers "F.Cu" "F.Mask" "F.Paste")
			(net "P12V_A")
		)
		(pad "2" smd rect
			(at -0.5715 0.813562 270)
			(size 2.286 1.143)
			(layers "F.Cu" "F.Mask" "F.Paste")
			(net "MB0_P12V_R")
		)
		(pad "3" smd rect
			(at 1.334008 -0.813562 270)
			(size 0.762 1.143)
			(layers "F.Cu" "F.Mask" "F.Paste")
			(net "MB0_CM_SENSE_R1_P")
		)
		(pad "4" smd rect
			(at 1.334008 0.813562 270)
			(size 0.762 1.143)
			(layers "F.Cu" "F.Mask" "F.Paste")
			(net "MB0_CM_SENSE_R1_N")
		)
		(zone
			(layer "F.Cu")
			(hatch none 0.5)
			(connect_pads
				(clearance 0)
			)
			(min_thickness 0.25)
			(keepout
				(tracks not_allowed)
				(vias allowed)
				(pads allowed)
				(copperpour not_allowed)
				(footprints allowed)
			)
			(placement
				(enabled no)
				(sheetname "")
			)
			(fill
				(thermal_gap 0.5)
				(thermal_bridge_width 0.5)
				(island_removal_mode 0)
			)
			(polygon
				(pts
					(xy 173.632876 -149.688804) (xy 173.632876 -149.307296) (xy 174.140114 -149.307296) (xy 174.140114 -149.688804)
				)
			)
		)
		(zone
			(layer "F.Cu")
			(hatch none 0.5)
			(connect_pads
				(clearance 0)
			)
			(min_thickness 0.25)
			(keepout
				(tracks allowed)
				(vias not_allowed)
				(pads allowed)
				(copperpour not_allowed)
				(footprints allowed)
			)
			(placement
				(enabled no)
				(sheetname "")
			)
			(fill
				(thermal_gap 0.5)
				(thermal_bridge_width 0.5)
				(island_removal_mode 0)
			)
			(polygon
				(pts
					(xy 173.632876 -149.688804) (xy 173.632876 -149.307296) (xy 174.140114 -149.307296) (xy 174.140114 -149.688804)
				)
			)
		)
		(zone
			(layer "F.Cu")
			(hatch none 0.5)
			(connect_pads
				(clearance 0)
			)
			(min_thickness 0.25)
			(keepout
				(tracks not_allowed)
				(vias allowed)
				(pads allowed)
				(copperpour not_allowed)
				(footprints allowed)
			)
			(placement
				(enabled no)
				(sheetname "")
			)
			(fill
				(thermal_gap 0.5)
				(thermal_bridge_width 0.5)
				(island_removal_mode 0)
			)
			(polygon
				(pts
					(xy 174.624238 -149.688804) (xy 174.624238 -149.307296) (xy 175.131476 -149.307296) (xy 175.131476 -149.688804)
				)
			)
		)
		(zone
			(layer "F.Cu")
			(hatch none 0.5)
			(connect_pads
				(clearance 0)
			)
			(min_thickness 0.25)
			(keepout
				(tracks allowed)
				(vias not_allowed)
				(pads allowed)
				(copperpour not_allowed)
				(footprints allowed)
			)
			(placement
				(enabled no)
				(sheetname "")
			)
			(fill
				(thermal_gap 0.5)
				(thermal_bridge_width 0.5)
				(island_removal_mode 0)
			)
			(polygon
				(pts
					(xy 174.624238 -149.688804) (xy 174.624238 -149.307296) (xy 175.131476 -149.307296) (xy 175.131476 -149.688804)
				)
			)
		)
	)
	(footprint ""
		(layer "F.Cu")
		(at 65.936876 -304.385472 180)
		(property "Reference" "R230"
			(at 0 0 180)
			(layer "F.SilkS")
			(hide yes)
			(effects
				(font
					(size 1.27 1.27)
				)
			)
		)
		(property "Value" "91R3F-1-GP"
			(at -0.0254 -2.5146 180)
			(unlocked yes)
			(layer "F.Fab")
			(hide yes)
			(effects
				(font
					(size 1.016 1.016)
					(thickness 0.1524)
				)
			)
		)
		(property "Device Type" "R603H22"
			(at -0.0254 -4.0386 180)
			(unlocked yes)
			(layer "F.Fab")
			(hide yes)
			(effects
				(font
					(size 1.016 1.016)
					(thickness 0.1524)
				)
			)
		)
		(duplicate_pad_numbers_are_jumpers no)
		(fp_line
			(start 0.2032 0)
			(end 0.4826 0)
			(stroke
				(width 0.2032)
				(type default)
			)
			(layer "F.SilkS")
		)
		(fp_line
			(start -0.4826 0)
			(end -0.2032 0)
			(stroke
				(width 0.2032)
				(type default)
			)
			(layer "F.SilkS")
		)
		(fp_rect
			(start -0.5842 1.3335)
			(end 0.5842 -1.3335)
			(stroke
				(width 0)
				(type default)
			)
			(fill no)
			(layer "F.CrtYd")
		)
		(fp_rect
			(start -0.5842 1.3335)
			(end 0.5842 -1.3335)
			(stroke
				(width 0)
				(type default)
			)
			(fill no)
			(layer "F.Fab")
		)
		(pad "1" smd custom
			(at 0 -0.762 180)
			(size 0.2159 0.2159)
			(layers "F.Cu" "F.Mask" "F.Paste")
			(net "P5V_B")
			(options
				(clearance outline)
				(anchor circle)
			)
			(primitives
				(gr_poly
					(pts
						(arc
							(start -0.3302 -0.4318)
							(mid -0.402042 -0.402042)
							(end -0.4318 -0.3302)
						)
						(arc
							(start -0.4318 0.3302)
							(mid -0.402042 0.402042)
							(end -0.3302 0.4318)
						)
						(arc
							(start 0.3302 0.4318)
							(mid 0.402042 0.402042)
							(end 0.4318 0.3302)
						)
						(arc
							(start 0.4318 -0.3302)
							(mid 0.402042 -0.402042)
							(end 0.3302 -0.4318)
						)
					)
					(width 0)
					(fill yes)
				)
			)
		)
		(pad "2" smd custom
			(at 0 0.762 180)
			(size 0.2159 0.2159)
			(layers "F.Cu" "F.Mask" "F.Paste")
			(net "DRV_ACT_26")
			(options
				(clearance outline)
				(anchor circle)
			)
			(primitives
				(gr_poly
					(pts
						(arc
							(start -0.3302 -0.4318)
							(mid -0.402042 -0.402042)
							(end -0.4318 -0.3302)
						)
						(arc
							(start -0.4318 0.3302)
							(mid -0.402042 0.402042)
							(end -0.3302 0.4318)
						)
						(arc
							(start 0.3302 0.4318)
							(mid 0.402042 0.402042)
							(end 0.4318 0.3302)
						)
						(arc
							(start 0.4318 -0.3302)
							(mid 0.402042 -0.402042)
							(end 0.3302 -0.4318)
						)
					)
					(width 0)
					(fill yes)
				)
			)
		)
	)
	(footprint ""
		(layer "F.Cu")
		(at 444.4619 -291.127942 -90)
		(property "Reference" "C176"
			(at 0 0 270)
			(layer "F.SilkS")
			(hide yes)
			(effects
				(font
					(size 1.27 1.27)
				)
			)
		)
		(property "Value" "SCD01U50V2KX-1GP"
			(at 1.1811 -2.7051 270)
			(unlocked yes)
			(layer "F.Fab")
			(hide yes)
			(effects
				(font
					(size 1.016 1.016)
					(thickness 0.1524)
				)
			)
		)
		(property "Device Type" "C402H22"
			(at 1.1811 -4.2291 270)
			(unlocked yes)
			(layer "F.Fab")
			(hide yes)
			(effects
				(font
					(size 1.016 1.016)
					(thickness 0.1524)
				)
			)
		)
		(duplicate_pad_numbers_are_jumpers no)
		(fp_rect
			(start -0.4318 0.9525)
			(end 0.4318 -0.9525)
			(stroke
				(width 0)
				(type default)
			)
			(fill no)
			(layer "F.CrtYd")
		)
		(fp_rect
			(start -0.4318 0.9525)
			(end 0.4318 -0.9525)
			(stroke
				(width 0)
				(type default)
			)
			(fill no)
			(layer "F.Fab")
		)
		(pad "1" smd custom
			(at 0 -0.4445 270)
			(size 0.1524 0.1524)
			(layers "F.Cu" "F.Mask" "F.Paste")
			(net "HDD_PRSNT_10")
			(options
				(clearance outline)
				(anchor circle)
			)
			(primitives
				(gr_poly
					(pts
						(arc
							(start 0.3048 -0.2032)
							(mid 0.275042 -0.275042)
							(end 0.2032 -0.3048)
						)
						(arc
							(start -0.2032 -0.3048)
							(mid -0.275042 -0.275042)
							(end -0.3048 -0.2032)
						)
						(arc
							(start -0.3048 0.2032)
							(mid -0.275042 0.275042)
							(end -0.2032 0.3048)
						)
						(arc
							(start 0.2032 0.3048)
							(mid 0.275042 0.275042)
							(end 0.3048 0.2032)
						)
					)
					(width 0)
					(fill yes)
				)
			)
		)
		(pad "2" smd custom
			(at 0 0.4445 270)
			(size 0.1524 0.1524)
			(layers "F.Cu" "F.Mask" "F.Paste")
			(net "GND")
			(options
				(clearance outline)
				(anchor circle)
			)
			(primitives
				(gr_poly
					(pts
						(arc
							(start 0.3048 -0.2032)
							(mid 0.275042 -0.275042)
							(end 0.2032 -0.3048)
						)
						(arc
							(start -0.2032 -0.3048)
							(mid -0.275042 -0.275042)
							(end -0.3048 -0.2032)
						)
						(arc
							(start -0.3048 0.2032)
							(mid -0.275042 0.275042)
							(end -0.2032 0.3048)
						)
						(arc
							(start 0.2032 0.3048)
							(mid 0.275042 0.275042)
							(end 0.3048 0.2032)
						)
					)
					(width 0)
					(fill yes)
				)
			)
		)
	)
	(footprint ""
		(layer "F.Cu")
		(at 190.258954 -277.750016 -90)
		(property "Reference" "VIA44"
			(at 0 0 270)
			(layer "F.SilkS")
			(hide yes)
			(effects
				(font
					(size 1.27 1.27)
				)
			)
		)
		(property "Value" "100OHM-8L-1D6MM-L18L16-GP"
			(at -3.7211 -4.5085 270)
			(unlocked yes)
			(layer "F.Fab")
			(hide yes)
			(effects
				(font
					(size 1.016 1.016)
					(thickness 0.1524)
				)
			)
		)
		(property "Device Type" "VIA-PCIE-4P-394076"
			(at -3.7211 -6.0325 270)
			(unlocked yes)
			(layer "F.Fab")
			(hide yes)
			(effects
				(font
					(size 1.016 1.016)
					(thickness 0.1524)
				)
			)
		)
		(duplicate_pad_numbers_are_jumpers no)
		(fp_rect
			(start -1.9685 0.381)
			(end 1.9685 -0.381)
			(stroke
				(width 0)
				(type default)
			)
			(fill no)
			(layer "F.CrtYd")
		)
		(fp_rect
			(start -1.9685 0.381)
			(end 1.9685 -0.381)
			(stroke
				(width 0)
				(type default)
			)
			(fill no)
			(layer "F.Fab")
		)
		(pad "1" thru_hole circle
			(at -1.5875 0 270)
			(size 0.508 0.508)
			(drill 0.254)
			(layers "*.Cu" "*.Mask")
			(remove_unused_layers no)
			(net "GND")
			(clearance 0.127)
			(thermal_gap 0.127)
		)
		(pad "2" thru_hole circle
			(at -0.5715 0 270)
			(size 0.508 0.508)
			(drill 0.254)
			(layers "*.Cu" "*.Mask")
			(remove_unused_layers no)
			(net "PHY_DRV_A_TO_SCC_A_5_DP")
			(clearance 0.127)
			(thermal_gap 0.127)
		)
		(pad "3" thru_hole circle
			(at 0.5715 0 270)
			(size 0.508 0.508)
			(drill 0.254)
			(layers "*.Cu" "*.Mask")
			(remove_unused_layers no)
			(net "PHY_DRV_A_TO_SCC_A_5_DN")
			(clearance 0.127)
			(thermal_gap 0.127)
		)
		(pad "4" thru_hole circle
			(at 1.5875 0 270)
			(size 0.508 0.508)
			(drill 0.254)
			(layers "*.Cu" "*.Mask")
			(remove_unused_layers no)
			(net "GND")
			(clearance 0.127)
			(thermal_gap 0.127)
		)
	)
	(footprint ""
		(layer "F.Cu")
		(at 300.0502 -63.4492 90)
		(property "Reference" "R365"
			(at 0 0 90)
			(layer "F.SilkS")
			(hide yes)
			(effects
				(font
					(size 1.27 1.27)
				)
			)
		)
		(property "Value" "0R2J-2-GP"
			(at 0.064008 -3.993896 90)
			(unlocked yes)
			(layer "F.Fab")
			(hide yes)
			(effects
				(font
					(size 1.016 1.016)
					(thickness 0.1524)
				)
			)
		)
		(property "Device Type" "R402H16"
			(at 0.064008 -5.517896 90)
			(unlocked yes)
			(layer "F.Fab")
			(hide yes)
			(effects
				(font
					(size 1.016 1.016)
					(thickness 0.1524)
				)
			)
		)
		(duplicate_pad_numbers_are_jumpers no)
		(fp_line
			(start 0.508 -0.9398)
			(end -0.508 -0.9398)
			(stroke
				(width 0.1524)
				(type default)
			)
			(layer "F.SilkS")
		)
		(fp_line
			(start -0.508 -0.9398)
			(end -0.508 0.9398)
			(stroke
				(width 0.1524)
				(type default)
			)
			(layer "F.SilkS")
		)
		(fp_rect
			(start -0.508 0.9398)
			(end 0.508 -0.9398)
			(stroke
				(width 0)
				(type default)
			)
			(fill no)
			(layer "F.CrtYd")
		)
		(fp_rect
			(start -0.508 0.9398)
			(end 0.508 -0.9398)
			(stroke
				(width 0)
				(type default)
			)
			(fill no)
			(layer "F.Fab")
		)
		(pad "1" smd custom
			(at 0 -0.4445 90)
			(size 0.1397 0.1397)
			(layers "F.Cu" "F.Mask" "F.Paste")
			(net "I2C_BMC_B_COMP_B_SDA")
			(options
				(clearance outline)
				(anchor circle)
			)
			(primitives
				(gr_poly
					(pts
						(arc
							(start -0.1778 -0.2794)
							(mid -0.249642 -0.249642)
							(end -0.2794 -0.1778)
						)
						(arc
							(start -0.2794 0.1778)
							(mid -0.249642 0.249642)
							(end -0.1778 0.2794)
						)
						(arc
							(start 0.1778 0.2794)
							(mid 0.249642 0.249642)
							(end 0.2794 0.1778)
						)
						(arc
							(start 0.2794 -0.1778)
							(mid 0.249642 -0.249642)
							(end 0.1778 -0.2794)
						)
					)
					(width 0)
					(fill yes)
				)
			)
		)
		(pad "2" smd custom
			(at 0 0.4445 90)
			(size 0.1397 0.1397)
			(layers "F.Cu" "F.Mask" "F.Paste")
			(net "I2C_BMC_B_COMP_B_SDA_R")
			(options
				(clearance outline)
				(anchor circle)
			)
			(primitives
				(gr_poly
					(pts
						(arc
							(start -0.1778 -0.2794)
							(mid -0.249642 -0.249642)
							(end -0.2794 -0.1778)
						)
						(arc
							(start -0.2794 0.1778)
							(mid -0.249642 0.249642)
							(end -0.1778 0.2794)
						)
						(arc
							(start 0.1778 0.2794)
							(mid 0.249642 0.249642)
							(end 0.2794 0.1778)
						)
						(arc
							(start 0.2794 -0.1778)
							(mid 0.249642 -0.249642)
							(end 0.1778 -0.2794)
						)
					)
					(width 0)
					(fill yes)
				)
			)
		)
	)
	(footprint ""
		(layer "F.Cu")
		(at 172.466 -179.683918 -90)
		(property "Reference" "C265"
			(at 0 0 270)
			(layer "F.SilkS")
			(hide yes)
			(effects
				(font
					(size 1.27 1.27)
				)
			)
		)
		(property "Value" "SC4D7U25V5KX-1-GP"
			(at -0.0762 -6.1214 270)
			(unlocked yes)
			(layer "F.Fab")
			(hide yes)
			(effects
				(font
					(size 1.016 1.016)
					(thickness 0.1524)
				)
			)
		)
		(property "Device Type" "C805H58"
			(at -0.0762 -8.1534 270)
			(unlocked yes)
			(layer "F.Fab")
			(hide yes)
			(effects
				(font
					(size 1.016 1.016)
					(thickness 0.1524)
				)
			)
		)
		(duplicate_pad_numbers_are_jumpers no)
		(fp_line
			(start 0.635 0)
			(end -0.635 0)
			(stroke
				(width 0.508)
				(type default)
			)
			(layer "F.SilkS")
		)
		(fp_rect
			(start -0.9652 1.778)
			(end 0.9652 -1.778)
			(stroke
				(width 0)
				(type default)
			)
			(fill no)
			(layer "F.CrtYd")
		)
		(fp_poly
			(pts
				(xy -0.9652 -1.778) (xy 0.9652 -1.778) (xy 0.9652 1.778) (xy -0.9652 1.778)
			)
			(stroke
				(width 0)
				(type default)
			)
			(fill no)
			(layer "F.Fab")
		)
		(pad "1" smd rect
			(at 0 -0.9652 270)
			(size 1.397 1.143)
			(layers "F.Cu" "F.Mask" "F.Paste")
			(net "P12V_HDD17")
		)
		(pad "2" smd rect
			(at 0 0.9652 270)
			(size 1.397 1.143)
			(layers "F.Cu" "F.Mask" "F.Paste")
			(net "GND")
		)
	)
	(footprint ""
		(layer "F.Cu")
		(at 424.469052 -304.335942 180)
		(property "Reference" "C164"
			(at 0 0 180)
			(layer "F.SilkS")
			(hide yes)
			(effects
				(font
					(size 1.27 1.27)
				)
			)
		)
		(property "Value" "SC1U25V3KX-GP"
			(at 0 -2.8194 180)
			(unlocked yes)
			(layer "F.Fab")
			(hide yes)
			(effects
				(font
					(size 1.016 1.016)
					(thickness 0.1524)
				)
			)
		)
		(property "Device Type" "C603H36"
			(at 0 -4.3434 180)
			(unlocked yes)
			(layer "F.Fab")
			(hide yes)
			(effects
				(font
					(size 1.016 1.016)
					(thickness 0.1524)
				)
			)
		)
		(duplicate_pad_numbers_are_jumpers no)
		(fp_line
			(start 0.508 0)
			(end -0.508 0)
			(stroke
				(width 0.2032)
				(type default)
			)
			(layer "F.SilkS")
		)
		(fp_rect
			(start -0.5842 1.3335)
			(end 0.5842 -1.3335)
			(stroke
				(width 0)
				(type default)
			)
			(fill no)
			(layer "F.CrtYd")
		)
		(fp_rect
			(start -0.5842 1.3335)
			(end 0.5842 -1.3335)
			(stroke
				(width 0)
				(type default)
			)
			(fill no)
			(layer "F.Fab")
		)
		(pad "1" smd custom
			(at 0 -0.762 180)
			(size 0.2159 0.2159)
			(layers "F.Cu" "F.Mask" "F.Paste")
			(net "P12V_HDD9")
			(options
				(clearance outline)
				(anchor circle)
			)
			(primitives
				(gr_poly
					(pts
						(arc
							(start -0.3302 -0.4318)
							(mid -0.402042 -0.402042)
							(end -0.4318 -0.3302)
						)
						(arc
							(start -0.4318 0.3302)
							(mid -0.402042 0.402042)
							(end -0.3302 0.4318)
						)
						(arc
							(start 0.3302 0.4318)
							(mid 0.402042 0.402042)
							(end 0.4318 0.3302)
						)
						(arc
							(start 0.4318 -0.3302)
							(mid 0.402042 -0.402042)
							(end 0.3302 -0.4318)
						)
					)
					(width 0)
					(fill yes)
				)
			)
		)
		(pad "2" smd custom
			(at 0 0.762 180)
			(size 0.2159 0.2159)
			(layers "F.Cu" "F.Mask" "F.Paste")
			(net "GND")
			(options
				(clearance outline)
				(anchor circle)
			)
			(primitives
				(gr_poly
					(pts
						(arc
							(start -0.3302 -0.4318)
							(mid -0.402042 -0.402042)
							(end -0.4318 -0.3302)
						)
						(arc
							(start -0.4318 0.3302)
							(mid -0.402042 0.402042)
							(end -0.3302 0.4318)
						)
						(arc
							(start 0.3302 0.4318)
							(mid 0.402042 0.402042)
							(end 0.4318 0.3302)
						)
						(arc
							(start 0.4318 -0.3302)
							(mid 0.402042 -0.402042)
							(end 0.3302 -0.4318)
						)
					)
					(width 0)
					(fill yes)
				)
			)
		)
	)
	(footprint ""
		(layer "F.Cu")
		(at 244.86489 -381.013208)
		(property "Reference" "R142"
			(at 0 0 0)
			(layer "F.SilkS")
			(hide yes)
			(effects
				(font
					(size 1.27 1.27)
				)
			)
		)
		(property "Value" "0R5J-5-GP"
			(at 0 -8.9535 0)
			(unlocked yes)
			(layer "F.Fab")
			(hide yes)
			(effects
				(font
					(size 1.27 1.016)
					(thickness 0.1524)
				)
			)
		)
		(property "Device Type" "R805H24"
			(at 0 -10.6299 0)
			(unlocked yes)
			(layer "F.Fab")
			(hide yes)
			(effects
				(font
					(size 1.27 1.016)
					(thickness 0.1524)
				)
			)
		)
		(duplicate_pad_numbers_are_jumpers no)
		(fp_line
			(start -0.889 -1.7018)
			(end -0.889 0.2794)
			(stroke
				(width 0.1524)
				(type default)
			)
			(layer "F.SilkS")
		)
		(fp_line
			(start -0.889 0.0762)
			(end -0.889 1.7018)
			(stroke
				(width 0.1524)
				(type default)
			)
			(layer "F.SilkS")
		)
		(fp_line
			(start -0.889 1.7018)
			(end 0.889 1.7018)
			(stroke
				(width 0.1524)
				(type default)
			)
			(layer "F.SilkS")
		)
		(fp_line
			(start 0.889 -1.7018)
			(end -0.889 -1.7018)
			(stroke
				(width 0.1524)
				(type default)
			)
			(layer "F.SilkS")
		)
		(fp_line
			(start 0.889 -1.7018)
			(end 0.889 -0.381)
			(stroke
				(width 0.1524)
				(type default)
			)
			(layer "F.SilkS")
		)
		(fp_line
			(start 0.889 1.7018)
			(end 0.889 -0.508)
			(stroke
				(width 0.1524)
				(type default)
			)
			(layer "F.SilkS")
		)
		(fp_poly
			(pts
				(xy 0.9652 -1.778) (xy 0.9652 1.778) (xy -0.9652 1.778) (xy -0.9652 -1.778)
			)
			(stroke
				(width 0)
				(type default)
			)
			(fill no)
			(layer "F.CrtYd")
		)
		(fp_rect
			(start -0.9652 1.778)
			(end 0.9652 -1.778)
			(stroke
				(width 0)
				(type default)
			)
			(fill no)
			(layer "F.Fab")
		)
		(pad "1" smd rect
			(at 0 -0.9652)
			(size 1.397 1.143)
			(layers "F.Cu" "F.Mask" "F.Paste")
			(net "MB3_CM_GATE_R")
		)
		(pad "2" smd rect
			(at 0 0.9652)
			(size 1.397 1.143)
			(layers "F.Cu" "F.Mask" "F.Paste")
			(net "MB3_CM_GATE_C")
		)
	)
	(footprint ""
		(layer "F.Cu")
		(at 431.454052 -62.016894)
		(property "Reference" "Q200"
			(at 0 0 0)
			(layer "F.SilkS")
			(hide yes)
			(effects
				(font
					(size 1.27 1.27)
				)
			)
		)
		(property "Value" "AO4407AL-GP"
			(at -3.707384 -1.5367 0)
			(unlocked yes)
			(layer "F.Fab")
			(hide yes)
			(effects
				(font
					(size 1.016 1.016)
					(thickness 0.1524)
				)
			)
		)
		(property "Device Type" "SOIC8H69"
			(at -3.707384 -3.0607 0)
			(unlocked yes)
			(layer "F.Fab")
			(hide yes)
			(effects
				(font
					(size 1.016 1.016)
					(thickness 0.1524)
				)
			)
		)
		(duplicate_pad_numbers_are_jumpers no)
		(fp_line
			(start -2.7432 -1.4224)
			(end -2.7432 1.4224)
			(stroke
				(width 0.1524)
				(type default)
			)
			(layer "F.SilkS")
		)
		(fp_line
			(start -2.7432 1.4224)
			(end -2.6416 1.4224)
			(stroke
				(width 0.1524)
				(type default)
			)
			(layer "F.SilkS")
		)
		(fp_line
			(start -2.7432 1.4224)
			(end 2.1336 1.4224)
			(stroke
				(width 0.1524)
				(type default)
			)
			(layer "F.SilkS")
		)
		(fp_line
			(start -2.7178 -0.508)
			(end -2.1844 -0.0508)
			(stroke
				(width 0.1524)
				(type default)
			)
			(layer "F.SilkS")
		)
		(fp_line
			(start -2.6289 3.4417)
			(end -2.6289 1.4732)
			(stroke
				(width 0.381)
				(type default)
			)
			(layer "F.SilkS")
		)
		(fp_line
			(start -2.1844 -0.0508)
			(end -2.7178 0.508)
			(stroke
				(width 0.1524)
				(type default)
			)
			(layer "F.SilkS")
		)
		(fp_line
			(start 2.1336 -1.4224)
			(end -2.7432 -1.4224)
			(stroke
				(width 0.1524)
				(type default)
			)
			(layer "F.SilkS")
		)
		(fp_line
			(start 2.1336 1.4224)
			(end 2.1336 -1.4224)
			(stroke
				(width 0.1524)
				(type default)
			)
			(layer "F.SilkS")
		)
		(fp_poly
			(pts
				(xy -2.2098 -1.4224) (xy -2.2098 1.4224) (xy 2.2098 1.4224) (xy 2.2098 -1.4224)
			)
			(stroke
				(width 0)
				(type default)
			)
			(fill yes)
			(layer "F.SilkS")
		)
		(fp_rect
			(start -2.450084 2.999994)
			(end 2.450084 -2.999994)
			(stroke
				(width 0)
				(type default)
			)
			(fill no)
			(layer "F.CrtYd")
		)
		(fp_poly
			(pts
				(xy -2.8194 3.6322) (xy -2.8194 -3.6322) (xy 2.8194 -3.6322) (xy 2.8194 1.18364) (xy 2.450084 1.18364)
				(xy 2.450084 -2.999994) (xy -2.450084 -2.999994) (xy -2.450084 2.999994) (xy 2.450084 2.999994)
				(xy 2.450084 1.18618) (xy 2.8194 1.18618) (xy 2.8194 3.6322)
			)
			(stroke
				(width 0)
				(type default)
			)
			(fill no)
			(layer "F.CrtYd")
		)
		(fp_rect
			(start -2.8194 3.6322)
			(end 2.8194 -3.6322)
			(stroke
				(width 0)
				(type default)
			)
			(fill no)
			(layer "F.Fab")
		)
		(pad "1" smd rect
			(at -1.905 2.54)
			(size 0.635 1.651)
			(layers "F.Cu" "F.Mask" "F.Paste")
			(net "P12V_A")
		)
		(pad "2" smd rect
			(at -0.635 2.54)
			(size 0.635 1.651)
			(layers "F.Cu" "F.Mask" "F.Paste")
			(net "P12V_A")
		)
		(pad "3" smd rect
			(at 0.635 2.54)
			(size 0.635 1.651)
			(layers "F.Cu" "F.Mask" "F.Paste")
			(net "P12V_A")
		)
		(pad "4" smd rect
			(at 1.905 2.54)
			(size 0.635 1.651)
			(layers "F.Cu" "F.Mask" "F.Paste")
			(net "SW_HDD_N33")
		)
		(pad "5" smd rect
			(at 1.905 -2.54)
			(size 0.635 1.651)
			(layers "F.Cu" "F.Mask" "F.Paste")
			(net "P12V_HDD33")
		)
		(pad "6" smd rect
			(at 0.635 -2.54)
			(size 0.635 1.651)
			(layers "F.Cu" "F.Mask" "F.Paste")
			(net "P12V_HDD33")
		)
		(pad "7" smd rect
			(at -0.635 -2.54)
			(size 0.635 1.651)
			(layers "F.Cu" "F.Mask" "F.Paste")
			(net "P12V_HDD33")
		)
		(pad "8" smd rect
			(at -1.905 -2.54)
			(size 0.635 1.651)
			(layers "F.Cu" "F.Mask" "F.Paste")
			(net "P12V_HDD33")
		)
	)
	(footprint ""
		(layer "F.Cu")
		(at 318.262 -176.127918 -90)
		(property "Reference" "C279"
			(at 0 0 270)
			(layer "F.SilkS")
			(hide yes)
			(effects
				(font
					(size 1.27 1.27)
				)
			)
		)
		(property "Value" "SCD01U50V2KX-1GP"
			(at 1.1811 -2.7051 270)
			(unlocked yes)
			(layer "F.Fab")
			(hide yes)
			(effects
				(font
					(size 1.016 1.016)
					(thickness 0.1524)
				)
			)
		)
		(property "Device Type" "C402H22"
			(at 1.1811 -4.2291 270)
			(unlocked yes)
			(layer "F.Fab")
			(hide yes)
			(effects
				(font
					(size 1.016 1.016)
					(thickness 0.1524)
				)
			)
		)
		(duplicate_pad_numbers_are_jumpers no)
		(fp_rect
			(start -0.4318 0.9525)
			(end 0.4318 -0.9525)
			(stroke
				(width 0)
				(type default)
			)
			(fill no)
			(layer "F.CrtYd")
		)
		(fp_rect
			(start -0.4318 0.9525)
			(end 0.4318 -0.9525)
			(stroke
				(width 0)
				(type default)
			)
			(fill no)
			(layer "F.Fab")
		)
		(pad "1" smd custom
			(at 0 -0.4445 270)
			(size 0.1524 0.1524)
			(layers "F.Cu" "F.Mask" "F.Paste")
			(net "HDD_PRSNT_18")
			(options
				(clearance outline)
				(anchor circle)
			)
			(primitives
				(gr_poly
					(pts
						(arc
							(start 0.3048 -0.2032)
							(mid 0.275042 -0.275042)
							(end 0.2032 -0.3048)
						)
						(arc
							(start -0.2032 -0.3048)
							(mid -0.275042 -0.275042)
							(end -0.3048 -0.2032)
						)
						(arc
							(start -0.3048 0.2032)
							(mid -0.275042 0.275042)
							(end -0.2032 0.3048)
						)
						(arc
							(start 0.2032 0.3048)
							(mid 0.275042 0.275042)
							(end 0.3048 0.2032)
						)
					)
					(width 0)
					(fill yes)
				)
			)
		)
		(pad "2" smd custom
			(at 0 0.4445 270)
			(size 0.1524 0.1524)
			(layers "F.Cu" "F.Mask" "F.Paste")
			(net "GND")
			(options
				(clearance outline)
				(anchor circle)
			)
			(primitives
				(gr_poly
					(pts
						(arc
							(start 0.3048 -0.2032)
							(mid 0.275042 -0.275042)
							(end 0.2032 -0.3048)
						)
						(arc
							(start -0.2032 -0.3048)
							(mid -0.275042 -0.275042)
							(end -0.3048 -0.2032)
						)
						(arc
							(start -0.3048 0.2032)
							(mid -0.275042 0.275042)
							(end -0.2032 0.3048)
						)
						(arc
							(start 0.2032 0.3048)
							(mid 0.275042 0.275042)
							(end 0.3048 0.2032)
						)
					)
					(width 0)
					(fill yes)
				)
			)
		)
	)
	(footprint ""
		(layer "F.Cu")
		(at 83.530948 -48.554894 180)
		(property "Reference" "Q157"
			(at 0 0 180)
			(layer "F.SilkS")
			(hide yes)
			(effects
				(font
					(size 1.27 1.27)
				)
			)
		)
		(property "Value" "2N7002KDW-GP"
			(at -2.3622 -8.2042 180)
			(unlocked yes)
			(layer "F.Fab")
			(hide yes)
			(effects
				(font
					(size 1.016 1.016)
					(thickness 0.1524)
				)
			)
		)
		(property "Device Type" "SOT-363H44"
			(at -2.3622 -10.1092 180)
			(unlocked yes)
			(layer "F.Fab")
			(hide yes)
			(effects
				(font
					(size 1.016 1.016)
					(thickness 0.1524)
				)
			)
		)
		(duplicate_pad_numbers_are_jumpers no)
		(fp_line
			(start 1.4478 1.7018)
			(end 1.4478 -1.7018)
			(stroke
				(width 0.1524)
				(type default)
			)
			(layer "F.SilkS")
		)
		(fp_line
			(start 1.4478 -1.7018)
			(end -1.4478 -1.7018)
			(stroke
				(width 0.1524)
				(type default)
			)
			(layer "F.SilkS")
		)
		(fp_line
			(start -1.27 1.524)
			(end -1.27 0.6604)
			(stroke
				(width 0.4826)
				(type default)
			)
			(layer "F.SilkS")
		)
		(fp_line
			(start -1.4478 1.7018)
			(end 1.4478 1.7018)
			(stroke
				(width 0.1524)
				(type default)
			)
			(layer "F.SilkS")
		)
		(fp_line
			(start -1.4478 -1.7018)
			(end -1.4478 1.7018)
			(stroke
				(width 0.1524)
				(type default)
			)
			(layer "F.SilkS")
		)
		(fp_poly
			(pts
				(xy -1.524 -1.778) (xy 1.524 -1.778) (xy 1.524 1.778) (xy -1.524 1.778)
			)
			(stroke
				(width 0)
				(type default)
			)
			(fill no)
			(layer "F.CrtYd")
		)
		(fp_poly
			(pts
				(xy -1.524 -1.778) (xy 1.524 -1.778) (xy 1.524 1.778) (xy -1.524 1.778)
			)
			(stroke
				(width 0)
				(type default)
			)
			(fill no)
			(layer "F.Fab")
		)
		(pad "1" smd rect
			(at -0.65024 0.9398 180)
			(size 0.4064 1.016)
			(layers "F.Cu" "F.Mask" "F.Paste")
			(net "GND")
		)
		(pad "2" smd rect
			(at 0 0.9398 180)
			(size 0.4064 1.016)
			(layers "F.Cu" "F.Mask" "F.Paste")
			(net "SW_PWR_R_HDD26")
		)
		(pad "3" smd rect
			(at 0.65024 0.9398 180)
			(size 0.4064 1.016)
			(layers "F.Cu" "F.Mask" "F.Paste")
			(net "SW_HDD_P26")
		)
		(pad "4" smd rect
			(at 0.65024 -0.9398 180)
			(size 0.4064 1.016)
			(layers "F.Cu" "F.Mask" "F.Paste")
			(net "GND")
		)
		(pad "5" smd rect
			(at 0 -0.9398 180)
			(size 0.4064 1.016)
			(layers "F.Cu" "F.Mask" "F.Paste")
			(net "SW_HDD_G26")
		)
		(pad "6" smd rect
			(at -0.65024 -0.9398 180)
			(size 0.4064 1.016)
			(layers "F.Cu" "F.Mask" "F.Paste")
			(net "SW_HDD_R26")
		)
	)
	(footprint ""
		(layer "F.Cu")
		(at 95.563436 -43.660568 90)
		(property "Reference" "C377"
			(at 0 0 90)
			(layer "F.SilkS")
			(hide yes)
			(effects
				(font
					(size 1.27 1.27)
				)
			)
		)
		(property "Value" "SCD01U16V1KX-GP"
			(at -2.8321 -1.7399 90)
			(unlocked yes)
			(layer "F.Fab")
			(hide yes)
			(effects
				(font
					(size 1.016 1.016)
					(thickness 0.1524)
				)
			)
		)
		(property "Device Type" "C0201H13"
			(at -2.8321 -3.2639 90)
			(unlocked yes)
			(layer "F.Fab")
			(hide yes)
			(effects
				(font
					(size 1.016 1.016)
					(thickness 0.1524)
				)
			)
		)
		(duplicate_pad_numbers_are_jumpers no)
		(fp_rect
			(start -0.2794 0.6477)
			(end 0.2794 -0.6477)
			(stroke
				(width 0)
				(type default)
			)
			(fill no)
			(layer "F.CrtYd")
		)
		(fp_rect
			(start -0.2794 0.6477)
			(end 0.2794 -0.6477)
			(stroke
				(width 0)
				(type default)
			)
			(fill no)
			(layer "F.Fab")
		)
		(pad "1" smd custom
			(at 0 -0.2794 90)
			(size 0.0762 0.0762)
			(layers "F.Cu" "F.Mask" "F.Paste")
			(net "SAS_HDD_RX_P26")
			(options
				(clearance outline)
				(anchor circle)
			)
			(primitives
				(gr_poly
					(pts
						(arc
							(start 0.1524 -0.127)
							(mid 0.137521 -0.162921)
							(end 0.1016 -0.1778)
						)
						(arc
							(start -0.1016 -0.1778)
							(mid -0.137521 -0.162921)
							(end -0.1524 -0.127)
						)
						(arc
							(start -0.1524 0.127)
							(mid -0.137521 0.162921)
							(end -0.1016 0.1778)
						)
						(arc
							(start 0.1016 0.1778)
							(mid 0.137521 0.162921)
							(end 0.1524 0.127)
						)
					)
					(width 0)
					(fill yes)
				)
			)
		)
		(pad "2" smd custom
			(at 0 0.2794 90)
			(size 0.0762 0.0762)
			(layers "F.Cu" "F.Mask" "F.Paste")
			(net "PHY_SCC_A_TO_DRV_A_26_DP")
			(options
				(clearance outline)
				(anchor circle)
			)
			(primitives
				(gr_poly
					(pts
						(arc
							(start 0.1524 -0.127)
							(mid 0.137521 -0.162921)
							(end 0.1016 -0.1778)
						)
						(arc
							(start -0.1016 -0.1778)
							(mid -0.137521 -0.162921)
							(end -0.1524 -0.127)
						)
						(arc
							(start -0.1524 0.127)
							(mid -0.137521 0.162921)
							(end -0.1016 0.1778)
						)
						(arc
							(start 0.1016 0.1778)
							(mid 0.137521 0.162921)
							(end 0.1524 0.127)
						)
					)
					(width 0)
					(fill yes)
				)
			)
		)
	)
	(footprint ""
		(layer "F.Cu")
		(at 471.955114 -279.091898 90)
		(property "Reference" "R390"
			(at 0 0 90)
			(layer "F.SilkS")
			(hide yes)
			(effects
				(font
					(size 1.27 1.27)
				)
			)
		)
		(property "Value" "4K7R2J-2-GP"
			(at 0.064008 -3.993896 90)
			(unlocked yes)
			(layer "F.Fab")
			(hide yes)
			(effects
				(font
					(size 1.016 1.016)
					(thickness 0.1524)
				)
			)
		)
		(property "Device Type" "R402H16"
			(at 0.064008 -5.517896 90)
			(unlocked yes)
			(layer "F.Fab")
			(hide yes)
			(effects
				(font
					(size 1.016 1.016)
					(thickness 0.1524)
				)
			)
		)
		(duplicate_pad_numbers_are_jumpers no)
		(fp_line
			(start 0.508 -0.9398)
			(end -0.508 -0.9398)
			(stroke
				(width 0.1524)
				(type default)
			)
			(layer "F.SilkS")
		)
		(fp_line
			(start -0.508 -0.9398)
			(end -0.508 0.9398)
			(stroke
				(width 0.1524)
				(type default)
			)
			(layer "F.SilkS")
		)
		(fp_rect
			(start -0.508 0.9398)
			(end 0.508 -0.9398)
			(stroke
				(width 0)
				(type default)
			)
			(fill no)
			(layer "F.CrtYd")
		)
		(fp_rect
			(start -0.508 0.9398)
			(end 0.508 -0.9398)
			(stroke
				(width 0)
				(type default)
			)
			(fill no)
			(layer "F.Fab")
		)
		(pad "1" smd custom
			(at 0 -0.4445 90)
			(size 0.1397 0.1397)
			(layers "F.Cu" "F.Mask" "F.Paste")
			(net "P12V_A")
			(options
				(clearance outline)
				(anchor circle)
			)
			(primitives
				(gr_poly
					(pts
						(arc
							(start -0.1778 -0.2794)
							(mid -0.249642 -0.249642)
							(end -0.2794 -0.1778)
						)
						(arc
							(start -0.2794 0.1778)
							(mid -0.249642 0.249642)
							(end -0.1778 0.2794)
						)
						(arc
							(start 0.1778 0.2794)
							(mid 0.249642 0.249642)
							(end 0.2794 0.1778)
						)
						(arc
							(start 0.2794 -0.1778)
							(mid 0.249642 -0.249642)
							(end 0.1778 -0.2794)
						)
					)
					(width 0)
					(fill yes)
				)
			)
		)
		(pad "2" smd custom
			(at 0 0.4445 90)
			(size 0.1397 0.1397)
			(layers "F.Cu" "F.Mask" "F.Paste")
			(net "SW_HDD_P11")
			(options
				(clearance outline)
				(anchor circle)
			)
			(primitives
				(gr_poly
					(pts
						(arc
							(start -0.1778 -0.2794)
							(mid -0.249642 -0.249642)
							(end -0.2794 -0.1778)
						)
						(arc
							(start -0.2794 0.1778)
							(mid -0.249642 0.249642)
							(end -0.1778 0.2794)
						)
						(arc
							(start 0.1778 0.2794)
							(mid 0.249642 0.249642)
							(end 0.2794 0.1778)
						)
						(arc
							(start 0.2794 -0.1778)
							(mid 0.249642 -0.249642)
							(end 0.1778 -0.2794)
						)
					)
					(width 0)
					(fill yes)
				)
			)
		)
	)
	(footprint ""
		(layer "F.Cu")
		(at 458.9399 -278.554942 -90)
		(property "Reference" "R367"
			(at 0 0 270)
			(layer "F.SilkS")
			(hide yes)
			(effects
				(font
					(size 1.27 1.27)
				)
			)
		)
		(property "Value" "4K7R2J-2-GP"
			(at 0.064008 -3.993896 270)
			(unlocked yes)
			(layer "F.Fab")
			(hide yes)
			(effects
				(font
					(size 1.016 1.016)
					(thickness 0.1524)
				)
			)
		)
		(property "Device Type" "R402H16"
			(at 0.064008 -5.517896 270)
			(unlocked yes)
			(layer "F.Fab")
			(hide yes)
			(effects
				(font
					(size 1.016 1.016)
					(thickness 0.1524)
				)
			)
		)
		(duplicate_pad_numbers_are_jumpers no)
		(fp_line
			(start -0.508 -0.9398)
			(end -0.508 0.9398)
			(stroke
				(width 0.1524)
				(type default)
			)
			(layer "F.SilkS")
		)
		(fp_line
			(start 0.508 -0.9398)
			(end -0.508 -0.9398)
			(stroke
				(width 0.1524)
				(type default)
			)
			(layer "F.SilkS")
		)
		(fp_rect
			(start -0.508 0.9398)
			(end 0.508 -0.9398)
			(stroke
				(width 0)
				(type default)
			)
			(fill no)
			(layer "F.CrtYd")
		)
		(fp_rect
			(start -0.508 0.9398)
			(end 0.508 -0.9398)
			(stroke
				(width 0)
				(type default)
			)
			(fill no)
			(layer "F.Fab")
		)
		(pad "1" smd custom
			(at 0 -0.4445 270)
			(size 0.1397 0.1397)
			(layers "F.Cu" "F.Mask" "F.Paste")
			(net "P12V_A")
			(options
				(clearance outline)
				(anchor circle)
			)
			(primitives
				(gr_poly
					(pts
						(arc
							(start -0.1778 -0.2794)
							(mid -0.249642 -0.249642)
							(end -0.2794 -0.1778)
						)
						(arc
							(start -0.2794 0.1778)
							(mid -0.249642 0.249642)
							(end -0.1778 0.2794)
						)
						(arc
							(start 0.1778 0.2794)
							(mid 0.249642 0.249642)
							(end 0.2794 0.1778)
						)
						(arc
							(start 0.2794 -0.1778)
							(mid 0.249642 -0.249642)
							(end 0.1778 -0.2794)
						)
					)
					(width 0)
					(fill yes)
				)
			)
		)
		(pad "2" smd custom
			(at 0 0.4445 270)
			(size 0.1397 0.1397)
			(layers "F.Cu" "F.Mask" "F.Paste")
			(net "SW_HDD_P10")
			(options
				(clearance outline)
				(anchor circle)
			)
			(primitives
				(gr_poly
					(pts
						(arc
							(start -0.1778 -0.2794)
							(mid -0.249642 -0.249642)
							(end -0.2794 -0.1778)
						)
						(arc
							(start -0.2794 0.1778)
							(mid -0.249642 0.249642)
							(end -0.1778 0.2794)
						)
						(arc
							(start 0.1778 0.2794)
							(mid 0.249642 0.249642)
							(end 0.2794 0.1778)
						)
						(arc
							(start 0.2794 -0.1778)
							(mid 0.249642 -0.249642)
							(end 0.1778 -0.2794)
						)
					)
					(width 0)
					(fill yes)
				)
			)
		)
	)
	(footprint ""
		(layer "F.Cu")
		(at 396.672054 -184.450228 -90)
		(property "Reference" "R591"
			(at 0 0 270)
			(layer "F.SilkS")
			(hide yes)
			(effects
				(font
					(size 1.27 1.27)
				)
			)
		)
		(property "Value" "2R6F-GP"
			(at -0.0508 -4.8514 270)
			(unlocked yes)
			(layer "F.Fab")
			(hide yes)
			(effects
				(font
					(size 1.016 1.016)
					(thickness 0.1524)
				)
			)
		)
		(property "Device Type" "R1206H26"
			(at 0 -6.3754 270)
			(unlocked yes)
			(layer "F.Fab")
			(hide yes)
			(effects
				(font
					(size 1.016 1.016)
					(thickness 0.1524)
				)
			)
		)
		(duplicate_pad_numbers_are_jumpers no)
		(fp_line
			(start -1.016 2.2352)
			(end -1.016 -2.2352)
			(stroke
				(width 0.1524)
				(type default)
			)
			(layer "F.SilkS")
		)
		(fp_line
			(start 1.016 2.2352)
			(end -1.016 2.2352)
			(stroke
				(width 0.1524)
				(type default)
			)
			(layer "F.SilkS")
		)
		(fp_line
			(start -1.016 -2.2352)
			(end 1.016 -2.2352)
			(stroke
				(width 0.1524)
				(type default)
			)
			(layer "F.SilkS")
		)
		(fp_line
			(start 1.016 -2.2352)
			(end 1.016 2.2352)
			(stroke
				(width 0.1524)
				(type default)
			)
			(layer "F.SilkS")
		)
		(fp_rect
			(start -1.0922 2.3114)
			(end 1.0922 -2.3114)
			(stroke
				(width 0)
				(type default)
			)
			(fill no)
			(layer "F.CrtYd")
		)
		(fp_poly
			(pts
				(xy -1.0922 -2.3114) (xy 1.0922 -2.3114) (xy 1.0922 2.3114) (xy -1.0922 2.3114)
			)
			(stroke
				(width 0)
				(type default)
			)
			(fill no)
			(layer "F.Fab")
		)
		(pad "1" smd rect
			(at 0 -1.397 270)
			(size 1.651 1.27)
			(layers "F.Cu" "F.Mask" "F.Paste")
			(net "P12V_HDD20")
		)
		(pad "2" smd rect
			(at 0 1.397 270)
			(size 1.651 1.27)
			(layers "F.Cu" "F.Mask" "F.Paste")
			(net "12V_PRE_20")
		)
	)
	(footprint ""
		(layer "F.Cu")
		(at 323.2531 -46.437042)
		(property "Reference" "VIA70"
			(at 0 0 0)
			(layer "F.SilkS")
			(hide yes)
			(effects
				(font
					(size 1.27 1.27)
				)
			)
		)
		(property "Value" "100OHM-8L-1D6MM-L18L16-GP"
			(at -3.7211 -4.5085 0)
			(unlocked yes)
			(layer "F.Fab")
			(hide yes)
			(effects
				(font
					(size 1.016 1.016)
					(thickness 0.1524)
				)
			)
		)
		(property "Device Type" "VIA-PCIE-4P-394076"
			(at -3.7211 -6.0325 0)
			(unlocked yes)
			(layer "F.Fab")
			(hide yes)
			(effects
				(font
					(size 1.016 1.016)
					(thickness 0.1524)
				)
			)
		)
		(duplicate_pad_numbers_are_jumpers no)
		(fp_rect
			(start -1.9685 0.381)
			(end 1.9685 -0.381)
			(stroke
				(width 0)
				(type default)
			)
			(fill no)
			(layer "F.CrtYd")
		)
		(fp_rect
			(start -1.9685 0.381)
			(end 1.9685 -0.381)
			(stroke
				(width 0)
				(type default)
			)
			(fill no)
			(layer "F.Fab")
		)
		(pad "1" thru_hole circle
			(at -1.5875 0)
			(size 0.508 0.508)
			(drill 0.254)
			(layers "*.Cu" "*.Mask")
			(remove_unused_layers no)
			(net "GND")
			(clearance 0.127)
			(thermal_gap 0.127)
		)
		(pad "2" thru_hole circle
			(at -0.5715 0)
			(size 0.508 0.508)
			(drill 0.254)
			(layers "*.Cu" "*.Mask")
			(remove_unused_layers no)
			(net "PHY_DRV_A_TO_SCC_A_30_DP")
			(clearance 0.127)
			(thermal_gap 0.127)
		)
		(pad "3" thru_hole circle
			(at 0.5715 0)
			(size 0.508 0.508)
			(drill 0.254)
			(layers "*.Cu" "*.Mask")
			(remove_unused_layers no)
			(net "PHY_DRV_A_TO_SCC_A_30_DN")
			(clearance 0.127)
			(thermal_gap 0.127)
		)
		(pad "4" thru_hole circle
			(at 1.5875 0)
			(size 0.508 0.508)
			(drill 0.254)
			(layers "*.Cu" "*.Mask")
			(remove_unused_layers no)
			(net "GND")
			(clearance 0.127)
			(thermal_gap 0.127)
		)
	)
	(footprint ""
		(layer "F.Cu")
		(at 133.497066 -137.993374)
		(property "Reference" "R1006"
			(at 0 0 0)
			(layer "F.SilkS")
			(hide yes)
			(effects
				(font
					(size 1.27 1.27)
				)
			)
		)
		(property "Value" "100KR2F-L1-GP"
			(at 0.064008 -3.993896 0)
			(unlocked yes)
			(layer "F.Fab")
			(hide yes)
			(effects
				(font
					(size 1.016 1.016)
					(thickness 0.1524)
				)
			)
		)
		(property "Device Type" "R402H16"
			(at 0.064008 -5.517896 0)
			(unlocked yes)
			(layer "F.Fab")
			(hide yes)
			(effects
				(font
					(size 1.016 1.016)
					(thickness 0.1524)
				)
			)
		)
		(duplicate_pad_numbers_are_jumpers no)
		(fp_line
			(start -0.508 -0.9398)
			(end -0.508 0.9398)
			(stroke
				(width 0.1524)
				(type default)
			)
			(layer "F.SilkS")
		)
		(fp_line
			(start 0.508 -0.9398)
			(end -0.508 -0.9398)
			(stroke
				(width 0.1524)
				(type default)
			)
			(layer "F.SilkS")
		)
		(fp_rect
			(start -0.508 0.9398)
			(end 0.508 -0.9398)
			(stroke
				(width 0)
				(type default)
			)
			(fill no)
			(layer "F.CrtYd")
		)
		(fp_rect
			(start -0.508 0.9398)
			(end 0.508 -0.9398)
			(stroke
				(width 0)
				(type default)
			)
			(fill no)
			(layer "F.Fab")
		)
		(pad "1" smd custom
			(at 0 -0.4445)
			(size 0.1397 0.1397)
			(layers "F.Cu" "F.Mask" "F.Paste")
			(net "COMP_A_PWR_EN")
			(options
				(clearance outline)
				(anchor circle)
			)
			(primitives
				(gr_poly
					(pts
						(arc
							(start -0.1778 -0.2794)
							(mid -0.249642 -0.249642)
							(end -0.2794 -0.1778)
						)
						(arc
							(start -0.2794 0.1778)
							(mid -0.249642 0.249642)
							(end -0.1778 0.2794)
						)
						(arc
							(start 0.1778 0.2794)
							(mid 0.249642 0.249642)
							(end 0.2794 0.1778)
						)
						(arc
							(start 0.2794 -0.1778)
							(mid 0.249642 -0.249642)
							(end 0.1778 -0.2794)
						)
					)
					(width 0)
					(fill yes)
				)
			)
		)
		(pad "2" smd custom
			(at 0 0.4445)
			(size 0.1397 0.1397)
			(layers "F.Cu" "F.Mask" "F.Paste")
			(net "GND")
			(options
				(clearance outline)
				(anchor circle)
			)
			(primitives
				(gr_poly
					(pts
						(arc
							(start -0.1778 -0.2794)
							(mid -0.249642 -0.249642)
							(end -0.2794 -0.1778)
						)
						(arc
							(start -0.2794 0.1778)
							(mid -0.249642 0.249642)
							(end -0.1778 0.2794)
						)
						(arc
							(start 0.1778 0.2794)
							(mid 0.249642 0.249642)
							(end 0.2794 0.1778)
						)
						(arc
							(start 0.2794 -0.1778)
							(mid 0.249642 -0.249642)
							(end 0.1778 -0.2794)
						)
					)
					(width 0)
					(fill yes)
				)
			)
		)
	)
	(footprint ""
		(layer "F.Cu")
		(at 300.19498 -243.19992)
		(property "Reference" ""
			(at 0 0 0)
			(layer "F.SilkS")
			(hide yes)
			(effects
				(font
					(size 1.27 1.27)
				)
			)
		)
		(property "Value" "*"
			(at -8.398764 -8.057642 0)
			(unlocked yes)
			(layer "F.Fab")
			(hide yes)
			(effects
				(font
					(size 1.016 1.016)
					(thickness 0.1524)
				)
			)
		)
		(duplicate_pad_numbers_are_jumpers no)
		(fp_poly
			(pts
				(arc
					(start 7.3152 0)
					(mid 0 7.3152)
					(end -7.3152 0)
				)
				(arc
					(start -7.3152 -5.9944)
					(mid 0 -13.3096)
					(end 7.3152 -5.9944)
				)
			)
			(stroke
				(width 0)
				(type default)
			)
			(fill no)
			(layer "B.CrtYd")
		)
		(fp_poly
			(pts
				(arc
					(start 7.3152 0)
					(mid 0 7.3152)
					(end -7.3152 0)
				)
				(arc
					(start -7.3152 -5.9944)
					(mid 0 -13.3096)
					(end 7.3152 -5.9944)
				)
			)
			(stroke
				(width 0)
				(type default)
			)
			(fill no)
			(layer "F.CrtYd")
		)
		(fp_poly
			(pts
				(arc
					(start 7.3152 0)
					(mid 0 7.3152)
					(end -7.3152 0)
				)
				(arc
					(start -7.3152 -5.9944)
					(mid 0 -13.3096)
					(end 7.3152 -5.9944)
				)
			)
			(stroke
				(width 0)
				(type default)
			)
			(fill no)
			(layer "B.Fab")
		)
		(fp_poly
			(pts
				(arc
					(start 7.3152 0)
					(mid 0 7.3152)
					(end -7.3152 0)
				)
				(arc
					(start -7.3152 -5.9944)
					(mid 0 -13.3096)
					(end 7.3152 -5.9944)
				)
			)
			(stroke
				(width 0)
				(type default)
			)
			(fill no)
			(layer "F.Fab")
		)
		(pad "1" thru_hole oval
			(at 0 0)
			(size 14.0208 20.0152)
			(drill 0.0254
				(offset 0 -2.9972)
			)
			(layers "*.Cu" "*.Mask")
			(remove_unused_layers no)
			(net "Net_64")
			(clearance -1.002284)
			(thermal_gap 0.1524)
			(padstack
				(mode front_inner_back)
				(layer "Inner"
					(shape custom)
					(size 2.928012 2.928012)
					(options
						(anchor circle)
					)
					(primitives
						(gr_poly
							(pts
								(arc
									(start 4.571746 -2.084324)
									(mid 0.000333 7.430372)
									(end -4.571492 -2.084324)
								)
								(arc
									(start -4.571492 -2.084324)
									(mid -3.570296 -3.611977)
									(end -2.875026 -5.30098)
								)
								(arc
									(start -2.875026 -5.30098)
									(mid 0.000217 -7.43089)
									(end 2.87528 -5.30098)
								)
								(arc
									(start 2.87528 -5.30098)
									(mid 3.570511 -3.611956)
									(end 4.571746 -2.084324)
								)
							)
							(width 0)
							(fill yes)
						)
					)
					(clearance 0.1524)
				)
				(layer "B.Cu"
					(shape oval)
					(size 14.0208 20.0152)
					(offset 0 -2.9972)
					(clearance -1.002284)
				)
			)
		)
		(zone
			(layers "F.Cu" "B.Cu" "In1.Cu" "In2.Cu" "In3.Cu" "In4.Cu" "In5.Cu" "In6.Cu"
				"In7.Cu" "In8.Cu" "In9.Cu" "In10.Cu"
			)
			(hatch none 0.5)
			(connect_pads
				(clearance 0)
			)
			(min_thickness 0.25)
			(keepout
				(tracks not_allowed)
				(vias allowed)
				(pads allowed)
				(copperpour not_allowed)
				(footprints allowed)
			)
			(placement
				(enabled no)
				(sheetname "")
			)
			(fill
				(thermal_gap 0.5)
				(thermal_bridge_width 0.5)
				(island_removal_mode 0)
			)
			(polygon
				(pts
					(arc
						(start 293.18458 -249.19432)
						(mid 300.19498 -256.20472)
						(end 307.20538 -249.19432)
					)
					(arc
						(start 307.20538 -243.19992)
						(mid 300.19498 -236.18952)
						(end 293.18458 -243.19992)
					)
				)
			)
		)
	)
	(footprint ""
		(layer "F.Cu")
		(at 15.223998 -277.157942 180)
		(property "Reference" "R974"
			(at 0 0 180)
			(layer "F.SilkS")
			(hide yes)
			(effects
				(font
					(size 1.27 1.27)
				)
			)
		)
		(property "Value" "200KR2F-L-GP"
			(at 0.064008 -3.993896 180)
			(unlocked yes)
			(layer "F.Fab")
			(hide yes)
			(effects
				(font
					(size 1.016 1.016)
					(thickness 0.1524)
				)
			)
		)
		(property "Device Type" "R402H16"
			(at 0.064008 -5.517896 180)
			(unlocked yes)
			(layer "F.Fab")
			(hide yes)
			(effects
				(font
					(size 1.016 1.016)
					(thickness 0.1524)
				)
			)
		)
		(duplicate_pad_numbers_are_jumpers no)
		(fp_line
			(start 0.508 -0.9398)
			(end -0.508 -0.9398)
			(stroke
				(width 0.1524)
				(type default)
			)
			(layer "F.SilkS")
		)
		(fp_line
			(start -0.508 -0.9398)
			(end -0.508 0.9398)
			(stroke
				(width 0.1524)
				(type default)
			)
			(layer "F.SilkS")
		)
		(fp_rect
			(start -0.508 0.9398)
			(end 0.508 -0.9398)
			(stroke
				(width 0)
				(type default)
			)
			(fill no)
			(layer "F.CrtYd")
		)
		(fp_rect
			(start -0.508 0.9398)
			(end 0.508 -0.9398)
			(stroke
				(width 0)
				(type default)
			)
			(fill no)
			(layer "F.Fab")
		)
		(pad "1" smd custom
			(at 0 -0.4445 180)
			(size 0.1397 0.1397)
			(layers "F.Cu" "F.Mask" "F.Paste")
			(net "SW_HDD_R0")
			(options
				(clearance outline)
				(anchor circle)
			)
			(primitives
				(gr_poly
					(pts
						(arc
							(start -0.1778 -0.2794)
							(mid -0.249642 -0.249642)
							(end -0.2794 -0.1778)
						)
						(arc
							(start -0.2794 0.1778)
							(mid -0.249642 0.249642)
							(end -0.1778 0.2794)
						)
						(arc
							(start 0.1778 0.2794)
							(mid 0.249642 0.249642)
							(end 0.2794 0.1778)
						)
						(arc
							(start 0.2794 -0.1778)
							(mid 0.249642 -0.249642)
							(end 0.1778 -0.2794)
						)
					)
					(width 0)
					(fill yes)
				)
			)
		)
		(pad "2" smd custom
			(at 0 0.4445 180)
			(size 0.1397 0.1397)
			(layers "F.Cu" "F.Mask" "F.Paste")
			(net "SW_HDD_N0")
			(options
				(clearance outline)
				(anchor circle)
			)
			(primitives
				(gr_poly
					(pts
						(arc
							(start -0.1778 -0.2794)
							(mid -0.249642 -0.249642)
							(end -0.2794 -0.1778)
						)
						(arc
							(start -0.2794 0.1778)
							(mid -0.249642 0.249642)
							(end -0.1778 0.2794)
						)
						(arc
							(start 0.1778 0.2794)
							(mid 0.249642 0.249642)
							(end 0.2794 0.1778)
						)
						(arc
							(start 0.2794 -0.1778)
							(mid 0.249642 -0.249642)
							(end 0.1778 -0.2794)
						)
					)
					(width 0)
					(fill yes)
				)
			)
		)
	)
	(footprint ""
		(layer "F.Cu")
		(at 447.834512 -273.660616 -90)
		(property "Reference" "C169"
			(at 0 0 270)
			(layer "F.SilkS")
			(hide yes)
			(effects
				(font
					(size 1.27 1.27)
				)
			)
		)
		(property "Value" "SCD01U16V1KX-GP"
			(at -2.8321 -1.7399 270)
			(unlocked yes)
			(layer "F.Fab")
			(hide yes)
			(effects
				(font
					(size 1.016 1.016)
					(thickness 0.1524)
				)
			)
		)
		(property "Device Type" "C0201H13"
			(at -2.8321 -3.2639 270)
			(unlocked yes)
			(layer "F.Fab")
			(hide yes)
			(effects
				(font
					(size 1.016 1.016)
					(thickness 0.1524)
				)
			)
		)
		(duplicate_pad_numbers_are_jumpers no)
		(fp_rect
			(start -0.2794 0.6477)
			(end 0.2794 -0.6477)
			(stroke
				(width 0)
				(type default)
			)
			(fill no)
			(layer "F.CrtYd")
		)
		(fp_rect
			(start -0.2794 0.6477)
			(end 0.2794 -0.6477)
			(stroke
				(width 0)
				(type default)
			)
			(fill no)
			(layer "F.Fab")
		)
		(pad "1" smd custom
			(at 0 -0.2794 270)
			(size 0.0762 0.0762)
			(layers "F.Cu" "F.Mask" "F.Paste")
			(net "SAS_HDD_RX_P10")
			(options
				(clearance outline)
				(anchor circle)
			)
			(primitives
				(gr_poly
					(pts
						(arc
							(start 0.1524 -0.127)
							(mid 0.137521 -0.162921)
							(end 0.1016 -0.1778)
						)
						(arc
							(start -0.1016 -0.1778)
							(mid -0.137521 -0.162921)
							(end -0.1524 -0.127)
						)
						(arc
							(start -0.1524 0.127)
							(mid -0.137521 0.162921)
							(end -0.1016 0.1778)
						)
						(arc
							(start 0.1016 0.1778)
							(mid 0.137521 0.162921)
							(end 0.1524 0.127)
						)
					)
					(width 0)
					(fill yes)
				)
			)
		)
		(pad "2" smd custom
			(at 0 0.2794 270)
			(size 0.0762 0.0762)
			(layers "F.Cu" "F.Mask" "F.Paste")
			(net "PHY_SCC_A_TO_DRV_A_10_DP")
			(options
				(clearance outline)
				(anchor circle)
			)
			(primitives
				(gr_poly
					(pts
						(arc
							(start 0.1524 -0.127)
							(mid 0.137521 -0.162921)
							(end 0.1016 -0.1778)
						)
						(arc
							(start -0.1016 -0.1778)
							(mid -0.137521 -0.162921)
							(end -0.1524 -0.127)
						)
						(arc
							(start -0.1524 0.127)
							(mid -0.137521 0.162921)
							(end -0.1016 0.1778)
						)
						(arc
							(start 0.1016 0.1778)
							(mid 0.137521 0.162921)
							(end 0.1524 0.127)
						)
					)
					(width 0)
					(fill yes)
				)
			)
		)
	)
	(footprint ""
		(layer "F.Cu")
		(at 161.997898 -62.169294 -90)
		(property "Reference" "R774"
			(at 0 0 270)
			(layer "F.SilkS")
			(hide yes)
			(effects
				(font
					(size 1.27 1.27)
				)
			)
		)
		(property "Value" "10KR2F-2-GP"
			(at 0.064008 -3.993896 270)
			(unlocked yes)
			(layer "F.Fab")
			(hide yes)
			(effects
				(font
					(size 1.016 1.016)
					(thickness 0.1524)
				)
			)
		)
		(property "Device Type" "R402H16"
			(at 0.064008 -5.517896 270)
			(unlocked yes)
			(layer "F.Fab")
			(hide yes)
			(effects
				(font
					(size 1.016 1.016)
					(thickness 0.1524)
				)
			)
		)
		(duplicate_pad_numbers_are_jumpers no)
		(fp_line
			(start -0.508 -0.9398)
			(end -0.508 0.9398)
			(stroke
				(width 0.1524)
				(type default)
			)
			(layer "F.SilkS")
		)
		(fp_line
			(start 0.508 -0.9398)
			(end -0.508 -0.9398)
			(stroke
				(width 0.1524)
				(type default)
			)
			(layer "F.SilkS")
		)
		(fp_rect
			(start -0.508 0.9398)
			(end 0.508 -0.9398)
			(stroke
				(width 0)
				(type default)
			)
			(fill no)
			(layer "F.CrtYd")
		)
		(fp_rect
			(start -0.508 0.9398)
			(end 0.508 -0.9398)
			(stroke
				(width 0)
				(type default)
			)
			(fill no)
			(layer "F.Fab")
		)
		(pad "1" smd custom
			(at 0 -0.4445 270)
			(size 0.1397 0.1397)
			(layers "F.Cu" "F.Mask" "F.Paste")
			(net "P3V3_STBY_A")
			(options
				(clearance outline)
				(anchor circle)
			)
			(primitives
				(gr_poly
					(pts
						(arc
							(start -0.1778 -0.2794)
							(mid -0.249642 -0.249642)
							(end -0.2794 -0.1778)
						)
						(arc
							(start -0.2794 0.1778)
							(mid -0.249642 0.249642)
							(end -0.1778 0.2794)
						)
						(arc
							(start 0.1778 0.2794)
							(mid 0.249642 0.249642)
							(end 0.2794 0.1778)
						)
						(arc
							(start 0.2794 -0.1778)
							(mid 0.249642 -0.249642)
							(end 0.1778 -0.2794)
						)
					)
					(width 0)
					(fill yes)
				)
			)
		)
		(pad "2" smd custom
			(at 0 0.4445 270)
			(size 0.1397 0.1397)
			(layers "F.Cu" "F.Mask" "F.Paste")
			(net "HDD_PRSNT_28")
			(options
				(clearance outline)
				(anchor circle)
			)
			(primitives
				(gr_poly
					(pts
						(arc
							(start -0.1778 -0.2794)
							(mid -0.249642 -0.249642)
							(end -0.2794 -0.1778)
						)
						(arc
							(start -0.2794 0.1778)
							(mid -0.249642 0.249642)
							(end -0.1778 0.2794)
						)
						(arc
							(start 0.1778 0.2794)
							(mid 0.249642 0.249642)
							(end 0.2794 0.1778)
						)
						(arc
							(start 0.2794 -0.1778)
							(mid 0.249642 -0.249642)
							(end 0.1778 -0.2794)
						)
					)
					(width 0)
					(fill yes)
				)
			)
		)
	)
	(footprint ""
		(layer "F.Cu")
		(at 433.359052 -56.809894 -90)
		(property "Reference" "R903"
			(at 0 0 270)
			(layer "F.SilkS")
			(hide yes)
			(effects
				(font
					(size 1.27 1.27)
				)
			)
		)
		(property "Value" "300KR2F-GP"
			(at 0.064008 -3.993896 270)
			(unlocked yes)
			(layer "F.Fab")
			(hide yes)
			(effects
				(font
					(size 1.016 1.016)
					(thickness 0.1524)
				)
			)
		)
		(property "Device Type" "R402H16"
			(at 0.064008 -5.517896 270)
			(unlocked yes)
			(layer "F.Fab")
			(hide yes)
			(effects
				(font
					(size 1.016 1.016)
					(thickness 0.1524)
				)
			)
		)
		(duplicate_pad_numbers_are_jumpers no)
		(fp_line
			(start -0.508 -0.9398)
			(end -0.508 0.9398)
			(stroke
				(width 0.1524)
				(type default)
			)
			(layer "F.SilkS")
		)
		(fp_line
			(start 0.508 -0.9398)
			(end -0.508 -0.9398)
			(stroke
				(width 0.1524)
				(type default)
			)
			(layer "F.SilkS")
		)
		(fp_rect
			(start -0.508 0.9398)
			(end 0.508 -0.9398)
			(stroke
				(width 0)
				(type default)
			)
			(fill no)
			(layer "F.CrtYd")
		)
		(fp_rect
			(start -0.508 0.9398)
			(end 0.508 -0.9398)
			(stroke
				(width 0)
				(type default)
			)
			(fill no)
			(layer "F.Fab")
		)
		(pad "1" smd custom
			(at 0 -0.4445 270)
			(size 0.1397 0.1397)
			(layers "F.Cu" "F.Mask" "F.Paste")
			(net "SW_HDD_N33")
			(options
				(clearance outline)
				(anchor circle)
			)
			(primitives
				(gr_poly
					(pts
						(arc
							(start -0.1778 -0.2794)
							(mid -0.249642 -0.249642)
							(end -0.2794 -0.1778)
						)
						(arc
							(start -0.2794 0.1778)
							(mid -0.249642 0.249642)
							(end -0.1778 0.2794)
						)
						(arc
							(start 0.1778 0.2794)
							(mid 0.249642 0.249642)
							(end 0.2794 0.1778)
						)
						(arc
							(start 0.2794 -0.1778)
							(mid 0.249642 -0.249642)
							(end 0.1778 -0.2794)
						)
					)
					(width 0)
					(fill yes)
				)
			)
		)
		(pad "2" smd custom
			(at 0 0.4445 270)
			(size 0.1397 0.1397)
			(layers "F.Cu" "F.Mask" "F.Paste")
			(net "P12V_A")
			(options
				(clearance outline)
				(anchor circle)
			)
			(primitives
				(gr_poly
					(pts
						(arc
							(start -0.1778 -0.2794)
							(mid -0.249642 -0.249642)
							(end -0.2794 -0.1778)
						)
						(arc
							(start -0.2794 0.1778)
							(mid -0.249642 0.249642)
							(end -0.1778 0.2794)
						)
						(arc
							(start 0.1778 0.2794)
							(mid 0.249642 0.249642)
							(end 0.2794 0.1778)
						)
						(arc
							(start 0.2794 -0.1778)
							(mid 0.249642 -0.249642)
							(end 0.1778 -0.2794)
						)
					)
					(width 0)
					(fill yes)
				)
			)
		)
	)
	(footprint ""
		(layer "F.Cu")
		(at 180.7464 -278.554942 90)
		(property "Reference" "R258"
			(at 0 0 90)
			(layer "F.SilkS")
			(hide yes)
			(effects
				(font
					(size 1.27 1.27)
				)
			)
		)
		(property "Value" "4K7R2J-2-GP"
			(at 0.064008 -3.993896 90)
			(unlocked yes)
			(layer "F.Fab")
			(hide yes)
			(effects
				(font
					(size 1.016 1.016)
					(thickness 0.1524)
				)
			)
		)
		(property "Device Type" "R402H16"
			(at 0.064008 -5.517896 90)
			(unlocked yes)
			(layer "F.Fab")
			(hide yes)
			(effects
				(font
					(size 1.016 1.016)
					(thickness 0.1524)
				)
			)
		)
		(duplicate_pad_numbers_are_jumpers no)
		(fp_line
			(start 0.508 -0.9398)
			(end -0.508 -0.9398)
			(stroke
				(width 0.1524)
				(type default)
			)
			(layer "F.SilkS")
		)
		(fp_line
			(start -0.508 -0.9398)
			(end -0.508 0.9398)
			(stroke
				(width 0.1524)
				(type default)
			)
			(layer "F.SilkS")
		)
		(fp_rect
			(start -0.508 0.9398)
			(end 0.508 -0.9398)
			(stroke
				(width 0)
				(type default)
			)
			(fill no)
			(layer "F.CrtYd")
		)
		(fp_rect
			(start -0.508 0.9398)
			(end 0.508 -0.9398)
			(stroke
				(width 0)
				(type default)
			)
			(fill no)
			(layer "F.Fab")
		)
		(pad "1" smd custom
			(at 0 -0.4445 90)
			(size 0.1397 0.1397)
			(layers "F.Cu" "F.Mask" "F.Paste")
			(net "SW_PWR_R_HDD5")
			(options
				(clearance outline)
				(anchor circle)
			)
			(primitives
				(gr_poly
					(pts
						(arc
							(start -0.1778 -0.2794)
							(mid -0.249642 -0.249642)
							(end -0.2794 -0.1778)
						)
						(arc
							(start -0.2794 0.1778)
							(mid -0.249642 0.249642)
							(end -0.1778 0.2794)
						)
						(arc
							(start 0.1778 0.2794)
							(mid 0.249642 0.249642)
							(end 0.2794 0.1778)
						)
						(arc
							(start 0.2794 -0.1778)
							(mid 0.249642 -0.249642)
							(end 0.1778 -0.2794)
						)
					)
					(width 0)
					(fill yes)
				)
			)
		)
		(pad "2" smd custom
			(at 0 0.4445 90)
			(size 0.1397 0.1397)
			(layers "F.Cu" "F.Mask" "F.Paste")
			(net "GND")
			(options
				(clearance outline)
				(anchor circle)
			)
			(primitives
				(gr_poly
					(pts
						(arc
							(start -0.1778 -0.2794)
							(mid -0.249642 -0.249642)
							(end -0.2794 -0.1778)
						)
						(arc
							(start -0.2794 0.1778)
							(mid -0.249642 0.249642)
							(end -0.1778 0.2794)
						)
						(arc
							(start 0.1778 0.2794)
							(mid 0.249642 0.249642)
							(end 0.2794 0.1778)
						)
						(arc
							(start 0.2794 -0.1778)
							(mid 0.249642 -0.249642)
							(end 0.1778 -0.2794)
						)
					)
					(width 0)
					(fill yes)
				)
			)
		)
	)
	(footprint ""
		(layer "F.Cu")
		(at 111.473996 -53.126894 -90)
		(property "Reference" "C399"
			(at 0 0 270)
			(layer "F.SilkS")
			(hide yes)
			(effects
				(font
					(size 1.27 1.27)
				)
			)
		)
		(property "Value" "SCD033U25V2KX-GP"
			(at 1.1811 -2.7051 270)
			(unlocked yes)
			(layer "F.Fab")
			(hide yes)
			(effects
				(font
					(size 1.016 1.016)
					(thickness 0.1524)
				)
			)
		)
		(property "Device Type" "C402H22"
			(at 1.1811 -4.2291 270)
			(unlocked yes)
			(layer "F.Fab")
			(hide yes)
			(effects
				(font
					(size 1.016 1.016)
					(thickness 0.1524)
				)
			)
		)
		(duplicate_pad_numbers_are_jumpers no)
		(fp_rect
			(start -0.4318 0.9525)
			(end 0.4318 -0.9525)
			(stroke
				(width 0)
				(type default)
			)
			(fill no)
			(layer "F.CrtYd")
		)
		(fp_rect
			(start -0.4318 0.9525)
			(end 0.4318 -0.9525)
			(stroke
				(width 0)
				(type default)
			)
			(fill no)
			(layer "F.Fab")
		)
		(pad "1" smd custom
			(at 0 -0.4445 270)
			(size 0.1524 0.1524)
			(layers "F.Cu" "F.Mask" "F.Paste")
			(net "SW_HDD_P27")
			(options
				(clearance outline)
				(anchor circle)
			)
			(primitives
				(gr_poly
					(pts
						(arc
							(start 0.3048 -0.2032)
							(mid 0.275042 -0.275042)
							(end 0.2032 -0.3048)
						)
						(arc
							(start -0.2032 -0.3048)
							(mid -0.275042 -0.275042)
							(end -0.3048 -0.2032)
						)
						(arc
							(start -0.3048 0.2032)
							(mid -0.275042 0.275042)
							(end -0.2032 0.3048)
						)
						(arc
							(start 0.2032 0.3048)
							(mid 0.275042 0.275042)
							(end 0.3048 0.2032)
						)
					)
					(width 0)
					(fill yes)
				)
			)
		)
		(pad "2" smd custom
			(at 0 0.4445 270)
			(size 0.1524 0.1524)
			(layers "F.Cu" "F.Mask" "F.Paste")
			(net "GND")
			(options
				(clearance outline)
				(anchor circle)
			)
			(primitives
				(gr_poly
					(pts
						(arc
							(start 0.3048 -0.2032)
							(mid 0.275042 -0.275042)
							(end 0.2032 -0.3048)
						)
						(arc
							(start -0.2032 -0.3048)
							(mid -0.275042 -0.275042)
							(end -0.3048 -0.2032)
						)
						(arc
							(start -0.3048 0.2032)
							(mid -0.275042 0.275042)
							(end -0.2032 0.3048)
						)
						(arc
							(start 0.2032 0.3048)
							(mid 0.275042 0.275042)
							(end 0.3048 0.2032)
						)
					)
					(width 0)
					(fill yes)
				)
			)
		)
	)
	(footprint ""
		(layer "F.Cu")
		(at 35.797998 -292.169342 -90)
		(property "Reference" "R958"
			(at 0 0 270)
			(layer "F.SilkS")
			(hide yes)
			(effects
				(font
					(size 1.27 1.27)
				)
			)
		)
		(property "Value" "10KR2F-2-GP"
			(at 0.064008 -3.993896 270)
			(unlocked yes)
			(layer "F.Fab")
			(hide yes)
			(effects
				(font
					(size 1.016 1.016)
					(thickness 0.1524)
				)
			)
		)
		(property "Device Type" "R402H16"
			(at 0.064008 -5.517896 270)
			(unlocked yes)
			(layer "F.Fab")
			(hide yes)
			(effects
				(font
					(size 1.016 1.016)
					(thickness 0.1524)
				)
			)
		)
		(duplicate_pad_numbers_are_jumpers no)
		(fp_line
			(start -0.508 -0.9398)
			(end -0.508 0.9398)
			(stroke
				(width 0.1524)
				(type default)
			)
			(layer "F.SilkS")
		)
		(fp_line
			(start 0.508 -0.9398)
			(end -0.508 -0.9398)
			(stroke
				(width 0.1524)
				(type default)
			)
			(layer "F.SilkS")
		)
		(fp_rect
			(start -0.508 0.9398)
			(end 0.508 -0.9398)
			(stroke
				(width 0)
				(type default)
			)
			(fill no)
			(layer "F.CrtYd")
		)
		(fp_rect
			(start -0.508 0.9398)
			(end 0.508 -0.9398)
			(stroke
				(width 0)
				(type default)
			)
			(fill no)
			(layer "F.Fab")
		)
		(pad "1" smd custom
			(at 0 -0.4445 270)
			(size 0.1397 0.1397)
			(layers "F.Cu" "F.Mask" "F.Paste")
			(net "P3V3_STBY_A")
			(options
				(clearance outline)
				(anchor circle)
			)
			(primitives
				(gr_poly
					(pts
						(arc
							(start -0.1778 -0.2794)
							(mid -0.249642 -0.249642)
							(end -0.2794 -0.1778)
						)
						(arc
							(start -0.2794 0.1778)
							(mid -0.249642 0.249642)
							(end -0.1778 0.2794)
						)
						(arc
							(start 0.1778 0.2794)
							(mid 0.249642 0.249642)
							(end 0.2794 0.1778)
						)
						(arc
							(start 0.2794 -0.1778)
							(mid 0.249642 -0.249642)
							(end 0.1778 -0.2794)
						)
					)
					(width 0)
					(fill yes)
				)
			)
		)
		(pad "2" smd custom
			(at 0 0.4445 270)
			(size 0.1397 0.1397)
			(layers "F.Cu" "F.Mask" "F.Paste")
			(net "HDD_PRSNT_0")
			(options
				(clearance outline)
				(anchor circle)
			)
			(primitives
				(gr_poly
					(pts
						(arc
							(start -0.1778 -0.2794)
							(mid -0.249642 -0.249642)
							(end -0.2794 -0.1778)
						)
						(arc
							(start -0.2794 0.1778)
							(mid -0.249642 0.249642)
							(end -0.1778 0.2794)
						)
						(arc
							(start 0.1778 0.2794)
							(mid 0.249642 0.249642)
							(end 0.2794 0.1778)
						)
						(arc
							(start 0.2794 -0.1778)
							(mid 0.249642 -0.249642)
							(end 0.1778 -0.2794)
						)
					)
					(width 0)
					(fill yes)
				)
			)
		)
	)
	(footprint ""
		(layer "F.Cu")
		(at 426.120052 -291.127942 -90)
		(property "Reference" "R336"
			(at 0 0 270)
			(layer "F.SilkS")
			(hide yes)
			(effects
				(font
					(size 1.27 1.27)
				)
			)
		)
		(property "Value" "2R6F-GP"
			(at -0.0508 -4.8514 270)
			(unlocked yes)
			(layer "F.Fab")
			(hide yes)
			(effects
				(font
					(size 1.016 1.016)
					(thickness 0.1524)
				)
			)
		)
		(property "Device Type" "R1206H26"
			(at 0 -6.3754 270)
			(unlocked yes)
			(layer "F.Fab")
			(hide yes)
			(effects
				(font
					(size 1.016 1.016)
					(thickness 0.1524)
				)
			)
		)
		(duplicate_pad_numbers_are_jumpers no)
		(fp_line
			(start -1.016 2.2352)
			(end -1.016 -2.2352)
			(stroke
				(width 0.1524)
				(type default)
			)
			(layer "F.SilkS")
		)
		(fp_line
			(start 1.016 2.2352)
			(end -1.016 2.2352)
			(stroke
				(width 0.1524)
				(type default)
			)
			(layer "F.SilkS")
		)
		(fp_line
			(start -1.016 -2.2352)
			(end 1.016 -2.2352)
			(stroke
				(width 0.1524)
				(type default)
			)
			(layer "F.SilkS")
		)
		(fp_line
			(start 1.016 -2.2352)
			(end 1.016 2.2352)
			(stroke
				(width 0.1524)
				(type default)
			)
			(layer "F.SilkS")
		)
		(fp_rect
			(start -1.0922 2.3114)
			(end 1.0922 -2.3114)
			(stroke
				(width 0)
				(type default)
			)
			(fill no)
			(layer "F.CrtYd")
		)
		(fp_poly
			(pts
				(xy -1.0922 -2.3114) (xy 1.0922 -2.3114) (xy 1.0922 2.3114) (xy -1.0922 2.3114)
			)
			(stroke
				(width 0)
				(type default)
			)
			(fill no)
			(layer "F.Fab")
		)
		(pad "1" smd rect
			(at 0 -1.397 270)
			(size 1.651 1.27)
			(layers "F.Cu" "F.Mask" "F.Paste")
			(net "P5V_HDD9")
		)
		(pad "2" smd rect
			(at 0 1.397 270)
			(size 1.651 1.27)
			(layers "F.Cu" "F.Mask" "F.Paste")
			(net "5V_PRE_9")
		)
	)
	(footprint ""
		(layer "F.Cu")
		(at 170.200066 -269.999968)
		(property "Reference" ""
			(at 0 0 0)
			(layer "F.SilkS")
			(hide yes)
			(effects
				(font
					(size 1.27 1.27)
				)
			)
		)
		(property "Value" "*"
			(at -6.3373 -0.4572 0)
			(unlocked yes)
			(layer "F.Fab")
			(hide yes)
			(effects
				(font
					(size 1.016 1.016)
					(thickness 0.1524)
				)
			)
		)
		(duplicate_pad_numbers_are_jumpers no)
		(fp_poly
			(pts
				(arc
					(start 5.0673 0)
					(mid -5.0673 0)
					(end 5.0673 0)
				)
			)
			(stroke
				(width 0)
				(type default)
			)
			(fill no)
			(layer "B.CrtYd")
		)
		(fp_poly
			(pts
				(arc
					(start 5.0673 0)
					(mid -5.0673 0)
					(end 5.0673 0)
				)
			)
			(stroke
				(width 0)
				(type default)
			)
			(fill no)
			(layer "F.CrtYd")
		)
		(fp_poly
			(pts
				(arc
					(start 5.0673 0)
					(mid -5.0673 0)
					(end 5.0673 0)
				)
			)
			(stroke
				(width 0)
				(type default)
			)
			(fill no)
			(layer "B.Fab")
		)
		(fp_poly
			(pts
				(arc
					(start 5.0673 0)
					(mid -5.0673 0)
					(end 5.0673 0)
				)
			)
			(stroke
				(width 0)
				(type default)
			)
			(fill no)
			(layer "F.Fab")
		)
		(pad "1" thru_hole circle
			(at 0 0)
			(size 9.525 9.525)
			(drill 3.556)
			(layers "*.Cu" "*.Mask")
			(remove_unused_layers no)
			(net "Net_90")
			(clearance -2.4765)
			(thermal_gap 0.3048)
			(padstack
				(mode front_inner_back)
				(layer "Inner"
					(shape circle)
					(size 3.9624 3.9624)
					(clearance 0.3048)
				)
				(layer "B.Cu"
					(shape circle)
					(size 9.525 9.525)
					(clearance -2.4765)
				)
			)
		)
		(zone
			(layers "F.Cu" "B.Cu" "In1.Cu" "In2.Cu" "In3.Cu" "In4.Cu" "In5.Cu" "In6.Cu"
				"In7.Cu" "In8.Cu" "In9.Cu" "In10.Cu"
			)
			(hatch none 0.5)
			(connect_pads
				(clearance 0)
			)
			(min_thickness 0.25)
			(keepout
				(tracks not_allowed)
				(vias allowed)
				(pads allowed)
				(copperpour not_allowed)
				(footprints allowed)
			)
			(placement
				(enabled no)
				(sheetname "")
			)
			(fill
				(thermal_gap 0.5)
				(thermal_bridge_width 0.5)
				(island_removal_mode 0)
			)
			(polygon
				(pts
					(arc
						(start 174.962566 -269.999968)
						(mid 165.437566 -269.999968)
						(end 174.962566 -269.999968)
					)
				)
			)
		)
	)
	(footprint ""
		(layer "F.Cu")
		(at 323.674994 -9.19988)
		(property "Reference" ""
			(at 0 0 0)
			(layer "F.SilkS")
			(hide yes)
			(effects
				(font
					(size 1.27 1.27)
				)
			)
		)
		(property "Value" "*"
			(at -6.1214 1.4351 0)
			(unlocked yes)
			(layer "F.Fab")
			(hide yes)
			(effects
				(font
					(size 1.016 1.016)
					(thickness 0.1524)
				)
			)
		)
		(duplicate_pad_numbers_are_jumpers no)
		(fp_poly
			(pts
				(arc
					(start 5.0673 0)
					(mid -5.0673 0)
					(end 5.0673 0)
				)
			)
			(stroke
				(width 0)
				(type default)
			)
			(fill no)
			(layer "B.CrtYd")
		)
		(fp_poly
			(pts
				(arc
					(start 5.0673 0)
					(mid -5.0673 0)
					(end 5.0673 0)
				)
			)
			(stroke
				(width 0)
				(type default)
			)
			(fill no)
			(layer "F.CrtYd")
		)
		(fp_poly
			(pts
				(arc
					(start 5.0673 0)
					(mid -5.0673 0)
					(end 5.0673 0)
				)
			)
			(stroke
				(width 0)
				(type default)
			)
			(fill no)
			(layer "B.Fab")
		)
		(fp_poly
			(pts
				(arc
					(start 5.0673 0)
					(mid -5.0673 0)
					(end 5.0673 0)
				)
			)
			(stroke
				(width 0)
				(type default)
			)
			(fill no)
			(layer "F.Fab")
		)
		(pad "1" thru_hole circle
			(at 0 0)
			(size 9.525 9.525)
			(drill 5.715)
			(layers "*.Cu" "*.Mask")
			(remove_unused_layers no)
			(net "Net_108")
			(clearance -1.397)
			(thermal_gap 0.3048)
			(padstack
				(mode front_inner_back)
				(layer "Inner"
					(shape circle)
					(size 6.1214 6.1214)
					(clearance 0.3048)
				)
				(layer "B.Cu"
					(shape circle)
					(size 9.525 9.525)
					(clearance -1.397)
				)
			)
		)
		(zone
			(layers "F.Cu" "B.Cu" "In1.Cu" "In2.Cu" "In3.Cu" "In4.Cu" "In5.Cu" "In6.Cu"
				"In7.Cu" "In8.Cu" "In9.Cu" "In10.Cu"
			)
			(hatch none 0.5)
			(connect_pads
				(clearance 0)
			)
			(min_thickness 0.25)
			(keepout
				(tracks not_allowed)
				(vias allowed)
				(pads allowed)
				(copperpour not_allowed)
				(footprints allowed)
			)
			(placement
				(enabled no)
				(sheetname "")
			)
			(fill
				(thermal_gap 0.5)
				(thermal_bridge_width 0.5)
				(island_removal_mode 0)
			)
			(polygon
				(pts
					(arc
						(start 328.437494 -9.19988)
						(mid 318.912494 -9.19988)
						(end 328.437494 -9.19988)
					)
				)
			)
		)
	)
	(footprint ""
		(layer "F.Cu")
		(at 475.530926 -62.778894 -90)
		(property "Reference" "C495"
			(at 0 0 270)
			(layer "F.SilkS")
			(hide yes)
			(effects
				(font
					(size 1.27 1.27)
				)
			)
		)
		(property "Value" "SC1U16V3KX-5GP"
			(at 0 -2.8194 270)
			(unlocked yes)
			(layer "F.Fab")
			(hide yes)
			(effects
				(font
					(size 1.016 1.016)
					(thickness 0.1524)
				)
			)
		)
		(property "Device Type" "C603H36"
			(at 0 -4.3434 270)
			(unlocked yes)
			(layer "F.Fab")
			(hide yes)
			(effects
				(font
					(size 1.016 1.016)
					(thickness 0.1524)
				)
			)
		)
		(duplicate_pad_numbers_are_jumpers no)
		(fp_line
			(start 0.508 0)
			(end -0.508 0)
			(stroke
				(width 0.2032)
				(type default)
			)
			(layer "F.SilkS")
		)
		(fp_rect
			(start -0.5842 1.3335)
			(end 0.5842 -1.3335)
			(stroke
				(width 0)
				(type default)
			)
			(fill no)
			(layer "F.CrtYd")
		)
		(fp_rect
			(start -0.5842 1.3335)
			(end 0.5842 -1.3335)
			(stroke
				(width 0)
				(type default)
			)
			(fill no)
			(layer "F.Fab")
		)
		(pad "1" smd custom
			(at 0 -0.762 270)
			(size 0.2159 0.2159)
			(layers "F.Cu" "F.Mask" "F.Paste")
			(net "P5V_HDD35")
			(options
				(clearance outline)
				(anchor circle)
			)
			(primitives
				(gr_poly
					(pts
						(arc
							(start -0.3302 -0.4318)
							(mid -0.402042 -0.402042)
							(end -0.4318 -0.3302)
						)
						(arc
							(start -0.4318 0.3302)
							(mid -0.402042 0.402042)
							(end -0.3302 0.4318)
						)
						(arc
							(start 0.3302 0.4318)
							(mid 0.402042 0.402042)
							(end 0.4318 0.3302)
						)
						(arc
							(start 0.4318 -0.3302)
							(mid 0.402042 -0.402042)
							(end 0.3302 -0.4318)
						)
					)
					(width 0)
					(fill yes)
				)
			)
		)
		(pad "2" smd custom
			(at 0 0.762 270)
			(size 0.2159 0.2159)
			(layers "F.Cu" "F.Mask" "F.Paste")
			(net "GND")
			(options
				(clearance outline)
				(anchor circle)
			)
			(primitives
				(gr_poly
					(pts
						(arc
							(start -0.3302 -0.4318)
							(mid -0.402042 -0.402042)
							(end -0.4318 -0.3302)
						)
						(arc
							(start -0.4318 0.3302)
							(mid -0.402042 0.402042)
							(end -0.3302 0.4318)
						)
						(arc
							(start 0.3302 0.4318)
							(mid 0.402042 0.402042)
							(end 0.4318 0.3302)
						)
						(arc
							(start 0.4318 -0.3302)
							(mid 0.402042 -0.402042)
							(end 0.3302 -0.4318)
						)
					)
					(width 0)
					(fill yes)
				)
			)
		)
	)
	(footprint ""
		(layer "F.Cu")
		(at 219.928948 -21.844 -90)
		(property "Reference" "C32"
			(at 0 0 270)
			(layer "F.SilkS")
			(hide yes)
			(effects
				(font
					(size 1.27 1.27)
				)
			)
		)
		(property "Value" "SC22U25V6KX-2-GP-U"
			(at -2.860802 -5.279644 270)
			(unlocked yes)
			(layer "F.Fab")
			(hide yes)
			(effects
				(font
					(size 1.016 1.016)
					(thickness 0.1524)
				)
			)
		)
		(property "Device Type" "C1206-TO0D3H75"
			(at -2.860802 -6.803644 270)
			(unlocked yes)
			(layer "F.Fab")
			(hide yes)
			(effects
				(font
					(size 1.016 1.016)
					(thickness 0.1524)
				)
			)
		)
		(duplicate_pad_numbers_are_jumpers no)
		(fp_line
			(start -1.3081 2.3749)
			(end -1.3081 -2.3749)
			(stroke
				(width 0.1524)
				(type default)
			)
			(layer "F.SilkS")
		)
		(fp_line
			(start 1.3081 2.3749)
			(end -1.3081 2.3749)
			(stroke
				(width 0.1524)
				(type default)
			)
			(layer "F.SilkS")
		)
		(fp_line
			(start -1.3081 -2.3749)
			(end 1.3081 -2.3749)
			(stroke
				(width 0.1524)
				(type default)
			)
			(layer "F.SilkS")
		)
		(fp_line
			(start 1.3081 -2.3749)
			(end 1.3081 2.3749)
			(stroke
				(width 0.1524)
				(type default)
			)
			(layer "F.SilkS")
		)
		(fp_rect
			(start -0.8001 1.6002)
			(end 0.8001 -1.6002)
			(stroke
				(width 0)
				(type default)
			)
			(fill no)
			(layer "F.CrtYd")
		)
		(fp_poly
			(pts
				(xy -1.5621 2.4511) (xy -1.5621 1.6002) (xy 0.8001 1.6002) (xy 0.8001 -1.6002) (xy -0.8001 -1.6002)
				(xy -0.8001 1.5875) (xy -1.5621 1.5875) (xy -1.5621 -2.4511) (xy 1.5621 -2.4511) (xy 1.5621 2.4511)
			)
			(stroke
				(width 0)
				(type default)
			)
			(fill no)
			(layer "F.CrtYd")
		)
		(fp_rect
			(start -1.5621 2.4511)
			(end 1.5621 -2.4511)
			(stroke
				(width 0)
				(type default)
			)
			(fill no)
			(layer "F.Fab")
		)
		(pad "1" smd rect
			(at 0 -1.392936 270)
			(size 2.1082 1.4478)
			(layers "F.Cu" "F.Mask" "F.Paste")
			(net "P12V_A_COMP")
		)
		(pad "2" smd rect
			(at 0 1.392936 270)
			(size 2.1082 1.4478)
			(layers "F.Cu" "F.Mask" "F.Paste")
			(net "GND")
		)
	)
	(footprint ""
		(layer "F.Cu")
		(at 164.283136 -188.875162)
		(property "Reference" "Q232"
			(at 0 0 0)
			(layer "F.SilkS")
			(hide yes)
			(effects
				(font
					(size 1.27 1.27)
				)
			)
		)
		(property "Value" "2N7002K-2-GP"
			(at 0.127 -8.9662 0)
			(unlocked yes)
			(layer "F.Fab")
			(hide yes)
			(effects
				(font
					(size 1.016 1.016)
					(thickness 0.1524)
				)
			)
		)
		(property "Device Type" "SOT23DGS2D4H44"
			(at 0.127 -10.4902 0)
			(unlocked yes)
			(layer "F.Fab")
			(hide yes)
			(effects
				(font
					(size 1.016 1.016)
					(thickness 0.1524)
				)
			)
		)
		(duplicate_pad_numbers_are_jumpers no)
		(fp_line
			(start -1.651 -1.778)
			(end -1.651 1.778)
			(stroke
				(width 0.1524)
				(type default)
			)
			(layer "F.SilkS")
		)
		(fp_line
			(start -1.651 1.778)
			(end 1.651 1.778)
			(stroke
				(width 0.1524)
				(type default)
			)
			(layer "F.SilkS")
		)
		(fp_line
			(start 1.651 -1.778)
			(end -1.651 -1.778)
			(stroke
				(width 0.1524)
				(type default)
			)
			(layer "F.SilkS")
		)
		(fp_line
			(start 1.651 1.778)
			(end 1.651 -1.778)
			(stroke
				(width 0.1524)
				(type default)
			)
			(layer "F.SilkS")
		)
		(fp_poly
			(pts
				(xy -1.778 1.8796) (xy -1.778 -1.8796) (xy 1.778 -1.8796) (xy 1.778 1.8796)
			)
			(stroke
				(width 0)
				(type default)
			)
			(fill no)
			(layer "F.CrtYd")
		)
		(fp_poly
			(pts
				(xy -1.778 1.8796) (xy -1.778 -1.8796) (xy 1.778 -1.8796) (xy 1.778 1.8796)
			)
			(stroke
				(width 0)
				(type default)
			)
			(fill no)
			(layer "F.Fab")
		)
		(pad "D" smd custom
			(at 0 -0.9525)
			(size 0.1905 0.1905)
			(layers "F.Cu" "F.Mask" "F.Paste")
			(net "FLT_HDD5_N")
			(options
				(clearance outline)
				(anchor circle)
			)
			(primitives
				(gr_poly
					(pts
						(arc
							(start -0.1778 0.5715)
							(mid -0.321484 0.511984)
							(end -0.381 0.3683)
						)
						(arc
							(start -0.381 -0.3683)
							(mid -0.321484 -0.511984)
							(end -0.1778 -0.5715)
						)
						(arc
							(start 0.1778 -0.5715)
							(mid 0.321484 -0.511984)
							(end 0.381 -0.3683)
						)
						(arc
							(start 0.381 0.3683)
							(mid 0.321484 0.511984)
							(end 0.1778 0.5715)
						)
					)
					(width 0)
					(fill yes)
				)
			)
		)
		(pad "G" smd custom
			(at -0.98425 0.9525)
			(size 0.1905 0.1905)
			(layers "F.Cu" "F.Mask" "F.Paste")
			(net "DRIVE_A_5_FLT_LED")
			(options
				(clearance outline)
				(anchor circle)
			)
			(primitives
				(gr_poly
					(pts
						(arc
							(start -0.1778 0.5715)
							(mid -0.321484 0.511984)
							(end -0.381 0.3683)
						)
						(arc
							(start -0.381 -0.3683)
							(mid -0.321484 -0.511984)
							(end -0.1778 -0.5715)
						)
						(arc
							(start 0.1778 -0.5715)
							(mid 0.321484 -0.511984)
							(end 0.381 -0.3683)
						)
						(arc
							(start 0.381 0.3683)
							(mid 0.321484 0.511984)
							(end 0.1778 0.5715)
						)
					)
					(width 0)
					(fill yes)
				)
			)
		)
		(pad "S" smd custom
			(at 0.98425 0.9525)
			(size 0.1905 0.1905)
			(layers "F.Cu" "F.Mask" "F.Paste")
			(net "GND")
			(options
				(clearance outline)
				(anchor circle)
			)
			(primitives
				(gr_poly
					(pts
						(arc
							(start -0.1778 0.5715)
							(mid -0.321484 0.511984)
							(end -0.381 0.3683)
						)
						(arc
							(start -0.381 -0.3683)
							(mid -0.321484 -0.511984)
							(end -0.1778 -0.5715)
						)
						(arc
							(start 0.1778 -0.5715)
							(mid 0.321484 -0.511984)
							(end 0.381 -0.3683)
						)
						(arc
							(start 0.381 0.3683)
							(mid 0.321484 0.511984)
							(end 0.1778 0.5715)
						)
					)
					(width 0)
					(fill yes)
				)
			)
		)
	)
	(footprint ""
		(layer "F.Cu")
		(at 264.356342 -210.617562 180)
		(property "Reference" "R402"
			(at 0 0 180)
			(layer "F.SilkS")
			(hide yes)
			(effects
				(font
					(size 1.27 1.27)
				)
			)
		)
		(property "Value" "1KR2F-3-GP"
			(at 0.064008 -3.993896 180)
			(unlocked yes)
			(layer "F.Fab")
			(hide yes)
			(effects
				(font
					(size 1.016 1.016)
					(thickness 0.1524)
				)
			)
		)
		(property "Device Type" "R402H16"
			(at 0.064008 -5.517896 180)
			(unlocked yes)
			(layer "F.Fab")
			(hide yes)
			(effects
				(font
					(size 1.016 1.016)
					(thickness 0.1524)
				)
			)
		)
		(duplicate_pad_numbers_are_jumpers no)
		(fp_line
			(start 0.508 -0.9398)
			(end -0.508 -0.9398)
			(stroke
				(width 0.1524)
				(type default)
			)
			(layer "F.SilkS")
		)
		(fp_line
			(start -0.508 -0.9398)
			(end -0.508 0.9398)
			(stroke
				(width 0.1524)
				(type default)
			)
			(layer "F.SilkS")
		)
		(fp_rect
			(start -0.508 0.9398)
			(end 0.508 -0.9398)
			(stroke
				(width 0)
				(type default)
			)
			(fill no)
			(layer "F.CrtYd")
		)
		(fp_rect
			(start -0.508 0.9398)
			(end 0.508 -0.9398)
			(stroke
				(width 0)
				(type default)
			)
			(fill no)
			(layer "F.Fab")
		)
		(pad "1" smd custom
			(at 0 -0.4445 180)
			(size 0.1397 0.1397)
			(layers "F.Cu" "F.Mask" "F.Paste")
			(net "P3V3_STBY_A")
			(options
				(clearance outline)
				(anchor circle)
			)
			(primitives
				(gr_poly
					(pts
						(arc
							(start -0.1778 -0.2794)
							(mid -0.249642 -0.249642)
							(end -0.2794 -0.1778)
						)
						(arc
							(start -0.2794 0.1778)
							(mid -0.249642 0.249642)
							(end -0.1778 0.2794)
						)
						(arc
							(start 0.1778 0.2794)
							(mid 0.249642 0.249642)
							(end 0.2794 0.1778)
						)
						(arc
							(start 0.2794 -0.1778)
							(mid 0.249642 -0.249642)
							(end 0.1778 -0.2794)
						)
					)
					(width 0)
					(fill yes)
				)
			)
		)
		(pad "2" smd custom
			(at 0 0.4445 180)
			(size 0.1397 0.1397)
			(layers "F.Cu" "F.Mask" "F.Paste")
			(net "I2C_DPB_A_SCL_BUF")
			(options
				(clearance outline)
				(anchor circle)
			)
			(primitives
				(gr_poly
					(pts
						(arc
							(start -0.1778 -0.2794)
							(mid -0.249642 -0.249642)
							(end -0.2794 -0.1778)
						)
						(arc
							(start -0.2794 0.1778)
							(mid -0.249642 0.249642)
							(end -0.1778 0.2794)
						)
						(arc
							(start 0.1778 0.2794)
							(mid 0.249642 0.249642)
							(end 0.2794 0.1778)
						)
						(arc
							(start 0.2794 -0.1778)
							(mid 0.249642 -0.249642)
							(end 0.1778 -0.2794)
						)
					)
					(width 0)
					(fill yes)
				)
			)
		)
	)
	(footprint ""
		(layer "F.Cu")
		(at 331.359002 -22.671532)
		(property "Reference" "R986"
			(at 0 0 0)
			(layer "F.SilkS")
			(hide yes)
			(effects
				(font
					(size 1.27 1.27)
				)
			)
		)
		(property "Value" "4K7R2F-GP"
			(at 0.064008 -3.993896 0)
			(unlocked yes)
			(layer "F.Fab")
			(hide yes)
			(effects
				(font
					(size 1.016 1.016)
					(thickness 0.1524)
				)
			)
		)
		(property "Device Type" "R402H16"
			(at 0.064008 -5.517896 0)
			(unlocked yes)
			(layer "F.Fab")
			(hide yes)
			(effects
				(font
					(size 1.016 1.016)
					(thickness 0.1524)
				)
			)
		)
		(duplicate_pad_numbers_are_jumpers no)
		(fp_line
			(start -0.508 -0.9398)
			(end -0.508 0.9398)
			(stroke
				(width 0.1524)
				(type default)
			)
			(layer "F.SilkS")
		)
		(fp_line
			(start 0.508 -0.9398)
			(end -0.508 -0.9398)
			(stroke
				(width 0.1524)
				(type default)
			)
			(layer "F.SilkS")
		)
		(fp_rect
			(start -0.508 0.9398)
			(end 0.508 -0.9398)
			(stroke
				(width 0)
				(type default)
			)
			(fill no)
			(layer "F.CrtYd")
		)
		(fp_rect
			(start -0.508 0.9398)
			(end 0.508 -0.9398)
			(stroke
				(width 0)
				(type default)
			)
			(fill no)
			(layer "F.Fab")
		)
		(pad "1" smd custom
			(at 0 -0.4445)
			(size 0.1397 0.1397)
			(layers "F.Cu" "F.Mask" "F.Paste")
			(net "IOM_B_SLOT_ID_0")
			(options
				(clearance outline)
				(anchor circle)
			)
			(primitives
				(gr_poly
					(pts
						(arc
							(start -0.1778 -0.2794)
							(mid -0.249642 -0.249642)
							(end -0.2794 -0.1778)
						)
						(arc
							(start -0.2794 0.1778)
							(mid -0.249642 0.249642)
							(end -0.1778 0.2794)
						)
						(arc
							(start 0.1778 0.2794)
							(mid 0.249642 0.249642)
							(end 0.2794 0.1778)
						)
						(arc
							(start 0.2794 -0.1778)
							(mid 0.249642 -0.249642)
							(end 0.1778 -0.2794)
						)
					)
					(width 0)
					(fill yes)
				)
			)
		)
		(pad "2" smd custom
			(at 0 0.4445)
			(size 0.1397 0.1397)
			(layers "F.Cu" "F.Mask" "F.Paste")
			(net "GND")
			(options
				(clearance outline)
				(anchor circle)
			)
			(primitives
				(gr_poly
					(pts
						(arc
							(start -0.1778 -0.2794)
							(mid -0.249642 -0.249642)
							(end -0.2794 -0.1778)
						)
						(arc
							(start -0.2794 0.1778)
							(mid -0.249642 0.249642)
							(end -0.1778 0.2794)
						)
						(arc
							(start 0.1778 0.2794)
							(mid 0.249642 0.249642)
							(end 0.2794 0.1778)
						)
						(arc
							(start 0.2794 -0.1778)
							(mid 0.249642 -0.249642)
							(end 0.1778 -0.2794)
						)
					)
					(width 0)
					(fill yes)
				)
			)
		)
	)
	(footprint ""
		(layer "F.Cu")
		(at 479.340926 -304.462942 180)
		(property "Reference" "C190"
			(at 0 0 180)
			(layer "F.SilkS")
			(hide yes)
			(effects
				(font
					(size 1.27 1.27)
				)
			)
		)
		(property "Value" "SC1U25V3KX-GP"
			(at 0 -2.8194 180)
			(unlocked yes)
			(layer "F.Fab")
			(hide yes)
			(effects
				(font
					(size 1.016 1.016)
					(thickness 0.1524)
				)
			)
		)
		(property "Device Type" "C603H36"
			(at 0 -4.3434 180)
			(unlocked yes)
			(layer "F.Fab")
			(hide yes)
			(effects
				(font
					(size 1.016 1.016)
					(thickness 0.1524)
				)
			)
		)
		(duplicate_pad_numbers_are_jumpers no)
		(fp_line
			(start 0.508 0)
			(end -0.508 0)
			(stroke
				(width 0.2032)
				(type default)
			)
			(layer "F.SilkS")
		)
		(fp_rect
			(start -0.5842 1.3335)
			(end 0.5842 -1.3335)
			(stroke
				(width 0)
				(type default)
			)
			(fill no)
			(layer "F.CrtYd")
		)
		(fp_rect
			(start -0.5842 1.3335)
			(end 0.5842 -1.3335)
			(stroke
				(width 0)
				(type default)
			)
			(fill no)
			(layer "F.Fab")
		)
		(pad "1" smd custom
			(at 0 -0.762 180)
			(size 0.2159 0.2159)
			(layers "F.Cu" "F.Mask" "F.Paste")
			(net "P12V_HDD11")
			(options
				(clearance outline)
				(anchor circle)
			)
			(primitives
				(gr_poly
					(pts
						(arc
							(start -0.3302 -0.4318)
							(mid -0.402042 -0.402042)
							(end -0.4318 -0.3302)
						)
						(arc
							(start -0.4318 0.3302)
							(mid -0.402042 0.402042)
							(end -0.3302 0.4318)
						)
						(arc
							(start 0.3302 0.4318)
							(mid 0.402042 0.402042)
							(end 0.4318 0.3302)
						)
						(arc
							(start 0.4318 -0.3302)
							(mid 0.402042 -0.402042)
							(end 0.3302 -0.4318)
						)
					)
					(width 0)
					(fill yes)
				)
			)
		)
		(pad "2" smd custom
			(at 0 0.762 180)
			(size 0.2159 0.2159)
			(layers "F.Cu" "F.Mask" "F.Paste")
			(net "GND")
			(options
				(clearance outline)
				(anchor circle)
			)
			(primitives
				(gr_poly
					(pts
						(arc
							(start -0.3302 -0.4318)
							(mid -0.402042 -0.402042)
							(end -0.4318 -0.3302)
						)
						(arc
							(start -0.4318 0.3302)
							(mid -0.402042 0.402042)
							(end -0.3302 0.4318)
						)
						(arc
							(start 0.3302 0.4318)
							(mid 0.402042 0.402042)
							(end 0.4318 0.3302)
						)
						(arc
							(start 0.4318 -0.3302)
							(mid 0.402042 -0.402042)
							(end 0.3302 -0.4318)
						)
					)
					(width 0)
					(fill yes)
				)
			)
		)
	)
	(footprint ""
		(layer "F.Cu")
		(at 146.247866 -145.372074 180)
		(property "Reference" "C548"
			(at 0 0 180)
			(layer "F.SilkS")
			(hide yes)
			(effects
				(font
					(size 1.27 1.27)
				)
			)
		)
		(property "Value" "SCD1U25V2KX-2-GP"
			(at 1.1811 -2.7051 180)
			(unlocked yes)
			(layer "F.Fab")
			(hide yes)
			(effects
				(font
					(size 1.016 1.016)
					(thickness 0.1524)
				)
			)
		)
		(property "Device Type" "C402H22"
			(at 1.1811 -4.2291 180)
			(unlocked yes)
			(layer "F.Fab")
			(hide yes)
			(effects
				(font
					(size 1.016 1.016)
					(thickness 0.1524)
				)
			)
		)
		(duplicate_pad_numbers_are_jumpers no)
		(fp_rect
			(start -0.4318 0.9525)
			(end 0.4318 -0.9525)
			(stroke
				(width 0)
				(type default)
			)
			(fill no)
			(layer "F.CrtYd")
		)
		(fp_rect
			(start -0.4318 0.9525)
			(end 0.4318 -0.9525)
			(stroke
				(width 0)
				(type default)
			)
			(fill no)
			(layer "F.Fab")
		)
		(pad "1" smd custom
			(at 0 -0.4445 180)
			(size 0.1524 0.1524)
			(layers "F.Cu" "F.Mask" "F.Paste")
			(net "MB0_ISET_R")
			(options
				(clearance outline)
				(anchor circle)
			)
			(primitives
				(gr_poly
					(pts
						(arc
							(start 0.3048 -0.2032)
							(mid 0.275042 -0.275042)
							(end 0.2032 -0.3048)
						)
						(arc
							(start -0.2032 -0.3048)
							(mid -0.275042 -0.275042)
							(end -0.3048 -0.2032)
						)
						(arc
							(start -0.3048 0.2032)
							(mid -0.275042 0.275042)
							(end -0.2032 0.3048)
						)
						(arc
							(start 0.2032 0.3048)
							(mid 0.275042 0.275042)
							(end 0.3048 0.2032)
						)
					)
					(width 0)
					(fill yes)
				)
			)
		)
		(pad "2" smd custom
			(at 0 0.4445 180)
			(size 0.1524 0.1524)
			(layers "F.Cu" "F.Mask" "F.Paste")
			(net "AGND_CURRENT_MONOA")
			(options
				(clearance outline)
				(anchor circle)
			)
			(primitives
				(gr_poly
					(pts
						(arc
							(start 0.3048 -0.2032)
							(mid 0.275042 -0.275042)
							(end 0.2032 -0.3048)
						)
						(arc
							(start -0.2032 -0.3048)
							(mid -0.275042 -0.275042)
							(end -0.3048 -0.2032)
						)
						(arc
							(start -0.3048 0.2032)
							(mid -0.275042 0.275042)
							(end -0.2032 0.3048)
						)
						(arc
							(start 0.2032 0.3048)
							(mid 0.275042 0.275042)
							(end 0.3048 0.2032)
						)
					)
					(width 0)
					(fill yes)
				)
			)
		)
	)
	(footprint ""
		(layer "F.Cu")
		(at 319.151 -177.2539 -90)
		(property "Reference" "R544"
			(at 0 0 270)
			(layer "F.SilkS")
			(hide yes)
			(effects
				(font
					(size 1.27 1.27)
				)
			)
		)
		(property "Value" "10KR2F-2-GP"
			(at 0.064008 -3.993896 270)
			(unlocked yes)
			(layer "F.Fab")
			(hide yes)
			(effects
				(font
					(size 1.016 1.016)
					(thickness 0.1524)
				)
			)
		)
		(property "Device Type" "R402H16"
			(at 0.064008 -5.517896 270)
			(unlocked yes)
			(layer "F.Fab")
			(hide yes)
			(effects
				(font
					(size 1.016 1.016)
					(thickness 0.1524)
				)
			)
		)
		(duplicate_pad_numbers_are_jumpers no)
		(fp_line
			(start -0.508 -0.9398)
			(end -0.508 0.9398)
			(stroke
				(width 0.1524)
				(type default)
			)
			(layer "F.SilkS")
		)
		(fp_line
			(start 0.508 -0.9398)
			(end -0.508 -0.9398)
			(stroke
				(width 0.1524)
				(type default)
			)
			(layer "F.SilkS")
		)
		(fp_rect
			(start -0.508 0.9398)
			(end 0.508 -0.9398)
			(stroke
				(width 0)
				(type default)
			)
			(fill no)
			(layer "F.CrtYd")
		)
		(fp_rect
			(start -0.508 0.9398)
			(end 0.508 -0.9398)
			(stroke
				(width 0)
				(type default)
			)
			(fill no)
			(layer "F.Fab")
		)
		(pad "1" smd custom
			(at 0 -0.4445 270)
			(size 0.1397 0.1397)
			(layers "F.Cu" "F.Mask" "F.Paste")
			(net "P3V3_STBY_A")
			(options
				(clearance outline)
				(anchor circle)
			)
			(primitives
				(gr_poly
					(pts
						(arc
							(start -0.1778 -0.2794)
							(mid -0.249642 -0.249642)
							(end -0.2794 -0.1778)
						)
						(arc
							(start -0.2794 0.1778)
							(mid -0.249642 0.249642)
							(end -0.1778 0.2794)
						)
						(arc
							(start 0.1778 0.2794)
							(mid 0.249642 0.249642)
							(end 0.2794 0.1778)
						)
						(arc
							(start 0.2794 -0.1778)
							(mid 0.249642 -0.249642)
							(end 0.1778 -0.2794)
						)
					)
					(width 0)
					(fill yes)
				)
			)
		)
		(pad "2" smd custom
			(at 0 0.4445 270)
			(size 0.1397 0.1397)
			(layers "F.Cu" "F.Mask" "F.Paste")
			(net "HDD_PRSNT_18")
			(options
				(clearance outline)
				(anchor circle)
			)
			(primitives
				(gr_poly
					(pts
						(arc
							(start -0.1778 -0.2794)
							(mid -0.249642 -0.249642)
							(end -0.2794 -0.1778)
						)
						(arc
							(start -0.2794 0.1778)
							(mid -0.249642 0.249642)
							(end -0.1778 0.2794)
						)
						(arc
							(start 0.1778 0.2794)
							(mid 0.249642 0.249642)
							(end 0.2794 0.1778)
						)
						(arc
							(start 0.2794 -0.1778)
							(mid 0.249642 -0.249642)
							(end 0.1778 -0.2794)
						)
					)
					(width 0)
					(fill yes)
				)
			)
		)
	)
	(footprint ""
		(layer "F.Cu")
		(at 223.88068 -342.566752 180)
		(property "Reference" "R158"
			(at 0 0 180)
			(layer "F.SilkS")
			(hide yes)
			(effects
				(font
					(size 1.27 1.27)
				)
			)
		)
		(property "Value" "4K7R2F-GP"
			(at 0.064008 -3.993896 180)
			(unlocked yes)
			(layer "F.Fab")
			(hide yes)
			(effects
				(font
					(size 1.016 1.016)
					(thickness 0.1524)
				)
			)
		)
		(property "Device Type" "R402H16"
			(at 0.064008 -5.517896 180)
			(unlocked yes)
			(layer "F.Fab")
			(hide yes)
			(effects
				(font
					(size 1.016 1.016)
					(thickness 0.1524)
				)
			)
		)
		(duplicate_pad_numbers_are_jumpers no)
		(fp_line
			(start 0.508 -0.9398)
			(end -0.508 -0.9398)
			(stroke
				(width 0.1524)
				(type default)
			)
			(layer "F.SilkS")
		)
		(fp_line
			(start -0.508 -0.9398)
			(end -0.508 0.9398)
			(stroke
				(width 0.1524)
				(type default)
			)
			(layer "F.SilkS")
		)
		(fp_rect
			(start -0.508 0.9398)
			(end 0.508 -0.9398)
			(stroke
				(width 0)
				(type default)
			)
			(fill no)
			(layer "F.CrtYd")
		)
		(fp_rect
			(start -0.508 0.9398)
			(end 0.508 -0.9398)
			(stroke
				(width 0)
				(type default)
			)
			(fill no)
			(layer "F.Fab")
		)
		(pad "1" smd custom
			(at 0 -0.4445 180)
			(size 0.1397 0.1397)
			(layers "F.Cu" "F.Mask" "F.Paste")
			(net "VOL_SEN_ADDR1")
			(options
				(clearance outline)
				(anchor circle)
			)
			(primitives
				(gr_poly
					(pts
						(arc
							(start -0.1778 -0.2794)
							(mid -0.249642 -0.249642)
							(end -0.2794 -0.1778)
						)
						(arc
							(start -0.2794 0.1778)
							(mid -0.249642 0.249642)
							(end -0.1778 0.2794)
						)
						(arc
							(start 0.1778 0.2794)
							(mid 0.249642 0.249642)
							(end 0.2794 0.1778)
						)
						(arc
							(start 0.2794 -0.1778)
							(mid 0.249642 -0.249642)
							(end 0.1778 -0.2794)
						)
					)
					(width 0)
					(fill yes)
				)
			)
		)
		(pad "2" smd custom
			(at 0 0.4445 180)
			(size 0.1397 0.1397)
			(layers "F.Cu" "F.Mask" "F.Paste")
			(net "GND")
			(options
				(clearance outline)
				(anchor circle)
			)
			(primitives
				(gr_poly
					(pts
						(arc
							(start -0.1778 -0.2794)
							(mid -0.249642 -0.249642)
							(end -0.2794 -0.1778)
						)
						(arc
							(start -0.2794 0.1778)
							(mid -0.249642 0.249642)
							(end -0.1778 0.2794)
						)
						(arc
							(start 0.1778 0.2794)
							(mid 0.249642 0.249642)
							(end 0.2794 0.1778)
						)
						(arc
							(start 0.2794 -0.1778)
							(mid 0.249642 -0.249642)
							(end 0.1778 -0.2794)
						)
					)
					(width 0)
					(fill yes)
				)
			)
		)
	)
	(footprint ""
		(layer "F.Cu")
		(at 6.80593 -287.4391)
		(property "Reference" "Q287"
			(at 0 0 0)
			(layer "F.SilkS")
			(hide yes)
			(effects
				(font
					(size 1.27 1.27)
				)
			)
		)
		(property "Value" "SSM3K324R-GP"
			(at 0.127 -8.9662 0)
			(unlocked yes)
			(layer "F.Fab")
			(hide yes)
			(effects
				(font
					(size 1.016 1.016)
					(thickness 0.1524)
				)
			)
		)
		(property "Device Type" "SOT23DGS2D4H35"
			(at 0.127 -10.4902 0)
			(unlocked yes)
			(layer "F.Fab")
			(hide yes)
			(effects
				(font
					(size 1.016 1.016)
					(thickness 0.1524)
				)
			)
		)
		(duplicate_pad_numbers_are_jumpers no)
		(fp_line
			(start -1.651 -1.778)
			(end -1.651 1.778)
			(stroke
				(width 0.1524)
				(type default)
			)
			(layer "F.SilkS")
		)
		(fp_line
			(start -1.651 1.778)
			(end 1.651 1.778)
			(stroke
				(width 0.1524)
				(type default)
			)
			(layer "F.SilkS")
		)
		(fp_line
			(start 1.651 -1.778)
			(end -1.651 -1.778)
			(stroke
				(width 0.1524)
				(type default)
			)
			(layer "F.SilkS")
		)
		(fp_line
			(start 1.651 1.778)
			(end 1.651 -1.778)
			(stroke
				(width 0.1524)
				(type default)
			)
			(layer "F.SilkS")
		)
		(fp_poly
			(pts
				(xy -1.778 1.8796) (xy -1.778 -1.8796) (xy 1.778 -1.8796) (xy 1.778 1.8796)
			)
			(stroke
				(width 0)
				(type default)
			)
			(fill no)
			(layer "F.CrtYd")
		)
		(fp_poly
			(pts
				(xy -1.778 1.8796) (xy -1.778 -1.8796) (xy 1.778 -1.8796) (xy 1.778 1.8796)
			)
			(stroke
				(width 0)
				(type default)
			)
			(fill no)
			(layer "F.Fab")
		)
		(pad "D" smd custom
			(at 0 -0.9525)
			(size 0.1905 0.1905)
			(layers "F.Cu" "F.Mask" "F.Paste")
			(net "DRV_ACT_24_N")
			(options
				(clearance outline)
				(anchor circle)
			)
			(primitives
				(gr_poly
					(pts
						(arc
							(start -0.1778 0.5715)
							(mid -0.321484 0.511984)
							(end -0.381 0.3683)
						)
						(arc
							(start -0.381 -0.3683)
							(mid -0.321484 -0.511984)
							(end -0.1778 -0.5715)
						)
						(arc
							(start 0.1778 -0.5715)
							(mid 0.321484 -0.511984)
							(end 0.381 -0.3683)
						)
						(arc
							(start 0.381 0.3683)
							(mid 0.321484 0.511984)
							(end 0.1778 0.5715)
						)
					)
					(width 0)
					(fill yes)
				)
			)
		)
		(pad "G" smd custom
			(at -0.98425 0.9525)
			(size 0.1905 0.1905)
			(layers "F.Cu" "F.Mask" "F.Paste")
			(net "DRIVE_B_24_ACT")
			(options
				(clearance outline)
				(anchor circle)
			)
			(primitives
				(gr_poly
					(pts
						(arc
							(start -0.1778 0.5715)
							(mid -0.321484 0.511984)
							(end -0.381 0.3683)
						)
						(arc
							(start -0.381 -0.3683)
							(mid -0.321484 -0.511984)
							(end -0.1778 -0.5715)
						)
						(arc
							(start 0.1778 -0.5715)
							(mid 0.321484 -0.511984)
							(end 0.381 -0.3683)
						)
						(arc
							(start 0.381 0.3683)
							(mid 0.321484 0.511984)
							(end 0.1778 0.5715)
						)
					)
					(width 0)
					(fill yes)
				)
			)
		)
		(pad "S" smd custom
			(at 0.98425 0.9525)
			(size 0.1905 0.1905)
			(layers "F.Cu" "F.Mask" "F.Paste")
			(net "GND")
			(options
				(clearance outline)
				(anchor circle)
			)
			(primitives
				(gr_poly
					(pts
						(arc
							(start -0.1778 0.5715)
							(mid -0.321484 0.511984)
							(end -0.381 0.3683)
						)
						(arc
							(start -0.381 -0.3683)
							(mid -0.321484 -0.511984)
							(end -0.1778 -0.5715)
						)
						(arc
							(start 0.1778 -0.5715)
							(mid 0.321484 -0.511984)
							(end 0.381 -0.3683)
						)
						(arc
							(start 0.381 0.3683)
							(mid 0.321484 0.511984)
							(end 0.1778 0.5715)
						)
					)
					(width 0)
					(fill yes)
				)
			)
		)
	)
	(footprint ""
		(layer "F.Cu")
		(at 447.16573 -256.811018 90)
		(property "Reference" "R1253"
			(at 0 0 90)
			(layer "F.SilkS")
			(hide yes)
			(effects
				(font
					(size 1.27 1.27)
				)
			)
		)
		(property "Value" "100KR2F-L1-GP"
			(at 0.064008 -3.993896 90)
			(unlocked yes)
			(layer "F.Fab")
			(hide yes)
			(effects
				(font
					(size 1.016 1.016)
					(thickness 0.1524)
				)
			)
		)
		(property "Device Type" "R402H16"
			(at 0.064008 -5.517896 90)
			(unlocked yes)
			(layer "F.Fab")
			(hide yes)
			(effects
				(font
					(size 1.016 1.016)
					(thickness 0.1524)
				)
			)
		)
		(duplicate_pad_numbers_are_jumpers no)
		(fp_line
			(start 0.508 -0.9398)
			(end -0.508 -0.9398)
			(stroke
				(width 0.1524)
				(type default)
			)
			(layer "F.SilkS")
		)
		(fp_line
			(start -0.508 -0.9398)
			(end -0.508 0.9398)
			(stroke
				(width 0.1524)
				(type default)
			)
			(layer "F.SilkS")
		)
		(fp_rect
			(start -0.508 0.9398)
			(end 0.508 -0.9398)
			(stroke
				(width 0)
				(type default)
			)
			(fill no)
			(layer "F.CrtYd")
		)
		(fp_rect
			(start -0.508 0.9398)
			(end 0.508 -0.9398)
			(stroke
				(width 0)
				(type default)
			)
			(fill no)
			(layer "F.Fab")
		)
		(pad "1" smd custom
			(at 0 -0.4445 90)
			(size 0.1397 0.1397)
			(layers "F.Cu" "F.Mask" "F.Paste")
			(net "AGND_P5V_C")
			(options
				(clearance outline)
				(anchor circle)
			)
			(primitives
				(gr_poly
					(pts
						(arc
							(start -0.1778 -0.2794)
							(mid -0.249642 -0.249642)
							(end -0.2794 -0.1778)
						)
						(arc
							(start -0.2794 0.1778)
							(mid -0.249642 0.249642)
							(end -0.1778 0.2794)
						)
						(arc
							(start 0.1778 0.2794)
							(mid 0.249642 0.249642)
							(end 0.2794 0.1778)
						)
						(arc
							(start 0.2794 -0.1778)
							(mid 0.249642 -0.249642)
							(end 0.1778 -0.2794)
						)
					)
					(width 0)
					(fill yes)
				)
			)
		)
		(pad "2" smd custom
			(at 0 0.4445 90)
			(size 0.1397 0.1397)
			(layers "F.Cu" "F.Mask" "F.Paste")
			(net "P5V_C_MODE")
			(options
				(clearance outline)
				(anchor circle)
			)
			(primitives
				(gr_poly
					(pts
						(arc
							(start -0.1778 -0.2794)
							(mid -0.249642 -0.249642)
							(end -0.2794 -0.1778)
						)
						(arc
							(start -0.2794 0.1778)
							(mid -0.249642 0.249642)
							(end -0.1778 0.2794)
						)
						(arc
							(start 0.1778 0.2794)
							(mid 0.249642 0.249642)
							(end 0.2794 0.1778)
						)
						(arc
							(start 0.2794 -0.1778)
							(mid 0.249642 -0.249642)
							(end 0.1778 -0.2794)
						)
					)
					(width 0)
					(fill yes)
				)
			)
		)
	)
	(footprint ""
		(layer "F.Cu")
		(at 81.600548 -275.633942)
		(property "Reference" "R193"
			(at 0 0 0)
			(layer "F.SilkS")
			(hide yes)
			(effects
				(font
					(size 1.27 1.27)
				)
			)
		)
		(property "Value" "0R2J-2-GP"
			(at 0.064008 -3.993896 0)
			(unlocked yes)
			(layer "F.Fab")
			(hide yes)
			(effects
				(font
					(size 1.016 1.016)
					(thickness 0.1524)
				)
			)
		)
		(property "Device Type" "R402H16"
			(at 0.064008 -5.517896 0)
			(unlocked yes)
			(layer "F.Fab")
			(hide yes)
			(effects
				(font
					(size 1.016 1.016)
					(thickness 0.1524)
				)
			)
		)
		(duplicate_pad_numbers_are_jumpers no)
		(fp_line
			(start -0.508 -0.9398)
			(end -0.508 0.9398)
			(stroke
				(width 0.1524)
				(type default)
			)
			(layer "F.SilkS")
		)
		(fp_line
			(start 0.508 -0.9398)
			(end -0.508 -0.9398)
			(stroke
				(width 0.1524)
				(type default)
			)
			(layer "F.SilkS")
		)
		(fp_rect
			(start -0.508 0.9398)
			(end 0.508 -0.9398)
			(stroke
				(width 0)
				(type default)
			)
			(fill no)
			(layer "F.CrtYd")
		)
		(fp_rect
			(start -0.508 0.9398)
			(end 0.508 -0.9398)
			(stroke
				(width 0)
				(type default)
			)
			(fill no)
			(layer "F.Fab")
		)
		(pad "1" smd custom
			(at 0 -0.4445)
			(size 0.1397 0.1397)
			(layers "F.Cu" "F.Mask" "F.Paste")
			(net "SW_HDD_G2")
			(options
				(clearance outline)
				(anchor circle)
			)
			(primitives
				(gr_poly
					(pts
						(arc
							(start -0.1778 -0.2794)
							(mid -0.249642 -0.249642)
							(end -0.2794 -0.1778)
						)
						(arc
							(start -0.2794 0.1778)
							(mid -0.249642 0.249642)
							(end -0.1778 0.2794)
						)
						(arc
							(start 0.1778 0.2794)
							(mid 0.249642 0.249642)
							(end 0.2794 0.1778)
						)
						(arc
							(start 0.2794 -0.1778)
							(mid 0.249642 -0.249642)
							(end 0.1778 -0.2794)
						)
					)
					(width 0)
					(fill yes)
				)
			)
		)
		(pad "2" smd custom
			(at 0 0.4445)
			(size 0.1397 0.1397)
			(layers "F.Cu" "F.Mask" "F.Paste")
			(net "SW_HDD_R2")
			(options
				(clearance outline)
				(anchor circle)
			)
			(primitives
				(gr_poly
					(pts
						(arc
							(start -0.1778 -0.2794)
							(mid -0.249642 -0.249642)
							(end -0.2794 -0.1778)
						)
						(arc
							(start -0.2794 0.1778)
							(mid -0.249642 0.249642)
							(end -0.1778 0.2794)
						)
						(arc
							(start 0.1778 0.2794)
							(mid 0.249642 0.249642)
							(end 0.2794 0.1778)
						)
						(arc
							(start 0.2794 -0.1778)
							(mid 0.249642 -0.249642)
							(end 0.1778 -0.2794)
						)
					)
					(width 0)
					(fill yes)
				)
			)
		)
	)
	(footprint ""
		(layer "F.Cu")
		(at 272.3388 -13.208 180)
		(property "Reference" "TP196"
			(at 0 0 180)
			(layer "F.SilkS")
			(hide yes)
			(effects
				(font
					(size 1.27 1.27)
				)
			)
		)
		(property "Value" "TPAD32-GP"
			(at -0.0508 -1.6764 180)
			(unlocked yes)
			(layer "F.Fab")
			(hide yes)
			(effects
				(font
					(size 1.016 1.016)
					(thickness 0.1524)
				)
			)
		)
		(property "Device Type" "TPAD32"
			(at -0.0508 -3.2004 180)
			(unlocked yes)
			(layer "F.Fab")
			(hide yes)
			(effects
				(font
					(size 1.016 1.016)
					(thickness 0.1524)
				)
			)
		)
		(duplicate_pad_numbers_are_jumpers no)
		(fp_poly
			(pts
				(arc
					(start -0.4064 0)
					(mid 0.4064 0)
					(end -0.4064 0)
				)
			)
			(stroke
				(width 0)
				(type default)
			)
			(fill no)
			(layer "F.CrtYd")
		)
		(fp_poly
			(pts
				(arc
					(start -0.7112 0)
					(mid 0.7112 0)
					(end -0.7112 0)
				)
			)
			(stroke
				(width 0)
				(type default)
			)
			(fill no)
			(layer "F.Fab")
		)
		(pad "1" smd circle
			(at 0 0 180)
			(size 0.8128 0.8128)
			(layers "F.Cu" "F.Mask" "F.Paste")
			(net "TP_COMP_B_NCSI_RXER")
		)
	)
	(footprint ""
		(layer "F.Cu")
		(at 240.284 -249.174)
		(property "Reference" "R52"
			(at 0 0 0)
			(layer "F.SilkS")
			(hide yes)
			(effects
				(font
					(size 1.27 1.27)
				)
			)
		)
		(property "Value" "0R2J-2-GP"
			(at 0.064008 -3.993896 0)
			(unlocked yes)
			(layer "F.Fab")
			(hide yes)
			(effects
				(font
					(size 1.016 1.016)
					(thickness 0.1524)
				)
			)
		)
		(property "Device Type" "R402H16"
			(at 0.064008 -5.517896 0)
			(unlocked yes)
			(layer "F.Fab")
			(hide yes)
			(effects
				(font
					(size 1.016 1.016)
					(thickness 0.1524)
				)
			)
		)
		(duplicate_pad_numbers_are_jumpers no)
		(fp_line
			(start -0.508 -0.9398)
			(end -0.508 0.9398)
			(stroke
				(width 0.1524)
				(type default)
			)
			(layer "F.SilkS")
		)
		(fp_line
			(start 0.508 -0.9398)
			(end -0.508 -0.9398)
			(stroke
				(width 0.1524)
				(type default)
			)
			(layer "F.SilkS")
		)
		(fp_rect
			(start -0.508 0.9398)
			(end 0.508 -0.9398)
			(stroke
				(width 0)
				(type default)
			)
			(fill no)
			(layer "F.CrtYd")
		)
		(fp_rect
			(start -0.508 0.9398)
			(end 0.508 -0.9398)
			(stroke
				(width 0)
				(type default)
			)
			(fill no)
			(layer "F.Fab")
		)
		(pad "1" smd custom
			(at 0 -0.4445)
			(size 0.1397 0.1397)
			(layers "F.Cu" "F.Mask" "F.Paste")
			(net "IO_EXP5_INT_N")
			(options
				(clearance outline)
				(anchor circle)
			)
			(primitives
				(gr_poly
					(pts
						(arc
							(start -0.1778 -0.2794)
							(mid -0.249642 -0.249642)
							(end -0.2794 -0.1778)
						)
						(arc
							(start -0.2794 0.1778)
							(mid -0.249642 0.249642)
							(end -0.1778 0.2794)
						)
						(arc
							(start 0.1778 0.2794)
							(mid 0.249642 0.249642)
							(end 0.2794 0.1778)
						)
						(arc
							(start 0.2794 -0.1778)
							(mid 0.249642 -0.249642)
							(end 0.1778 -0.2794)
						)
					)
					(width 0)
					(fill yes)
				)
			)
		)
		(pad "2" smd custom
			(at 0 0.4445)
			(size 0.1397 0.1397)
			(layers "F.Cu" "F.Mask" "F.Paste")
			(net "DRIVE_INSERT_ALERT_A_N")
			(options
				(clearance outline)
				(anchor circle)
			)
			(primitives
				(gr_poly
					(pts
						(arc
							(start -0.1778 -0.2794)
							(mid -0.249642 -0.249642)
							(end -0.2794 -0.1778)
						)
						(arc
							(start -0.2794 0.1778)
							(mid -0.249642 0.249642)
							(end -0.1778 0.2794)
						)
						(arc
							(start 0.1778 0.2794)
							(mid 0.249642 0.249642)
							(end 0.2794 0.1778)
						)
						(arc
							(start 0.2794 -0.1778)
							(mid 0.249642 -0.249642)
							(end 0.1778 -0.2794)
						)
					)
					(width 0)
					(fill yes)
				)
			)
		)
	)
	(footprint ""
		(layer "F.Cu")
		(at 122.849894 -57.909968 -90)
		(property "Reference" "HDDSAS27"
			(at 0 0 270)
			(layer "F.SilkS")
			(hide yes)
			(effects
				(font
					(size 1.27 1.27)
				)
			)
		)
		(property "Value" "SKT-SAS15P-14P-45-GP"
			(at -20.7645 -8.9789 270)
			(unlocked yes)
			(layer "F.Fab")
			(hide yes)
			(effects
				(font
					(size 1.016 1.016)
					(thickness 0.1524)
				)
			)
		)
		(property "Device Type" "10120818-001C-TRLF"
			(at -20.7645 -10.5029 270)
			(unlocked yes)
			(layer "F.Fab")
			(hide yes)
			(effects
				(font
					(size 1.016 1.016)
					(thickness 0.1524)
				)
			)
		)
		(duplicate_pad_numbers_are_jumpers no)
		(fp_line
			(start 1.651 4.2926)
			(end 1.651 3.0099)
			(stroke
				(width 0.1524)
				(type default)
			)
			(layer "F.SilkS")
		)
		(fp_line
			(start 8.509 4.2926)
			(end 1.651 4.2926)
			(stroke
				(width 0.1524)
				(type default)
			)
			(layer "F.SilkS")
		)
		(fp_line
			(start -23.4188 3.0099)
			(end -23.4188 -3.2512)
			(stroke
				(width 0.1524)
				(type default)
			)
			(layer "F.SilkS")
		)
		(fp_line
			(start 1.651 3.0099)
			(end -23.4188 3.0099)
			(stroke
				(width 0.1524)
				(type default)
			)
			(layer "F.SilkS")
		)
		(fp_line
			(start 8.509 3.0099)
			(end 8.509 4.2926)
			(stroke
				(width 0.1524)
				(type default)
			)
			(layer "F.SilkS")
		)
		(fp_line
			(start 23.4188 3.0099)
			(end 8.509 3.0099)
			(stroke
				(width 0.1524)
				(type default)
			)
			(layer "F.SilkS")
		)
		(fp_line
			(start -23.4188 -3.2512)
			(end 23.4188 -3.2512)
			(stroke
				(width 0.1524)
				(type default)
			)
			(layer "F.SilkS")
		)
		(fp_line
			(start 23.4188 -3.2512)
			(end 23.4188 3.0099)
			(stroke
				(width 0.1524)
				(type default)
			)
			(layer "F.SilkS")
		)
		(fp_line
			(start 15.5067 -3.3401)
			(end 16.2687 -3.3401)
			(stroke
				(width 0.3302)
				(type default)
			)
			(layer "F.SilkS")
		)
		(fp_poly
			(pts
				(xy 15.868904 -3.230372) (xy 16.503904 -3.865372) (xy 15.233904 -3.865372)
			)
			(stroke
				(width 0)
				(type default)
			)
			(fill yes)
			(layer "F.SilkS")
		)
		(fp_poly
			(pts
				(xy -22.8727 -2.7559) (xy 22.8727 -2.7559) (xy 22.8727 2.7559) (xy 8.255 2.7559) (xy 8.255 3.5179)
				(xy 1.905 3.5179) (xy 1.905 2.7559) (xy -22.8727 2.7559)
			)
			(stroke
				(width 0)
				(type default)
			)
			(fill no)
			(layer "F.CrtYd")
		)
		(fp_poly
			(pts
				(xy 1.397 4.5466) (xy 1.397 3.2639) (xy -23.6728 3.2639) (xy -23.6728 -3.5052) (xy 23.6728 -3.5052)
				(xy 23.6728 -0.00635) (xy 22.8727 -0.00635) (xy 22.8727 -2.7559) (xy -22.8727 -2.7559) (xy -22.8727 2.7559)
				(xy 1.905 2.7559) (xy 1.905 3.5179) (xy 8.255 3.5179) (xy 8.255 2.7559) (xy 22.8727 2.7559) (xy 22.8727 0.00635)
				(xy 23.6728 0.00635) (xy 23.6728 3.2639) (xy 8.763 3.2639) (xy 8.763 4.5466)
			)
			(stroke
				(width 0)
				(type default)
			)
			(fill no)
			(layer "F.CrtYd")
		)
		(fp_poly
			(pts
				(xy 1.397 4.5466) (xy 1.397 3.2639) (xy -23.6728 3.2639) (xy -23.6728 -3.5052) (xy 23.6728 -3.5052)
				(xy 23.6728 3.2639) (xy 8.763 3.2639) (xy 8.763 4.5466)
			)
			(stroke
				(width 0)
				(type default)
			)
			(fill no)
			(layer "F.Fab")
		)
		(pad "" np_thru_hole circle
			(at -18.874994 0 270)
			(size 0.254 0.254)
			(drill 1.3462)
			(layers "*.Cu" "*.Mask")
			(clearance 0.9017)
			(thermal_gap 0.9017)
		)
		(pad "" np_thru_hole circle
			(at 18.874994 0 270)
			(size 0.254 0.254)
			(drill 0.9398)
			(layers "*.Cu" "*.Mask")
			(clearance 0.6985)
			(thermal_gap 0.6985)
		)
		(pad "G1" smd rect
			(at 21.874988 0 270)
			(size 2.5908 2.5908)
			(layers "F.Cu" "F.Mask" "F.Paste")
			(net "GND")
		)
		(pad "G2" smd rect
			(at -21.874988 0 270)
			(size 2.5908 2.5908)
			(layers "F.Cu" "F.Mask" "F.Paste")
			(net "GND")
		)
		(pad "P1" smd rect
			(at 1.905 -1.82499 270)
			(size 0.6096 2.3622)
			(layers "F.Cu" "F.Mask" "F.Paste")
			(net "Net_2076")
		)
		(pad "P2" smd rect
			(at 0.635 -1.82499 270)
			(size 0.6096 2.3622)
			(layers "F.Cu" "F.Mask" "F.Paste")
			(net "Net_2077")
		)
		(pad "P3" smd rect
			(at -0.635 -1.82499 270)
			(size 0.6096 2.3622)
			(layers "F.Cu" "F.Mask" "F.Paste")
			(net "Net_2078")
		)
		(pad "P4" smd rect
			(at -1.905 -1.82499 270)
			(size 0.6096 2.3622)
			(layers "F.Cu" "F.Mask" "F.Paste")
			(net "GND")
		)
		(pad "P5" smd rect
			(at -3.175 -1.82499 270)
			(size 0.6096 2.3622)
			(layers "F.Cu" "F.Mask" "F.Paste")
			(net "HDD_PRSNT_27")
		)
		(pad "P6" smd rect
			(at -4.445 -1.82499 270)
			(size 0.6096 2.3622)
			(layers "F.Cu" "F.Mask" "F.Paste")
			(net "GND")
		)
		(pad "P7" smd rect
			(at -5.715 -1.82499 270)
			(size 0.6096 2.3622)
			(layers "F.Cu" "F.Mask" "F.Paste")
			(net "5V_PRE_27")
		)
		(pad "P8" smd rect
			(at -6.985 -1.82499 270)
			(size 0.6096 2.3622)
			(layers "F.Cu" "F.Mask" "F.Paste")
			(net "P5V_HDD27")
		)
		(pad "P9" smd rect
			(at -8.255 -1.82499 270)
			(size 0.6096 2.3622)
			(layers "F.Cu" "F.Mask" "F.Paste")
			(net "P5V_HDD27")
		)
		(pad "P10" smd rect
			(at -9.525 -1.82499 270)
			(size 0.6096 2.3622)
			(layers "F.Cu" "F.Mask" "F.Paste")
			(net "GND")
		)
		(pad "P11" smd rect
			(at -10.795 -1.82499 270)
			(size 0.6096 2.3622)
			(layers "F.Cu" "F.Mask" "F.Paste")
			(net "ACT_HDD_27")
		)
		(pad "P12" smd rect
			(at -12.065 -1.82499 270)
			(size 0.6096 2.3622)
			(layers "F.Cu" "F.Mask" "F.Paste")
			(net "GND")
		)
		(pad "P13" smd rect
			(at -13.335 -1.82499 270)
			(size 0.6096 2.3622)
			(layers "F.Cu" "F.Mask" "F.Paste")
			(net "12V_PRE_27")
		)
		(pad "P14" smd rect
			(at -14.605 -1.82499 270)
			(size 0.6096 2.3622)
			(layers "F.Cu" "F.Mask" "F.Paste")
			(net "P12V_HDD27")
		)
		(pad "P15" smd rect
			(at -15.875 -1.82499 270)
			(size 0.6096 2.3622)
			(layers "F.Cu" "F.Mask" "F.Paste")
			(net "P12V_HDD27")
		)
		(pad "S1" smd rect
			(at 15.875 -1.82499 270)
			(size 0.6096 2.3622)
			(layers "F.Cu" "F.Mask" "F.Paste")
			(net "GND")
		)
		(pad "S2" smd rect
			(at 14.605 -1.82499 270)
			(size 0.6096 2.3622)
			(layers "F.Cu" "F.Mask" "F.Paste")
			(net "SAS_HDD_RX_P27")
		)
		(pad "S3" smd rect
			(at 13.335 -1.82499 270)
			(size 0.6096 2.3622)
			(layers "F.Cu" "F.Mask" "F.Paste")
			(net "SAS_HDD_RX_N27")
		)
		(pad "S4" smd rect
			(at 12.065 -1.82499 270)
			(size 0.6096 2.3622)
			(layers "F.Cu" "F.Mask" "F.Paste")
			(net "GND")
		)
		(pad "S5" smd rect
			(at 10.795 -1.82499 270)
			(size 0.6096 2.3622)
			(layers "F.Cu" "F.Mask" "F.Paste")
			(net "PHY_DRV_A_TO_SCC_A_27_DN")
		)
		(pad "S6" smd rect
			(at 9.525 -1.82499 270)
			(size 0.6096 2.3622)
			(layers "F.Cu" "F.Mask" "F.Paste")
			(net "PHY_DRV_A_TO_SCC_A_27_DP")
		)
		(pad "S7" smd rect
			(at 8.255 -1.82499 270)
			(size 0.6096 2.3622)
			(layers "F.Cu" "F.Mask" "F.Paste")
			(net "GND")
		)
		(pad "S8" smd rect
			(at 7.480046 2.845054 270)
			(size 0.508 2.3622)
			(layers "F.Cu" "F.Mask" "F.Paste")
			(net "GND")
		)
		(pad "S9" smd rect
			(at 6.679946 2.845054 270)
			(size 0.508 2.3622)
			(layers "F.Cu" "F.Mask" "F.Paste")
			(net "Net_465")
		)
		(pad "S10" smd rect
			(at 5.8801 2.845054 270)
			(size 0.508 2.3622)
			(layers "F.Cu" "F.Mask" "F.Paste")
			(net "Net_357")
		)
		(pad "S11" smd rect
			(at 5.08 2.845054 270)
			(size 0.508 2.3622)
			(layers "F.Cu" "F.Mask" "F.Paste")
			(net "GND")
		)
		(pad "S12" smd rect
			(at 4.2799 2.845054 270)
			(size 0.508 2.3622)
			(layers "F.Cu" "F.Mask" "F.Paste")
			(net "Net_393")
		)
		(pad "S13" smd rect
			(at 3.480054 2.845054 270)
			(size 0.508 2.3622)
			(layers "F.Cu" "F.Mask" "F.Paste")
			(net "Net_429")
		)
		(pad "S14" smd rect
			(at 2.679954 2.845054 270)
			(size 0.508 2.3622)
			(layers "F.Cu" "F.Mask" "F.Paste")
			(net "GND")
		)
		(zone
			(layer "F.Cu")
			(hatch none 0.5)
			(connect_pads
				(clearance 0)
			)
			(min_thickness 0.25)
			(keepout
				(tracks not_allowed)
				(vias allowed)
				(pads allowed)
				(copperpour not_allowed)
				(footprints allowed)
			)
			(placement
				(enabled no)
				(sheetname "")
			)
			(fill
				(thermal_gap 0.5)
				(thermal_bridge_width 0.5)
				(island_removal_mode 0)
			)
			(polygon
				(pts
					(xy 126.507494 -74.648568) (xy 119.433594 -74.648568) (xy 119.433594 -81.582768) (xy 120.538494 -81.582768)
					(xy 120.538494 -77.467968) (xy 125.161294 -77.467968) (xy 125.161294 -81.582768) (xy 126.507494 -81.582768)
				)
			)
		)
		(zone
			(layer "F.Cu")
			(hatch none 0.5)
			(connect_pads
				(clearance 0)
			)
			(min_thickness 0.25)
			(keepout
				(tracks allowed)
				(vias not_allowed)
				(pads allowed)
				(copperpour not_allowed)
				(footprints allowed)
			)
			(placement
				(enabled no)
				(sheetname "")
			)
			(fill
				(thermal_gap 0.5)
				(thermal_bridge_width 0.5)
				(island_removal_mode 0)
			)
			(polygon
				(pts
					(xy 126.507494 -74.648568) (xy 119.433594 -74.648568) (xy 119.433594 -81.582768) (xy 120.538494 -81.582768)
					(xy 120.538494 -77.467968) (xy 125.161294 -77.467968) (xy 125.161294 -81.582768) (xy 126.507494 -81.582768)
				)
			)
		)
		(zone
			(layer "F.Cu")
			(hatch none 0.5)
			(connect_pads
				(clearance 0)
			)
			(min_thickness 0.25)
			(keepout
				(tracks not_allowed)
				(vias allowed)
				(pads allowed)
				(copperpour not_allowed)
				(footprints allowed)
			)
			(placement
				(enabled no)
				(sheetname "")
			)
			(fill
				(thermal_gap 0.5)
				(thermal_bridge_width 0.5)
				(island_removal_mode 0)
			)
			(polygon
				(pts
					(xy 126.507494 -41.171368) (xy 119.433594 -41.171368) (xy 119.433594 -34.237168) (xy 120.538494 -34.237168)
					(xy 120.538494 -38.351968) (xy 125.161294 -38.351968) (xy 125.161294 -34.237168) (xy 126.507494 -34.237168)
				)
			)
		)
		(zone
			(layer "F.Cu")
			(hatch none 0.5)
			(connect_pads
				(clearance 0)
			)
			(min_thickness 0.25)
			(keepout
				(tracks allowed)
				(vias not_allowed)
				(pads allowed)
				(copperpour not_allowed)
				(footprints allowed)
			)
			(placement
				(enabled no)
				(sheetname "")
			)
			(fill
				(thermal_gap 0.5)
				(thermal_bridge_width 0.5)
				(island_removal_mode 0)
			)
			(polygon
				(pts
					(xy 126.507494 -41.171368) (xy 119.433594 -41.171368) (xy 119.433594 -34.237168) (xy 120.538494 -34.237168)
					(xy 120.538494 -38.351968) (xy 125.161294 -38.351968) (xy 125.161294 -34.237168) (xy 126.507494 -34.237168)
				)
			)
		)
		(zone
			(layers "F.Cu" "B.Cu" "In1.Cu" "In2.Cu" "In3.Cu" "In4.Cu" "In5.Cu" "In6.Cu"
				"In7.Cu" "In8.Cu" "In9.Cu" "In10.Cu"
			)
			(hatch none 0.5)
			(connect_pads
				(clearance 0)
			)
			(min_thickness 0.25)
			(keepout
				(tracks not_allowed)
				(vias allowed)
				(pads allowed)
				(copperpour not_allowed)
				(footprints allowed)
			)
			(placement
				(enabled no)
				(sheetname "")
			)
			(fill
				(thermal_gap 0.5)
				(thermal_bridge_width 0.5)
				(island_removal_mode 0)
			)
			(polygon
				(pts
					(arc
						(start 123.624594 -39.034974)
						(mid 122.075194 -39.034974)
						(end 123.624594 -39.034974)
					)
				)
			)
		)
		(zone
			(layers "F.Cu" "B.Cu" "In1.Cu" "In2.Cu" "In3.Cu" "In4.Cu" "In5.Cu" "In6.Cu"
				"In7.Cu" "In8.Cu" "In9.Cu" "In10.Cu"
			)
			(hatch none 0.5)
			(connect_pads
				(clearance 0)
			)
			(min_thickness 0.25)
			(keepout
				(tracks not_allowed)
				(vias allowed)
				(pads allowed)
				(copperpour not_allowed)
				(footprints allowed)
			)
			(placement
				(enabled no)
				(sheetname "")
			)
			(fill
				(thermal_gap 0.5)
				(thermal_bridge_width 0.5)
				(island_removal_mode 0)
			)
			(polygon
				(pts
					(arc
						(start 123.827794 -76.784962)
						(mid 121.871994 -76.784962)
						(end 123.827794 -76.784962)
					)
				)
			)
		)
	)
	(footprint ""
		(layer "F.Cu")
		(at 366.994948 -149.428454 90)
		(property "Reference" "R144"
			(at 0 0 90)
			(layer "F.SilkS")
			(hide yes)
			(effects
				(font
					(size 1.27 1.27)
				)
			)
		)
		(property "Value" "0R5J-5-GP"
			(at 0 -8.9535 90)
			(unlocked yes)
			(layer "F.Fab")
			(hide yes)
			(effects
				(font
					(size 1.27 1.016)
					(thickness 0.1524)
				)
			)
		)
		(property "Device Type" "R805H24"
			(at 0 -10.6299 90)
			(unlocked yes)
			(layer "F.Fab")
			(hide yes)
			(effects
				(font
					(size 1.27 1.016)
					(thickness 0.1524)
				)
			)
		)
		(duplicate_pad_numbers_are_jumpers no)
		(fp_line
			(start 0.889 -1.7018)
			(end -0.889 -1.7018)
			(stroke
				(width 0.1524)
				(type default)
			)
			(layer "F.SilkS")
		)
		(fp_line
			(start 0.889 -1.7018)
			(end 0.889 -0.381)
			(stroke
				(width 0.1524)
				(type default)
			)
			(layer "F.SilkS")
		)
		(fp_line
			(start -0.889 -1.7018)
			(end -0.889 0.2794)
			(stroke
				(width 0.1524)
				(type default)
			)
			(layer "F.SilkS")
		)
		(fp_line
			(start -0.889 0.0762)
			(end -0.889 1.7018)
			(stroke
				(width 0.1524)
				(type default)
			)
			(layer "F.SilkS")
		)
		(fp_line
			(start 0.889 1.7018)
			(end 0.889 -0.508)
			(stroke
				(width 0.1524)
				(type default)
			)
			(layer "F.SilkS")
		)
		(fp_line
			(start -0.889 1.7018)
			(end 0.889 1.7018)
			(stroke
				(width 0.1524)
				(type default)
			)
			(layer "F.SilkS")
		)
		(fp_poly
			(pts
				(xy 0.9652 -1.778) (xy 0.9652 1.778) (xy -0.9652 1.778) (xy -0.9652 -1.778)
			)
			(stroke
				(width 0)
				(type default)
			)
			(fill no)
			(layer "F.CrtYd")
		)
		(fp_rect
			(start -0.9652 1.778)
			(end 0.9652 -1.778)
			(stroke
				(width 0)
				(type default)
			)
			(fill no)
			(layer "F.Fab")
		)
		(pad "1" smd rect
			(at 0 -0.9652 90)
			(size 1.397 1.143)
			(layers "F.Cu" "F.Mask" "F.Paste")
			(net "MB1_CM_GATE_R")
		)
		(pad "2" smd rect
			(at 0 0.9652 90)
			(size 1.397 1.143)
			(layers "F.Cu" "F.Mask" "F.Paste")
			(net "MB1_CM_GATE_C")
		)
	)
	(footprint ""
		(layer "F.Cu")
		(at 370.144294 -149.417024 90)
		(property "Reference" "C568"
			(at 0 0 90)
			(layer "F.SilkS")
			(hide yes)
			(effects
				(font
					(size 1.27 1.27)
				)
			)
		)
		(property "Value" "SCD033U50V3KX-1GP"
			(at 0 -2.8194 90)
			(unlocked yes)
			(layer "F.Fab")
			(hide yes)
			(effects
				(font
					(size 1.016 1.016)
					(thickness 0.1524)
				)
			)
		)
		(property "Device Type" "C603H36"
			(at 0 -4.3434 90)
			(unlocked yes)
			(layer "F.Fab")
			(hide yes)
			(effects
				(font
					(size 1.016 1.016)
					(thickness 0.1524)
				)
			)
		)
		(duplicate_pad_numbers_are_jumpers no)
		(fp_line
			(start 0.508 0)
			(end -0.508 0)
			(stroke
				(width 0.2032)
				(type default)
			)
			(layer "F.SilkS")
		)
		(fp_rect
			(start -0.5842 1.3335)
			(end 0.5842 -1.3335)
			(stroke
				(width 0)
				(type default)
			)
			(fill no)
			(layer "F.CrtYd")
		)
		(fp_rect
			(start -0.5842 1.3335)
			(end 0.5842 -1.3335)
			(stroke
				(width 0)
				(type default)
			)
			(fill no)
			(layer "F.Fab")
		)
		(pad "1" smd custom
			(at 0 -0.762 90)
			(size 0.2159 0.2159)
			(layers "F.Cu" "F.Mask" "F.Paste")
			(net "MB1_CM_GATE_C")
			(options
				(clearance outline)
				(anchor circle)
			)
			(primitives
				(gr_poly
					(pts
						(arc
							(start -0.3302 -0.4318)
							(mid -0.402042 -0.402042)
							(end -0.4318 -0.3302)
						)
						(arc
							(start -0.4318 0.3302)
							(mid -0.402042 0.402042)
							(end -0.3302 0.4318)
						)
						(arc
							(start 0.3302 0.4318)
							(mid 0.402042 0.402042)
							(end 0.4318 0.3302)
						)
						(arc
							(start 0.4318 -0.3302)
							(mid 0.402042 -0.402042)
							(end 0.3302 -0.4318)
						)
					)
					(width 0)
					(fill yes)
				)
			)
		)
		(pad "2" smd custom
			(at 0 0.762 90)
			(size 0.2159 0.2159)
			(layers "F.Cu" "F.Mask" "F.Paste")
			(net "GND")
			(options
				(clearance outline)
				(anchor circle)
			)
			(primitives
				(gr_poly
					(pts
						(arc
							(start -0.3302 -0.4318)
							(mid -0.402042 -0.402042)
							(end -0.4318 -0.3302)
						)
						(arc
							(start -0.4318 0.3302)
							(mid -0.402042 0.402042)
							(end -0.3302 0.4318)
						)
						(arc
							(start 0.3302 0.4318)
							(mid 0.402042 0.402042)
							(end 0.4318 0.3302)
						)
						(arc
							(start 0.4318 -0.3302)
							(mid 0.402042 -0.402042)
							(end 0.3302 -0.4318)
						)
					)
					(width 0)
					(fill yes)
				)
			)
		)
	)
	(footprint ""
		(layer "F.Cu")
		(at 299.351446 -25.74544 90)
		(property "Reference" "R1128"
			(at 0 0 90)
			(layer "F.SilkS")
			(hide yes)
			(effects
				(font
					(size 1.27 1.27)
				)
			)
		)
		(property "Value" "100KR2F-L1-GP"
			(at 0.064008 -3.993896 90)
			(unlocked yes)
			(layer "F.Fab")
			(hide yes)
			(effects
				(font
					(size 1.016 1.016)
					(thickness 0.1524)
				)
			)
		)
		(property "Device Type" "R402H16"
			(at 0.064008 -5.517896 90)
			(unlocked yes)
			(layer "F.Fab")
			(hide yes)
			(effects
				(font
					(size 1.016 1.016)
					(thickness 0.1524)
				)
			)
		)
		(duplicate_pad_numbers_are_jumpers no)
		(fp_line
			(start 0.508 -0.9398)
			(end -0.508 -0.9398)
			(stroke
				(width 0.1524)
				(type default)
			)
			(layer "F.SilkS")
		)
		(fp_line
			(start -0.508 -0.9398)
			(end -0.508 0.9398)
			(stroke
				(width 0.1524)
				(type default)
			)
			(layer "F.SilkS")
		)
		(fp_rect
			(start -0.508 0.9398)
			(end 0.508 -0.9398)
			(stroke
				(width 0)
				(type default)
			)
			(fill no)
			(layer "F.CrtYd")
		)
		(fp_rect
			(start -0.508 0.9398)
			(end 0.508 -0.9398)
			(stroke
				(width 0)
				(type default)
			)
			(fill no)
			(layer "F.Fab")
		)
		(pad "1" smd custom
			(at 0 -0.4445 90)
			(size 0.1397 0.1397)
			(layers "F.Cu" "F.Mask" "F.Paste")
			(net "PCIE_COMP_B_TO_IOM_B_RST_3")
			(options
				(clearance outline)
				(anchor circle)
			)
			(primitives
				(gr_poly
					(pts
						(arc
							(start -0.1778 -0.2794)
							(mid -0.249642 -0.249642)
							(end -0.2794 -0.1778)
						)
						(arc
							(start -0.2794 0.1778)
							(mid -0.249642 0.249642)
							(end -0.1778 0.2794)
						)
						(arc
							(start 0.1778 0.2794)
							(mid 0.249642 0.249642)
							(end 0.2794 0.1778)
						)
						(arc
							(start 0.2794 -0.1778)
							(mid 0.249642 -0.249642)
							(end 0.1778 -0.2794)
						)
					)
					(width 0)
					(fill yes)
				)
			)
		)
		(pad "2" smd custom
			(at 0 0.4445 90)
			(size 0.1397 0.1397)
			(layers "F.Cu" "F.Mask" "F.Paste")
			(net "GND")
			(options
				(clearance outline)
				(anchor circle)
			)
			(primitives
				(gr_poly
					(pts
						(arc
							(start -0.1778 -0.2794)
							(mid -0.249642 -0.249642)
							(end -0.2794 -0.1778)
						)
						(arc
							(start -0.2794 0.1778)
							(mid -0.249642 0.249642)
							(end -0.1778 0.2794)
						)
						(arc
							(start 0.1778 0.2794)
							(mid 0.249642 0.249642)
							(end 0.2794 0.1778)
						)
						(arc
							(start 0.2794 -0.1778)
							(mid 0.249642 -0.249642)
							(end 0.1778 -0.2794)
						)
					)
					(width 0)
					(fill yes)
				)
			)
		)
	)
	(footprint ""
		(layer "F.Cu")
		(at 474.006926 -64.683894 90)
		(property "Reference" "R936"
			(at 0 0 90)
			(layer "F.SilkS")
			(hide yes)
			(effects
				(font
					(size 1.27 1.27)
				)
			)
		)
		(property "Value" "2R6F-GP"
			(at -0.0508 -4.8514 90)
			(unlocked yes)
			(layer "F.Fab")
			(hide yes)
			(effects
				(font
					(size 1.016 1.016)
					(thickness 0.1524)
				)
			)
		)
		(property "Device Type" "R1206H26"
			(at 0 -6.3754 90)
			(unlocked yes)
			(layer "F.Fab")
			(hide yes)
			(effects
				(font
					(size 1.016 1.016)
					(thickness 0.1524)
				)
			)
		)
		(duplicate_pad_numbers_are_jumpers no)
		(fp_line
			(start 1.016 -2.2352)
			(end 1.016 2.2352)
			(stroke
				(width 0.1524)
				(type default)
			)
			(layer "F.SilkS")
		)
		(fp_line
			(start -1.016 -2.2352)
			(end 1.016 -2.2352)
			(stroke
				(width 0.1524)
				(type default)
			)
			(layer "F.SilkS")
		)
		(fp_line
			(start 1.016 2.2352)
			(end -1.016 2.2352)
			(stroke
				(width 0.1524)
				(type default)
			)
			(layer "F.SilkS")
		)
		(fp_line
			(start -1.016 2.2352)
			(end -1.016 -2.2352)
			(stroke
				(width 0.1524)
				(type default)
			)
			(layer "F.SilkS")
		)
		(fp_rect
			(start -1.0922 2.3114)
			(end 1.0922 -2.3114)
			(stroke
				(width 0)
				(type default)
			)
			(fill no)
			(layer "F.CrtYd")
		)
		(fp_poly
			(pts
				(xy -1.0922 -2.3114) (xy 1.0922 -2.3114) (xy 1.0922 2.3114) (xy -1.0922 2.3114)
			)
			(stroke
				(width 0)
				(type default)
			)
			(fill no)
			(layer "F.Fab")
		)
		(pad "1" smd rect
			(at 0 -1.397 90)
			(size 1.651 1.27)
			(layers "F.Cu" "F.Mask" "F.Paste")
			(net "P12V_HDD35")
		)
		(pad "2" smd rect
			(at 0 1.397 90)
			(size 1.651 1.27)
			(layers "F.Cu" "F.Mask" "F.Paste")
			(net "12V_PRE_35")
		)
	)
	(footprint ""
		(layer "F.Cu")
		(at 368.862102 -47.792894 90)
		(property "Reference" "D31"
			(at 0 0 90)
			(layer "F.SilkS")
			(hide yes)
			(effects
				(font
					(size 1.27 1.27)
				)
			)
		)
		(property "Value" "RB551V30-GP"
			(at 0 -6.7818 90)
			(unlocked yes)
			(layer "F.Fab")
			(hide yes)
			(effects
				(font
					(size 1.016 1.016)
					(thickness 0.1524)
				)
			)
		)
		(property "Device Type" "SOD323AKH38"
			(at 0 -8.6868 90)
			(unlocked yes)
			(layer "F.Fab")
			(hide yes)
			(effects
				(font
					(size 1.016 1.016)
					(thickness 0.1524)
				)
			)
		)
		(duplicate_pad_numbers_are_jumpers no)
		(fp_line
			(start 0.889 -1.9304)
			(end 0.889 2.159)
			(stroke
				(width 0.1524)
				(type default)
			)
			(layer "F.SilkS")
		)
		(fp_line
			(start -0.889 -1.9304)
			(end 0.889 -1.9304)
			(stroke
				(width 0.1524)
				(type default)
			)
			(layer "F.SilkS")
		)
		(fp_line
			(start 0.762 2.0574)
			(end -0.762 2.0574)
			(stroke
				(width 0.508)
				(type default)
			)
			(layer "F.SilkS")
		)
		(fp_line
			(start 0.889 2.159)
			(end -0.889 2.159)
			(stroke
				(width 0.1524)
				(type default)
			)
			(layer "F.SilkS")
		)
		(fp_line
			(start -0.889 2.159)
			(end -0.889 -1.9304)
			(stroke
				(width 0.1524)
				(type default)
			)
			(layer "F.SilkS")
		)
		(fp_rect
			(start -1.016 2.3114)
			(end 1.016 -2.0066)
			(stroke
				(width 0)
				(type default)
			)
			(fill no)
			(layer "F.CrtYd")
		)
		(fp_poly
			(pts
				(xy -1.016 -2.0066) (xy 1.016 -2.0066) (xy 1.016 2.3114) (xy -1.016 2.3114)
			)
			(stroke
				(width 0)
				(type default)
			)
			(fill no)
			(layer "F.Fab")
		)
		(pad "A" smd rect
			(at 0 -1.143 90)
			(size 0.5588 1.016)
			(layers "F.Cu" "F.Mask" "F.Paste")
			(net "SW_HDD_R31")
		)
		(pad "K" smd rect
			(at 0 1.143 90)
			(size 0.5588 1.016)
			(layers "F.Cu" "F.Mask" "F.Paste")
			(net "SW_HDD_N31")
		)
	)
	(footprint ""
		(layer "F.Cu")
		(at 23.936198 -186.287918)
		(property "Reference" "C202"
			(at 0 0 0)
			(layer "F.SilkS")
			(hide yes)
			(effects
				(font
					(size 1.27 1.27)
				)
			)
		)
		(property "Value" "SC4D7U25V5KX-1-GP"
			(at -0.0762 -6.1214 0)
			(unlocked yes)
			(layer "F.Fab")
			(hide yes)
			(effects
				(font
					(size 1.016 1.016)
					(thickness 0.1524)
				)
			)
		)
		(property "Device Type" "C805H58"
			(at -0.0762 -8.1534 0)
			(unlocked yes)
			(layer "F.Fab")
			(hide yes)
			(effects
				(font
					(size 1.016 1.016)
					(thickness 0.1524)
				)
			)
		)
		(duplicate_pad_numbers_are_jumpers no)
		(fp_line
			(start 0.635 0)
			(end -0.635 0)
			(stroke
				(width 0.508)
				(type default)
			)
			(layer "F.SilkS")
		)
		(fp_rect
			(start -0.9652 1.778)
			(end 0.9652 -1.778)
			(stroke
				(width 0)
				(type default)
			)
			(fill no)
			(layer "F.CrtYd")
		)
		(fp_poly
			(pts
				(xy -0.9652 -1.778) (xy 0.9652 -1.778) (xy 0.9652 1.778) (xy -0.9652 1.778)
			)
			(stroke
				(width 0)
				(type default)
			)
			(fill no)
			(layer "F.Fab")
		)
		(pad "1" smd rect
			(at 0 -0.9652)
			(size 1.397 1.143)
			(layers "F.Cu" "F.Mask" "F.Paste")
			(net "P12V_HDD12")
		)
		(pad "2" smd rect
			(at 0 0.9652)
			(size 1.397 1.143)
			(layers "F.Cu" "F.Mask" "F.Paste")
			(net "GND")
		)
	)
	(footprint ""
		(layer "F.Cu")
		(at 158.663386 -273.660616 90)
		(property "Reference" "C91"
			(at 0 0 90)
			(layer "F.SilkS")
			(hide yes)
			(effects
				(font
					(size 1.27 1.27)
				)
			)
		)
		(property "Value" "SCD01U16V1KX-GP"
			(at -2.8321 -1.7399 90)
			(unlocked yes)
			(layer "F.Fab")
			(hide yes)
			(effects
				(font
					(size 1.016 1.016)
					(thickness 0.1524)
				)
			)
		)
		(property "Device Type" "C0201H13"
			(at -2.8321 -3.2639 90)
			(unlocked yes)
			(layer "F.Fab")
			(hide yes)
			(effects
				(font
					(size 1.016 1.016)
					(thickness 0.1524)
				)
			)
		)
		(duplicate_pad_numbers_are_jumpers no)
		(fp_rect
			(start -0.2794 0.6477)
			(end 0.2794 -0.6477)
			(stroke
				(width 0)
				(type default)
			)
			(fill no)
			(layer "F.CrtYd")
		)
		(fp_rect
			(start -0.2794 0.6477)
			(end 0.2794 -0.6477)
			(stroke
				(width 0)
				(type default)
			)
			(fill no)
			(layer "F.Fab")
		)
		(pad "1" smd custom
			(at 0 -0.2794 90)
			(size 0.0762 0.0762)
			(layers "F.Cu" "F.Mask" "F.Paste")
			(net "SAS_HDD_RX_P4")
			(options
				(clearance outline)
				(anchor circle)
			)
			(primitives
				(gr_poly
					(pts
						(arc
							(start 0.1524 -0.127)
							(mid 0.137521 -0.162921)
							(end 0.1016 -0.1778)
						)
						(arc
							(start -0.1016 -0.1778)
							(mid -0.137521 -0.162921)
							(end -0.1524 -0.127)
						)
						(arc
							(start -0.1524 0.127)
							(mid -0.137521 0.162921)
							(end -0.1016 0.1778)
						)
						(arc
							(start 0.1016 0.1778)
							(mid 0.137521 0.162921)
							(end 0.1524 0.127)
						)
					)
					(width 0)
					(fill yes)
				)
			)
		)
		(pad "2" smd custom
			(at 0 0.2794 90)
			(size 0.0762 0.0762)
			(layers "F.Cu" "F.Mask" "F.Paste")
			(net "PHY_SCC_A_TO_DRV_A_4_DP")
			(options
				(clearance outline)
				(anchor circle)
			)
			(primitives
				(gr_poly
					(pts
						(arc
							(start 0.1524 -0.127)
							(mid 0.137521 -0.162921)
							(end 0.1016 -0.1778)
						)
						(arc
							(start -0.1016 -0.1778)
							(mid -0.137521 -0.162921)
							(end -0.1524 -0.127)
						)
						(arc
							(start -0.1524 0.127)
							(mid -0.137521 0.162921)
							(end -0.1016 0.1778)
						)
						(arc
							(start 0.1016 0.1778)
							(mid 0.137521 0.162921)
							(end 0.1524 0.127)
						)
					)
					(width 0)
					(fill yes)
				)
			)
		)
	)
	(footprint ""
		(layer "F.Cu")
		(at 190.213488 -43.660568 90)
		(property "Reference" "C416"
			(at 0 0 90)
			(layer "F.SilkS")
			(hide yes)
			(effects
				(font
					(size 1.27 1.27)
				)
			)
		)
		(property "Value" "SCD01U16V1KX-GP"
			(at -2.8321 -1.7399 90)
			(unlocked yes)
			(layer "F.Fab")
			(hide yes)
			(effects
				(font
					(size 1.016 1.016)
					(thickness 0.1524)
				)
			)
		)
		(property "Device Type" "C0201H13"
			(at -2.8321 -3.2639 90)
			(unlocked yes)
			(layer "F.Fab")
			(hide yes)
			(effects
				(font
					(size 1.016 1.016)
					(thickness 0.1524)
				)
			)
		)
		(duplicate_pad_numbers_are_jumpers no)
		(fp_rect
			(start -0.2794 0.6477)
			(end 0.2794 -0.6477)
			(stroke
				(width 0)
				(type default)
			)
			(fill no)
			(layer "F.CrtYd")
		)
		(fp_rect
			(start -0.2794 0.6477)
			(end 0.2794 -0.6477)
			(stroke
				(width 0)
				(type default)
			)
			(fill no)
			(layer "F.Fab")
		)
		(pad "1" smd custom
			(at 0 -0.2794 90)
			(size 0.0762 0.0762)
			(layers "F.Cu" "F.Mask" "F.Paste")
			(net "SAS_HDD_RX_P29")
			(options
				(clearance outline)
				(anchor circle)
			)
			(primitives
				(gr_poly
					(pts
						(arc
							(start 0.1524 -0.127)
							(mid 0.137521 -0.162921)
							(end 0.1016 -0.1778)
						)
						(arc
							(start -0.1016 -0.1778)
							(mid -0.137521 -0.162921)
							(end -0.1524 -0.127)
						)
						(arc
							(start -0.1524 0.127)
							(mid -0.137521 0.162921)
							(end -0.1016 0.1778)
						)
						(arc
							(start 0.1016 0.1778)
							(mid 0.137521 0.162921)
							(end 0.1524 0.127)
						)
					)
					(width 0)
					(fill yes)
				)
			)
		)
		(pad "2" smd custom
			(at 0 0.2794 90)
			(size 0.0762 0.0762)
			(layers "F.Cu" "F.Mask" "F.Paste")
			(net "PHY_SCC_A_TO_DRV_A_29_DP")
			(options
				(clearance outline)
				(anchor circle)
			)
			(primitives
				(gr_poly
					(pts
						(arc
							(start 0.1524 -0.127)
							(mid 0.137521 -0.162921)
							(end 0.1016 -0.1778)
						)
						(arc
							(start -0.1016 -0.1778)
							(mid -0.137521 -0.162921)
							(end -0.1524 -0.127)
						)
						(arc
							(start -0.1524 0.127)
							(mid -0.137521 0.162921)
							(end -0.1016 0.1778)
						)
						(arc
							(start 0.1016 0.1778)
							(mid 0.137521 0.162921)
							(end 0.1524 0.127)
						)
					)
					(width 0)
					(fill yes)
				)
			)
		)
	)
	(footprint ""
		(layer "F.Cu")
		(at 176.2506 -275.633942)
		(property "Reference" "R262"
			(at 0 0 0)
			(layer "F.SilkS")
			(hide yes)
			(effects
				(font
					(size 1.27 1.27)
				)
			)
		)
		(property "Value" "0R2J-2-GP"
			(at 0.064008 -3.993896 0)
			(unlocked yes)
			(layer "F.Fab")
			(hide yes)
			(effects
				(font
					(size 1.016 1.016)
					(thickness 0.1524)
				)
			)
		)
		(property "Device Type" "R402H16"
			(at 0.064008 -5.517896 0)
			(unlocked yes)
			(layer "F.Fab")
			(hide yes)
			(effects
				(font
					(size 1.016 1.016)
					(thickness 0.1524)
				)
			)
		)
		(duplicate_pad_numbers_are_jumpers no)
		(fp_line
			(start -0.508 -0.9398)
			(end -0.508 0.9398)
			(stroke
				(width 0.1524)
				(type default)
			)
			(layer "F.SilkS")
		)
		(fp_line
			(start 0.508 -0.9398)
			(end -0.508 -0.9398)
			(stroke
				(width 0.1524)
				(type default)
			)
			(layer "F.SilkS")
		)
		(fp_rect
			(start -0.508 0.9398)
			(end 0.508 -0.9398)
			(stroke
				(width 0)
				(type default)
			)
			(fill no)
			(layer "F.CrtYd")
		)
		(fp_rect
			(start -0.508 0.9398)
			(end 0.508 -0.9398)
			(stroke
				(width 0)
				(type default)
			)
			(fill no)
			(layer "F.Fab")
		)
		(pad "1" smd custom
			(at 0 -0.4445)
			(size 0.1397 0.1397)
			(layers "F.Cu" "F.Mask" "F.Paste")
			(net "SW_HDD_G5")
			(options
				(clearance outline)
				(anchor circle)
			)
			(primitives
				(gr_poly
					(pts
						(arc
							(start -0.1778 -0.2794)
							(mid -0.249642 -0.249642)
							(end -0.2794 -0.1778)
						)
						(arc
							(start -0.2794 0.1778)
							(mid -0.249642 0.249642)
							(end -0.1778 0.2794)
						)
						(arc
							(start 0.1778 0.2794)
							(mid 0.249642 0.249642)
							(end 0.2794 0.1778)
						)
						(arc
							(start 0.2794 -0.1778)
							(mid 0.249642 -0.249642)
							(end 0.1778 -0.2794)
						)
					)
					(width 0)
					(fill yes)
				)
			)
		)
		(pad "2" smd custom
			(at 0 0.4445)
			(size 0.1397 0.1397)
			(layers "F.Cu" "F.Mask" "F.Paste")
			(net "SW_HDD_R5")
			(options
				(clearance outline)
				(anchor circle)
			)
			(primitives
				(gr_poly
					(pts
						(arc
							(start -0.1778 -0.2794)
							(mid -0.249642 -0.249642)
							(end -0.2794 -0.1778)
						)
						(arc
							(start -0.2794 0.1778)
							(mid -0.249642 0.249642)
							(end -0.1778 0.2794)
						)
						(arc
							(start 0.1778 0.2794)
							(mid 0.249642 0.249642)
							(end 0.2794 0.1778)
						)
						(arc
							(start 0.2794 -0.1778)
							(mid 0.249642 -0.249642)
							(end 0.1778 -0.2794)
						)
					)
					(width 0)
					(fill yes)
				)
			)
		)
	)
	(footprint ""
		(layer "F.Cu")
		(at 190.5 -172.1358 -90)
		(property "Reference" "R521"
			(at 0 0 270)
			(layer "F.SilkS")
			(hide yes)
			(effects
				(font
					(size 1.27 1.27)
				)
			)
		)
		(property "Value" "10KR2F-2-GP"
			(at 0.064008 -3.993896 270)
			(unlocked yes)
			(layer "F.Fab")
			(hide yes)
			(effects
				(font
					(size 1.016 1.016)
					(thickness 0.1524)
				)
			)
		)
		(property "Device Type" "R402H16"
			(at 0.064008 -5.517896 270)
			(unlocked yes)
			(layer "F.Fab")
			(hide yes)
			(effects
				(font
					(size 1.016 1.016)
					(thickness 0.1524)
				)
			)
		)
		(duplicate_pad_numbers_are_jumpers no)
		(fp_line
			(start -0.508 -0.9398)
			(end -0.508 0.9398)
			(stroke
				(width 0.1524)
				(type default)
			)
			(layer "F.SilkS")
		)
		(fp_line
			(start 0.508 -0.9398)
			(end -0.508 -0.9398)
			(stroke
				(width 0.1524)
				(type default)
			)
			(layer "F.SilkS")
		)
		(fp_rect
			(start -0.508 0.9398)
			(end 0.508 -0.9398)
			(stroke
				(width 0)
				(type default)
			)
			(fill no)
			(layer "F.CrtYd")
		)
		(fp_rect
			(start -0.508 0.9398)
			(end 0.508 -0.9398)
			(stroke
				(width 0)
				(type default)
			)
			(fill no)
			(layer "F.Fab")
		)
		(pad "1" smd custom
			(at 0 -0.4445 270)
			(size 0.1397 0.1397)
			(layers "F.Cu" "F.Mask" "F.Paste")
			(net "P3V3_STBY_A")
			(options
				(clearance outline)
				(anchor circle)
			)
			(primitives
				(gr_poly
					(pts
						(arc
							(start -0.1778 -0.2794)
							(mid -0.249642 -0.249642)
							(end -0.2794 -0.1778)
						)
						(arc
							(start -0.2794 0.1778)
							(mid -0.249642 0.249642)
							(end -0.1778 0.2794)
						)
						(arc
							(start 0.1778 0.2794)
							(mid 0.249642 0.249642)
							(end 0.2794 0.1778)
						)
						(arc
							(start 0.2794 -0.1778)
							(mid 0.249642 -0.249642)
							(end 0.1778 -0.2794)
						)
					)
					(width 0)
					(fill yes)
				)
			)
		)
		(pad "2" smd custom
			(at 0 0.4445 270)
			(size 0.1397 0.1397)
			(layers "F.Cu" "F.Mask" "F.Paste")
			(net "HDD_PRSNT_17")
			(options
				(clearance outline)
				(anchor circle)
			)
			(primitives
				(gr_poly
					(pts
						(arc
							(start -0.1778 -0.2794)
							(mid -0.249642 -0.249642)
							(end -0.2794 -0.1778)
						)
						(arc
							(start -0.2794 0.1778)
							(mid -0.249642 0.249642)
							(end -0.1778 0.2794)
						)
						(arc
							(start 0.1778 0.2794)
							(mid 0.249642 0.249642)
							(end 0.2794 0.1778)
						)
						(arc
							(start 0.2794 -0.1778)
							(mid 0.249642 -0.249642)
							(end 0.1778 -0.2794)
						)
					)
					(width 0)
					(fill yes)
				)
			)
		)
	)
	(footprint ""
		(layer "F.Cu")
		(at 130.828796 -180.064918 90)
		(property "Reference" "R479"
			(at 0 0 90)
			(layer "F.SilkS")
			(hide yes)
			(effects
				(font
					(size 1.27 1.27)
				)
			)
		)
		(property "Value" "220R3F-1-GP"
			(at -0.0254 -2.5146 90)
			(unlocked yes)
			(layer "F.Fab")
			(hide yes)
			(effects
				(font
					(size 1.016 1.016)
					(thickness 0.1524)
				)
			)
		)
		(property "Device Type" "R603H22"
			(at -0.0254 -4.0386 90)
			(unlocked yes)
			(layer "F.Fab")
			(hide yes)
			(effects
				(font
					(size 1.016 1.016)
					(thickness 0.1524)
				)
			)
		)
		(duplicate_pad_numbers_are_jumpers no)
		(fp_line
			(start 0.2032 0)
			(end 0.4826 0)
			(stroke
				(width 0.2032)
				(type default)
			)
			(layer "F.SilkS")
		)
		(fp_line
			(start -0.4826 0)
			(end -0.2032 0)
			(stroke
				(width 0.2032)
				(type default)
			)
			(layer "F.SilkS")
		)
		(fp_rect
			(start -0.5842 1.3335)
			(end 0.5842 -1.3335)
			(stroke
				(width 0)
				(type default)
			)
			(fill no)
			(layer "F.CrtYd")
		)
		(fp_rect
			(start -0.5842 1.3335)
			(end 0.5842 -1.3335)
			(stroke
				(width 0)
				(type default)
			)
			(fill no)
			(layer "F.Fab")
		)
		(pad "1" smd custom
			(at 0 -0.762 90)
			(size 0.2159 0.2159)
			(layers "F.Cu" "F.Mask" "F.Paste")
			(net "HDD_PRSNT_15")
			(options
				(clearance outline)
				(anchor circle)
			)
			(primitives
				(gr_poly
					(pts
						(arc
							(start -0.3302 -0.4318)
							(mid -0.402042 -0.402042)
							(end -0.4318 -0.3302)
						)
						(arc
							(start -0.4318 0.3302)
							(mid -0.402042 0.402042)
							(end -0.3302 0.4318)
						)
						(arc
							(start 0.3302 0.4318)
							(mid 0.402042 0.402042)
							(end 0.4318 0.3302)
						)
						(arc
							(start 0.4318 -0.3302)
							(mid 0.402042 -0.402042)
							(end 0.3302 -0.4318)
						)
					)
					(width 0)
					(fill yes)
				)
			)
		)
		(pad "2" smd custom
			(at 0 0.762 90)
			(size 0.2159 0.2159)
			(layers "F.Cu" "F.Mask" "F.Paste")
			(net "DRIVE_A_15_INS")
			(options
				(clearance outline)
				(anchor circle)
			)
			(primitives
				(gr_poly
					(pts
						(arc
							(start -0.3302 -0.4318)
							(mid -0.402042 -0.402042)
							(end -0.4318 -0.3302)
						)
						(arc
							(start -0.4318 0.3302)
							(mid -0.402042 0.402042)
							(end -0.3302 0.4318)
						)
						(arc
							(start 0.3302 0.4318)
							(mid 0.402042 0.402042)
							(end 0.4318 0.3302)
						)
						(arc
							(start 0.4318 -0.3302)
							(mid 0.402042 -0.402042)
							(end 0.3302 -0.4318)
						)
					)
					(width 0)
					(fill yes)
				)
			)
		)
	)
	(footprint ""
		(layer "F.Cu")
		(at 457.6699 -73.954894 180)
		(property "Reference" "C486"
			(at 0 0 180)
			(layer "F.SilkS")
			(hide yes)
			(effects
				(font
					(size 1.27 1.27)
				)
			)
		)
		(property "Value" "SC4D7U25V5KX-1-GP"
			(at -0.0762 -6.1214 180)
			(unlocked yes)
			(layer "F.Fab")
			(hide yes)
			(effects
				(font
					(size 1.016 1.016)
					(thickness 0.1524)
				)
			)
		)
		(property "Device Type" "C805H58"
			(at -0.0762 -8.1534 180)
			(unlocked yes)
			(layer "F.Fab")
			(hide yes)
			(effects
				(font
					(size 1.016 1.016)
					(thickness 0.1524)
				)
			)
		)
		(duplicate_pad_numbers_are_jumpers no)
		(fp_line
			(start 0.635 0)
			(end -0.635 0)
			(stroke
				(width 0.508)
				(type default)
			)
			(layer "F.SilkS")
		)
		(fp_rect
			(start -0.9652 1.778)
			(end 0.9652 -1.778)
			(stroke
				(width 0)
				(type default)
			)
			(fill no)
			(layer "F.CrtYd")
		)
		(fp_poly
			(pts
				(xy -0.9652 -1.778) (xy 0.9652 -1.778) (xy 0.9652 1.778) (xy -0.9652 1.778)
			)
			(stroke
				(width 0)
				(type default)
			)
			(fill no)
			(layer "F.Fab")
		)
		(pad "1" smd rect
			(at 0 -0.9652 180)
			(size 1.397 1.143)
			(layers "F.Cu" "F.Mask" "F.Paste")
			(net "P12V_HDD34")
		)
		(pad "2" smd rect
			(at 0 0.9652 180)
			(size 1.397 1.143)
			(layers "F.Cu" "F.Mask" "F.Paste")
			(net "GND")
		)
	)
	(footprint ""
		(layer "F.Cu")
		(at 272.8976 11.184128 180)
		(property "Reference" "R615"
			(at 0 0 180)
			(layer "F.SilkS")
			(hide yes)
			(effects
				(font
					(size 1.27 1.27)
				)
			)
		)
		(property "Value" "10KR2F-2-GP"
			(at 0.064008 -3.993896 180)
			(unlocked yes)
			(layer "F.Fab")
			(hide yes)
			(effects
				(font
					(size 1.016 1.016)
					(thickness 0.1524)
				)
			)
		)
		(property "Device Type" "R402H16"
			(at 0.064008 -5.517896 180)
			(unlocked yes)
			(layer "F.Fab")
			(hide yes)
			(effects
				(font
					(size 1.016 1.016)
					(thickness 0.1524)
				)
			)
		)
		(duplicate_pad_numbers_are_jumpers no)
		(fp_line
			(start 0.508 -0.9398)
			(end -0.508 -0.9398)
			(stroke
				(width 0.1524)
				(type default)
			)
			(layer "F.SilkS")
		)
		(fp_line
			(start -0.508 -0.9398)
			(end -0.508 0.9398)
			(stroke
				(width 0.1524)
				(type default)
			)
			(layer "F.SilkS")
		)
		(fp_rect
			(start -0.508 0.9398)
			(end 0.508 -0.9398)
			(stroke
				(width 0)
				(type default)
			)
			(fill no)
			(layer "F.CrtYd")
		)
		(fp_rect
			(start -0.508 0.9398)
			(end 0.508 -0.9398)
			(stroke
				(width 0)
				(type default)
			)
			(fill no)
			(layer "F.Fab")
		)
		(pad "1" smd custom
			(at 0 -0.4445 180)
			(size 0.1397 0.1397)
			(layers "F.Cu" "F.Mask" "F.Paste")
			(net "IOM_B_FAULT_LED")
			(options
				(clearance outline)
				(anchor circle)
			)
			(primitives
				(gr_poly
					(pts
						(arc
							(start -0.1778 -0.2794)
							(mid -0.249642 -0.249642)
							(end -0.2794 -0.1778)
						)
						(arc
							(start -0.2794 0.1778)
							(mid -0.249642 0.249642)
							(end -0.1778 0.2794)
						)
						(arc
							(start 0.1778 0.2794)
							(mid 0.249642 0.249642)
							(end 0.2794 0.1778)
						)
						(arc
							(start 0.2794 -0.1778)
							(mid 0.249642 -0.249642)
							(end 0.1778 -0.2794)
						)
					)
					(width 0)
					(fill yes)
				)
			)
		)
		(pad "2" smd custom
			(at 0 0.4445 180)
			(size 0.1397 0.1397)
			(layers "F.Cu" "F.Mask" "F.Paste")
			(net "GND")
			(options
				(clearance outline)
				(anchor circle)
			)
			(primitives
				(gr_poly
					(pts
						(arc
							(start -0.1778 -0.2794)
							(mid -0.249642 -0.249642)
							(end -0.2794 -0.1778)
						)
						(arc
							(start -0.2794 0.1778)
							(mid -0.249642 0.249642)
							(end -0.1778 0.2794)
						)
						(arc
							(start 0.1778 0.2794)
							(mid 0.249642 0.249642)
							(end 0.2794 0.1778)
						)
						(arc
							(start 0.2794 -0.1778)
							(mid 0.249642 -0.249642)
							(end 0.1778 -0.2794)
						)
					)
					(width 0)
					(fill yes)
				)
			)
		)
	)
	(footprint ""
		(layer "F.Cu")
		(at 218.44 -381.762 180)
		(property "Reference" "R131"
			(at 0 0 180)
			(layer "F.SilkS")
			(hide yes)
			(effects
				(font
					(size 1.27 1.27)
				)
			)
		)
		(property "Value" "10KR2F-2-GP"
			(at 0.064008 -3.993896 180)
			(unlocked yes)
			(layer "F.Fab")
			(hide yes)
			(effects
				(font
					(size 1.016 1.016)
					(thickness 0.1524)
				)
			)
		)
		(property "Device Type" "R402H16"
			(at 0.064008 -5.517896 180)
			(unlocked yes)
			(layer "F.Fab")
			(hide yes)
			(effects
				(font
					(size 1.016 1.016)
					(thickness 0.1524)
				)
			)
		)
		(duplicate_pad_numbers_are_jumpers no)
		(fp_line
			(start 0.508 -0.9398)
			(end -0.508 -0.9398)
			(stroke
				(width 0.1524)
				(type default)
			)
			(layer "F.SilkS")
		)
		(fp_line
			(start -0.508 -0.9398)
			(end -0.508 0.9398)
			(stroke
				(width 0.1524)
				(type default)
			)
			(layer "F.SilkS")
		)
		(fp_rect
			(start -0.508 0.9398)
			(end 0.508 -0.9398)
			(stroke
				(width 0)
				(type default)
			)
			(fill no)
			(layer "F.CrtYd")
		)
		(fp_rect
			(start -0.508 0.9398)
			(end 0.508 -0.9398)
			(stroke
				(width 0)
				(type default)
			)
			(fill no)
			(layer "F.Fab")
		)
		(pad "1" smd custom
			(at 0 -0.4445 180)
			(size 0.1397 0.1397)
			(layers "F.Cu" "F.Mask" "F.Paste")
			(net "P5V_A_1")
			(options
				(clearance outline)
				(anchor circle)
			)
			(primitives
				(gr_poly
					(pts
						(arc
							(start -0.1778 -0.2794)
							(mid -0.249642 -0.249642)
							(end -0.2794 -0.1778)
						)
						(arc
							(start -0.2794 0.1778)
							(mid -0.249642 0.249642)
							(end -0.1778 0.2794)
						)
						(arc
							(start 0.1778 0.2794)
							(mid 0.249642 0.249642)
							(end 0.2794 0.1778)
						)
						(arc
							(start 0.2794 -0.1778)
							(mid 0.249642 -0.249642)
							(end 0.1778 -0.2794)
						)
					)
					(width 0)
					(fill yes)
				)
			)
		)
		(pad "2" smd custom
			(at 0 0.4445 180)
			(size 0.1397 0.1397)
			(layers "F.Cu" "F.Mask" "F.Paste")
			(net "SCC_FULL_PWR_EN_5V_R")
			(options
				(clearance outline)
				(anchor circle)
			)
			(primitives
				(gr_poly
					(pts
						(arc
							(start -0.1778 -0.2794)
							(mid -0.249642 -0.249642)
							(end -0.2794 -0.1778)
						)
						(arc
							(start -0.2794 0.1778)
							(mid -0.249642 0.249642)
							(end -0.1778 0.2794)
						)
						(arc
							(start 0.1778 0.2794)
							(mid 0.249642 0.249642)
							(end 0.2794 0.1778)
						)
						(arc
							(start 0.2794 -0.1778)
							(mid 0.249642 -0.249642)
							(end 0.1778 -0.2794)
						)
					)
					(width 0)
					(fill yes)
				)
			)
		)
	)
	(footprint ""
		(layer "F.Cu")
		(at 331.47 -176.127918 -90)
		(property "Reference" "R543"
			(at 0 0 270)
			(layer "F.SilkS")
			(hide yes)
			(effects
				(font
					(size 1.27 1.27)
				)
			)
		)
		(property "Value" "2R6F-GP"
			(at -0.0508 -4.8514 270)
			(unlocked yes)
			(layer "F.Fab")
			(hide yes)
			(effects
				(font
					(size 1.016 1.016)
					(thickness 0.1524)
				)
			)
		)
		(property "Device Type" "R1206H26"
			(at 0 -6.3754 270)
			(unlocked yes)
			(layer "F.Fab")
			(hide yes)
			(effects
				(font
					(size 1.016 1.016)
					(thickness 0.1524)
				)
			)
		)
		(duplicate_pad_numbers_are_jumpers no)
		(fp_line
			(start -1.016 2.2352)
			(end -1.016 -2.2352)
			(stroke
				(width 0.1524)
				(type default)
			)
			(layer "F.SilkS")
		)
		(fp_line
			(start 1.016 2.2352)
			(end -1.016 2.2352)
			(stroke
				(width 0.1524)
				(type default)
			)
			(layer "F.SilkS")
		)
		(fp_line
			(start -1.016 -2.2352)
			(end 1.016 -2.2352)
			(stroke
				(width 0.1524)
				(type default)
			)
			(layer "F.SilkS")
		)
		(fp_line
			(start 1.016 -2.2352)
			(end 1.016 2.2352)
			(stroke
				(width 0.1524)
				(type default)
			)
			(layer "F.SilkS")
		)
		(fp_rect
			(start -1.0922 2.3114)
			(end 1.0922 -2.3114)
			(stroke
				(width 0)
				(type default)
			)
			(fill no)
			(layer "F.CrtYd")
		)
		(fp_poly
			(pts
				(xy -1.0922 -2.3114) (xy 1.0922 -2.3114) (xy 1.0922 2.3114) (xy -1.0922 2.3114)
			)
			(stroke
				(width 0)
				(type default)
			)
			(fill no)
			(layer "F.Fab")
		)
		(pad "1" smd rect
			(at 0 -1.397 270)
			(size 1.651 1.27)
			(layers "F.Cu" "F.Mask" "F.Paste")
			(net "P5V_HDD18")
		)
		(pad "2" smd rect
			(at 0 1.397 270)
			(size 1.651 1.27)
			(layers "F.Cu" "F.Mask" "F.Paste")
			(net "5V_PRE_18")
		)
	)
	(footprint ""
		(layer "F.Cu")
		(at 111.795052 -127.254)
		(property "Reference" "R293"
			(at 0 0 0)
			(layer "F.SilkS")
			(hide yes)
			(effects
				(font
					(size 1.27 1.27)
				)
			)
		)
		(property "Value" "130R3F-GP"
			(at -0.0254 -2.5146 0)
			(unlocked yes)
			(layer "F.Fab")
			(hide yes)
			(effects
				(font
					(size 1.016 1.016)
					(thickness 0.1524)
				)
			)
		)
		(property "Device Type" "R603H22"
			(at -0.0254 -4.0386 0)
			(unlocked yes)
			(layer "F.Fab")
			(hide yes)
			(effects
				(font
					(size 1.016 1.016)
					(thickness 0.1524)
				)
			)
		)
		(duplicate_pad_numbers_are_jumpers no)
		(fp_line
			(start -0.4826 0)
			(end -0.2032 0)
			(stroke
				(width 0.2032)
				(type default)
			)
			(layer "F.SilkS")
		)
		(fp_line
			(start 0.2032 0)
			(end 0.4826 0)
			(stroke
				(width 0.2032)
				(type default)
			)
			(layer "F.SilkS")
		)
		(fp_rect
			(start -0.5842 1.3335)
			(end 0.5842 -1.3335)
			(stroke
				(width 0)
				(type default)
			)
			(fill no)
			(layer "F.CrtYd")
		)
		(fp_rect
			(start -0.5842 1.3335)
			(end 0.5842 -1.3335)
			(stroke
				(width 0)
				(type default)
			)
			(fill no)
			(layer "F.Fab")
		)
		(pad "1" smd custom
			(at 0 -0.762)
			(size 0.2159 0.2159)
			(layers "F.Cu" "F.Mask" "F.Paste")
			(net "P5V_A_2")
			(options
				(clearance outline)
				(anchor circle)
			)
			(primitives
				(gr_poly
					(pts
						(arc
							(start -0.3302 -0.4318)
							(mid -0.402042 -0.402042)
							(end -0.4318 -0.3302)
						)
						(arc
							(start -0.4318 0.3302)
							(mid -0.402042 0.402042)
							(end -0.3302 0.4318)
						)
						(arc
							(start 0.3302 0.4318)
							(mid 0.402042 0.402042)
							(end 0.4318 0.3302)
						)
						(arc
							(start 0.4318 -0.3302)
							(mid 0.402042 -0.402042)
							(end 0.3302 -0.4318)
						)
					)
					(width 0)
					(fill yes)
				)
			)
		)
		(pad "2" smd custom
			(at 0 0.762)
			(size 0.2159 0.2159)
			(layers "F.Cu" "F.Mask" "F.Paste")
			(net "FLT_HDD15")
			(options
				(clearance outline)
				(anchor circle)
			)
			(primitives
				(gr_poly
					(pts
						(arc
							(start -0.3302 -0.4318)
							(mid -0.402042 -0.402042)
							(end -0.4318 -0.3302)
						)
						(arc
							(start -0.4318 0.3302)
							(mid -0.402042 0.402042)
							(end -0.3302 0.4318)
						)
						(arc
							(start 0.3302 0.4318)
							(mid 0.402042 0.402042)
							(end 0.4318 0.3302)
						)
						(arc
							(start 0.4318 -0.3302)
							(mid 0.402042 -0.402042)
							(end 0.3302 -0.4318)
						)
					)
					(width 0)
					(fill yes)
				)
			)
		)
	)
	(footprint ""
		(layer "F.Cu")
		(at 42.667428 -127.798068 180)
		(property "Reference" "Q276"
			(at 0 0 180)
			(layer "F.SilkS")
			(hide yes)
			(effects
				(font
					(size 1.27 1.27)
				)
			)
		)
		(property "Value" "SSM3K324R-GP"
			(at 0.127 -8.9662 180)
			(unlocked yes)
			(layer "F.Fab")
			(hide yes)
			(effects
				(font
					(size 1.016 1.016)
					(thickness 0.1524)
				)
			)
		)
		(property "Device Type" "SOT23DGS2D4H35"
			(at 0.127 -10.4902 180)
			(unlocked yes)
			(layer "F.Fab")
			(hide yes)
			(effects
				(font
					(size 1.016 1.016)
					(thickness 0.1524)
				)
			)
		)
		(duplicate_pad_numbers_are_jumpers no)
		(fp_line
			(start 1.651 1.778)
			(end 1.651 -1.778)
			(stroke
				(width 0.1524)
				(type default)
			)
			(layer "F.SilkS")
		)
		(fp_line
			(start 1.651 -1.778)
			(end -1.651 -1.778)
			(stroke
				(width 0.1524)
				(type default)
			)
			(layer "F.SilkS")
		)
		(fp_line
			(start -1.651 1.778)
			(end 1.651 1.778)
			(stroke
				(width 0.1524)
				(type default)
			)
			(layer "F.SilkS")
		)
		(fp_line
			(start -1.651 -1.778)
			(end -1.651 1.778)
			(stroke
				(width 0.1524)
				(type default)
			)
			(layer "F.SilkS")
		)
		(fp_poly
			(pts
				(xy -1.778 1.8796) (xy -1.778 -1.8796) (xy 1.778 -1.8796) (xy 1.778 1.8796)
			)
			(stroke
				(width 0)
				(type default)
			)
			(fill no)
			(layer "F.CrtYd")
		)
		(fp_poly
			(pts
				(xy -1.778 1.8796) (xy -1.778 -1.8796) (xy 1.778 -1.8796) (xy 1.778 1.8796)
			)
			(stroke
				(width 0)
				(type default)
			)
			(fill no)
			(layer "F.Fab")
		)
		(pad "D" smd custom
			(at 0 -0.9525 180)
			(size 0.1905 0.1905)
			(layers "F.Cu" "F.Mask" "F.Paste")
			(net "DRV_ACT_13_N")
			(options
				(clearance outline)
				(anchor circle)
			)
			(primitives
				(gr_poly
					(pts
						(arc
							(start -0.1778 0.5715)
							(mid -0.321484 0.511984)
							(end -0.381 0.3683)
						)
						(arc
							(start -0.381 -0.3683)
							(mid -0.321484 -0.511984)
							(end -0.1778 -0.5715)
						)
						(arc
							(start 0.1778 -0.5715)
							(mid 0.321484 -0.511984)
							(end 0.381 -0.3683)
						)
						(arc
							(start 0.381 0.3683)
							(mid 0.321484 0.511984)
							(end 0.1778 0.5715)
						)
					)
					(width 0)
					(fill yes)
				)
			)
		)
		(pad "G" smd custom
			(at -0.98425 0.9525 180)
			(size 0.1905 0.1905)
			(layers "F.Cu" "F.Mask" "F.Paste")
			(net "DRIVE_A_13_ACT")
			(options
				(clearance outline)
				(anchor circle)
			)
			(primitives
				(gr_poly
					(pts
						(arc
							(start -0.1778 0.5715)
							(mid -0.321484 0.511984)
							(end -0.381 0.3683)
						)
						(arc
							(start -0.381 -0.3683)
							(mid -0.321484 -0.511984)
							(end -0.1778 -0.5715)
						)
						(arc
							(start 0.1778 -0.5715)
							(mid 0.321484 -0.511984)
							(end 0.381 -0.3683)
						)
						(arc
							(start 0.381 0.3683)
							(mid 0.321484 0.511984)
							(end 0.1778 0.5715)
						)
					)
					(width 0)
					(fill yes)
				)
			)
		)
		(pad "S" smd custom
			(at 0.98425 0.9525 180)
			(size 0.1905 0.1905)
			(layers "F.Cu" "F.Mask" "F.Paste")
			(net "GND")
			(options
				(clearance outline)
				(anchor circle)
			)
			(primitives
				(gr_poly
					(pts
						(arc
							(start -0.1778 0.5715)
							(mid -0.321484 0.511984)
							(end -0.381 0.3683)
						)
						(arc
							(start -0.381 -0.3683)
							(mid -0.321484 -0.511984)
							(end -0.1778 -0.5715)
						)
						(arc
							(start 0.1778 -0.5715)
							(mid 0.321484 -0.511984)
							(end 0.381 -0.3683)
						)
						(arc
							(start 0.381 0.3683)
							(mid 0.321484 0.511984)
							(end 0.1778 0.5715)
						)
					)
					(width 0)
					(fill yes)
				)
			)
		)
	)
	(footprint ""
		(layer "F.Cu")
		(at 141.548866 -131.656074)
		(property "Reference" "R1055"
			(at 0 0 0)
			(layer "F.SilkS")
			(hide yes)
			(effects
				(font
					(size 1.27 1.27)
				)
			)
		)
		(property "Value" "3K83R2F-GP"
			(at 0.064008 -3.993896 0)
			(unlocked yes)
			(layer "F.Fab")
			(hide yes)
			(effects
				(font
					(size 1.016 1.016)
					(thickness 0.1524)
				)
			)
		)
		(property "Device Type" "R402H16"
			(at 0.064008 -5.517896 0)
			(unlocked yes)
			(layer "F.Fab")
			(hide yes)
			(effects
				(font
					(size 1.016 1.016)
					(thickness 0.1524)
				)
			)
		)
		(duplicate_pad_numbers_are_jumpers no)
		(fp_line
			(start -0.508 -0.9398)
			(end -0.508 0.9398)
			(stroke
				(width 0.1524)
				(type default)
			)
			(layer "F.SilkS")
		)
		(fp_line
			(start 0.508 -0.9398)
			(end -0.508 -0.9398)
			(stroke
				(width 0.1524)
				(type default)
			)
			(layer "F.SilkS")
		)
		(fp_rect
			(start -0.508 0.9398)
			(end 0.508 -0.9398)
			(stroke
				(width 0)
				(type default)
			)
			(fill no)
			(layer "F.CrtYd")
		)
		(fp_rect
			(start -0.508 0.9398)
			(end 0.508 -0.9398)
			(stroke
				(width 0)
				(type default)
			)
			(fill no)
			(layer "F.Fab")
		)
		(pad "1" smd custom
			(at 0 -0.4445)
			(size 0.1397 0.1397)
			(layers "F.Cu" "F.Mask" "F.Paste")
			(net "COMP_A_PGOOD")
			(options
				(clearance outline)
				(anchor circle)
			)
			(primitives
				(gr_poly
					(pts
						(arc
							(start -0.1778 -0.2794)
							(mid -0.249642 -0.249642)
							(end -0.2794 -0.1778)
						)
						(arc
							(start -0.2794 0.1778)
							(mid -0.249642 0.249642)
							(end -0.1778 0.2794)
						)
						(arc
							(start 0.1778 0.2794)
							(mid 0.249642 0.249642)
							(end 0.2794 0.1778)
						)
						(arc
							(start 0.2794 -0.1778)
							(mid 0.249642 -0.249642)
							(end 0.1778 -0.2794)
						)
					)
					(width 0)
					(fill yes)
				)
			)
		)
		(pad "2" smd custom
			(at 0 0.4445)
			(size 0.1397 0.1397)
			(layers "F.Cu" "F.Mask" "F.Paste")
			(net "GND")
			(options
				(clearance outline)
				(anchor circle)
			)
			(primitives
				(gr_poly
					(pts
						(arc
							(start -0.1778 -0.2794)
							(mid -0.249642 -0.249642)
							(end -0.2794 -0.1778)
						)
						(arc
							(start -0.2794 0.1778)
							(mid -0.249642 0.249642)
							(end -0.1778 0.2794)
						)
						(arc
							(start 0.1778 0.2794)
							(mid 0.249642 0.249642)
							(end 0.2794 0.1778)
						)
						(arc
							(start 0.2794 -0.1778)
							(mid 0.249642 -0.249642)
							(end 0.1778 -0.2794)
						)
					)
					(width 0)
					(fill yes)
				)
			)
		)
	)
	(footprint ""
		(layer "F.Cu")
		(at 477.739202 -43.939968 90)
		(property "Reference" "VIA16"
			(at 0 0 90)
			(layer "F.SilkS")
			(hide yes)
			(effects
				(font
					(size 1.27 1.27)
				)
			)
		)
		(property "Value" "100OHM-8L-1D6MM-L18L16-GP"
			(at -3.7211 -4.5085 90)
			(unlocked yes)
			(layer "F.Fab")
			(hide yes)
			(effects
				(font
					(size 1.016 1.016)
					(thickness 0.1524)
				)
			)
		)
		(property "Device Type" "VIA-PCIE-4P-394076"
			(at -3.7211 -6.0325 90)
			(unlocked yes)
			(layer "F.Fab")
			(hide yes)
			(effects
				(font
					(size 1.016 1.016)
					(thickness 0.1524)
				)
			)
		)
		(duplicate_pad_numbers_are_jumpers no)
		(fp_rect
			(start -1.9685 0.381)
			(end 1.9685 -0.381)
			(stroke
				(width 0)
				(type default)
			)
			(fill no)
			(layer "F.CrtYd")
		)
		(fp_rect
			(start -1.9685 0.381)
			(end 1.9685 -0.381)
			(stroke
				(width 0)
				(type default)
			)
			(fill no)
			(layer "F.Fab")
		)
		(pad "1" thru_hole circle
			(at -1.5875 0 90)
			(size 0.508 0.508)
			(drill 0.254)
			(layers "*.Cu" "*.Mask")
			(remove_unused_layers no)
			(net "GND")
			(clearance 0.127)
			(thermal_gap 0.127)
		)
		(pad "2" thru_hole circle
			(at -0.5715 0 90)
			(size 0.508 0.508)
			(drill 0.254)
			(layers "*.Cu" "*.Mask")
			(remove_unused_layers no)
			(net "PHY_SCC_A_TO_DRV_A_35_DP")
			(clearance 0.127)
			(thermal_gap 0.127)
		)
		(pad "3" thru_hole circle
			(at 0.5715 0 90)
			(size 0.508 0.508)
			(drill 0.254)
			(layers "*.Cu" "*.Mask")
			(remove_unused_layers no)
			(net "PHY_SCC_A_TO_DRV_A_35_DN")
			(clearance 0.127)
			(thermal_gap 0.127)
		)
		(pad "4" thru_hole circle
			(at 1.5875 0 90)
			(size 0.508 0.508)
			(drill 0.254)
			(layers "*.Cu" "*.Mask")
			(remove_unused_layers no)
			(net "GND")
			(clearance 0.127)
			(thermal_gap 0.127)
		)
	)
	(footprint ""
		(layer "F.Cu")
		(at 132.581396 -285.260542 180)
		(property "Reference" "Q18"
			(at 0 0 180)
			(layer "F.SilkS")
			(hide yes)
			(effects
				(font
					(size 1.27 1.27)
				)
			)
		)
		(property "Value" "AO4406AL-GP"
			(at -3.707384 -1.5367 180)
			(unlocked yes)
			(layer "F.Fab")
			(hide yes)
			(effects
				(font
					(size 1.016 1.016)
					(thickness 0.1524)
				)
			)
		)
		(property "Device Type" "SOIC8H69"
			(at -3.707384 -3.0607 180)
			(unlocked yes)
			(layer "F.Fab")
			(hide yes)
			(effects
				(font
					(size 1.016 1.016)
					(thickness 0.1524)
				)
			)
		)
		(duplicate_pad_numbers_are_jumpers no)
		(fp_line
			(start 2.1336 1.4224)
			(end 2.1336 -1.4224)
			(stroke
				(width 0.1524)
				(type default)
			)
			(layer "F.SilkS")
		)
		(fp_line
			(start 2.1336 -1.4224)
			(end -2.7432 -1.4224)
			(stroke
				(width 0.1524)
				(type default)
			)
			(layer "F.SilkS")
		)
		(fp_line
			(start -2.1844 -0.0508)
			(end -2.7178 0.508)
			(stroke
				(width 0.1524)
				(type default)
			)
			(layer "F.SilkS")
		)
		(fp_line
			(start -2.6289 3.4417)
			(end -2.6289 1.4732)
			(stroke
				(width 0.381)
				(type default)
			)
			(layer "F.SilkS")
		)
		(fp_line
			(start -2.7178 -0.508)
			(end -2.1844 -0.0508)
			(stroke
				(width 0.1524)
				(type default)
			)
			(layer "F.SilkS")
		)
		(fp_line
			(start -2.7432 1.4224)
			(end 2.1336 1.4224)
			(stroke
				(width 0.1524)
				(type default)
			)
			(layer "F.SilkS")
		)
		(fp_line
			(start -2.7432 1.4224)
			(end -2.6416 1.4224)
			(stroke
				(width 0.1524)
				(type default)
			)
			(layer "F.SilkS")
		)
		(fp_line
			(start -2.7432 -1.4224)
			(end -2.7432 1.4224)
			(stroke
				(width 0.1524)
				(type default)
			)
			(layer "F.SilkS")
		)
		(fp_poly
			(pts
				(xy -2.2098 -1.4224) (xy -2.2098 1.4224) (xy 2.2098 1.4224) (xy 2.2098 -1.4224)
			)
			(stroke
				(width 0)
				(type default)
			)
			(fill yes)
			(layer "F.SilkS")
		)
		(fp_rect
			(start -2.450084 2.999994)
			(end 2.450084 -2.999994)
			(stroke
				(width 0)
				(type default)
			)
			(fill no)
			(layer "F.CrtYd")
		)
		(fp_poly
			(pts
				(xy -2.8194 3.6322) (xy -2.8194 -3.6322) (xy 2.8194 -3.6322) (xy 2.8194 1.18364) (xy 2.450084 1.18364)
				(xy 2.450084 -2.999994) (xy -2.450084 -2.999994) (xy -2.450084 2.999994) (xy 2.450084 2.999994)
				(xy 2.450084 1.18618) (xy 2.8194 1.18618) (xy 2.8194 3.6322)
			)
			(stroke
				(width 0)
				(type default)
			)
			(fill no)
			(layer "F.CrtYd")
		)
		(fp_rect
			(start -2.8194 3.6322)
			(end 2.8194 -3.6322)
			(stroke
				(width 0)
				(type default)
			)
			(fill no)
			(layer "F.Fab")
		)
		(pad "1" smd rect
			(at -1.905 2.54 180)
			(size 0.635 1.651)
			(layers "F.Cu" "F.Mask" "F.Paste")
			(net "P5V_HDD3")
		)
		(pad "2" smd rect
			(at -0.635 2.54 180)
			(size 0.635 1.651)
			(layers "F.Cu" "F.Mask" "F.Paste")
			(net "P5V_HDD3")
		)
		(pad "3" smd rect
			(at 0.635 2.54 180)
			(size 0.635 1.651)
			(layers "F.Cu" "F.Mask" "F.Paste")
			(net "P5V_HDD3")
		)
		(pad "4" smd rect
			(at 1.905 2.54 180)
			(size 0.635 1.651)
			(layers "F.Cu" "F.Mask" "F.Paste")
			(net "SW_HDD_P3")
		)
		(pad "5" smd rect
			(at 1.905 -2.54 180)
			(size 0.635 1.651)
			(layers "F.Cu" "F.Mask" "F.Paste")
			(net "P5V_A_1")
		)
		(pad "6" smd rect
			(at 0.635 -2.54 180)
			(size 0.635 1.651)
			(layers "F.Cu" "F.Mask" "F.Paste")
			(net "P5V_A_1")
		)
		(pad "7" smd rect
			(at -0.635 -2.54 180)
			(size 0.635 1.651)
			(layers "F.Cu" "F.Mask" "F.Paste")
			(net "P5V_A_1")
		)
		(pad "8" smd rect
			(at -1.905 -2.54 180)
			(size 0.635 1.651)
			(layers "F.Cu" "F.Mask" "F.Paste")
			(net "P5V_A_1")
		)
	)
	(footprint ""
		(layer "F.Cu")
		(at 87.340948 -189.462918 180)
		(property "Reference" "C229"
			(at 0 0 180)
			(layer "F.SilkS")
			(hide yes)
			(effects
				(font
					(size 1.27 1.27)
				)
			)
		)
		(property "Value" "SC1U25V3KX-GP"
			(at 0 -2.8194 180)
			(unlocked yes)
			(layer "F.Fab")
			(hide yes)
			(effects
				(font
					(size 1.016 1.016)
					(thickness 0.1524)
				)
			)
		)
		(property "Device Type" "C603H36"
			(at 0 -4.3434 180)
			(unlocked yes)
			(layer "F.Fab")
			(hide yes)
			(effects
				(font
					(size 1.016 1.016)
					(thickness 0.1524)
				)
			)
		)
		(duplicate_pad_numbers_are_jumpers no)
		(fp_line
			(start 0.508 0)
			(end -0.508 0)
			(stroke
				(width 0.2032)
				(type default)
			)
			(layer "F.SilkS")
		)
		(fp_rect
			(start -0.5842 1.3335)
			(end 0.5842 -1.3335)
			(stroke
				(width 0)
				(type default)
			)
			(fill no)
			(layer "F.CrtYd")
		)
		(fp_rect
			(start -0.5842 1.3335)
			(end 0.5842 -1.3335)
			(stroke
				(width 0)
				(type default)
			)
			(fill no)
			(layer "F.Fab")
		)
		(pad "1" smd custom
			(at 0 -0.762 180)
			(size 0.2159 0.2159)
			(layers "F.Cu" "F.Mask" "F.Paste")
			(net "P12V_HDD14")
			(options
				(clearance outline)
				(anchor circle)
			)
			(primitives
				(gr_poly
					(pts
						(arc
							(start -0.3302 -0.4318)
							(mid -0.402042 -0.402042)
							(end -0.4318 -0.3302)
						)
						(arc
							(start -0.4318 0.3302)
							(mid -0.402042 0.402042)
							(end -0.3302 0.4318)
						)
						(arc
							(start 0.3302 0.4318)
							(mid 0.402042 0.402042)
							(end 0.4318 0.3302)
						)
						(arc
							(start 0.4318 -0.3302)
							(mid 0.402042 -0.402042)
							(end 0.3302 -0.4318)
						)
					)
					(width 0)
					(fill yes)
				)
			)
		)
		(pad "2" smd custom
			(at 0 0.762 180)
			(size 0.2159 0.2159)
			(layers "F.Cu" "F.Mask" "F.Paste")
			(net "GND")
			(options
				(clearance outline)
				(anchor circle)
			)
			(primitives
				(gr_poly
					(pts
						(arc
							(start -0.3302 -0.4318)
							(mid -0.402042 -0.402042)
							(end -0.4318 -0.3302)
						)
						(arc
							(start -0.4318 0.3302)
							(mid -0.402042 0.402042)
							(end -0.3302 0.4318)
						)
						(arc
							(start 0.3302 0.4318)
							(mid 0.402042 0.402042)
							(end 0.4318 0.3302)
						)
						(arc
							(start 0.4318 -0.3302)
							(mid 0.402042 -0.402042)
							(end 0.3302 -0.4318)
						)
					)
					(width 0)
					(fill yes)
				)
			)
		)
	)
	(footprint ""
		(layer "F.Cu")
		(at 244.094 -387.9088)
		(property "Reference" "C610"
			(at 0 0 0)
			(layer "F.SilkS")
			(hide yes)
			(effects
				(font
					(size 1.27 1.27)
				)
			)
		)
		(property "Value" "SCD015U25V2KX-GP"
			(at 1.1811 -2.7051 0)
			(unlocked yes)
			(layer "F.Fab")
			(hide yes)
			(effects
				(font
					(size 1.016 1.016)
					(thickness 0.1524)
				)
			)
		)
		(property "Device Type" "C402H22"
			(at 1.1811 -4.2291 0)
			(unlocked yes)
			(layer "F.Fab")
			(hide yes)
			(effects
				(font
					(size 1.016 1.016)
					(thickness 0.1524)
				)
			)
		)
		(duplicate_pad_numbers_are_jumpers no)
		(fp_rect
			(start -0.4318 0.9525)
			(end 0.4318 -0.9525)
			(stroke
				(width 0)
				(type default)
			)
			(fill no)
			(layer "F.CrtYd")
		)
		(fp_rect
			(start -0.4318 0.9525)
			(end 0.4318 -0.9525)
			(stroke
				(width 0)
				(type default)
			)
			(fill no)
			(layer "F.Fab")
		)
		(pad "1" smd custom
			(at 0 -0.4445)
			(size 0.1524 0.1524)
			(layers "F.Cu" "F.Mask" "F.Paste")
			(net "MB3_HS_SENSE_P")
			(options
				(clearance outline)
				(anchor circle)
			)
			(primitives
				(gr_poly
					(pts
						(arc
							(start 0.3048 -0.2032)
							(mid 0.275042 -0.275042)
							(end 0.2032 -0.3048)
						)
						(arc
							(start -0.2032 -0.3048)
							(mid -0.275042 -0.275042)
							(end -0.3048 -0.2032)
						)
						(arc
							(start -0.3048 0.2032)
							(mid -0.275042 0.275042)
							(end -0.2032 0.3048)
						)
						(arc
							(start 0.2032 0.3048)
							(mid 0.275042 0.275042)
							(end 0.3048 0.2032)
						)
					)
					(width 0)
					(fill yes)
				)
			)
		)
		(pad "2" smd custom
			(at 0 0.4445)
			(size 0.1524 0.1524)
			(layers "F.Cu" "F.Mask" "F.Paste")
			(net "MB3_HS_SENSE_N")
			(options
				(clearance outline)
				(anchor circle)
			)
			(primitives
				(gr_poly
					(pts
						(arc
							(start 0.3048 -0.2032)
							(mid 0.275042 -0.275042)
							(end 0.2032 -0.3048)
						)
						(arc
							(start -0.2032 -0.3048)
							(mid -0.275042 -0.275042)
							(end -0.3048 -0.2032)
						)
						(arc
							(start -0.3048 0.2032)
							(mid -0.275042 0.275042)
							(end -0.2032 0.3048)
						)
						(arc
							(start 0.2032 0.3048)
							(mid 0.275042 0.275042)
							(end 0.3048 0.2032)
						)
					)
					(width 0)
					(fill yes)
				)
			)
		)
	)
	(footprint ""
		(layer "F.Cu")
		(at 178.181 -292.778942 -90)
		(property "Reference" "C105"
			(at 0 0 270)
			(layer "F.SilkS")
			(hide yes)
			(effects
				(font
					(size 1.27 1.27)
				)
			)
		)
		(property "Value" "SC1U16V3KX-5GP"
			(at 0 -2.8194 270)
			(unlocked yes)
			(layer "F.Fab")
			(hide yes)
			(effects
				(font
					(size 1.016 1.016)
					(thickness 0.1524)
				)
			)
		)
		(property "Device Type" "C603H36"
			(at 0 -4.3434 270)
			(unlocked yes)
			(layer "F.Fab")
			(hide yes)
			(effects
				(font
					(size 1.016 1.016)
					(thickness 0.1524)
				)
			)
		)
		(duplicate_pad_numbers_are_jumpers no)
		(fp_line
			(start 0.508 0)
			(end -0.508 0)
			(stroke
				(width 0.2032)
				(type default)
			)
			(layer "F.SilkS")
		)
		(fp_rect
			(start -0.5842 1.3335)
			(end 0.5842 -1.3335)
			(stroke
				(width 0)
				(type default)
			)
			(fill no)
			(layer "F.CrtYd")
		)
		(fp_rect
			(start -0.5842 1.3335)
			(end 0.5842 -1.3335)
			(stroke
				(width 0)
				(type default)
			)
			(fill no)
			(layer "F.Fab")
		)
		(pad "1" smd custom
			(at 0 -0.762 270)
			(size 0.2159 0.2159)
			(layers "F.Cu" "F.Mask" "F.Paste")
			(net "P5V_HDD5")
			(options
				(clearance outline)
				(anchor circle)
			)
			(primitives
				(gr_poly
					(pts
						(arc
							(start -0.3302 -0.4318)
							(mid -0.402042 -0.402042)
							(end -0.4318 -0.3302)
						)
						(arc
							(start -0.4318 0.3302)
							(mid -0.402042 0.402042)
							(end -0.3302 0.4318)
						)
						(arc
							(start 0.3302 0.4318)
							(mid 0.402042 0.402042)
							(end 0.4318 0.3302)
						)
						(arc
							(start 0.4318 -0.3302)
							(mid 0.402042 -0.402042)
							(end 0.3302 -0.4318)
						)
					)
					(width 0)
					(fill yes)
				)
			)
		)
		(pad "2" smd custom
			(at 0 0.762 270)
			(size 0.2159 0.2159)
			(layers "F.Cu" "F.Mask" "F.Paste")
			(net "GND")
			(options
				(clearance outline)
				(anchor circle)
			)
			(primitives
				(gr_poly
					(pts
						(arc
							(start -0.3302 -0.4318)
							(mid -0.402042 -0.402042)
							(end -0.4318 -0.3302)
						)
						(arc
							(start -0.4318 0.3302)
							(mid -0.402042 0.402042)
							(end -0.3302 0.4318)
						)
						(arc
							(start 0.3302 0.4318)
							(mid 0.402042 0.402042)
							(end 0.4318 0.3302)
						)
						(arc
							(start 0.4318 -0.3302)
							(mid 0.402042 -0.402042)
							(end 0.3302 -0.4318)
						)
					)
					(width 0)
					(fill yes)
				)
			)
		)
	)
	(footprint ""
		(layer "F.Cu")
		(at 406.679654 -127.78867 180)
		(property "Reference" "Q248"
			(at 0 0 180)
			(layer "F.SilkS")
			(hide yes)
			(effects
				(font
					(size 1.27 1.27)
				)
			)
		)
		(property "Value" "2N7002K-2-GP"
			(at 0.127 -8.9662 180)
			(unlocked yes)
			(layer "F.Fab")
			(hide yes)
			(effects
				(font
					(size 1.016 1.016)
					(thickness 0.1524)
				)
			)
		)
		(property "Device Type" "SOT23DGS2D4H44"
			(at 0.127 -10.4902 180)
			(unlocked yes)
			(layer "F.Fab")
			(hide yes)
			(effects
				(font
					(size 1.016 1.016)
					(thickness 0.1524)
				)
			)
		)
		(duplicate_pad_numbers_are_jumpers no)
		(fp_line
			(start 1.651 1.778)
			(end 1.651 -1.778)
			(stroke
				(width 0.1524)
				(type default)
			)
			(layer "F.SilkS")
		)
		(fp_line
			(start 1.651 -1.778)
			(end -1.651 -1.778)
			(stroke
				(width 0.1524)
				(type default)
			)
			(layer "F.SilkS")
		)
		(fp_line
			(start -1.651 1.778)
			(end 1.651 1.778)
			(stroke
				(width 0.1524)
				(type default)
			)
			(layer "F.SilkS")
		)
		(fp_line
			(start -1.651 -1.778)
			(end -1.651 1.778)
			(stroke
				(width 0.1524)
				(type default)
			)
			(layer "F.SilkS")
		)
		(fp_poly
			(pts
				(xy -1.778 1.8796) (xy -1.778 -1.8796) (xy 1.778 -1.8796) (xy 1.778 1.8796)
			)
			(stroke
				(width 0)
				(type default)
			)
			(fill no)
			(layer "F.CrtYd")
		)
		(fp_poly
			(pts
				(xy -1.778 1.8796) (xy -1.778 -1.8796) (xy 1.778 -1.8796) (xy 1.778 1.8796)
			)
			(stroke
				(width 0)
				(type default)
			)
			(fill no)
			(layer "F.Fab")
		)
		(pad "D" smd custom
			(at 0 -0.9525 180)
			(size 0.1905 0.1905)
			(layers "F.Cu" "F.Mask" "F.Paste")
			(net "FLT_HDD21_N")
			(options
				(clearance outline)
				(anchor circle)
			)
			(primitives
				(gr_poly
					(pts
						(arc
							(start -0.1778 0.5715)
							(mid -0.321484 0.511984)
							(end -0.381 0.3683)
						)
						(arc
							(start -0.381 -0.3683)
							(mid -0.321484 -0.511984)
							(end -0.1778 -0.5715)
						)
						(arc
							(start 0.1778 -0.5715)
							(mid 0.321484 -0.511984)
							(end 0.381 -0.3683)
						)
						(arc
							(start 0.381 0.3683)
							(mid 0.321484 0.511984)
							(end 0.1778 0.5715)
						)
					)
					(width 0)
					(fill yes)
				)
			)
		)
		(pad "G" smd custom
			(at -0.98425 0.9525 180)
			(size 0.1905 0.1905)
			(layers "F.Cu" "F.Mask" "F.Paste")
			(net "DRIVE_A_21_FLT_LED")
			(options
				(clearance outline)
				(anchor circle)
			)
			(primitives
				(gr_poly
					(pts
						(arc
							(start -0.1778 0.5715)
							(mid -0.321484 0.511984)
							(end -0.381 0.3683)
						)
						(arc
							(start -0.381 -0.3683)
							(mid -0.321484 -0.511984)
							(end -0.1778 -0.5715)
						)
						(arc
							(start 0.1778 -0.5715)
							(mid 0.321484 -0.511984)
							(end 0.381 -0.3683)
						)
						(arc
							(start 0.381 0.3683)
							(mid 0.321484 0.511984)
							(end 0.1778 0.5715)
						)
					)
					(width 0)
					(fill yes)
				)
			)
		)
		(pad "S" smd custom
			(at 0.98425 0.9525 180)
			(size 0.1905 0.1905)
			(layers "F.Cu" "F.Mask" "F.Paste")
			(net "GND")
			(options
				(clearance outline)
				(anchor circle)
			)
			(primitives
				(gr_poly
					(pts
						(arc
							(start -0.1778 0.5715)
							(mid -0.321484 0.511984)
							(end -0.381 0.3683)
						)
						(arc
							(start -0.381 -0.3683)
							(mid -0.321484 -0.511984)
							(end -0.1778 -0.5715)
						)
						(arc
							(start 0.1778 -0.5715)
							(mid 0.321484 -0.511984)
							(end 0.381 -0.3683)
						)
						(arc
							(start 0.381 0.3683)
							(mid 0.321484 0.511984)
							(end 0.1778 0.5715)
						)
					)
					(width 0)
					(fill yes)
				)
			)
		)
	)
	(footprint ""
		(layer "F.Cu")
		(at 115.334796 -55.285894 180)
		(property "Reference" "Q161"
			(at 0 0 180)
			(layer "F.SilkS")
			(hide yes)
			(effects
				(font
					(size 1.27 1.27)
				)
			)
		)
		(property "Value" "AO4406AL-GP"
			(at -3.707384 -1.5367 180)
			(unlocked yes)
			(layer "F.Fab")
			(hide yes)
			(effects
				(font
					(size 1.016 1.016)
					(thickness 0.1524)
				)
			)
		)
		(property "Device Type" "SOIC8H69"
			(at -3.707384 -3.0607 180)
			(unlocked yes)
			(layer "F.Fab")
			(hide yes)
			(effects
				(font
					(size 1.016 1.016)
					(thickness 0.1524)
				)
			)
		)
		(duplicate_pad_numbers_are_jumpers no)
		(fp_line
			(start 2.1336 1.4224)
			(end 2.1336 -1.4224)
			(stroke
				(width 0.1524)
				(type default)
			)
			(layer "F.SilkS")
		)
		(fp_line
			(start 2.1336 -1.4224)
			(end -2.7432 -1.4224)
			(stroke
				(width 0.1524)
				(type default)
			)
			(layer "F.SilkS")
		)
		(fp_line
			(start -2.1844 -0.0508)
			(end -2.7178 0.508)
			(stroke
				(width 0.1524)
				(type default)
			)
			(layer "F.SilkS")
		)
		(fp_line
			(start -2.6289 3.4417)
			(end -2.6289 1.4732)
			(stroke
				(width 0.381)
				(type default)
			)
			(layer "F.SilkS")
		)
		(fp_line
			(start -2.7178 -0.508)
			(end -2.1844 -0.0508)
			(stroke
				(width 0.1524)
				(type default)
			)
			(layer "F.SilkS")
		)
		(fp_line
			(start -2.7432 1.4224)
			(end 2.1336 1.4224)
			(stroke
				(width 0.1524)
				(type default)
			)
			(layer "F.SilkS")
		)
		(fp_line
			(start -2.7432 1.4224)
			(end -2.6416 1.4224)
			(stroke
				(width 0.1524)
				(type default)
			)
			(layer "F.SilkS")
		)
		(fp_line
			(start -2.7432 -1.4224)
			(end -2.7432 1.4224)
			(stroke
				(width 0.1524)
				(type default)
			)
			(layer "F.SilkS")
		)
		(fp_poly
			(pts
				(xy -2.2098 -1.4224) (xy -2.2098 1.4224) (xy 2.2098 1.4224) (xy 2.2098 -1.4224)
			)
			(stroke
				(width 0)
				(type default)
			)
			(fill yes)
			(layer "F.SilkS")
		)
		(fp_rect
			(start -2.450084 2.999994)
			(end 2.450084 -2.999994)
			(stroke
				(width 0)
				(type default)
			)
			(fill no)
			(layer "F.CrtYd")
		)
		(fp_poly
			(pts
				(xy -2.8194 3.6322) (xy -2.8194 -3.6322) (xy 2.8194 -3.6322) (xy 2.8194 1.18364) (xy 2.450084 1.18364)
				(xy 2.450084 -2.999994) (xy -2.450084 -2.999994) (xy -2.450084 2.999994) (xy 2.450084 2.999994)
				(xy 2.450084 1.18618) (xy 2.8194 1.18618) (xy 2.8194 3.6322)
			)
			(stroke
				(width 0)
				(type default)
			)
			(fill no)
			(layer "F.CrtYd")
		)
		(fp_rect
			(start -2.8194 3.6322)
			(end 2.8194 -3.6322)
			(stroke
				(width 0)
				(type default)
			)
			(fill no)
			(layer "F.Fab")
		)
		(pad "1" smd rect
			(at -1.905 2.54 180)
			(size 0.635 1.651)
			(layers "F.Cu" "F.Mask" "F.Paste")
			(net "P5V_HDD27")
		)
		(pad "2" smd rect
			(at -0.635 2.54 180)
			(size 0.635 1.651)
			(layers "F.Cu" "F.Mask" "F.Paste")
			(net "P5V_HDD27")
		)
		(pad "3" smd rect
			(at 0.635 2.54 180)
			(size 0.635 1.651)
			(layers "F.Cu" "F.Mask" "F.Paste")
			(net "P5V_HDD27")
		)
		(pad "4" smd rect
			(at 1.905 2.54 180)
			(size 0.635 1.651)
			(layers "F.Cu" "F.Mask" "F.Paste")
			(net "SW_HDD_P27")
		)
		(pad "5" smd rect
			(at 1.905 -2.54 180)
			(size 0.635 1.651)
			(layers "F.Cu" "F.Mask" "F.Paste")
			(net "P5V_A_2")
		)
		(pad "6" smd rect
			(at 0.635 -2.54 180)
			(size 0.635 1.651)
			(layers "F.Cu" "F.Mask" "F.Paste")
			(net "P5V_A_2")
		)
		(pad "7" smd rect
			(at -0.635 -2.54 180)
			(size 0.635 1.651)
			(layers "F.Cu" "F.Mask" "F.Paste")
			(net "P5V_A_2")
		)
		(pad "8" smd rect
			(at -1.905 -2.54 180)
			(size 0.635 1.651)
			(layers "F.Cu" "F.Mask" "F.Paste")
			(net "P5V_A_2")
		)
	)
	(footprint ""
		(layer "F.Cu")
		(at 252.73 -290.195 180)
		(property "Reference" "R1"
			(at 0 0 180)
			(layer "F.SilkS")
			(hide yes)
			(effects
				(font
					(size 1.27 1.27)
				)
			)
		)
		(property "Value" "4K7R2F-GP"
			(at 0.064008 -3.993896 180)
			(unlocked yes)
			(layer "F.Fab")
			(hide yes)
			(effects
				(font
					(size 1.016 1.016)
					(thickness 0.1524)
				)
			)
		)
		(property "Device Type" "R402H16"
			(at 0.064008 -5.517896 180)
			(unlocked yes)
			(layer "F.Fab")
			(hide yes)
			(effects
				(font
					(size 1.016 1.016)
					(thickness 0.1524)
				)
			)
		)
		(duplicate_pad_numbers_are_jumpers no)
		(fp_line
			(start 0.508 -0.9398)
			(end -0.508 -0.9398)
			(stroke
				(width 0.1524)
				(type default)
			)
			(layer "F.SilkS")
		)
		(fp_line
			(start -0.508 -0.9398)
			(end -0.508 0.9398)
			(stroke
				(width 0.1524)
				(type default)
			)
			(layer "F.SilkS")
		)
		(fp_rect
			(start -0.508 0.9398)
			(end 0.508 -0.9398)
			(stroke
				(width 0)
				(type default)
			)
			(fill no)
			(layer "F.CrtYd")
		)
		(fp_rect
			(start -0.508 0.9398)
			(end 0.508 -0.9398)
			(stroke
				(width 0)
				(type default)
			)
			(fill no)
			(layer "F.Fab")
		)
		(pad "1" smd custom
			(at 0 -0.4445 180)
			(size 0.1397 0.1397)
			(layers "F.Cu" "F.Mask" "F.Paste")
			(net "P3V3_STBY_A")
			(options
				(clearance outline)
				(anchor circle)
			)
			(primitives
				(gr_poly
					(pts
						(arc
							(start -0.1778 -0.2794)
							(mid -0.249642 -0.249642)
							(end -0.2794 -0.1778)
						)
						(arc
							(start -0.2794 0.1778)
							(mid -0.249642 0.249642)
							(end -0.1778 0.2794)
						)
						(arc
							(start 0.1778 0.2794)
							(mid 0.249642 0.249642)
							(end 0.2794 0.1778)
						)
						(arc
							(start 0.2794 -0.1778)
							(mid 0.249642 -0.249642)
							(end 0.1778 -0.2794)
						)
					)
					(width 0)
					(fill yes)
				)
			)
		)
		(pad "2" smd custom
			(at 0 0.4445 180)
			(size 0.1397 0.1397)
			(layers "F.Cu" "F.Mask" "F.Paste")
			(net "EEPROM_A0")
			(options
				(clearance outline)
				(anchor circle)
			)
			(primitives
				(gr_poly
					(pts
						(arc
							(start -0.1778 -0.2794)
							(mid -0.249642 -0.249642)
							(end -0.2794 -0.1778)
						)
						(arc
							(start -0.2794 0.1778)
							(mid -0.249642 0.249642)
							(end -0.1778 0.2794)
						)
						(arc
							(start 0.1778 0.2794)
							(mid 0.249642 0.249642)
							(end 0.2794 0.1778)
						)
						(arc
							(start 0.2794 -0.1778)
							(mid 0.249642 -0.249642)
							(end 0.1778 -0.2794)
						)
					)
					(width 0)
					(fill yes)
				)
			)
		)
	)
	(footprint ""
		(layer "F.Cu")
		(at 224.528126 -139.239498 -90)
		(property "Reference" "TP226"
			(at 0 0 270)
			(layer "F.SilkS")
			(hide yes)
			(effects
				(font
					(size 1.27 1.27)
				)
			)
		)
		(property "Value" "TPAD32-GP"
			(at -0.0508 -1.6764 270)
			(unlocked yes)
			(layer "F.Fab")
			(hide yes)
			(effects
				(font
					(size 1.016 1.016)
					(thickness 0.1524)
				)
			)
		)
		(property "Device Type" "TPAD32"
			(at -0.0508 -3.2004 270)
			(unlocked yes)
			(layer "F.Fab")
			(hide yes)
			(effects
				(font
					(size 1.016 1.016)
					(thickness 0.1524)
				)
			)
		)
		(duplicate_pad_numbers_are_jumpers no)
		(fp_poly
			(pts
				(arc
					(start 0 -0.4064)
					(mid 0 0.4064)
					(end 0 -0.4064)
				)
			)
			(stroke
				(width 0)
				(type default)
			)
			(fill no)
			(layer "F.CrtYd")
		)
		(fp_poly
			(pts
				(arc
					(start 0 -0.7112)
					(mid 0 0.7112)
					(end 0 -0.7112)
				)
			)
			(stroke
				(width 0)
				(type default)
			)
			(fill no)
			(layer "F.Fab")
		)
		(pad "1" smd circle
			(at 0 0 270)
			(size 0.8128 0.8128)
			(layers "F.Cu" "F.Mask" "F.Paste")
			(net "TP_SMB_COMP_A_NIC_ALERT_N")
		)
	)
	(footprint ""
		(layer "F.Cu")
		(at 331.47 -291.127942 -90)
		(property "Reference" "R267"
			(at 0 0 270)
			(layer "F.SilkS")
			(hide yes)
			(effects
				(font
					(size 1.27 1.27)
				)
			)
		)
		(property "Value" "2R6F-GP"
			(at -0.0508 -4.8514 270)
			(unlocked yes)
			(layer "F.Fab")
			(hide yes)
			(effects
				(font
					(size 1.016 1.016)
					(thickness 0.1524)
				)
			)
		)
		(property "Device Type" "R1206H26"
			(at 0 -6.3754 270)
			(unlocked yes)
			(layer "F.Fab")
			(hide yes)
			(effects
				(font
					(size 1.016 1.016)
					(thickness 0.1524)
				)
			)
		)
		(duplicate_pad_numbers_are_jumpers no)
		(fp_line
			(start -1.016 2.2352)
			(end -1.016 -2.2352)
			(stroke
				(width 0.1524)
				(type default)
			)
			(layer "F.SilkS")
		)
		(fp_line
			(start 1.016 2.2352)
			(end -1.016 2.2352)
			(stroke
				(width 0.1524)
				(type default)
			)
			(layer "F.SilkS")
		)
		(fp_line
			(start -1.016 -2.2352)
			(end 1.016 -2.2352)
			(stroke
				(width 0.1524)
				(type default)
			)
			(layer "F.SilkS")
		)
		(fp_line
			(start 1.016 -2.2352)
			(end 1.016 2.2352)
			(stroke
				(width 0.1524)
				(type default)
			)
			(layer "F.SilkS")
		)
		(fp_rect
			(start -1.0922 2.3114)
			(end 1.0922 -2.3114)
			(stroke
				(width 0)
				(type default)
			)
			(fill no)
			(layer "F.CrtYd")
		)
		(fp_poly
			(pts
				(xy -1.0922 -2.3114) (xy 1.0922 -2.3114) (xy 1.0922 2.3114) (xy -1.0922 2.3114)
			)
			(stroke
				(width 0)
				(type default)
			)
			(fill no)
			(layer "F.Fab")
		)
		(pad "1" smd rect
			(at 0 -1.397 270)
			(size 1.651 1.27)
			(layers "F.Cu" "F.Mask" "F.Paste")
			(net "P5V_HDD6")
		)
		(pad "2" smd rect
			(at 0 1.397 270)
			(size 1.651 1.27)
			(layers "F.Cu" "F.Mask" "F.Paste")
			(net "5V_PRE_6")
		)
	)
	(footprint ""
		(layer "F.Cu")
		(at 363.020102 -176.127918 -90)
		(property "Reference" "R566"
			(at 0 0 270)
			(layer "F.SilkS")
			(hide yes)
			(effects
				(font
					(size 1.27 1.27)
				)
			)
		)
		(property "Value" "2R6F-GP"
			(at -0.0508 -4.8514 270)
			(unlocked yes)
			(layer "F.Fab")
			(hide yes)
			(effects
				(font
					(size 1.016 1.016)
					(thickness 0.1524)
				)
			)
		)
		(property "Device Type" "R1206H26"
			(at 0 -6.3754 270)
			(unlocked yes)
			(layer "F.Fab")
			(hide yes)
			(effects
				(font
					(size 1.016 1.016)
					(thickness 0.1524)
				)
			)
		)
		(duplicate_pad_numbers_are_jumpers no)
		(fp_line
			(start -1.016 2.2352)
			(end -1.016 -2.2352)
			(stroke
				(width 0.1524)
				(type default)
			)
			(layer "F.SilkS")
		)
		(fp_line
			(start 1.016 2.2352)
			(end -1.016 2.2352)
			(stroke
				(width 0.1524)
				(type default)
			)
			(layer "F.SilkS")
		)
		(fp_line
			(start -1.016 -2.2352)
			(end 1.016 -2.2352)
			(stroke
				(width 0.1524)
				(type default)
			)
			(layer "F.SilkS")
		)
		(fp_line
			(start 1.016 -2.2352)
			(end 1.016 2.2352)
			(stroke
				(width 0.1524)
				(type default)
			)
			(layer "F.SilkS")
		)
		(fp_rect
			(start -1.0922 2.3114)
			(end 1.0922 -2.3114)
			(stroke
				(width 0)
				(type default)
			)
			(fill no)
			(layer "F.CrtYd")
		)
		(fp_poly
			(pts
				(xy -1.0922 -2.3114) (xy 1.0922 -2.3114) (xy 1.0922 2.3114) (xy -1.0922 2.3114)
			)
			(stroke
				(width 0)
				(type default)
			)
			(fill no)
			(layer "F.Fab")
		)
		(pad "1" smd rect
			(at 0 -1.397 270)
			(size 1.651 1.27)
			(layers "F.Cu" "F.Mask" "F.Paste")
			(net "P5V_HDD19")
		)
		(pad "2" smd rect
			(at 0 1.397 270)
			(size 1.651 1.27)
			(layers "F.Cu" "F.Mask" "F.Paste")
			(net "5V_PRE_19")
		)
	)
	(footprint ""
		(layer "F.Cu")
		(at 229.849934 -143.49984)
		(property "Reference" ""
			(at 0 0 0)
			(layer "F.SilkS")
			(hide yes)
			(effects
				(font
					(size 1.27 1.27)
				)
			)
		)
		(property "Value" "*"
			(at -4.729734 -0.095504 0)
			(unlocked yes)
			(layer "F.Fab")
			(hide yes)
			(effects
				(font
					(size 1.016 1.016)
					(thickness 0.1524)
				)
			)
		)
		(duplicate_pad_numbers_are_jumpers no)
		(fp_poly
			(pts
				(arc
					(start 4.064 0)
					(mid -4.064 0)
					(end 4.064 0)
				)
			)
			(stroke
				(width 0)
				(type default)
			)
			(fill no)
			(layer "B.CrtYd")
		)
		(fp_poly
			(pts
				(arc
					(start 4.064 0)
					(mid -4.064 0)
					(end 4.064 0)
				)
			)
			(stroke
				(width 0)
				(type default)
			)
			(fill no)
			(layer "F.CrtYd")
		)
		(fp_poly
			(pts
				(arc
					(start 4.064 0)
					(mid -4.064 0)
					(end 4.064 0)
				)
			)
			(stroke
				(width 0)
				(type default)
			)
			(fill no)
			(layer "B.Fab")
		)
		(fp_poly
			(pts
				(arc
					(start 4.064 0)
					(mid -4.064 0)
					(end 4.064 0)
				)
			)
			(stroke
				(width 0)
				(type default)
			)
			(fill no)
			(layer "F.Fab")
		)
		(pad "1" thru_hole circle
			(at 0 0)
			(size 7.5184 7.5184)
			(drill 4.2164)
			(layers "*.Cu" "*.Mask")
			(remove_unused_layers no)
			(net "Net_60")
			(clearance -1.143)
			(thermal_gap 0.3048)
			(padstack
				(mode front_inner_back)
				(layer "Inner"
					(shape circle)
					(size 4.6228 4.6228)
					(clearance 0.3048)
				)
				(layer "B.Cu"
					(shape circle)
					(size 7.5184 7.5184)
					(clearance -1.143)
				)
			)
		)
	)
	(footprint ""
		(layer "F.Cu")
		(at 150.057866 -143.848074 90)
		(property "Reference" "R1056"
			(at 0 0 90)
			(layer "F.SilkS")
			(hide yes)
			(effects
				(font
					(size 1.27 1.27)
				)
			)
		)
		(property "Value" "100KR2F-L1-GP"
			(at 0.064008 -3.993896 90)
			(unlocked yes)
			(layer "F.Fab")
			(hide yes)
			(effects
				(font
					(size 1.016 1.016)
					(thickness 0.1524)
				)
			)
		)
		(property "Device Type" "R402H16"
			(at 0.064008 -5.517896 90)
			(unlocked yes)
			(layer "F.Fab")
			(hide yes)
			(effects
				(font
					(size 1.016 1.016)
					(thickness 0.1524)
				)
			)
		)
		(duplicate_pad_numbers_are_jumpers no)
		(fp_line
			(start 0.508 -0.9398)
			(end -0.508 -0.9398)
			(stroke
				(width 0.1524)
				(type default)
			)
			(layer "F.SilkS")
		)
		(fp_line
			(start -0.508 -0.9398)
			(end -0.508 0.9398)
			(stroke
				(width 0.1524)
				(type default)
			)
			(layer "F.SilkS")
		)
		(fp_rect
			(start -0.508 0.9398)
			(end 0.508 -0.9398)
			(stroke
				(width 0)
				(type default)
			)
			(fill no)
			(layer "F.CrtYd")
		)
		(fp_rect
			(start -0.508 0.9398)
			(end 0.508 -0.9398)
			(stroke
				(width 0)
				(type default)
			)
			(fill no)
			(layer "F.Fab")
		)
		(pad "1" smd custom
			(at 0 -0.4445 90)
			(size 0.1397 0.1397)
			(layers "F.Cu" "F.Mask" "F.Paste")
			(net "MB0_VCAP_R")
			(options
				(clearance outline)
				(anchor circle)
			)
			(primitives
				(gr_poly
					(pts
						(arc
							(start -0.1778 -0.2794)
							(mid -0.249642 -0.249642)
							(end -0.2794 -0.1778)
						)
						(arc
							(start -0.2794 0.1778)
							(mid -0.249642 0.249642)
							(end -0.1778 0.2794)
						)
						(arc
							(start 0.1778 0.2794)
							(mid 0.249642 0.249642)
							(end 0.2794 0.1778)
						)
						(arc
							(start 0.2794 -0.1778)
							(mid 0.249642 -0.249642)
							(end 0.1778 -0.2794)
						)
					)
					(width 0)
					(fill yes)
				)
			)
		)
		(pad "2" smd custom
			(at 0 0.4445 90)
			(size 0.1397 0.1397)
			(layers "F.Cu" "F.Mask" "F.Paste")
			(net "MB0_PSET_R")
			(options
				(clearance outline)
				(anchor circle)
			)
			(primitives
				(gr_poly
					(pts
						(arc
							(start -0.1778 -0.2794)
							(mid -0.249642 -0.249642)
							(end -0.2794 -0.1778)
						)
						(arc
							(start -0.2794 0.1778)
							(mid -0.249642 0.249642)
							(end -0.1778 0.2794)
						)
						(arc
							(start 0.1778 0.2794)
							(mid 0.249642 0.249642)
							(end 0.2794 0.1778)
						)
						(arc
							(start 0.2794 -0.1778)
							(mid 0.249642 -0.249642)
							(end 0.1778 -0.2794)
						)
					)
					(width 0)
					(fill yes)
				)
			)
		)
	)
	(footprint ""
		(layer "F.Cu")
		(at 400.03095 -275.760942 180)
		(property "Reference" "R328"
			(at 0 0 180)
			(layer "F.SilkS")
			(hide yes)
			(effects
				(font
					(size 1.27 1.27)
				)
			)
		)
		(property "Value" "4K7R2J-2-GP"
			(at 0.064008 -3.993896 180)
			(unlocked yes)
			(layer "F.Fab")
			(hide yes)
			(effects
				(font
					(size 1.016 1.016)
					(thickness 0.1524)
				)
			)
		)
		(property "Device Type" "R402H16"
			(at 0.064008 -5.517896 180)
			(unlocked yes)
			(layer "F.Fab")
			(hide yes)
			(effects
				(font
					(size 1.016 1.016)
					(thickness 0.1524)
				)
			)
		)
		(duplicate_pad_numbers_are_jumpers no)
		(fp_line
			(start 0.508 -0.9398)
			(end -0.508 -0.9398)
			(stroke
				(width 0.1524)
				(type default)
			)
			(layer "F.SilkS")
		)
		(fp_line
			(start -0.508 -0.9398)
			(end -0.508 0.9398)
			(stroke
				(width 0.1524)
				(type default)
			)
			(layer "F.SilkS")
		)
		(fp_rect
			(start -0.508 0.9398)
			(end 0.508 -0.9398)
			(stroke
				(width 0)
				(type default)
			)
			(fill no)
			(layer "F.CrtYd")
		)
		(fp_rect
			(start -0.508 0.9398)
			(end 0.508 -0.9398)
			(stroke
				(width 0)
				(type default)
			)
			(fill no)
			(layer "F.Fab")
		)
		(pad "1" smd custom
			(at 0 -0.4445 180)
			(size 0.1397 0.1397)
			(layers "F.Cu" "F.Mask" "F.Paste")
			(net "P12V_A")
			(options
				(clearance outline)
				(anchor circle)
			)
			(primitives
				(gr_poly
					(pts
						(arc
							(start -0.1778 -0.2794)
							(mid -0.249642 -0.249642)
							(end -0.2794 -0.1778)
						)
						(arc
							(start -0.2794 0.1778)
							(mid -0.249642 0.249642)
							(end -0.1778 0.2794)
						)
						(arc
							(start 0.1778 0.2794)
							(mid 0.249642 0.249642)
							(end 0.2794 0.1778)
						)
						(arc
							(start 0.2794 -0.1778)
							(mid 0.249642 -0.249642)
							(end 0.1778 -0.2794)
						)
					)
					(width 0)
					(fill yes)
				)
			)
		)
		(pad "2" smd custom
			(at 0 0.4445 180)
			(size 0.1397 0.1397)
			(layers "F.Cu" "F.Mask" "F.Paste")
			(net "SW_HDD_R8")
			(options
				(clearance outline)
				(anchor circle)
			)
			(primitives
				(gr_poly
					(pts
						(arc
							(start -0.1778 -0.2794)
							(mid -0.249642 -0.249642)
							(end -0.2794 -0.1778)
						)
						(arc
							(start -0.2794 0.1778)
							(mid -0.249642 0.249642)
							(end -0.1778 0.2794)
						)
						(arc
							(start 0.1778 0.2794)
							(mid 0.249642 0.249642)
							(end 0.2794 0.1778)
						)
						(arc
							(start 0.2794 -0.1778)
							(mid 0.249642 -0.249642)
							(end 0.1778 -0.2794)
						)
					)
					(width 0)
					(fill yes)
				)
			)
		)
	)
	(footprint ""
		(layer "F.Cu")
		(at 478.30359 -269.224252 -90)
		(property "Reference" "R383"
			(at 0 0 270)
			(layer "F.SilkS")
			(hide yes)
			(effects
				(font
					(size 1.27 1.27)
				)
			)
		)
		(property "Value" "10KR2F-2-GP"
			(at 0.064008 -3.993896 270)
			(unlocked yes)
			(layer "F.Fab")
			(hide yes)
			(effects
				(font
					(size 1.016 1.016)
					(thickness 0.1524)
				)
			)
		)
		(property "Device Type" "R402H16"
			(at 0.064008 -5.517896 270)
			(unlocked yes)
			(layer "F.Fab")
			(hide yes)
			(effects
				(font
					(size 1.016 1.016)
					(thickness 0.1524)
				)
			)
		)
		(duplicate_pad_numbers_are_jumpers no)
		(fp_line
			(start -0.508 -0.9398)
			(end -0.508 0.9398)
			(stroke
				(width 0.1524)
				(type default)
			)
			(layer "F.SilkS")
		)
		(fp_line
			(start 0.508 -0.9398)
			(end -0.508 -0.9398)
			(stroke
				(width 0.1524)
				(type default)
			)
			(layer "F.SilkS")
		)
		(fp_rect
			(start -0.508 0.9398)
			(end 0.508 -0.9398)
			(stroke
				(width 0)
				(type default)
			)
			(fill no)
			(layer "F.CrtYd")
		)
		(fp_rect
			(start -0.508 0.9398)
			(end 0.508 -0.9398)
			(stroke
				(width 0)
				(type default)
			)
			(fill no)
			(layer "F.Fab")
		)
		(pad "1" smd custom
			(at 0 -0.4445 270)
			(size 0.1397 0.1397)
			(layers "F.Cu" "F.Mask" "F.Paste")
			(net "P3V3_STBY_A")
			(options
				(clearance outline)
				(anchor circle)
			)
			(primitives
				(gr_poly
					(pts
						(arc
							(start -0.1778 -0.2794)
							(mid -0.249642 -0.249642)
							(end -0.2794 -0.1778)
						)
						(arc
							(start -0.2794 0.1778)
							(mid -0.249642 0.249642)
							(end -0.1778 0.2794)
						)
						(arc
							(start 0.1778 0.2794)
							(mid 0.249642 0.249642)
							(end 0.2794 0.1778)
						)
						(arc
							(start 0.2794 -0.1778)
							(mid 0.249642 -0.249642)
							(end 0.1778 -0.2794)
						)
					)
					(width 0)
					(fill yes)
				)
			)
		)
		(pad "2" smd custom
			(at 0 0.4445 270)
			(size 0.1397 0.1397)
			(layers "F.Cu" "F.Mask" "F.Paste")
			(net "HDD_PRSNT_11")
			(options
				(clearance outline)
				(anchor circle)
			)
			(primitives
				(gr_poly
					(pts
						(arc
							(start -0.1778 -0.2794)
							(mid -0.249642 -0.249642)
							(end -0.2794 -0.1778)
						)
						(arc
							(start -0.2794 0.1778)
							(mid -0.249642 0.249642)
							(end -0.1778 0.2794)
						)
						(arc
							(start 0.1778 0.2794)
							(mid 0.249642 0.249642)
							(end 0.2794 0.1778)
						)
						(arc
							(start 0.2794 -0.1778)
							(mid 0.249642 -0.249642)
							(end 0.1778 -0.2794)
						)
					)
					(width 0)
					(fill yes)
				)
			)
		)
	)
	(footprint ""
		(layer "F.Cu")
		(at 262.017002 -218.021662)
		(property "Reference" "C56"
			(at 0 0 0)
			(layer "F.SilkS")
			(hide yes)
			(effects
				(font
					(size 1.27 1.27)
				)
			)
		)
		(property "Value" "SCD1U16V2KX-3GP"
			(at 1.1811 -2.7051 0)
			(unlocked yes)
			(layer "F.Fab")
			(hide yes)
			(effects
				(font
					(size 1.016 1.016)
					(thickness 0.1524)
				)
			)
		)
		(property "Device Type" "C402H22"
			(at 1.1811 -4.2291 0)
			(unlocked yes)
			(layer "F.Fab")
			(hide yes)
			(effects
				(font
					(size 1.016 1.016)
					(thickness 0.1524)
				)
			)
		)
		(duplicate_pad_numbers_are_jumpers no)
		(fp_rect
			(start -0.4318 0.9525)
			(end 0.4318 -0.9525)
			(stroke
				(width 0)
				(type default)
			)
			(fill no)
			(layer "F.CrtYd")
		)
		(fp_rect
			(start -0.4318 0.9525)
			(end 0.4318 -0.9525)
			(stroke
				(width 0)
				(type default)
			)
			(fill no)
			(layer "F.Fab")
		)
		(pad "1" smd custom
			(at 0 -0.4445)
			(size 0.1524 0.1524)
			(layers "F.Cu" "F.Mask" "F.Paste")
			(net "P3V3_STBY_A")
			(options
				(clearance outline)
				(anchor circle)
			)
			(primitives
				(gr_poly
					(pts
						(arc
							(start 0.3048 -0.2032)
							(mid 0.275042 -0.275042)
							(end 0.2032 -0.3048)
						)
						(arc
							(start -0.2032 -0.3048)
							(mid -0.275042 -0.275042)
							(end -0.3048 -0.2032)
						)
						(arc
							(start -0.3048 0.2032)
							(mid -0.275042 0.275042)
							(end -0.2032 0.3048)
						)
						(arc
							(start 0.2032 0.3048)
							(mid 0.275042 0.275042)
							(end 0.3048 0.2032)
						)
					)
					(width 0)
					(fill yes)
				)
			)
		)
		(pad "2" smd custom
			(at 0 0.4445)
			(size 0.1524 0.1524)
			(layers "F.Cu" "F.Mask" "F.Paste")
			(net "GND")
			(options
				(clearance outline)
				(anchor circle)
			)
			(primitives
				(gr_poly
					(pts
						(arc
							(start 0.3048 -0.2032)
							(mid 0.275042 -0.275042)
							(end 0.2032 -0.3048)
						)
						(arc
							(start -0.2032 -0.3048)
							(mid -0.275042 -0.275042)
							(end -0.3048 -0.2032)
						)
						(arc
							(start -0.3048 0.2032)
							(mid -0.275042 0.275042)
							(end -0.2032 0.3048)
						)
						(arc
							(start 0.2032 0.3048)
							(mid 0.275042 0.275042)
							(end 0.3048 0.2032)
						)
					)
					(width 0)
					(fill yes)
				)
			)
		)
	)
	(footprint ""
		(layer "F.Cu")
		(at 114.699796 -176.000918 -90)
		(property "Reference" "C236"
			(at 0 0 270)
			(layer "F.SilkS")
			(hide yes)
			(effects
				(font
					(size 1.27 1.27)
				)
			)
		)
		(property "Value" "SC10U16V6KX-2GP"
			(at -0.0762 -5.1308 270)
			(unlocked yes)
			(layer "F.Fab")
			(hide yes)
			(effects
				(font
					(size 1.016 1.016)
					(thickness 0.1524)
				)
			)
		)
		(property "Device Type" "C1206H71"
			(at -0.127 -6.6548 270)
			(unlocked yes)
			(layer "F.Fab")
			(hide yes)
			(effects
				(font
					(size 1.016 1.016)
					(thickness 0.1524)
				)
			)
		)
		(duplicate_pad_numbers_are_jumpers no)
		(fp_line
			(start -1.016 2.2352)
			(end -1.016 0.8382)
			(stroke
				(width 0.1524)
				(type default)
			)
			(layer "F.SilkS")
		)
		(fp_line
			(start 1.016 2.2352)
			(end -1.016 2.2352)
			(stroke
				(width 0.1524)
				(type default)
			)
			(layer "F.SilkS")
		)
		(fp_line
			(start 1.016 0.8382)
			(end 1.016 2.2352)
			(stroke
				(width 0.1524)
				(type default)
			)
			(layer "F.SilkS")
		)
		(fp_line
			(start -1.016 -0.8382)
			(end -1.016 -2.2352)
			(stroke
				(width 0.1524)
				(type default)
			)
			(layer "F.SilkS")
		)
		(fp_line
			(start -1.016 -2.2352)
			(end 1.016 -2.2352)
			(stroke
				(width 0.1524)
				(type default)
			)
			(layer "F.SilkS")
		)
		(fp_line
			(start 1.016 -2.2352)
			(end 1.016 -0.8382)
			(stroke
				(width 0.1524)
				(type default)
			)
			(layer "F.SilkS")
		)
		(fp_rect
			(start -1.0922 2.3114)
			(end 1.0922 -2.3114)
			(stroke
				(width 0)
				(type default)
			)
			(fill no)
			(layer "F.CrtYd")
		)
		(fp_poly
			(pts
				(xy 1.0922 -2.3114) (xy 1.0922 2.3114) (xy -1.0922 2.3114) (xy -1.0922 -2.3114)
			)
			(stroke
				(width 0)
				(type default)
			)
			(fill no)
			(layer "F.Fab")
		)
		(pad "1" smd rect
			(at 0 -1.397 270)
			(size 1.651 1.27)
			(layers "F.Cu" "F.Mask" "F.Paste")
			(net "P5V_HDD15")
		)
		(pad "2" smd rect
			(at 0 1.397 270)
			(size 1.651 1.27)
			(layers "F.Cu" "F.Mask" "F.Paste")
			(net "GND")
		)
	)
	(footprint ""
		(layer "F.Cu")
		(at 46.265846 -294.683942 -90)
		(property "Reference" "C59"
			(at 0 0 270)
			(layer "F.SilkS")
			(hide yes)
			(effects
				(font
					(size 1.27 1.27)
				)
			)
		)
		(property "Value" "SC4D7U25V5KX-1-GP"
			(at -0.0762 -6.1214 270)
			(unlocked yes)
			(layer "F.Fab")
			(hide yes)
			(effects
				(font
					(size 1.016 1.016)
					(thickness 0.1524)
				)
			)
		)
		(property "Device Type" "C805H58"
			(at -0.0762 -8.1534 270)
			(unlocked yes)
			(layer "F.Fab")
			(hide yes)
			(effects
				(font
					(size 1.016 1.016)
					(thickness 0.1524)
				)
			)
		)
		(duplicate_pad_numbers_are_jumpers no)
		(fp_line
			(start 0.635 0)
			(end -0.635 0)
			(stroke
				(width 0.508)
				(type default)
			)
			(layer "F.SilkS")
		)
		(fp_rect
			(start -0.9652 1.778)
			(end 0.9652 -1.778)
			(stroke
				(width 0)
				(type default)
			)
			(fill no)
			(layer "F.CrtYd")
		)
		(fp_poly
			(pts
				(xy -0.9652 -1.778) (xy 0.9652 -1.778) (xy 0.9652 1.778) (xy -0.9652 1.778)
			)
			(stroke
				(width 0)
				(type default)
			)
			(fill no)
			(layer "F.Fab")
		)
		(pad "1" smd rect
			(at 0 -0.9652 270)
			(size 1.397 1.143)
			(layers "F.Cu" "F.Mask" "F.Paste")
			(net "P12V_HDD1")
		)
		(pad "2" smd rect
			(at 0 0.9652 270)
			(size 1.397 1.143)
			(layers "F.Cu" "F.Mask" "F.Paste")
			(net "GND")
		)
	)
	(footprint ""
		(layer "F.Cu")
		(at 180.7464 -48.554894 90)
		(property "Reference" "R810"
			(at 0 0 90)
			(layer "F.SilkS")
			(hide yes)
			(effects
				(font
					(size 1.27 1.27)
				)
			)
		)
		(property "Value" "4K7R2J-2-GP"
			(at 0.064008 -3.993896 90)
			(unlocked yes)
			(layer "F.Fab")
			(hide yes)
			(effects
				(font
					(size 1.016 1.016)
					(thickness 0.1524)
				)
			)
		)
		(property "Device Type" "R402H16"
			(at 0.064008 -5.517896 90)
			(unlocked yes)
			(layer "F.Fab")
			(hide yes)
			(effects
				(font
					(size 1.016 1.016)
					(thickness 0.1524)
				)
			)
		)
		(duplicate_pad_numbers_are_jumpers no)
		(fp_line
			(start 0.508 -0.9398)
			(end -0.508 -0.9398)
			(stroke
				(width 0.1524)
				(type default)
			)
			(layer "F.SilkS")
		)
		(fp_line
			(start -0.508 -0.9398)
			(end -0.508 0.9398)
			(stroke
				(width 0.1524)
				(type default)
			)
			(layer "F.SilkS")
		)
		(fp_rect
			(start -0.508 0.9398)
			(end 0.508 -0.9398)
			(stroke
				(width 0)
				(type default)
			)
			(fill no)
			(layer "F.CrtYd")
		)
		(fp_rect
			(start -0.508 0.9398)
			(end 0.508 -0.9398)
			(stroke
				(width 0)
				(type default)
			)
			(fill no)
			(layer "F.Fab")
		)
		(pad "1" smd custom
			(at 0 -0.4445 90)
			(size 0.1397 0.1397)
			(layers "F.Cu" "F.Mask" "F.Paste")
			(net "SW_PWR_R_HDD29")
			(options
				(clearance outline)
				(anchor circle)
			)
			(primitives
				(gr_poly
					(pts
						(arc
							(start -0.1778 -0.2794)
							(mid -0.249642 -0.249642)
							(end -0.2794 -0.1778)
						)
						(arc
							(start -0.2794 0.1778)
							(mid -0.249642 0.249642)
							(end -0.1778 0.2794)
						)
						(arc
							(start 0.1778 0.2794)
							(mid 0.249642 0.249642)
							(end 0.2794 0.1778)
						)
						(arc
							(start 0.2794 -0.1778)
							(mid 0.249642 -0.249642)
							(end 0.1778 -0.2794)
						)
					)
					(width 0)
					(fill yes)
				)
			)
		)
		(pad "2" smd custom
			(at 0 0.4445 90)
			(size 0.1397 0.1397)
			(layers "F.Cu" "F.Mask" "F.Paste")
			(net "GND")
			(options
				(clearance outline)
				(anchor circle)
			)
			(primitives
				(gr_poly
					(pts
						(arc
							(start -0.1778 -0.2794)
							(mid -0.249642 -0.249642)
							(end -0.2794 -0.1778)
						)
						(arc
							(start -0.2794 0.1778)
							(mid -0.249642 0.249642)
							(end -0.1778 0.2794)
						)
						(arc
							(start 0.1778 0.2794)
							(mid 0.249642 0.249642)
							(end 0.2794 0.1778)
						)
						(arc
							(start 0.2794 -0.1778)
							(mid 0.249642 -0.249642)
							(end 0.1778 -0.2794)
						)
					)
					(width 0)
					(fill yes)
				)
			)
		)
	)
	(footprint ""
		(layer "F.Cu")
		(at 363.655102 -275.252942 -90)
		(property "Reference" "Q43"
			(at 0 0 270)
			(layer "F.SilkS")
			(hide yes)
			(effects
				(font
					(size 1.27 1.27)
				)
			)
		)
		(property "Value" "2N7002KDW-GP"
			(at -2.3622 -8.2042 270)
			(unlocked yes)
			(layer "F.Fab")
			(hide yes)
			(effects
				(font
					(size 1.016 1.016)
					(thickness 0.1524)
				)
			)
		)
		(property "Device Type" "SOT-363H44"
			(at -2.3622 -10.1092 270)
			(unlocked yes)
			(layer "F.Fab")
			(hide yes)
			(effects
				(font
					(size 1.016 1.016)
					(thickness 0.1524)
				)
			)
		)
		(duplicate_pad_numbers_are_jumpers no)
		(fp_line
			(start -1.4478 1.7018)
			(end 1.4478 1.7018)
			(stroke
				(width 0.1524)
				(type default)
			)
			(layer "F.SilkS")
		)
		(fp_line
			(start 1.4478 1.7018)
			(end 1.4478 -1.7018)
			(stroke
				(width 0.1524)
				(type default)
			)
			(layer "F.SilkS")
		)
		(fp_line
			(start -1.27 1.524)
			(end -1.27 0.6604)
			(stroke
				(width 0.4826)
				(type default)
			)
			(layer "F.SilkS")
		)
		(fp_line
			(start -1.4478 -1.7018)
			(end -1.4478 1.7018)
			(stroke
				(width 0.1524)
				(type default)
			)
			(layer "F.SilkS")
		)
		(fp_line
			(start 1.4478 -1.7018)
			(end -1.4478 -1.7018)
			(stroke
				(width 0.1524)
				(type default)
			)
			(layer "F.SilkS")
		)
		(fp_poly
			(pts
				(xy -1.524 -1.778) (xy 1.524 -1.778) (xy 1.524 1.778) (xy -1.524 1.778)
			)
			(stroke
				(width 0)
				(type default)
			)
			(fill no)
			(layer "F.CrtYd")
		)
		(fp_poly
			(pts
				(xy -1.524 -1.778) (xy 1.524 -1.778) (xy 1.524 1.778) (xy -1.524 1.778)
			)
			(stroke
				(width 0)
				(type default)
			)
			(fill no)
			(layer "F.Fab")
		)
		(pad "1" smd rect
			(at -0.65024 0.9398 270)
			(size 0.4064 1.016)
			(layers "F.Cu" "F.Mask" "F.Paste")
			(net "GND")
		)
		(pad "2" smd rect
			(at 0 0.9398 270)
			(size 0.4064 1.016)
			(layers "F.Cu" "F.Mask" "F.Paste")
			(net "SW_PWR_R_HDD7")
		)
		(pad "3" smd rect
			(at 0.65024 0.9398 270)
			(size 0.4064 1.016)
			(layers "F.Cu" "F.Mask" "F.Paste")
			(net "SW_HDD_P7")
		)
		(pad "4" smd rect
			(at 0.65024 -0.9398 270)
			(size 0.4064 1.016)
			(layers "F.Cu" "F.Mask" "F.Paste")
			(net "GND")
		)
		(pad "5" smd rect
			(at 0 -0.9398 270)
			(size 0.4064 1.016)
			(layers "F.Cu" "F.Mask" "F.Paste")
			(net "SW_HDD_G7")
		)
		(pad "6" smd rect
			(at -0.65024 -0.9398 270)
			(size 0.4064 1.016)
			(layers "F.Cu" "F.Mask" "F.Paste")
			(net "SW_HDD_R7")
		)
	)
	(footprint ""
		(layer "F.Cu")
		(at 334.68437 -29.095954)
		(property "Reference" "C16"
			(at 0 0 0)
			(layer "F.SilkS")
			(hide yes)
			(effects
				(font
					(size 1.27 1.27)
				)
			)
		)
		(property "Value" "SCD1U16V2KX-3GP"
			(at 1.1811 -2.7051 0)
			(unlocked yes)
			(layer "F.Fab")
			(hide yes)
			(effects
				(font
					(size 1.016 1.016)
					(thickness 0.1524)
				)
			)
		)
		(property "Device Type" "C402H22"
			(at 1.1811 -4.2291 0)
			(unlocked yes)
			(layer "F.Fab")
			(hide yes)
			(effects
				(font
					(size 1.016 1.016)
					(thickness 0.1524)
				)
			)
		)
		(duplicate_pad_numbers_are_jumpers no)
		(fp_rect
			(start -0.4318 0.9525)
			(end 0.4318 -0.9525)
			(stroke
				(width 0)
				(type default)
			)
			(fill no)
			(layer "F.CrtYd")
		)
		(fp_rect
			(start -0.4318 0.9525)
			(end 0.4318 -0.9525)
			(stroke
				(width 0)
				(type default)
			)
			(fill no)
			(layer "F.Fab")
		)
		(pad "1" smd custom
			(at 0 -0.4445)
			(size 0.1524 0.1524)
			(layers "F.Cu" "F.Mask" "F.Paste")
			(net "P3V3_STBY_B")
			(options
				(clearance outline)
				(anchor circle)
			)
			(primitives
				(gr_poly
					(pts
						(arc
							(start 0.3048 -0.2032)
							(mid 0.275042 -0.275042)
							(end 0.2032 -0.3048)
						)
						(arc
							(start -0.2032 -0.3048)
							(mid -0.275042 -0.275042)
							(end -0.3048 -0.2032)
						)
						(arc
							(start -0.3048 0.2032)
							(mid -0.275042 0.275042)
							(end -0.2032 0.3048)
						)
						(arc
							(start 0.2032 0.3048)
							(mid 0.275042 0.275042)
							(end 0.3048 0.2032)
						)
					)
					(width 0)
					(fill yes)
				)
			)
		)
		(pad "2" smd custom
			(at 0 0.4445)
			(size 0.1524 0.1524)
			(layers "F.Cu" "F.Mask" "F.Paste")
			(net "GND")
			(options
				(clearance outline)
				(anchor circle)
			)
			(primitives
				(gr_poly
					(pts
						(arc
							(start 0.3048 -0.2032)
							(mid 0.275042 -0.275042)
							(end 0.2032 -0.3048)
						)
						(arc
							(start -0.2032 -0.3048)
							(mid -0.275042 -0.275042)
							(end -0.3048 -0.2032)
						)
						(arc
							(start -0.3048 0.2032)
							(mid -0.275042 0.275042)
							(end -0.2032 0.3048)
						)
						(arc
							(start 0.2032 0.3048)
							(mid 0.275042 0.275042)
							(end 0.3048 0.2032)
						)
					)
					(width 0)
					(fill yes)
				)
			)
		)
	)
	(footprint ""
		(layer "F.Cu")
		(at 349.812102 -177.169318 90)
		(property "Reference" "R567"
			(at 0 0 90)
			(layer "F.SilkS")
			(hide yes)
			(effects
				(font
					(size 1.27 1.27)
				)
			)
		)
		(property "Value" "10KR2F-2-GP"
			(at 0.064008 -3.993896 90)
			(unlocked yes)
			(layer "F.Fab")
			(hide yes)
			(effects
				(font
					(size 1.016 1.016)
					(thickness 0.1524)
				)
			)
		)
		(property "Device Type" "R402H16"
			(at 0.064008 -5.517896 90)
			(unlocked yes)
			(layer "F.Fab")
			(hide yes)
			(effects
				(font
					(size 1.016 1.016)
					(thickness 0.1524)
				)
			)
		)
		(duplicate_pad_numbers_are_jumpers no)
		(fp_line
			(start 0.508 -0.9398)
			(end -0.508 -0.9398)
			(stroke
				(width 0.1524)
				(type default)
			)
			(layer "F.SilkS")
		)
		(fp_line
			(start -0.508 -0.9398)
			(end -0.508 0.9398)
			(stroke
				(width 0.1524)
				(type default)
			)
			(layer "F.SilkS")
		)
		(fp_rect
			(start -0.508 0.9398)
			(end 0.508 -0.9398)
			(stroke
				(width 0)
				(type default)
			)
			(fill no)
			(layer "F.CrtYd")
		)
		(fp_rect
			(start -0.508 0.9398)
			(end 0.508 -0.9398)
			(stroke
				(width 0)
				(type default)
			)
			(fill no)
			(layer "F.Fab")
		)
		(pad "1" smd custom
			(at 0 -0.4445 90)
			(size 0.1397 0.1397)
			(layers "F.Cu" "F.Mask" "F.Paste")
			(net "P3V3_STBY_A")
			(options
				(clearance outline)
				(anchor circle)
			)
			(primitives
				(gr_poly
					(pts
						(arc
							(start -0.1778 -0.2794)
							(mid -0.249642 -0.249642)
							(end -0.2794 -0.1778)
						)
						(arc
							(start -0.2794 0.1778)
							(mid -0.249642 0.249642)
							(end -0.1778 0.2794)
						)
						(arc
							(start 0.1778 0.2794)
							(mid 0.249642 0.249642)
							(end 0.2794 0.1778)
						)
						(arc
							(start 0.2794 -0.1778)
							(mid 0.249642 -0.249642)
							(end 0.1778 -0.2794)
						)
					)
					(width 0)
					(fill yes)
				)
			)
		)
		(pad "2" smd custom
			(at 0 0.4445 90)
			(size 0.1397 0.1397)
			(layers "F.Cu" "F.Mask" "F.Paste")
			(net "HDD_PRSNT_19")
			(options
				(clearance outline)
				(anchor circle)
			)
			(primitives
				(gr_poly
					(pts
						(arc
							(start -0.1778 -0.2794)
							(mid -0.249642 -0.249642)
							(end -0.2794 -0.1778)
						)
						(arc
							(start -0.2794 0.1778)
							(mid -0.249642 0.249642)
							(end -0.1778 0.2794)
						)
						(arc
							(start 0.1778 0.2794)
							(mid 0.249642 0.249642)
							(end 0.2794 0.1778)
						)
						(arc
							(start 0.2794 -0.1778)
							(mid 0.249642 -0.249642)
							(end 0.1778 -0.2794)
						)
					)
					(width 0)
					(fill yes)
				)
			)
		)
	)
	(footprint ""
		(layer "F.Cu")
		(at 255.498092 -18.418556 -90)
		(property "Reference" "TP245"
			(at 0 0 270)
			(layer "F.SilkS")
			(hide yes)
			(effects
				(font
					(size 1.27 1.27)
				)
			)
		)
		(property "Value" "TPAD32-GP"
			(at -0.0508 -1.6764 270)
			(unlocked yes)
			(layer "F.Fab")
			(hide yes)
			(effects
				(font
					(size 1.016 1.016)
					(thickness 0.1524)
				)
			)
		)
		(property "Device Type" "TPAD32"
			(at -0.0508 -3.2004 270)
			(unlocked yes)
			(layer "F.Fab")
			(hide yes)
			(effects
				(font
					(size 1.016 1.016)
					(thickness 0.1524)
				)
			)
		)
		(duplicate_pad_numbers_are_jumpers no)
		(fp_poly
			(pts
				(arc
					(start 0 -0.4064)
					(mid 0 0.4064)
					(end 0 -0.4064)
				)
			)
			(stroke
				(width 0)
				(type default)
			)
			(fill no)
			(layer "F.CrtYd")
		)
		(fp_poly
			(pts
				(arc
					(start 0 -0.7112)
					(mid 0 0.7112)
					(end 0 -0.7112)
				)
			)
			(stroke
				(width 0)
				(type default)
			)
			(fill no)
			(layer "F.Fab")
		)
		(pad "1" smd circle
			(at 0 0 270)
			(size 0.8128 0.8128)
			(layers "F.Cu" "F.Mask" "F.Paste")
			(net "TP_PCIE_COMP_A_CLK_P5")
		)
	)
	(footprint ""
		(layer "F.Cu")
		(at 406.711912 -242.831112 180)
		(property "Reference" "Q236"
			(at 0 0 180)
			(layer "F.SilkS")
			(hide yes)
			(effects
				(font
					(size 1.27 1.27)
				)
			)
		)
		(property "Value" "2N7002K-2-GP"
			(at 0.127 -8.9662 180)
			(unlocked yes)
			(layer "F.Fab")
			(hide yes)
			(effects
				(font
					(size 1.016 1.016)
					(thickness 0.1524)
				)
			)
		)
		(property "Device Type" "SOT23DGS2D4H44"
			(at 0.127 -10.4902 180)
			(unlocked yes)
			(layer "F.Fab")
			(hide yes)
			(effects
				(font
					(size 1.016 1.016)
					(thickness 0.1524)
				)
			)
		)
		(duplicate_pad_numbers_are_jumpers no)
		(fp_line
			(start 1.651 1.778)
			(end 1.651 -1.778)
			(stroke
				(width 0.1524)
				(type default)
			)
			(layer "F.SilkS")
		)
		(fp_line
			(start 1.651 -1.778)
			(end -1.651 -1.778)
			(stroke
				(width 0.1524)
				(type default)
			)
			(layer "F.SilkS")
		)
		(fp_line
			(start -1.651 1.778)
			(end 1.651 1.778)
			(stroke
				(width 0.1524)
				(type default)
			)
			(layer "F.SilkS")
		)
		(fp_line
			(start -1.651 -1.778)
			(end -1.651 1.778)
			(stroke
				(width 0.1524)
				(type default)
			)
			(layer "F.SilkS")
		)
		(fp_poly
			(pts
				(xy -1.778 1.8796) (xy -1.778 -1.8796) (xy 1.778 -1.8796) (xy 1.778 1.8796)
			)
			(stroke
				(width 0)
				(type default)
			)
			(fill no)
			(layer "F.CrtYd")
		)
		(fp_poly
			(pts
				(xy -1.778 1.8796) (xy -1.778 -1.8796) (xy 1.778 -1.8796) (xy 1.778 1.8796)
			)
			(stroke
				(width 0)
				(type default)
			)
			(fill no)
			(layer "F.Fab")
		)
		(pad "D" smd custom
			(at 0 -0.9525 180)
			(size 0.1905 0.1905)
			(layers "F.Cu" "F.Mask" "F.Paste")
			(net "FLT_HDD9_N")
			(options
				(clearance outline)
				(anchor circle)
			)
			(primitives
				(gr_poly
					(pts
						(arc
							(start -0.1778 0.5715)
							(mid -0.321484 0.511984)
							(end -0.381 0.3683)
						)
						(arc
							(start -0.381 -0.3683)
							(mid -0.321484 -0.511984)
							(end -0.1778 -0.5715)
						)
						(arc
							(start 0.1778 -0.5715)
							(mid 0.321484 -0.511984)
							(end 0.381 -0.3683)
						)
						(arc
							(start 0.381 0.3683)
							(mid 0.321484 0.511984)
							(end 0.1778 0.5715)
						)
					)
					(width 0)
					(fill yes)
				)
			)
		)
		(pad "G" smd custom
			(at -0.98425 0.9525 180)
			(size 0.1905 0.1905)
			(layers "F.Cu" "F.Mask" "F.Paste")
			(net "DRIVE_A_9_FLT_LED")
			(options
				(clearance outline)
				(anchor circle)
			)
			(primitives
				(gr_poly
					(pts
						(arc
							(start -0.1778 0.5715)
							(mid -0.321484 0.511984)
							(end -0.381 0.3683)
						)
						(arc
							(start -0.381 -0.3683)
							(mid -0.321484 -0.511984)
							(end -0.1778 -0.5715)
						)
						(arc
							(start 0.1778 -0.5715)
							(mid 0.321484 -0.511984)
							(end 0.381 -0.3683)
						)
						(arc
							(start 0.381 0.3683)
							(mid 0.321484 0.511984)
							(end 0.1778 0.5715)
						)
					)
					(width 0)
					(fill yes)
				)
			)
		)
		(pad "S" smd custom
			(at 0.98425 0.9525 180)
			(size 0.1905 0.1905)
			(layers "F.Cu" "F.Mask" "F.Paste")
			(net "GND")
			(options
				(clearance outline)
				(anchor circle)
			)
			(primitives
				(gr_poly
					(pts
						(arc
							(start -0.1778 0.5715)
							(mid -0.321484 0.511984)
							(end -0.381 0.3683)
						)
						(arc
							(start -0.381 -0.3683)
							(mid -0.321484 -0.511984)
							(end -0.1778 -0.5715)
						)
						(arc
							(start 0.1778 -0.5715)
							(mid 0.321484 -0.511984)
							(end 0.381 -0.3683)
						)
						(arc
							(start 0.381 0.3683)
							(mid 0.321484 0.511984)
							(end 0.1778 0.5715)
						)
					)
					(width 0)
					(fill yes)
				)
			)
		)
	)
	(footprint ""
		(layer "F.Cu")
		(at 56.314848 -242.20297)
		(property "Reference" "R199"
			(at 0 0 0)
			(layer "F.SilkS")
			(hide yes)
			(effects
				(font
					(size 1.27 1.27)
				)
			)
		)
		(property "Value" "91R3F-1-GP"
			(at -0.0254 -2.5146 0)
			(unlocked yes)
			(layer "F.Fab")
			(hide yes)
			(effects
				(font
					(size 1.016 1.016)
					(thickness 0.1524)
				)
			)
		)
		(property "Device Type" "R603H22"
			(at -0.0254 -4.0386 0)
			(unlocked yes)
			(layer "F.Fab")
			(hide yes)
			(effects
				(font
					(size 1.016 1.016)
					(thickness 0.1524)
				)
			)
		)
		(duplicate_pad_numbers_are_jumpers no)
		(fp_line
			(start -0.4826 0)
			(end -0.2032 0)
			(stroke
				(width 0.2032)
				(type default)
			)
			(layer "F.SilkS")
		)
		(fp_line
			(start 0.2032 0)
			(end 0.4826 0)
			(stroke
				(width 0.2032)
				(type default)
			)
			(layer "F.SilkS")
		)
		(fp_rect
			(start -0.5842 1.3335)
			(end 0.5842 -1.3335)
			(stroke
				(width 0)
				(type default)
			)
			(fill no)
			(layer "F.CrtYd")
		)
		(fp_rect
			(start -0.5842 1.3335)
			(end 0.5842 -1.3335)
			(stroke
				(width 0)
				(type default)
			)
			(fill no)
			(layer "F.Fab")
		)
		(pad "1" smd custom
			(at 0 -0.762)
			(size 0.2159 0.2159)
			(layers "F.Cu" "F.Mask" "F.Paste")
			(net "P5V_A_1")
			(options
				(clearance outline)
				(anchor circle)
			)
			(primitives
				(gr_poly
					(pts
						(arc
							(start -0.3302 -0.4318)
							(mid -0.402042 -0.402042)
							(end -0.4318 -0.3302)
						)
						(arc
							(start -0.4318 0.3302)
							(mid -0.402042 0.402042)
							(end -0.3302 0.4318)
						)
						(arc
							(start 0.3302 0.4318)
							(mid 0.402042 0.402042)
							(end 0.4318 0.3302)
						)
						(arc
							(start 0.4318 -0.3302)
							(mid 0.402042 -0.402042)
							(end 0.3302 -0.4318)
						)
					)
					(width 0)
					(fill yes)
				)
			)
		)
		(pad "2" smd custom
			(at 0 0.762)
			(size 0.2159 0.2159)
			(layers "F.Cu" "F.Mask" "F.Paste")
			(net "DRV_ACT_1")
			(options
				(clearance outline)
				(anchor circle)
			)
			(primitives
				(gr_poly
					(pts
						(arc
							(start -0.3302 -0.4318)
							(mid -0.402042 -0.402042)
							(end -0.4318 -0.3302)
						)
						(arc
							(start -0.4318 0.3302)
							(mid -0.402042 0.402042)
							(end -0.3302 0.4318)
						)
						(arc
							(start 0.3302 0.4318)
							(mid 0.402042 0.402042)
							(end 0.4318 0.3302)
						)
						(arc
							(start 0.4318 -0.3302)
							(mid 0.402042 -0.402042)
							(end 0.3302 -0.4318)
						)
					)
					(width 0)
					(fill yes)
				)
			)
		)
	)
	(footprint ""
		(layer "F.Cu")
		(at 357.100124 -287.910016 -90)
		(property "Reference" "HDDSAS7"
			(at 0 0 270)
			(layer "F.SilkS")
			(hide yes)
			(effects
				(font
					(size 1.27 1.27)
				)
			)
		)
		(property "Value" "SKT-SAS15P-14P-45-GP"
			(at -20.7645 -8.9789 270)
			(unlocked yes)
			(layer "F.Fab")
			(hide yes)
			(effects
				(font
					(size 1.016 1.016)
					(thickness 0.1524)
				)
			)
		)
		(property "Device Type" "10120818-001C-TRLF"
			(at -20.7645 -10.5029 270)
			(unlocked yes)
			(layer "F.Fab")
			(hide yes)
			(effects
				(font
					(size 1.016 1.016)
					(thickness 0.1524)
				)
			)
		)
		(duplicate_pad_numbers_are_jumpers no)
		(fp_line
			(start 1.651 4.2926)
			(end 1.651 3.0099)
			(stroke
				(width 0.1524)
				(type default)
			)
			(layer "F.SilkS")
		)
		(fp_line
			(start 8.509 4.2926)
			(end 1.651 4.2926)
			(stroke
				(width 0.1524)
				(type default)
			)
			(layer "F.SilkS")
		)
		(fp_line
			(start -23.4188 3.0099)
			(end -23.4188 -3.2512)
			(stroke
				(width 0.1524)
				(type default)
			)
			(layer "F.SilkS")
		)
		(fp_line
			(start 1.651 3.0099)
			(end -23.4188 3.0099)
			(stroke
				(width 0.1524)
				(type default)
			)
			(layer "F.SilkS")
		)
		(fp_line
			(start 8.509 3.0099)
			(end 8.509 4.2926)
			(stroke
				(width 0.1524)
				(type default)
			)
			(layer "F.SilkS")
		)
		(fp_line
			(start 23.4188 3.0099)
			(end 8.509 3.0099)
			(stroke
				(width 0.1524)
				(type default)
			)
			(layer "F.SilkS")
		)
		(fp_line
			(start -23.4188 -3.2512)
			(end 23.4188 -3.2512)
			(stroke
				(width 0.1524)
				(type default)
			)
			(layer "F.SilkS")
		)
		(fp_line
			(start 23.4188 -3.2512)
			(end 23.4188 3.0099)
			(stroke
				(width 0.1524)
				(type default)
			)
			(layer "F.SilkS")
		)
		(fp_line
			(start 15.5067 -3.3401)
			(end 16.2687 -3.3401)
			(stroke
				(width 0.3302)
				(type default)
			)
			(layer "F.SilkS")
		)
		(fp_poly
			(pts
				(xy 15.868904 -3.230372) (xy 16.503904 -3.865372) (xy 15.233904 -3.865372)
			)
			(stroke
				(width 0)
				(type default)
			)
			(fill yes)
			(layer "F.SilkS")
		)
		(fp_poly
			(pts
				(xy -22.8727 -2.7559) (xy 22.8727 -2.7559) (xy 22.8727 2.7559) (xy 8.255 2.7559) (xy 8.255 3.5179)
				(xy 1.905 3.5179) (xy 1.905 2.7559) (xy -22.8727 2.7559)
			)
			(stroke
				(width 0)
				(type default)
			)
			(fill no)
			(layer "F.CrtYd")
		)
		(fp_poly
			(pts
				(xy 1.397 4.5466) (xy 1.397 3.2639) (xy -23.6728 3.2639) (xy -23.6728 -3.5052) (xy 23.6728 -3.5052)
				(xy 23.6728 -0.00635) (xy 22.8727 -0.00635) (xy 22.8727 -2.7559) (xy -22.8727 -2.7559) (xy -22.8727 2.7559)
				(xy 1.905 2.7559) (xy 1.905 3.5179) (xy 8.255 3.5179) (xy 8.255 2.7559) (xy 22.8727 2.7559) (xy 22.8727 0.00635)
				(xy 23.6728 0.00635) (xy 23.6728 3.2639) (xy 8.763 3.2639) (xy 8.763 4.5466)
			)
			(stroke
				(width 0)
				(type default)
			)
			(fill no)
			(layer "F.CrtYd")
		)
		(fp_poly
			(pts
				(xy 1.397 4.5466) (xy 1.397 3.2639) (xy -23.6728 3.2639) (xy -23.6728 -3.5052) (xy 23.6728 -3.5052)
				(xy 23.6728 3.2639) (xy 8.763 3.2639) (xy 8.763 4.5466)
			)
			(stroke
				(width 0)
				(type default)
			)
			(fill no)
			(layer "F.Fab")
		)
		(pad "" np_thru_hole circle
			(at -18.874994 0 270)
			(size 0.254 0.254)
			(drill 1.3462)
			(layers "*.Cu" "*.Mask")
			(clearance 0.9017)
			(thermal_gap 0.9017)
		)
		(pad "" np_thru_hole circle
			(at 18.874994 0 270)
			(size 0.254 0.254)
			(drill 0.9398)
			(layers "*.Cu" "*.Mask")
			(clearance 0.6985)
			(thermal_gap 0.6985)
		)
		(pad "G1" smd rect
			(at 21.874988 0 270)
			(size 2.5908 2.5908)
			(layers "F.Cu" "F.Mask" "F.Paste")
			(net "GND")
		)
		(pad "G2" smd rect
			(at -21.874988 0 270)
			(size 2.5908 2.5908)
			(layers "F.Cu" "F.Mask" "F.Paste")
			(net "GND")
		)
		(pad "P1" smd rect
			(at 1.905 -1.82499 270)
			(size 0.6096 2.3622)
			(layers "F.Cu" "F.Mask" "F.Paste")
			(net "Net_2006")
		)
		(pad "P2" smd rect
			(at 0.635 -1.82499 270)
			(size 0.6096 2.3622)
			(layers "F.Cu" "F.Mask" "F.Paste")
			(net "Net_2007")
		)
		(pad "P3" smd rect
			(at -0.635 -1.82499 270)
			(size 0.6096 2.3622)
			(layers "F.Cu" "F.Mask" "F.Paste")
			(net "Net_2008")
		)
		(pad "P4" smd rect
			(at -1.905 -1.82499 270)
			(size 0.6096 2.3622)
			(layers "F.Cu" "F.Mask" "F.Paste")
			(net "GND")
		)
		(pad "P5" smd rect
			(at -3.175 -1.82499 270)
			(size 0.6096 2.3622)
			(layers "F.Cu" "F.Mask" "F.Paste")
			(net "HDD_PRSNT_7")
		)
		(pad "P6" smd rect
			(at -4.445 -1.82499 270)
			(size 0.6096 2.3622)
			(layers "F.Cu" "F.Mask" "F.Paste")
			(net "GND")
		)
		(pad "P7" smd rect
			(at -5.715 -1.82499 270)
			(size 0.6096 2.3622)
			(layers "F.Cu" "F.Mask" "F.Paste")
			(net "5V_PRE_7")
		)
		(pad "P8" smd rect
			(at -6.985 -1.82499 270)
			(size 0.6096 2.3622)
			(layers "F.Cu" "F.Mask" "F.Paste")
			(net "P5V_HDD7")
		)
		(pad "P9" smd rect
			(at -8.255 -1.82499 270)
			(size 0.6096 2.3622)
			(layers "F.Cu" "F.Mask" "F.Paste")
			(net "P5V_HDD7")
		)
		(pad "P10" smd rect
			(at -9.525 -1.82499 270)
			(size 0.6096 2.3622)
			(layers "F.Cu" "F.Mask" "F.Paste")
			(net "GND")
		)
		(pad "P11" smd rect
			(at -10.795 -1.82499 270)
			(size 0.6096 2.3622)
			(layers "F.Cu" "F.Mask" "F.Paste")
			(net "ACT_HDD_7")
		)
		(pad "P12" smd rect
			(at -12.065 -1.82499 270)
			(size 0.6096 2.3622)
			(layers "F.Cu" "F.Mask" "F.Paste")
			(net "GND")
		)
		(pad "P13" smd rect
			(at -13.335 -1.82499 270)
			(size 0.6096 2.3622)
			(layers "F.Cu" "F.Mask" "F.Paste")
			(net "12V_PRE_7")
		)
		(pad "P14" smd rect
			(at -14.605 -1.82499 270)
			(size 0.6096 2.3622)
			(layers "F.Cu" "F.Mask" "F.Paste")
			(net "P12V_HDD7")
		)
		(pad "P15" smd rect
			(at -15.875 -1.82499 270)
			(size 0.6096 2.3622)
			(layers "F.Cu" "F.Mask" "F.Paste")
			(net "P12V_HDD7")
		)
		(pad "S1" smd rect
			(at 15.875 -1.82499 270)
			(size 0.6096 2.3622)
			(layers "F.Cu" "F.Mask" "F.Paste")
			(net "GND")
		)
		(pad "S2" smd rect
			(at 14.605 -1.82499 270)
			(size 0.6096 2.3622)
			(layers "F.Cu" "F.Mask" "F.Paste")
			(net "SAS_HDD_RX_P7")
		)
		(pad "S3" smd rect
			(at 13.335 -1.82499 270)
			(size 0.6096 2.3622)
			(layers "F.Cu" "F.Mask" "F.Paste")
			(net "SAS_HDD_RX_N7")
		)
		(pad "S4" smd rect
			(at 12.065 -1.82499 270)
			(size 0.6096 2.3622)
			(layers "F.Cu" "F.Mask" "F.Paste")
			(net "GND")
		)
		(pad "S5" smd rect
			(at 10.795 -1.82499 270)
			(size 0.6096 2.3622)
			(layers "F.Cu" "F.Mask" "F.Paste")
			(net "PHY_DRV_A_TO_SCC_A_7_DN")
		)
		(pad "S6" smd rect
			(at 9.525 -1.82499 270)
			(size 0.6096 2.3622)
			(layers "F.Cu" "F.Mask" "F.Paste")
			(net "PHY_DRV_A_TO_SCC_A_7_DP")
		)
		(pad "S7" smd rect
			(at 8.255 -1.82499 270)
			(size 0.6096 2.3622)
			(layers "F.Cu" "F.Mask" "F.Paste")
			(net "GND")
		)
		(pad "S8" smd rect
			(at 7.480046 2.845054 270)
			(size 0.508 2.3622)
			(layers "F.Cu" "F.Mask" "F.Paste")
			(net "GND")
		)
		(pad "S9" smd rect
			(at 6.679946 2.845054 270)
			(size 0.508 2.3622)
			(layers "F.Cu" "F.Mask" "F.Paste")
			(net "Net_479")
		)
		(pad "S10" smd rect
			(at 5.8801 2.845054 270)
			(size 0.508 2.3622)
			(layers "F.Cu" "F.Mask" "F.Paste")
			(net "Net_371")
		)
		(pad "S11" smd rect
			(at 5.08 2.845054 270)
			(size 0.508 2.3622)
			(layers "F.Cu" "F.Mask" "F.Paste")
			(net "GND")
		)
		(pad "S12" smd rect
			(at 4.2799 2.845054 270)
			(size 0.508 2.3622)
			(layers "F.Cu" "F.Mask" "F.Paste")
			(net "Net_407")
		)
		(pad "S13" smd rect
			(at 3.480054 2.845054 270)
			(size 0.508 2.3622)
			(layers "F.Cu" "F.Mask" "F.Paste")
			(net "Net_443")
		)
		(pad "S14" smd rect
			(at 2.679954 2.845054 270)
			(size 0.508 2.3622)
			(layers "F.Cu" "F.Mask" "F.Paste")
			(net "GND")
		)
		(zone
			(layer "F.Cu")
			(hatch none 0.5)
			(connect_pads
				(clearance 0)
			)
			(min_thickness 0.25)
			(keepout
				(tracks allowed)
				(vias not_allowed)
				(pads allowed)
				(copperpour not_allowed)
				(footprints allowed)
			)
			(placement
				(enabled no)
				(sheetname "")
			)
			(fill
				(thermal_gap 0.5)
				(thermal_bridge_width 0.5)
				(island_removal_mode 0)
			)
			(polygon
				(pts
					(xy 360.757724 -304.648616) (xy 353.683824 -304.648616) (xy 353.683824 -311.582816) (xy 354.788724 -311.582816)
					(xy 354.788724 -307.468016) (xy 359.411524 -307.468016) (xy 359.411524 -311.582816) (xy 360.757724 -311.582816)
				)
			)
		)
		(zone
			(layer "F.Cu")
			(hatch none 0.5)
			(connect_pads
				(clearance 0)
			)
			(min_thickness 0.25)
			(keepout
				(tracks not_allowed)
				(vias allowed)
				(pads allowed)
				(copperpour not_allowed)
				(footprints allowed)
			)
			(placement
				(enabled no)
				(sheetname "")
			)
			(fill
				(thermal_gap 0.5)
				(thermal_bridge_width 0.5)
				(island_removal_mode 0)
			)
			(polygon
				(pts
					(xy 360.757724 -304.648616) (xy 353.683824 -304.648616) (xy 353.683824 -311.582816) (xy 354.788724 -311.582816)
					(xy 354.788724 -307.468016) (xy 359.411524 -307.468016) (xy 359.411524 -311.582816) (xy 360.757724 -311.582816)
				)
			)
		)
		(zone
			(layer "F.Cu")
			(hatch none 0.5)
			(connect_pads
				(clearance 0)
			)
			(min_thickness 0.25)
			(keepout
				(tracks not_allowed)
				(vias allowed)
				(pads allowed)
				(copperpour not_allowed)
				(footprints allowed)
			)
			(placement
				(enabled no)
				(sheetname "")
			)
			(fill
				(thermal_gap 0.5)
				(thermal_bridge_width 0.5)
				(island_removal_mode 0)
			)
			(polygon
				(pts
					(xy 360.757724 -271.171416) (xy 353.683824 -271.171416) (xy 353.683824 -264.237216) (xy 354.788724 -264.237216)
					(xy 354.788724 -268.352016) (xy 359.411524 -268.352016) (xy 359.411524 -264.237216) (xy 360.757724 -264.237216)
				)
			)
		)
		(zone
			(layer "F.Cu")
			(hatch none 0.5)
			(connect_pads
				(clearance 0)
			)
			(min_thickness 0.25)
			(keepout
				(tracks allowed)
				(vias not_allowed)
				(pads allowed)
				(copperpour not_allowed)
				(footprints allowed)
			)
			(placement
				(enabled no)
				(sheetname "")
			)
			(fill
				(thermal_gap 0.5)
				(thermal_bridge_width 0.5)
				(island_removal_mode 0)
			)
			(polygon
				(pts
					(xy 360.757724 -271.171416) (xy 353.683824 -271.171416) (xy 353.683824 -264.237216) (xy 354.788724 -264.237216)
					(xy 354.788724 -268.352016) (xy 359.411524 -268.352016) (xy 359.411524 -264.237216) (xy 360.757724 -264.237216)
				)
			)
		)
		(zone
			(layers "F.Cu" "B.Cu" "In1.Cu" "In2.Cu" "In3.Cu" "In4.Cu" "In5.Cu" "In6.Cu"
				"In7.Cu" "In8.Cu" "In9.Cu" "In10.Cu"
			)
			(hatch none 0.5)
			(connect_pads
				(clearance 0)
			)
			(min_thickness 0.25)
			(keepout
				(tracks not_allowed)
				(vias allowed)
				(pads allowed)
				(copperpour not_allowed)
				(footprints allowed)
			)
			(placement
				(enabled no)
				(sheetname "")
			)
			(fill
				(thermal_gap 0.5)
				(thermal_bridge_width 0.5)
				(island_removal_mode 0)
			)
			(polygon
				(pts
					(arc
						(start 357.874824 -269.035022)
						(mid 356.325424 -269.035022)
						(end 357.874824 -269.035022)
					)
				)
			)
		)
		(zone
			(layers "F.Cu" "B.Cu" "In1.Cu" "In2.Cu" "In3.Cu" "In4.Cu" "In5.Cu" "In6.Cu"
				"In7.Cu" "In8.Cu" "In9.Cu" "In10.Cu"
			)
			(hatch none 0.5)
			(connect_pads
				(clearance 0)
			)
			(min_thickness 0.25)
			(keepout
				(tracks not_allowed)
				(vias allowed)
				(pads allowed)
				(copperpour not_allowed)
				(footprints allowed)
			)
			(placement
				(enabled no)
				(sheetname "")
			)
			(fill
				(thermal_gap 0.5)
				(thermal_bridge_width 0.5)
				(island_removal_mode 0)
			)
			(polygon
				(pts
					(arc
						(start 358.078024 -306.78501)
						(mid 356.122224 -306.78501)
						(end 358.078024 -306.78501)
					)
				)
			)
		)
	)
	(footprint ""
		(layer "F.Cu")
		(at 141.017498 -160.608518 90)
		(property "Reference" "R512"
			(at 0 0 90)
			(layer "F.SilkS")
			(hide yes)
			(effects
				(font
					(size 1.27 1.27)
				)
			)
		)
		(property "Value" "4K7R2J-2-GP"
			(at 0.064008 -3.993896 90)
			(unlocked yes)
			(layer "F.Fab")
			(hide yes)
			(effects
				(font
					(size 1.016 1.016)
					(thickness 0.1524)
				)
			)
		)
		(property "Device Type" "R402H16"
			(at 0.064008 -5.517896 90)
			(unlocked yes)
			(layer "F.Fab")
			(hide yes)
			(effects
				(font
					(size 1.016 1.016)
					(thickness 0.1524)
				)
			)
		)
		(duplicate_pad_numbers_are_jumpers no)
		(fp_line
			(start 0.508 -0.9398)
			(end -0.508 -0.9398)
			(stroke
				(width 0.1524)
				(type default)
			)
			(layer "F.SilkS")
		)
		(fp_line
			(start -0.508 -0.9398)
			(end -0.508 0.9398)
			(stroke
				(width 0.1524)
				(type default)
			)
			(layer "F.SilkS")
		)
		(fp_rect
			(start -0.508 0.9398)
			(end 0.508 -0.9398)
			(stroke
				(width 0)
				(type default)
			)
			(fill no)
			(layer "F.CrtYd")
		)
		(fp_rect
			(start -0.508 0.9398)
			(end 0.508 -0.9398)
			(stroke
				(width 0)
				(type default)
			)
			(fill no)
			(layer "F.Fab")
		)
		(pad "1" smd custom
			(at 0 -0.4445 90)
			(size 0.1397 0.1397)
			(layers "F.Cu" "F.Mask" "F.Paste")
			(net "P12V_A")
			(options
				(clearance outline)
				(anchor circle)
			)
			(primitives
				(gr_poly
					(pts
						(arc
							(start -0.1778 -0.2794)
							(mid -0.249642 -0.249642)
							(end -0.2794 -0.1778)
						)
						(arc
							(start -0.2794 0.1778)
							(mid -0.249642 0.249642)
							(end -0.1778 0.2794)
						)
						(arc
							(start 0.1778 0.2794)
							(mid 0.249642 0.249642)
							(end 0.2794 0.1778)
						)
						(arc
							(start 0.2794 -0.1778)
							(mid 0.249642 -0.249642)
							(end 0.1778 -0.2794)
						)
					)
					(width 0)
					(fill yes)
				)
			)
		)
		(pad "2" smd custom
			(at 0 0.4445 90)
			(size 0.1397 0.1397)
			(layers "F.Cu" "F.Mask" "F.Paste")
			(net "SW_HDD_R16")
			(options
				(clearance outline)
				(anchor circle)
			)
			(primitives
				(gr_poly
					(pts
						(arc
							(start -0.1778 -0.2794)
							(mid -0.249642 -0.249642)
							(end -0.2794 -0.1778)
						)
						(arc
							(start -0.2794 0.1778)
							(mid -0.249642 0.249642)
							(end -0.1778 0.2794)
						)
						(arc
							(start 0.1778 0.2794)
							(mid 0.249642 0.249642)
							(end 0.2794 0.1778)
						)
						(arc
							(start 0.2794 -0.1778)
							(mid 0.249642 -0.249642)
							(end 0.1778 -0.2794)
						)
					)
					(width 0)
					(fill yes)
				)
			)
		)
	)
	(footprint ""
		(layer "F.Cu")
		(at 181.991 -74.462894 180)
		(property "Reference" "C424"
			(at 0 0 180)
			(layer "F.SilkS")
			(hide yes)
			(effects
				(font
					(size 1.27 1.27)
				)
			)
		)
		(property "Value" "SC1U25V3KX-GP"
			(at 0 -2.8194 180)
			(unlocked yes)
			(layer "F.Fab")
			(hide yes)
			(effects
				(font
					(size 1.016 1.016)
					(thickness 0.1524)
				)
			)
		)
		(property "Device Type" "C603H36"
			(at 0 -4.3434 180)
			(unlocked yes)
			(layer "F.Fab")
			(hide yes)
			(effects
				(font
					(size 1.016 1.016)
					(thickness 0.1524)
				)
			)
		)
		(duplicate_pad_numbers_are_jumpers no)
		(fp_line
			(start 0.508 0)
			(end -0.508 0)
			(stroke
				(width 0.2032)
				(type default)
			)
			(layer "F.SilkS")
		)
		(fp_rect
			(start -0.5842 1.3335)
			(end 0.5842 -1.3335)
			(stroke
				(width 0)
				(type default)
			)
			(fill no)
			(layer "F.CrtYd")
		)
		(fp_rect
			(start -0.5842 1.3335)
			(end 0.5842 -1.3335)
			(stroke
				(width 0)
				(type default)
			)
			(fill no)
			(layer "F.Fab")
		)
		(pad "1" smd custom
			(at 0 -0.762 180)
			(size 0.2159 0.2159)
			(layers "F.Cu" "F.Mask" "F.Paste")
			(net "P12V_HDD29")
			(options
				(clearance outline)
				(anchor circle)
			)
			(primitives
				(gr_poly
					(pts
						(arc
							(start -0.3302 -0.4318)
							(mid -0.402042 -0.402042)
							(end -0.4318 -0.3302)
						)
						(arc
							(start -0.4318 0.3302)
							(mid -0.402042 0.402042)
							(end -0.3302 0.4318)
						)
						(arc
							(start 0.3302 0.4318)
							(mid 0.402042 0.402042)
							(end 0.4318 0.3302)
						)
						(arc
							(start 0.4318 -0.3302)
							(mid 0.402042 -0.402042)
							(end 0.3302 -0.4318)
						)
					)
					(width 0)
					(fill yes)
				)
			)
		)
		(pad "2" smd custom
			(at 0 0.762 180)
			(size 0.2159 0.2159)
			(layers "F.Cu" "F.Mask" "F.Paste")
			(net "GND")
			(options
				(clearance outline)
				(anchor circle)
			)
			(primitives
				(gr_poly
					(pts
						(arc
							(start -0.3302 -0.4318)
							(mid -0.402042 -0.402042)
							(end -0.4318 -0.3302)
						)
						(arc
							(start -0.4318 0.3302)
							(mid -0.402042 0.402042)
							(end -0.3302 0.4318)
						)
						(arc
							(start 0.3302 0.4318)
							(mid 0.402042 0.402042)
							(end 0.4318 0.3302)
						)
						(arc
							(start 0.4318 -0.3302)
							(mid 0.402042 -0.402042)
							(end 0.3302 -0.4318)
						)
					)
					(width 0)
					(fill yes)
				)
			)
		)
	)
	(footprint ""
		(layer "F.Cu")
		(at 161.7472 -298.704)
		(property "Reference" "TP22"
			(at 0 0 0)
			(layer "F.SilkS")
			(hide yes)
			(effects
				(font
					(size 1.27 1.27)
				)
			)
		)
		(property "Value" "TPAD32-GP"
			(at -0.0508 -1.6764 0)
			(unlocked yes)
			(layer "F.Fab")
			(hide yes)
			(effects
				(font
					(size 1.016 1.016)
					(thickness 0.1524)
				)
			)
		)
		(property "Device Type" "TPAD32"
			(at -0.0508 -3.2004 0)
			(unlocked yes)
			(layer "F.Fab")
			(hide yes)
			(effects
				(font
					(size 1.016 1.016)
					(thickness 0.1524)
				)
			)
		)
		(duplicate_pad_numbers_are_jumpers no)
		(fp_poly
			(pts
				(arc
					(start 0.4064 0)
					(mid -0.4064 0)
					(end 0.4064 0)
				)
			)
			(stroke
				(width 0)
				(type default)
			)
			(fill no)
			(layer "F.CrtYd")
		)
		(fp_poly
			(pts
				(arc
					(start 0.7112 0)
					(mid -0.7112 0)
					(end 0.7112 0)
				)
			)
			(stroke
				(width 0)
				(type default)
			)
			(fill no)
			(layer "F.Fab")
		)
		(pad "1" smd circle
			(at 0 0)
			(size 0.8128 0.8128)
			(layers "F.Cu" "F.Mask" "F.Paste")
			(net "ACT_HDD_4")
		)
	)
	(footprint ""
		(layer "F.Cu")
		(at 225.451162 -217.608658 -90)
		(property "Reference" "R411"
			(at 0 0 270)
			(layer "F.SilkS")
			(hide yes)
			(effects
				(font
					(size 1.27 1.27)
				)
			)
		)
		(property "Value" "10KR2F-2-GP"
			(at 0.064008 -3.993896 270)
			(unlocked yes)
			(layer "F.Fab")
			(hide yes)
			(effects
				(font
					(size 1.016 1.016)
					(thickness 0.1524)
				)
			)
		)
		(property "Device Type" "R402H16"
			(at 0.064008 -5.517896 270)
			(unlocked yes)
			(layer "F.Fab")
			(hide yes)
			(effects
				(font
					(size 1.016 1.016)
					(thickness 0.1524)
				)
			)
		)
		(duplicate_pad_numbers_are_jumpers no)
		(fp_line
			(start -0.508 -0.9398)
			(end -0.508 0.9398)
			(stroke
				(width 0.1524)
				(type default)
			)
			(layer "F.SilkS")
		)
		(fp_line
			(start 0.508 -0.9398)
			(end -0.508 -0.9398)
			(stroke
				(width 0.1524)
				(type default)
			)
			(layer "F.SilkS")
		)
		(fp_rect
			(start -0.508 0.9398)
			(end 0.508 -0.9398)
			(stroke
				(width 0)
				(type default)
			)
			(fill no)
			(layer "F.CrtYd")
		)
		(fp_rect
			(start -0.508 0.9398)
			(end 0.508 -0.9398)
			(stroke
				(width 0)
				(type default)
			)
			(fill no)
			(layer "F.Fab")
		)
		(pad "1" smd custom
			(at 0 -0.4445 270)
			(size 0.1397 0.1397)
			(layers "F.Cu" "F.Mask" "F.Paste")
			(net "P3V3_STBY_A")
			(options
				(clearance outline)
				(anchor circle)
			)
			(primitives
				(gr_poly
					(pts
						(arc
							(start -0.1778 -0.2794)
							(mid -0.249642 -0.249642)
							(end -0.2794 -0.1778)
						)
						(arc
							(start -0.2794 0.1778)
							(mid -0.249642 0.249642)
							(end -0.1778 0.2794)
						)
						(arc
							(start 0.1778 0.2794)
							(mid 0.249642 0.249642)
							(end 0.2794 0.1778)
						)
						(arc
							(start 0.2794 -0.1778)
							(mid 0.249642 -0.249642)
							(end 0.1778 -0.2794)
						)
					)
					(width 0)
					(fill yes)
				)
			)
		)
		(pad "2" smd custom
			(at 0 0.4445 270)
			(size 0.1397 0.1397)
			(layers "F.Cu" "F.Mask" "F.Paste")
			(net "I2C_SCC_BUFF_READY")
			(options
				(clearance outline)
				(anchor circle)
			)
			(primitives
				(gr_poly
					(pts
						(arc
							(start -0.1778 -0.2794)
							(mid -0.249642 -0.249642)
							(end -0.2794 -0.1778)
						)
						(arc
							(start -0.2794 0.1778)
							(mid -0.249642 0.249642)
							(end -0.1778 0.2794)
						)
						(arc
							(start 0.1778 0.2794)
							(mid 0.249642 0.249642)
							(end 0.2794 0.1778)
						)
						(arc
							(start 0.2794 -0.1778)
							(mid 0.249642 -0.249642)
							(end 0.1778 -0.2794)
						)
					)
					(width 0)
					(fill yes)
				)
			)
		)
	)
	(footprint ""
		(layer "F.Cu")
		(at 83.255866 -17.35963 90)
		(property "Reference" "R51"
			(at 0 0 90)
			(layer "F.SilkS")
			(hide yes)
			(effects
				(font
					(size 1.27 1.27)
				)
			)
		)
		(property "Value" "4K7R2F-GP"
			(at 0.064008 -3.993896 90)
			(unlocked yes)
			(layer "F.Fab")
			(hide yes)
			(effects
				(font
					(size 1.016 1.016)
					(thickness 0.1524)
				)
			)
		)
		(property "Device Type" "R402H16"
			(at 0.064008 -5.517896 90)
			(unlocked yes)
			(layer "F.Fab")
			(hide yes)
			(effects
				(font
					(size 1.016 1.016)
					(thickness 0.1524)
				)
			)
		)
		(duplicate_pad_numbers_are_jumpers no)
		(fp_line
			(start 0.508 -0.9398)
			(end -0.508 -0.9398)
			(stroke
				(width 0.1524)
				(type default)
			)
			(layer "F.SilkS")
		)
		(fp_line
			(start -0.508 -0.9398)
			(end -0.508 0.9398)
			(stroke
				(width 0.1524)
				(type default)
			)
			(layer "F.SilkS")
		)
		(fp_rect
			(start -0.508 0.9398)
			(end 0.508 -0.9398)
			(stroke
				(width 0)
				(type default)
			)
			(fill no)
			(layer "F.CrtYd")
		)
		(fp_rect
			(start -0.508 0.9398)
			(end 0.508 -0.9398)
			(stroke
				(width 0)
				(type default)
			)
			(fill no)
			(layer "F.Fab")
		)
		(pad "1" smd custom
			(at 0 -0.4445 90)
			(size 0.1397 0.1397)
			(layers "F.Cu" "F.Mask" "F.Paste")
			(net "P3V3_STBY_A")
			(options
				(clearance outline)
				(anchor circle)
			)
			(primitives
				(gr_poly
					(pts
						(arc
							(start -0.1778 -0.2794)
							(mid -0.249642 -0.249642)
							(end -0.2794 -0.1778)
						)
						(arc
							(start -0.2794 0.1778)
							(mid -0.249642 0.249642)
							(end -0.1778 0.2794)
						)
						(arc
							(start 0.1778 0.2794)
							(mid 0.249642 0.249642)
							(end 0.2794 0.1778)
						)
						(arc
							(start 0.2794 -0.1778)
							(mid 0.249642 -0.249642)
							(end 0.1778 -0.2794)
						)
					)
					(width 0)
					(fill yes)
				)
			)
		)
		(pad "2" smd custom
			(at 0 0.4445 90)
			(size 0.1397 0.1397)
			(layers "F.Cu" "F.Mask" "F.Paste")
			(net "IO_EXP10_A2")
			(options
				(clearance outline)
				(anchor circle)
			)
			(primitives
				(gr_poly
					(pts
						(arc
							(start -0.1778 -0.2794)
							(mid -0.249642 -0.249642)
							(end -0.2794 -0.1778)
						)
						(arc
							(start -0.2794 0.1778)
							(mid -0.249642 0.249642)
							(end -0.1778 0.2794)
						)
						(arc
							(start 0.1778 0.2794)
							(mid 0.249642 0.249642)
							(end 0.2794 0.1778)
						)
						(arc
							(start 0.2794 -0.1778)
							(mid 0.249642 -0.249642)
							(end 0.1778 -0.2794)
						)
					)
					(width 0)
					(fill yes)
				)
			)
		)
	)
	(footprint ""
		(layer "F.Cu")
		(at 338.709 -57.851294 90)
		(property "Reference" "C439"
			(at 0 0 90)
			(layer "F.SilkS")
			(hide yes)
			(effects
				(font
					(size 1.27 1.27)
				)
			)
		)
		(property "Value" "SCD033U25V2KX-GP"
			(at 1.1811 -2.7051 90)
			(unlocked yes)
			(layer "F.Fab")
			(hide yes)
			(effects
				(font
					(size 1.016 1.016)
					(thickness 0.1524)
				)
			)
		)
		(property "Device Type" "C402H22"
			(at 1.1811 -4.2291 90)
			(unlocked yes)
			(layer "F.Fab")
			(hide yes)
			(effects
				(font
					(size 1.016 1.016)
					(thickness 0.1524)
				)
			)
		)
		(duplicate_pad_numbers_are_jumpers no)
		(fp_rect
			(start -0.4318 0.9525)
			(end 0.4318 -0.9525)
			(stroke
				(width 0)
				(type default)
			)
			(fill no)
			(layer "F.CrtYd")
		)
		(fp_rect
			(start -0.4318 0.9525)
			(end 0.4318 -0.9525)
			(stroke
				(width 0)
				(type default)
			)
			(fill no)
			(layer "F.Fab")
		)
		(pad "1" smd custom
			(at 0 -0.4445 90)
			(size 0.1524 0.1524)
			(layers "F.Cu" "F.Mask" "F.Paste")
			(net "P12V_A")
			(options
				(clearance outline)
				(anchor circle)
			)
			(primitives
				(gr_poly
					(pts
						(arc
							(start 0.3048 -0.2032)
							(mid 0.275042 -0.275042)
							(end 0.2032 -0.3048)
						)
						(arc
							(start -0.2032 -0.3048)
							(mid -0.275042 -0.275042)
							(end -0.3048 -0.2032)
						)
						(arc
							(start -0.3048 0.2032)
							(mid -0.275042 0.275042)
							(end -0.2032 0.3048)
						)
						(arc
							(start 0.2032 0.3048)
							(mid 0.275042 0.275042)
							(end 0.3048 0.2032)
						)
					)
					(width 0)
					(fill yes)
				)
			)
		)
		(pad "2" smd custom
			(at 0 0.4445 90)
			(size 0.1524 0.1524)
			(layers "F.Cu" "F.Mask" "F.Paste")
			(net "SW_HDD_N30")
			(options
				(clearance outline)
				(anchor circle)
			)
			(primitives
				(gr_poly
					(pts
						(arc
							(start 0.3048 -0.2032)
							(mid 0.275042 -0.275042)
							(end 0.2032 -0.3048)
						)
						(arc
							(start -0.2032 -0.3048)
							(mid -0.275042 -0.275042)
							(end -0.3048 -0.2032)
						)
						(arc
							(start -0.3048 0.2032)
							(mid -0.275042 0.275042)
							(end -0.2032 0.3048)
						)
						(arc
							(start 0.2032 0.3048)
							(mid 0.275042 0.275042)
							(end 0.3048 0.2032)
						)
					)
					(width 0)
					(fill yes)
				)
			)
		)
	)
	(footprint ""
		(layer "F.Cu")
		(at 143.049498 -53.126894 -90)
		(property "Reference" "C412"
			(at 0 0 270)
			(layer "F.SilkS")
			(hide yes)
			(effects
				(font
					(size 1.27 1.27)
				)
			)
		)
		(property "Value" "SCD033U25V2KX-GP"
			(at 1.1811 -2.7051 270)
			(unlocked yes)
			(layer "F.Fab")
			(hide yes)
			(effects
				(font
					(size 1.016 1.016)
					(thickness 0.1524)
				)
			)
		)
		(property "Device Type" "C402H22"
			(at 1.1811 -4.2291 270)
			(unlocked yes)
			(layer "F.Fab")
			(hide yes)
			(effects
				(font
					(size 1.016 1.016)
					(thickness 0.1524)
				)
			)
		)
		(duplicate_pad_numbers_are_jumpers no)
		(fp_rect
			(start -0.4318 0.9525)
			(end 0.4318 -0.9525)
			(stroke
				(width 0)
				(type default)
			)
			(fill no)
			(layer "F.CrtYd")
		)
		(fp_rect
			(start -0.4318 0.9525)
			(end 0.4318 -0.9525)
			(stroke
				(width 0)
				(type default)
			)
			(fill no)
			(layer "F.Fab")
		)
		(pad "1" smd custom
			(at 0 -0.4445 270)
			(size 0.1524 0.1524)
			(layers "F.Cu" "F.Mask" "F.Paste")
			(net "SW_HDD_P28")
			(options
				(clearance outline)
				(anchor circle)
			)
			(primitives
				(gr_poly
					(pts
						(arc
							(start 0.3048 -0.2032)
							(mid 0.275042 -0.275042)
							(end 0.2032 -0.3048)
						)
						(arc
							(start -0.2032 -0.3048)
							(mid -0.275042 -0.275042)
							(end -0.3048 -0.2032)
						)
						(arc
							(start -0.3048 0.2032)
							(mid -0.275042 0.275042)
							(end -0.2032 0.3048)
						)
						(arc
							(start 0.2032 0.3048)
							(mid 0.275042 0.275042)
							(end 0.3048 0.2032)
						)
					)
					(width 0)
					(fill yes)
				)
			)
		)
		(pad "2" smd custom
			(at 0 0.4445 270)
			(size 0.1524 0.1524)
			(layers "F.Cu" "F.Mask" "F.Paste")
			(net "GND")
			(options
				(clearance outline)
				(anchor circle)
			)
			(primitives
				(gr_poly
					(pts
						(arc
							(start 0.3048 -0.2032)
							(mid 0.275042 -0.275042)
							(end 0.2032 -0.3048)
						)
						(arc
							(start -0.2032 -0.3048)
							(mid -0.275042 -0.275042)
							(end -0.3048 -0.2032)
						)
						(arc
							(start -0.3048 0.2032)
							(mid -0.275042 0.275042)
							(end -0.2032 0.3048)
						)
						(arc
							(start 0.2032 0.3048)
							(mid 0.275042 0.275042)
							(end 0.3048 0.2032)
						)
					)
					(width 0)
					(fill yes)
				)
			)
		)
	)
	(footprint ""
		(layer "F.Cu")
		(at 377.835414 -136.489948)
		(property "Reference" "C24"
			(at 0 0 0)
			(layer "F.SilkS")
			(hide yes)
			(effects
				(font
					(size 1.27 1.27)
				)
			)
		)
		(property "Value" "SCD1U16V2KX-3GP"
			(at 1.1811 -2.7051 0)
			(unlocked yes)
			(layer "F.Fab")
			(hide yes)
			(effects
				(font
					(size 1.016 1.016)
					(thickness 0.1524)
				)
			)
		)
		(property "Device Type" "C402H22"
			(at 1.1811 -4.2291 0)
			(unlocked yes)
			(layer "F.Fab")
			(hide yes)
			(effects
				(font
					(size 1.016 1.016)
					(thickness 0.1524)
				)
			)
		)
		(duplicate_pad_numbers_are_jumpers no)
		(fp_rect
			(start -0.4318 0.9525)
			(end 0.4318 -0.9525)
			(stroke
				(width 0)
				(type default)
			)
			(fill no)
			(layer "F.CrtYd")
		)
		(fp_rect
			(start -0.4318 0.9525)
			(end 0.4318 -0.9525)
			(stroke
				(width 0)
				(type default)
			)
			(fill no)
			(layer "F.Fab")
		)
		(pad "1" smd custom
			(at 0 -0.4445)
			(size 0.1524 0.1524)
			(layers "F.Cu" "F.Mask" "F.Paste")
			(net "P3V3_B_BIAS")
			(options
				(clearance outline)
				(anchor circle)
			)
			(primitives
				(gr_poly
					(pts
						(arc
							(start 0.3048 -0.2032)
							(mid 0.275042 -0.275042)
							(end 0.2032 -0.3048)
						)
						(arc
							(start -0.2032 -0.3048)
							(mid -0.275042 -0.275042)
							(end -0.3048 -0.2032)
						)
						(arc
							(start -0.3048 0.2032)
							(mid -0.275042 0.275042)
							(end -0.2032 0.3048)
						)
						(arc
							(start 0.2032 0.3048)
							(mid 0.275042 0.275042)
							(end 0.3048 0.2032)
						)
					)
					(width 0)
					(fill yes)
				)
			)
		)
		(pad "2" smd custom
			(at 0 0.4445)
			(size 0.1524 0.1524)
			(layers "F.Cu" "F.Mask" "F.Paste")
			(net "GND")
			(options
				(clearance outline)
				(anchor circle)
			)
			(primitives
				(gr_poly
					(pts
						(arc
							(start 0.3048 -0.2032)
							(mid 0.275042 -0.275042)
							(end 0.2032 -0.3048)
						)
						(arc
							(start -0.2032 -0.3048)
							(mid -0.275042 -0.275042)
							(end -0.3048 -0.2032)
						)
						(arc
							(start -0.3048 0.2032)
							(mid -0.275042 0.275042)
							(end -0.2032 0.3048)
						)
						(arc
							(start 0.2032 0.3048)
							(mid 0.275042 0.275042)
							(end 0.3048 0.2032)
						)
					)
					(width 0)
					(fill yes)
				)
			)
		)
	)
	(footprint ""
		(layer "F.Cu")
		(at 82.248502 -31.399988 180)
		(property "Reference" "R1298"
			(at 0 0 180)
			(layer "F.SilkS")
			(hide yes)
			(effects
				(font
					(size 1.27 1.27)
				)
			)
		)
		(property "Value" "2K2R2F-GP"
			(at 0.064008 -3.993896 180)
			(unlocked yes)
			(layer "F.Fab")
			(hide yes)
			(effects
				(font
					(size 1.016 1.016)
					(thickness 0.1524)
				)
			)
		)
		(property "Device Type" "R402H16"
			(at 0.064008 -5.517896 180)
			(unlocked yes)
			(layer "F.Fab")
			(hide yes)
			(effects
				(font
					(size 1.016 1.016)
					(thickness 0.1524)
				)
			)
		)
		(duplicate_pad_numbers_are_jumpers no)
		(fp_line
			(start 0.508 -0.9398)
			(end -0.508 -0.9398)
			(stroke
				(width 0.1524)
				(type default)
			)
			(layer "F.SilkS")
		)
		(fp_line
			(start -0.508 -0.9398)
			(end -0.508 0.9398)
			(stroke
				(width 0.1524)
				(type default)
			)
			(layer "F.SilkS")
		)
		(fp_rect
			(start -0.508 0.9398)
			(end 0.508 -0.9398)
			(stroke
				(width 0)
				(type default)
			)
			(fill no)
			(layer "F.CrtYd")
		)
		(fp_rect
			(start -0.508 0.9398)
			(end 0.508 -0.9398)
			(stroke
				(width 0)
				(type default)
			)
			(fill no)
			(layer "F.Fab")
		)
		(pad "1" smd custom
			(at 0 -0.4445 180)
			(size 0.1397 0.1397)
			(layers "F.Cu" "F.Mask" "F.Paste")
			(net "P3V3_STBY_A")
			(options
				(clearance outline)
				(anchor circle)
			)
			(primitives
				(gr_poly
					(pts
						(arc
							(start -0.1778 -0.2794)
							(mid -0.249642 -0.249642)
							(end -0.2794 -0.1778)
						)
						(arc
							(start -0.2794 0.1778)
							(mid -0.249642 0.249642)
							(end -0.1778 0.2794)
						)
						(arc
							(start 0.1778 0.2794)
							(mid 0.249642 0.249642)
							(end 0.2794 0.1778)
						)
						(arc
							(start 0.2794 -0.1778)
							(mid 0.249642 -0.249642)
							(end 0.1778 -0.2794)
						)
					)
					(width 0)
					(fill yes)
				)
			)
		)
		(pad "2" smd custom
			(at 0 0.4445 180)
			(size 0.1397 0.1397)
			(layers "F.Cu" "F.Mask" "F.Paste")
			(net "I2C_BMC_A_MISC_SCL")
			(options
				(clearance outline)
				(anchor circle)
			)
			(primitives
				(gr_poly
					(pts
						(arc
							(start -0.1778 -0.2794)
							(mid -0.249642 -0.249642)
							(end -0.2794 -0.1778)
						)
						(arc
							(start -0.2794 0.1778)
							(mid -0.249642 0.249642)
							(end -0.1778 0.2794)
						)
						(arc
							(start 0.1778 0.2794)
							(mid 0.249642 0.249642)
							(end 0.2794 0.1778)
						)
						(arc
							(start 0.2794 -0.1778)
							(mid 0.249642 -0.249642)
							(end 0.1778 -0.2794)
						)
					)
					(width 0)
					(fill yes)
				)
			)
		)
	)
	(footprint ""
		(layer "F.Cu")
		(at 232.41 -392.2268 -90)
		(property "Reference" "R1142"
			(at 0 0 270)
			(layer "F.SilkS")
			(hide yes)
			(effects
				(font
					(size 1.27 1.27)
				)
			)
		)
		(property "Value" "0R2J-2-GP"
			(at 0.064008 -3.993896 270)
			(unlocked yes)
			(layer "F.Fab")
			(hide yes)
			(effects
				(font
					(size 1.016 1.016)
					(thickness 0.1524)
				)
			)
		)
		(property "Device Type" "R402H16"
			(at 0.064008 -5.517896 270)
			(unlocked yes)
			(layer "F.Fab")
			(hide yes)
			(effects
				(font
					(size 1.016 1.016)
					(thickness 0.1524)
				)
			)
		)
		(duplicate_pad_numbers_are_jumpers no)
		(fp_line
			(start -0.508 -0.9398)
			(end -0.508 0.9398)
			(stroke
				(width 0.1524)
				(type default)
			)
			(layer "F.SilkS")
		)
		(fp_line
			(start 0.508 -0.9398)
			(end -0.508 -0.9398)
			(stroke
				(width 0.1524)
				(type default)
			)
			(layer "F.SilkS")
		)
		(fp_rect
			(start -0.508 0.9398)
			(end 0.508 -0.9398)
			(stroke
				(width 0)
				(type default)
			)
			(fill no)
			(layer "F.CrtYd")
		)
		(fp_rect
			(start -0.508 0.9398)
			(end 0.508 -0.9398)
			(stroke
				(width 0)
				(type default)
			)
			(fill no)
			(layer "F.Fab")
		)
		(pad "1" smd custom
			(at 0 -0.4445 270)
			(size 0.1397 0.1397)
			(layers "F.Cu" "F.Mask" "F.Paste")
			(net "MB3_CM_ADR2_R")
			(options
				(clearance outline)
				(anchor circle)
			)
			(primitives
				(gr_poly
					(pts
						(arc
							(start -0.1778 -0.2794)
							(mid -0.249642 -0.249642)
							(end -0.2794 -0.1778)
						)
						(arc
							(start -0.2794 0.1778)
							(mid -0.249642 0.249642)
							(end -0.1778 0.2794)
						)
						(arc
							(start 0.1778 0.2794)
							(mid 0.249642 0.249642)
							(end 0.2794 0.1778)
						)
						(arc
							(start 0.2794 -0.1778)
							(mid 0.249642 -0.249642)
							(end 0.1778 -0.2794)
						)
					)
					(width 0)
					(fill yes)
				)
			)
		)
		(pad "2" smd custom
			(at 0 0.4445 270)
			(size 0.1397 0.1397)
			(layers "F.Cu" "F.Mask" "F.Paste")
			(net "AGND_CURRENT_DPB")
			(options
				(clearance outline)
				(anchor circle)
			)
			(primitives
				(gr_poly
					(pts
						(arc
							(start -0.1778 -0.2794)
							(mid -0.249642 -0.249642)
							(end -0.2794 -0.1778)
						)
						(arc
							(start -0.2794 0.1778)
							(mid -0.249642 0.249642)
							(end -0.1778 0.2794)
						)
						(arc
							(start 0.1778 0.2794)
							(mid 0.249642 0.249642)
							(end 0.2794 0.1778)
						)
						(arc
							(start 0.2794 -0.1778)
							(mid 0.249642 -0.249642)
							(end 0.1778 -0.2794)
						)
					)
					(width 0)
					(fill yes)
				)
			)
		)
	)
	(footprint ""
		(layer "F.Cu")
		(at 315.149992 -209.399886)
		(property "Reference" "FLED7"
			(at 0 0 0)
			(layer "F.SilkS")
			(hide yes)
			(effects
				(font
					(size 1.27 1.27)
				)
			)
		)
		(property "Value" "LED-BY-19-GP"
			(at -2.132076 1.414018 0)
			(unlocked yes)
			(layer "F.Fab")
			(hide yes)
			(effects
				(font
					(size 1.016 1.016)
					(thickness 0.1524)
				)
			)
		)
		(property "Device Type" "LED-1615-4PH26"
			(at -2.132076 -0.109982 0)
			(unlocked yes)
			(layer "F.Fab")
			(hide yes)
			(effects
				(font
					(size 1.016 1.016)
					(thickness 0.1524)
				)
			)
		)
		(duplicate_pad_numbers_are_jumpers no)
		(fp_line
			(start -1.2954 0.254)
			(end -1.2954 1.6002)
			(stroke
				(width 0.508)
				(type default)
			)
			(layer "F.SilkS")
		)
		(fp_line
			(start -1.2954 1.6002)
			(end 1.2954 1.6002)
			(stroke
				(width 0.508)
				(type default)
			)
			(layer "F.SilkS")
		)
		(fp_line
			(start -1.1176 -1.4224)
			(end 1.1176 -1.4224)
			(stroke
				(width 0.1524)
				(type default)
			)
			(layer "F.SilkS")
		)
		(fp_line
			(start -1.1176 1.4224)
			(end -1.1176 -1.4224)
			(stroke
				(width 0.1524)
				(type default)
			)
			(layer "F.SilkS")
		)
		(fp_line
			(start 1.1176 -1.4224)
			(end 1.1176 1.4224)
			(stroke
				(width 0.1524)
				(type default)
			)
			(layer "F.SilkS")
		)
		(fp_line
			(start 1.1176 1.4224)
			(end -1.1176 1.4224)
			(stroke
				(width 0.1524)
				(type default)
			)
			(layer "F.SilkS")
		)
		(fp_line
			(start 1.2954 1.6002)
			(end 1.2954 0.254)
			(stroke
				(width 0.508)
				(type default)
			)
			(layer "F.SilkS")
		)
		(fp_rect
			(start -0.7493 0.8001)
			(end 0.7493 -0.8001)
			(stroke
				(width 0)
				(type default)
			)
			(fill no)
			(layer "F.CrtYd")
		)
		(fp_poly
			(pts
				(xy -1.3716 1.6764) (xy -1.3716 -1.6764) (xy 1.3716 -1.6764) (xy 1.3716 0.0635) (xy 0.7493 0.0635)
				(xy 0.7493 -0.8001) (xy -0.7493 -0.8001) (xy -0.7493 0.8001) (xy 0.7493 0.8001) (xy 0.7493 0.0762)
				(xy 1.3716 0.0762) (xy 1.3716 1.6764)
			)
			(stroke
				(width 0)
				(type default)
			)
			(fill no)
			(layer "F.CrtYd")
		)
		(fp_rect
			(start -1.3716 1.6764)
			(end 1.3716 -1.6764)
			(stroke
				(width 0)
				(type default)
			)
			(fill no)
			(layer "F.Fab")
		)
		(pad "1" smd rect
			(at 0.50038 -0.73025)
			(size 0.7112 0.8636)
			(layers "F.Cu" "F.Mask" "F.Paste")
			(net "DRV_ACT_6")
		)
		(pad "2" smd rect
			(at -0.50038 -0.73025)
			(size 0.7112 0.8636)
			(layers "F.Cu" "F.Mask" "F.Paste")
			(net "FLT_HDD6")
		)
		(pad "3" smd rect
			(at 0.50038 0.73025)
			(size 0.7112 0.8636)
			(layers "F.Cu" "F.Mask" "F.Paste")
			(net "DRV_ACT_6_N")
		)
		(pad "4" smd rect
			(at -0.50038 0.73025)
			(size 0.7112 0.8636)
			(layers "F.Cu" "F.Mask" "F.Paste")
			(net "FLT_HDD6_N")
		)
	)
	(footprint ""
		(layer "F.Cu")
		(at 79.974948 -161.649918 180)
		(property "Reference" "D14"
			(at 0 0 180)
			(layer "F.SilkS")
			(hide yes)
			(effects
				(font
					(size 1.27 1.27)
				)
			)
		)
		(property "Value" "RB551V30-GP"
			(at 0 -6.7818 180)
			(unlocked yes)
			(layer "F.Fab")
			(hide yes)
			(effects
				(font
					(size 1.016 1.016)
					(thickness 0.1524)
				)
			)
		)
		(property "Device Type" "SOD323AKH38"
			(at 0 -8.6868 180)
			(unlocked yes)
			(layer "F.Fab")
			(hide yes)
			(effects
				(font
					(size 1.016 1.016)
					(thickness 0.1524)
				)
			)
		)
		(duplicate_pad_numbers_are_jumpers no)
		(fp_line
			(start 0.889 2.159)
			(end -0.889 2.159)
			(stroke
				(width 0.1524)
				(type default)
			)
			(layer "F.SilkS")
		)
		(fp_line
			(start 0.889 -1.9304)
			(end 0.889 2.159)
			(stroke
				(width 0.1524)
				(type default)
			)
			(layer "F.SilkS")
		)
		(fp_line
			(start 0.762 2.0574)
			(end -0.762 2.0574)
			(stroke
				(width 0.508)
				(type default)
			)
			(layer "F.SilkS")
		)
		(fp_line
			(start -0.889 2.159)
			(end -0.889 -1.9304)
			(stroke
				(width 0.1524)
				(type default)
			)
			(layer "F.SilkS")
		)
		(fp_line
			(start -0.889 -1.9304)
			(end 0.889 -1.9304)
			(stroke
				(width 0.1524)
				(type default)
			)
			(layer "F.SilkS")
		)
		(fp_rect
			(start -1.016 2.3114)
			(end 1.016 -2.0066)
			(stroke
				(width 0)
				(type default)
			)
			(fill no)
			(layer "F.CrtYd")
		)
		(fp_poly
			(pts
				(xy -1.016 -2.0066) (xy 1.016 -2.0066) (xy 1.016 2.3114) (xy -1.016 2.3114)
			)
			(stroke
				(width 0)
				(type default)
			)
			(fill no)
			(layer "F.Fab")
		)
		(pad "A" smd rect
			(at 0 -1.143 180)
			(size 0.5588 1.016)
			(layers "F.Cu" "F.Mask" "F.Paste")
			(net "SW_HDD_R14")
		)
		(pad "K" smd rect
			(at 0 1.143 180)
			(size 0.5588 1.016)
			(layers "F.Cu" "F.Mask" "F.Paste")
			(net "SW_HDD_N14")
		)
	)
	(footprint ""
		(layer "F.Cu")
		(at 239.014 -395.9098 180)
		(property "Reference" "R1165"
			(at 0 0 180)
			(layer "F.SilkS")
			(hide yes)
			(effects
				(font
					(size 1.27 1.27)
				)
			)
		)
		(property "Value" "12K4R2F-GP"
			(at 0.064008 -3.993896 180)
			(unlocked yes)
			(layer "F.Fab")
			(hide yes)
			(effects
				(font
					(size 1.016 1.016)
					(thickness 0.1524)
				)
			)
		)
		(property "Device Type" "R402H16"
			(at 0.064008 -5.517896 180)
			(unlocked yes)
			(layer "F.Fab")
			(hide yes)
			(effects
				(font
					(size 1.016 1.016)
					(thickness 0.1524)
				)
			)
		)
		(duplicate_pad_numbers_are_jumpers no)
		(fp_line
			(start 0.508 -0.9398)
			(end -0.508 -0.9398)
			(stroke
				(width 0.1524)
				(type default)
			)
			(layer "F.SilkS")
		)
		(fp_line
			(start -0.508 -0.9398)
			(end -0.508 0.9398)
			(stroke
				(width 0.1524)
				(type default)
			)
			(layer "F.SilkS")
		)
		(fp_rect
			(start -0.508 0.9398)
			(end 0.508 -0.9398)
			(stroke
				(width 0)
				(type default)
			)
			(fill no)
			(layer "F.CrtYd")
		)
		(fp_rect
			(start -0.508 0.9398)
			(end 0.508 -0.9398)
			(stroke
				(width 0)
				(type default)
			)
			(fill no)
			(layer "F.Fab")
		)
		(pad "1" smd custom
			(at 0 -0.4445 180)
			(size 0.1397 0.1397)
			(layers "F.Cu" "F.Mask" "F.Paste")
			(net "MB3_ISTART_R")
			(options
				(clearance outline)
				(anchor circle)
			)
			(primitives
				(gr_poly
					(pts
						(arc
							(start -0.1778 -0.2794)
							(mid -0.249642 -0.249642)
							(end -0.2794 -0.1778)
						)
						(arc
							(start -0.2794 0.1778)
							(mid -0.249642 0.249642)
							(end -0.1778 0.2794)
						)
						(arc
							(start 0.1778 0.2794)
							(mid 0.249642 0.249642)
							(end 0.2794 0.1778)
						)
						(arc
							(start 0.2794 -0.1778)
							(mid 0.249642 -0.249642)
							(end 0.1778 -0.2794)
						)
					)
					(width 0)
					(fill yes)
				)
			)
		)
		(pad "2" smd custom
			(at 0 0.4445 180)
			(size 0.1397 0.1397)
			(layers "F.Cu" "F.Mask" "F.Paste")
			(net "AGND_CURRENT_DPB")
			(options
				(clearance outline)
				(anchor circle)
			)
			(primitives
				(gr_poly
					(pts
						(arc
							(start -0.1778 -0.2794)
							(mid -0.249642 -0.249642)
							(end -0.2794 -0.1778)
						)
						(arc
							(start -0.2794 0.1778)
							(mid -0.249642 0.249642)
							(end -0.1778 0.2794)
						)
						(arc
							(start 0.1778 0.2794)
							(mid 0.249642 0.249642)
							(end 0.2794 0.1778)
						)
						(arc
							(start 0.2794 -0.1778)
							(mid 0.249642 -0.249642)
							(end 0.1778 -0.2794)
						)
					)
					(width 0)
					(fill yes)
				)
			)
		)
	)
	(footprint ""
		(layer "F.Cu")
		(at 479.036126 -301.287942)
		(property "Reference" "C187"
			(at 0 0 0)
			(layer "F.SilkS")
			(hide yes)
			(effects
				(font
					(size 1.27 1.27)
				)
			)
		)
		(property "Value" "SC4D7U25V5KX-1-GP"
			(at -0.0762 -6.1214 0)
			(unlocked yes)
			(layer "F.Fab")
			(hide yes)
			(effects
				(font
					(size 1.016 1.016)
					(thickness 0.1524)
				)
			)
		)
		(property "Device Type" "C805H58"
			(at -0.0762 -8.1534 0)
			(unlocked yes)
			(layer "F.Fab")
			(hide yes)
			(effects
				(font
					(size 1.016 1.016)
					(thickness 0.1524)
				)
			)
		)
		(duplicate_pad_numbers_are_jumpers no)
		(fp_line
			(start 0.635 0)
			(end -0.635 0)
			(stroke
				(width 0.508)
				(type default)
			)
			(layer "F.SilkS")
		)
		(fp_rect
			(start -0.9652 1.778)
			(end 0.9652 -1.778)
			(stroke
				(width 0)
				(type default)
			)
			(fill no)
			(layer "F.CrtYd")
		)
		(fp_poly
			(pts
				(xy -0.9652 -1.778) (xy 0.9652 -1.778) (xy 0.9652 1.778) (xy -0.9652 1.778)
			)
			(stroke
				(width 0)
				(type default)
			)
			(fill no)
			(layer "F.Fab")
		)
		(pad "1" smd rect
			(at 0 -0.9652)
			(size 1.397 1.143)
			(layers "F.Cu" "F.Mask" "F.Paste")
			(net "P12V_HDD11")
		)
		(pad "2" smd rect
			(at 0 0.9652)
			(size 1.397 1.143)
			(layers "F.Cu" "F.Mask" "F.Paste")
			(net "GND")
		)
	)
	(footprint ""
		(layer "F.Cu")
		(at 337.312 -162.792918 90)
		(property "Reference" "D18"
			(at 0 0 90)
			(layer "F.SilkS")
			(hide yes)
			(effects
				(font
					(size 1.27 1.27)
				)
			)
		)
		(property "Value" "RB551V30-GP"
			(at 0 -6.7818 90)
			(unlocked yes)
			(layer "F.Fab")
			(hide yes)
			(effects
				(font
					(size 1.016 1.016)
					(thickness 0.1524)
				)
			)
		)
		(property "Device Type" "SOD323AKH38"
			(at 0 -8.6868 90)
			(unlocked yes)
			(layer "F.Fab")
			(hide yes)
			(effects
				(font
					(size 1.016 1.016)
					(thickness 0.1524)
				)
			)
		)
		(duplicate_pad_numbers_are_jumpers no)
		(fp_line
			(start 0.889 -1.9304)
			(end 0.889 2.159)
			(stroke
				(width 0.1524)
				(type default)
			)
			(layer "F.SilkS")
		)
		(fp_line
			(start -0.889 -1.9304)
			(end 0.889 -1.9304)
			(stroke
				(width 0.1524)
				(type default)
			)
			(layer "F.SilkS")
		)
		(fp_line
			(start 0.762 2.0574)
			(end -0.762 2.0574)
			(stroke
				(width 0.508)
				(type default)
			)
			(layer "F.SilkS")
		)
		(fp_line
			(start 0.889 2.159)
			(end -0.889 2.159)
			(stroke
				(width 0.1524)
				(type default)
			)
			(layer "F.SilkS")
		)
		(fp_line
			(start -0.889 2.159)
			(end -0.889 -1.9304)
			(stroke
				(width 0.1524)
				(type default)
			)
			(layer "F.SilkS")
		)
		(fp_rect
			(start -1.016 2.3114)
			(end 1.016 -2.0066)
			(stroke
				(width 0)
				(type default)
			)
			(fill no)
			(layer "F.CrtYd")
		)
		(fp_poly
			(pts
				(xy -1.016 -2.0066) (xy 1.016 -2.0066) (xy 1.016 2.3114) (xy -1.016 2.3114)
			)
			(stroke
				(width 0)
				(type default)
			)
			(fill no)
			(layer "F.Fab")
		)
		(pad "A" smd rect
			(at 0 -1.143 90)
			(size 0.5588 1.016)
			(layers "F.Cu" "F.Mask" "F.Paste")
			(net "SW_HDD_R18")
		)
		(pad "K" smd rect
			(at 0 1.143 90)
			(size 0.5588 1.016)
			(layers "F.Cu" "F.Mask" "F.Paste")
			(net "SW_HDD_N18")
		)
	)
	(footprint ""
		(layer "F.Cu")
		(at 146.630898 -62.778894 -90)
		(property "Reference" "C404"
			(at 0 0 270)
			(layer "F.SilkS")
			(hide yes)
			(effects
				(font
					(size 1.27 1.27)
				)
			)
		)
		(property "Value" "SC1U16V3KX-5GP"
			(at 0 -2.8194 270)
			(unlocked yes)
			(layer "F.Fab")
			(hide yes)
			(effects
				(font
					(size 1.016 1.016)
					(thickness 0.1524)
				)
			)
		)
		(property "Device Type" "C603H36"
			(at 0 -4.3434 270)
			(unlocked yes)
			(layer "F.Fab")
			(hide yes)
			(effects
				(font
					(size 1.016 1.016)
					(thickness 0.1524)
				)
			)
		)
		(duplicate_pad_numbers_are_jumpers no)
		(fp_line
			(start 0.508 0)
			(end -0.508 0)
			(stroke
				(width 0.2032)
				(type default)
			)
			(layer "F.SilkS")
		)
		(fp_rect
			(start -0.5842 1.3335)
			(end 0.5842 -1.3335)
			(stroke
				(width 0)
				(type default)
			)
			(fill no)
			(layer "F.CrtYd")
		)
		(fp_rect
			(start -0.5842 1.3335)
			(end 0.5842 -1.3335)
			(stroke
				(width 0)
				(type default)
			)
			(fill no)
			(layer "F.Fab")
		)
		(pad "1" smd custom
			(at 0 -0.762 270)
			(size 0.2159 0.2159)
			(layers "F.Cu" "F.Mask" "F.Paste")
			(net "P5V_HDD28")
			(options
				(clearance outline)
				(anchor circle)
			)
			(primitives
				(gr_poly
					(pts
						(arc
							(start -0.3302 -0.4318)
							(mid -0.402042 -0.402042)
							(end -0.4318 -0.3302)
						)
						(arc
							(start -0.4318 0.3302)
							(mid -0.402042 0.402042)
							(end -0.3302 0.4318)
						)
						(arc
							(start 0.3302 0.4318)
							(mid 0.402042 0.402042)
							(end 0.4318 0.3302)
						)
						(arc
							(start 0.4318 -0.3302)
							(mid 0.402042 -0.402042)
							(end 0.3302 -0.4318)
						)
					)
					(width 0)
					(fill yes)
				)
			)
		)
		(pad "2" smd custom
			(at 0 0.762 270)
			(size 0.2159 0.2159)
			(layers "F.Cu" "F.Mask" "F.Paste")
			(net "GND")
			(options
				(clearance outline)
				(anchor circle)
			)
			(primitives
				(gr_poly
					(pts
						(arc
							(start -0.3302 -0.4318)
							(mid -0.402042 -0.402042)
							(end -0.4318 -0.3302)
						)
						(arc
							(start -0.4318 0.3302)
							(mid -0.402042 0.402042)
							(end -0.3302 0.4318)
						)
						(arc
							(start 0.3302 0.4318)
							(mid 0.402042 0.402042)
							(end 0.4318 0.3302)
						)
						(arc
							(start 0.4318 -0.3302)
							(mid 0.402042 -0.402042)
							(end 0.3302 -0.4318)
						)
					)
					(width 0)
					(fill yes)
				)
			)
		)
	)
	(footprint ""
		(layer "F.Cu")
		(at 283.21 -284.5308 180)
		(property "Reference" "R125"
			(at 0 0 180)
			(layer "F.SilkS")
			(hide yes)
			(effects
				(font
					(size 1.27 1.27)
				)
			)
		)
		(property "Value" "0R2J-2-GP"
			(at 0.064008 -3.993896 180)
			(unlocked yes)
			(layer "F.Fab")
			(hide yes)
			(effects
				(font
					(size 1.016 1.016)
					(thickness 0.1524)
				)
			)
		)
		(property "Device Type" "R402H16"
			(at 0.064008 -5.517896 180)
			(unlocked yes)
			(layer "F.Fab")
			(hide yes)
			(effects
				(font
					(size 1.016 1.016)
					(thickness 0.1524)
				)
			)
		)
		(duplicate_pad_numbers_are_jumpers no)
		(fp_line
			(start 0.508 -0.9398)
			(end -0.508 -0.9398)
			(stroke
				(width 0.1524)
				(type default)
			)
			(layer "F.SilkS")
		)
		(fp_line
			(start -0.508 -0.9398)
			(end -0.508 0.9398)
			(stroke
				(width 0.1524)
				(type default)
			)
			(layer "F.SilkS")
		)
		(fp_rect
			(start -0.508 0.9398)
			(end 0.508 -0.9398)
			(stroke
				(width 0)
				(type default)
			)
			(fill no)
			(layer "F.CrtYd")
		)
		(fp_rect
			(start -0.508 0.9398)
			(end 0.508 -0.9398)
			(stroke
				(width 0)
				(type default)
			)
			(fill no)
			(layer "F.Fab")
		)
		(pad "1" smd custom
			(at 0 -0.4445 180)
			(size 0.1397 0.1397)
			(layers "F.Cu" "F.Mask" "F.Paste")
			(net "IO_EXP2_LED_SDA")
			(options
				(clearance outline)
				(anchor circle)
			)
			(primitives
				(gr_poly
					(pts
						(arc
							(start -0.1778 -0.2794)
							(mid -0.249642 -0.249642)
							(end -0.2794 -0.1778)
						)
						(arc
							(start -0.2794 0.1778)
							(mid -0.249642 0.249642)
							(end -0.1778 0.2794)
						)
						(arc
							(start 0.1778 0.2794)
							(mid 0.249642 0.249642)
							(end 0.2794 0.1778)
						)
						(arc
							(start 0.2794 -0.1778)
							(mid 0.249642 -0.249642)
							(end 0.1778 -0.2794)
						)
					)
					(width 0)
					(fill yes)
				)
			)
		)
		(pad "2" smd custom
			(at 0 0.4445 180)
			(size 0.1397 0.1397)
			(layers "F.Cu" "F.Mask" "F.Paste")
			(net "I2C_DRIVE_A_FLT_LED_SDA")
			(options
				(clearance outline)
				(anchor circle)
			)
			(primitives
				(gr_poly
					(pts
						(arc
							(start -0.1778 -0.2794)
							(mid -0.249642 -0.249642)
							(end -0.2794 -0.1778)
						)
						(arc
							(start -0.2794 0.1778)
							(mid -0.249642 0.249642)
							(end -0.1778 0.2794)
						)
						(arc
							(start 0.1778 0.2794)
							(mid 0.249642 0.249642)
							(end 0.2794 0.1778)
						)
						(arc
							(start 0.2794 -0.1778)
							(mid 0.249642 -0.249642)
							(end 0.1778 -0.2794)
						)
					)
					(width 0)
					(fill yes)
				)
			)
		)
	)
	(footprint ""
		(layer "F.Cu")
		(at 118.585996 -71.287894)
		(property "Reference" "C397"
			(at 0 0 0)
			(layer "F.SilkS")
			(hide yes)
			(effects
				(font
					(size 1.27 1.27)
				)
			)
		)
		(property "Value" "SC4D7U25V5KX-1-GP"
			(at -0.0762 -6.1214 0)
			(unlocked yes)
			(layer "F.Fab")
			(hide yes)
			(effects
				(font
					(size 1.016 1.016)
					(thickness 0.1524)
				)
			)
		)
		(property "Device Type" "C805H58"
			(at -0.0762 -8.1534 0)
			(unlocked yes)
			(layer "F.Fab")
			(hide yes)
			(effects
				(font
					(size 1.016 1.016)
					(thickness 0.1524)
				)
			)
		)
		(duplicate_pad_numbers_are_jumpers no)
		(fp_line
			(start 0.635 0)
			(end -0.635 0)
			(stroke
				(width 0.508)
				(type default)
			)
			(layer "F.SilkS")
		)
		(fp_rect
			(start -0.9652 1.778)
			(end 0.9652 -1.778)
			(stroke
				(width 0)
				(type default)
			)
			(fill no)
			(layer "F.CrtYd")
		)
		(fp_poly
			(pts
				(xy -0.9652 -1.778) (xy 0.9652 -1.778) (xy 0.9652 1.778) (xy -0.9652 1.778)
			)
			(stroke
				(width 0)
				(type default)
			)
			(fill no)
			(layer "F.Fab")
		)
		(pad "1" smd rect
			(at 0 -0.9652)
			(size 1.397 1.143)
			(layers "F.Cu" "F.Mask" "F.Paste")
			(net "P12V_HDD27")
		)
		(pad "2" smd rect
			(at 0 0.9652)
			(size 1.397 1.143)
			(layers "F.Cu" "F.Mask" "F.Paste")
			(net "GND")
		)
	)
	(footprint ""
		(layer "F.Cu")
		(at 54.546246 -158.347918 -90)
		(property "Reference" "R437"
			(at 0 0 270)
			(layer "F.SilkS")
			(hide yes)
			(effects
				(font
					(size 1.27 1.27)
				)
			)
		)
		(property "Value" "1KR2F-3-GP"
			(at 0.064008 -3.993896 270)
			(unlocked yes)
			(layer "F.Fab")
			(hide yes)
			(effects
				(font
					(size 1.016 1.016)
					(thickness 0.1524)
				)
			)
		)
		(property "Device Type" "R402H16"
			(at 0.064008 -5.517896 270)
			(unlocked yes)
			(layer "F.Fab")
			(hide yes)
			(effects
				(font
					(size 1.016 1.016)
					(thickness 0.1524)
				)
			)
		)
		(duplicate_pad_numbers_are_jumpers no)
		(fp_line
			(start -0.508 -0.9398)
			(end -0.508 0.9398)
			(stroke
				(width 0.1524)
				(type default)
			)
			(layer "F.SilkS")
		)
		(fp_line
			(start 0.508 -0.9398)
			(end -0.508 -0.9398)
			(stroke
				(width 0.1524)
				(type default)
			)
			(layer "F.SilkS")
		)
		(fp_rect
			(start -0.508 0.9398)
			(end 0.508 -0.9398)
			(stroke
				(width 0)
				(type default)
			)
			(fill no)
			(layer "F.CrtYd")
		)
		(fp_rect
			(start -0.508 0.9398)
			(end 0.508 -0.9398)
			(stroke
				(width 0)
				(type default)
			)
			(fill no)
			(layer "F.Fab")
		)
		(pad "1" smd custom
			(at 0 -0.4445 270)
			(size 0.1397 0.1397)
			(layers "F.Cu" "F.Mask" "F.Paste")
			(net "P3V3_STBY_A")
			(options
				(clearance outline)
				(anchor circle)
			)
			(primitives
				(gr_poly
					(pts
						(arc
							(start -0.1778 -0.2794)
							(mid -0.249642 -0.249642)
							(end -0.2794 -0.1778)
						)
						(arc
							(start -0.2794 0.1778)
							(mid -0.249642 0.249642)
							(end -0.1778 0.2794)
						)
						(arc
							(start 0.1778 0.2794)
							(mid 0.249642 0.249642)
							(end 0.2794 0.1778)
						)
						(arc
							(start 0.2794 -0.1778)
							(mid 0.249642 -0.249642)
							(end 0.1778 -0.2794)
						)
					)
					(width 0)
					(fill yes)
				)
			)
		)
		(pad "2" smd custom
			(at 0 0.4445 270)
			(size 0.1397 0.1397)
			(layers "F.Cu" "F.Mask" "F.Paste")
			(net "SW_PWR_R_HDD13")
			(options
				(clearance outline)
				(anchor circle)
			)
			(primitives
				(gr_poly
					(pts
						(arc
							(start -0.1778 -0.2794)
							(mid -0.249642 -0.249642)
							(end -0.2794 -0.1778)
						)
						(arc
							(start -0.2794 0.1778)
							(mid -0.249642 0.249642)
							(end -0.1778 0.2794)
						)
						(arc
							(start 0.1778 0.2794)
							(mid 0.249642 0.249642)
							(end 0.2794 0.1778)
						)
						(arc
							(start 0.2794 -0.1778)
							(mid 0.249642 -0.249642)
							(end 0.1778 -0.2794)
						)
					)
					(width 0)
					(fill yes)
				)
			)
		)
	)
	(footprint ""
		(layer "F.Cu")
		(at 33.325054 -322.799964)
		(property "Reference" ""
			(at 0 0 0)
			(layer "F.SilkS")
			(hide yes)
			(effects
				(font
					(size 1.27 1.27)
				)
			)
		)
		(property "Value" "*"
			(at -8.398764 -8.057642 0)
			(unlocked yes)
			(layer "F.Fab")
			(hide yes)
			(effects
				(font
					(size 1.016 1.016)
					(thickness 0.1524)
				)
			)
		)
		(duplicate_pad_numbers_are_jumpers no)
		(fp_poly
			(pts
				(arc
					(start 7.3152 0)
					(mid 0 7.3152)
					(end -7.3152 0)
				)
				(arc
					(start -7.3152 -5.9944)
					(mid 0 -13.3096)
					(end 7.3152 -5.9944)
				)
			)
			(stroke
				(width 0)
				(type default)
			)
			(fill no)
			(layer "B.CrtYd")
		)
		(fp_poly
			(pts
				(arc
					(start 7.3152 0)
					(mid 0 7.3152)
					(end -7.3152 0)
				)
				(arc
					(start -7.3152 -5.9944)
					(mid 0 -13.3096)
					(end 7.3152 -5.9944)
				)
			)
			(stroke
				(width 0)
				(type default)
			)
			(fill no)
			(layer "F.CrtYd")
		)
		(fp_poly
			(pts
				(arc
					(start 7.3152 0)
					(mid 0 7.3152)
					(end -7.3152 0)
				)
				(arc
					(start -7.3152 -5.9944)
					(mid 0 -13.3096)
					(end 7.3152 -5.9944)
				)
			)
			(stroke
				(width 0)
				(type default)
			)
			(fill no)
			(layer "B.Fab")
		)
		(fp_poly
			(pts
				(arc
					(start 7.3152 0)
					(mid 0 7.3152)
					(end -7.3152 0)
				)
				(arc
					(start -7.3152 -5.9944)
					(mid 0 -13.3096)
					(end 7.3152 -5.9944)
				)
			)
			(stroke
				(width 0)
				(type default)
			)
			(fill no)
			(layer "F.Fab")
		)
		(pad "1" thru_hole oval
			(at 0 0)
			(size 14.0208 20.0152)
			(drill 0.0254
				(offset 0 -2.9972)
			)
			(layers "*.Cu" "*.Mask")
			(remove_unused_layers no)
			(net "Net_39")
			(clearance -1.002284)
			(thermal_gap 0.1524)
			(padstack
				(mode front_inner_back)
				(layer "Inner"
					(shape custom)
					(size 2.928012 2.928012)
					(options
						(anchor circle)
					)
					(primitives
						(gr_poly
							(pts
								(arc
									(start 4.571746 -2.084324)
									(mid 0.000333 7.430372)
									(end -4.571492 -2.084324)
								)
								(arc
									(start -4.571492 -2.084324)
									(mid -3.570296 -3.611977)
									(end -2.875026 -5.30098)
								)
								(arc
									(start -2.875026 -5.30098)
									(mid 0.000217 -7.43089)
									(end 2.87528 -5.30098)
								)
								(arc
									(start 2.87528 -5.30098)
									(mid 3.570511 -3.611956)
									(end 4.571746 -2.084324)
								)
							)
							(width 0)
							(fill yes)
						)
					)
					(clearance 0.1524)
				)
				(layer "B.Cu"
					(shape oval)
					(size 14.0208 20.0152)
					(offset 0 -2.9972)
					(clearance -1.002284)
				)
			)
		)
		(zone
			(layers "F.Cu" "B.Cu" "In1.Cu" "In2.Cu" "In3.Cu" "In4.Cu" "In5.Cu" "In6.Cu"
				"In7.Cu" "In8.Cu" "In9.Cu" "In10.Cu"
			)
			(hatch none 0.5)
			(connect_pads
				(clearance 0)
			)
			(min_thickness 0.25)
			(keepout
				(tracks not_allowed)
				(vias allowed)
				(pads allowed)
				(copperpour not_allowed)
				(footprints allowed)
			)
			(placement
				(enabled no)
				(sheetname "")
			)
			(fill
				(thermal_gap 0.5)
				(thermal_bridge_width 0.5)
				(island_removal_mode 0)
			)
			(polygon
				(pts
					(arc
						(start 26.314654 -328.794364)
						(mid 33.325054 -335.804764)
						(end 40.335454 -328.794364)
					)
					(arc
						(start 40.335454 -322.799964)
						(mid 33.325054 -315.789564)
						(end 26.314654 -322.799964)
					)
				)
			)
		)
	)
	(footprint ""
		(layer "F.Cu")
		(at 33.798002 -255.96215)
		(property "Reference" "R1205"
			(at 0 0 0)
			(layer "F.SilkS")
			(hide yes)
			(effects
				(font
					(size 1.27 1.27)
				)
			)
		)
		(property "Value" "49K9R2F-L-GP"
			(at 0.064008 -3.993896 0)
			(unlocked yes)
			(layer "F.Fab")
			(hide yes)
			(effects
				(font
					(size 1.016 1.016)
					(thickness 0.1524)
				)
			)
		)
		(property "Device Type" "R402H16"
			(at 0.064008 -5.517896 0)
			(unlocked yes)
			(layer "F.Fab")
			(hide yes)
			(effects
				(font
					(size 1.016 1.016)
					(thickness 0.1524)
				)
			)
		)
		(duplicate_pad_numbers_are_jumpers no)
		(fp_line
			(start -0.508 -0.9398)
			(end -0.508 0.9398)
			(stroke
				(width 0.1524)
				(type default)
			)
			(layer "F.SilkS")
		)
		(fp_line
			(start 0.508 -0.9398)
			(end -0.508 -0.9398)
			(stroke
				(width 0.1524)
				(type default)
			)
			(layer "F.SilkS")
		)
		(fp_rect
			(start -0.508 0.9398)
			(end 0.508 -0.9398)
			(stroke
				(width 0)
				(type default)
			)
			(fill no)
			(layer "F.CrtYd")
		)
		(fp_rect
			(start -0.508 0.9398)
			(end 0.508 -0.9398)
			(stroke
				(width 0)
				(type default)
			)
			(fill no)
			(layer "F.Fab")
		)
		(pad "1" smd custom
			(at 0 -0.4445)
			(size 0.1397 0.1397)
			(layers "F.Cu" "F.Mask" "F.Paste")
			(net "P12V_A")
			(options
				(clearance outline)
				(anchor circle)
			)
			(primitives
				(gr_poly
					(pts
						(arc
							(start -0.1778 -0.2794)
							(mid -0.249642 -0.249642)
							(end -0.2794 -0.1778)
						)
						(arc
							(start -0.2794 0.1778)
							(mid -0.249642 0.249642)
							(end -0.1778 0.2794)
						)
						(arc
							(start 0.1778 0.2794)
							(mid 0.249642 0.249642)
							(end 0.2794 0.1778)
						)
						(arc
							(start 0.2794 -0.1778)
							(mid 0.249642 -0.249642)
							(end 0.1778 -0.2794)
						)
					)
					(width 0)
					(fill yes)
				)
			)
		)
		(pad "2" smd custom
			(at 0 0.4445)
			(size 0.1397 0.1397)
			(layers "F.Cu" "F.Mask" "F.Paste")
			(net "P5V_A_EN_R")
			(options
				(clearance outline)
				(anchor circle)
			)
			(primitives
				(gr_poly
					(pts
						(arc
							(start -0.1778 -0.2794)
							(mid -0.249642 -0.249642)
							(end -0.2794 -0.1778)
						)
						(arc
							(start -0.2794 0.1778)
							(mid -0.249642 0.249642)
							(end -0.1778 0.2794)
						)
						(arc
							(start 0.1778 0.2794)
							(mid 0.249642 0.249642)
							(end 0.2794 0.1778)
						)
						(arc
							(start 0.2794 -0.1778)
							(mid 0.249642 -0.249642)
							(end 0.1778 -0.2794)
						)
					)
					(width 0)
					(fill yes)
				)
			)
		)
	)
	(footprint ""
		(layer "F.Cu")
		(at 246.253 -388.4168 -90)
		(property "Reference" "R1155"
			(at 0 0 270)
			(layer "F.SilkS")
			(hide yes)
			(effects
				(font
					(size 1.27 1.27)
				)
			)
		)
		(property "Value" "10R2F-L-GP"
			(at 0.064008 -3.993896 270)
			(unlocked yes)
			(layer "F.Fab")
			(hide yes)
			(effects
				(font
					(size 1.016 1.016)
					(thickness 0.1524)
				)
			)
		)
		(property "Device Type" "R402H14"
			(at 0.064008 -5.517896 270)
			(unlocked yes)
			(layer "F.Fab")
			(hide yes)
			(effects
				(font
					(size 1.016 1.016)
					(thickness 0.1524)
				)
			)
		)
		(duplicate_pad_numbers_are_jumpers no)
		(fp_line
			(start -0.508 -0.9398)
			(end -0.508 0.9398)
			(stroke
				(width 0.1524)
				(type default)
			)
			(layer "F.SilkS")
		)
		(fp_line
			(start 0.508 -0.9398)
			(end -0.508 -0.9398)
			(stroke
				(width 0.1524)
				(type default)
			)
			(layer "F.SilkS")
		)
		(fp_rect
			(start -0.508 0.9398)
			(end 0.508 -0.9398)
			(stroke
				(width 0)
				(type default)
			)
			(fill no)
			(layer "F.CrtYd")
		)
		(fp_rect
			(start -0.508 0.9398)
			(end 0.508 -0.9398)
			(stroke
				(width 0)
				(type default)
			)
			(fill no)
			(layer "F.Fab")
		)
		(pad "1" smd custom
			(at 0 -0.4445 270)
			(size 0.1397 0.1397)
			(layers "F.Cu" "F.Mask" "F.Paste")
			(net "MB3_CM_SENSE_R1_P")
			(options
				(clearance outline)
				(anchor circle)
			)
			(primitives
				(gr_poly
					(pts
						(arc
							(start -0.1778 -0.2794)
							(mid -0.249642 -0.249642)
							(end -0.2794 -0.1778)
						)
						(arc
							(start -0.2794 0.1778)
							(mid -0.249642 0.249642)
							(end -0.1778 0.2794)
						)
						(arc
							(start 0.1778 0.2794)
							(mid 0.249642 0.249642)
							(end 0.2794 0.1778)
						)
						(arc
							(start 0.2794 -0.1778)
							(mid 0.249642 -0.249642)
							(end 0.1778 -0.2794)
						)
					)
					(width 0)
					(fill yes)
				)
			)
		)
		(pad "2" smd custom
			(at 0 0.4445 270)
			(size 0.1397 0.1397)
			(layers "F.Cu" "F.Mask" "F.Paste")
			(net "MB3_HS_SENSE_P")
			(options
				(clearance outline)
				(anchor circle)
			)
			(primitives
				(gr_poly
					(pts
						(arc
							(start -0.1778 -0.2794)
							(mid -0.249642 -0.249642)
							(end -0.2794 -0.1778)
						)
						(arc
							(start -0.2794 0.1778)
							(mid -0.249642 0.249642)
							(end -0.1778 0.2794)
						)
						(arc
							(start 0.1778 0.2794)
							(mid 0.249642 0.249642)
							(end 0.2794 0.1778)
						)
						(arc
							(start 0.2794 -0.1778)
							(mid 0.249642 -0.249642)
							(end 0.1778 -0.2794)
						)
					)
					(width 0)
					(fill yes)
				)
			)
		)
	)
	(footprint ""
		(layer "F.Cu")
		(at 223.887792 -344.628978 180)
		(property "Reference" "R28"
			(at 0 0 180)
			(layer "F.SilkS")
			(hide yes)
			(effects
				(font
					(size 1.27 1.27)
				)
			)
		)
		(property "Value" "4K7R2F-GP"
			(at 0.064008 -3.993896 180)
			(unlocked yes)
			(layer "F.Fab")
			(hide yes)
			(effects
				(font
					(size 1.016 1.016)
					(thickness 0.1524)
				)
			)
		)
		(property "Device Type" "R402H16"
			(at 0.064008 -5.517896 180)
			(unlocked yes)
			(layer "F.Fab")
			(hide yes)
			(effects
				(font
					(size 1.016 1.016)
					(thickness 0.1524)
				)
			)
		)
		(duplicate_pad_numbers_are_jumpers no)
		(fp_line
			(start 0.508 -0.9398)
			(end -0.508 -0.9398)
			(stroke
				(width 0.1524)
				(type default)
			)
			(layer "F.SilkS")
		)
		(fp_line
			(start -0.508 -0.9398)
			(end -0.508 0.9398)
			(stroke
				(width 0.1524)
				(type default)
			)
			(layer "F.SilkS")
		)
		(fp_rect
			(start -0.508 0.9398)
			(end 0.508 -0.9398)
			(stroke
				(width 0)
				(type default)
			)
			(fill no)
			(layer "F.CrtYd")
		)
		(fp_rect
			(start -0.508 0.9398)
			(end 0.508 -0.9398)
			(stroke
				(width 0)
				(type default)
			)
			(fill no)
			(layer "F.Fab")
		)
		(pad "1" smd custom
			(at 0 -0.4445 180)
			(size 0.1397 0.1397)
			(layers "F.Cu" "F.Mask" "F.Paste")
			(net "VOL_SEN_ADDR0")
			(options
				(clearance outline)
				(anchor circle)
			)
			(primitives
				(gr_poly
					(pts
						(arc
							(start -0.1778 -0.2794)
							(mid -0.249642 -0.249642)
							(end -0.2794 -0.1778)
						)
						(arc
							(start -0.2794 0.1778)
							(mid -0.249642 0.249642)
							(end -0.1778 0.2794)
						)
						(arc
							(start 0.1778 0.2794)
							(mid 0.249642 0.249642)
							(end 0.2794 0.1778)
						)
						(arc
							(start 0.2794 -0.1778)
							(mid 0.249642 -0.249642)
							(end 0.1778 -0.2794)
						)
					)
					(width 0)
					(fill yes)
				)
			)
		)
		(pad "2" smd custom
			(at 0 0.4445 180)
			(size 0.1397 0.1397)
			(layers "F.Cu" "F.Mask" "F.Paste")
			(net "GND")
			(options
				(clearance outline)
				(anchor circle)
			)
			(primitives
				(gr_poly
					(pts
						(arc
							(start -0.1778 -0.2794)
							(mid -0.249642 -0.249642)
							(end -0.2794 -0.1778)
						)
						(arc
							(start -0.2794 0.1778)
							(mid -0.249642 0.249642)
							(end -0.1778 0.2794)
						)
						(arc
							(start 0.1778 0.2794)
							(mid 0.249642 0.249642)
							(end 0.2794 0.1778)
						)
						(arc
							(start 0.2794 -0.1778)
							(mid 0.249642 -0.249642)
							(end 0.1778 -0.2794)
						)
					)
					(width 0)
					(fill yes)
				)
			)
		)
	)
	(footprint ""
		(layer "F.Cu")
		(at 82.006948 -179.683918 90)
		(property "Reference" "R453"
			(at 0 0 90)
			(layer "F.SilkS")
			(hide yes)
			(effects
				(font
					(size 1.27 1.27)
				)
			)
		)
		(property "Value" "2R6F-GP"
			(at -0.0508 -4.8514 90)
			(unlocked yes)
			(layer "F.Fab")
			(hide yes)
			(effects
				(font
					(size 1.016 1.016)
					(thickness 0.1524)
				)
			)
		)
		(property "Device Type" "R1206H26"
			(at 0 -6.3754 90)
			(unlocked yes)
			(layer "F.Fab")
			(hide yes)
			(effects
				(font
					(size 1.016 1.016)
					(thickness 0.1524)
				)
			)
		)
		(duplicate_pad_numbers_are_jumpers no)
		(fp_line
			(start 1.016 -2.2352)
			(end 1.016 2.2352)
			(stroke
				(width 0.1524)
				(type default)
			)
			(layer "F.SilkS")
		)
		(fp_line
			(start -1.016 -2.2352)
			(end 1.016 -2.2352)
			(stroke
				(width 0.1524)
				(type default)
			)
			(layer "F.SilkS")
		)
		(fp_line
			(start 1.016 2.2352)
			(end -1.016 2.2352)
			(stroke
				(width 0.1524)
				(type default)
			)
			(layer "F.SilkS")
		)
		(fp_line
			(start -1.016 2.2352)
			(end -1.016 -2.2352)
			(stroke
				(width 0.1524)
				(type default)
			)
			(layer "F.SilkS")
		)
		(fp_rect
			(start -1.0922 2.3114)
			(end 1.0922 -2.3114)
			(stroke
				(width 0)
				(type default)
			)
			(fill no)
			(layer "F.CrtYd")
		)
		(fp_poly
			(pts
				(xy -1.0922 -2.3114) (xy 1.0922 -2.3114) (xy 1.0922 2.3114) (xy -1.0922 2.3114)
			)
			(stroke
				(width 0)
				(type default)
			)
			(fill no)
			(layer "F.Fab")
		)
		(pad "1" smd rect
			(at 0 -1.397 90)
			(size 1.651 1.27)
			(layers "F.Cu" "F.Mask" "F.Paste")
			(net "P12V_HDD14")
		)
		(pad "2" smd rect
			(at 0 1.397 90)
			(size 1.651 1.27)
			(layers "F.Cu" "F.Mask" "F.Paste")
			(net "12V_PRE_14")
		)
	)
	(footprint ""
		(layer "F.Cu")
		(at 440.694826 -127.254)
		(property "Reference" "R339"
			(at 0 0 0)
			(layer "F.SilkS")
			(hide yes)
			(effects
				(font
					(size 1.27 1.27)
				)
			)
		)
		(property "Value" "130R3F-GP"
			(at -0.0254 -2.5146 0)
			(unlocked yes)
			(layer "F.Fab")
			(hide yes)
			(effects
				(font
					(size 1.016 1.016)
					(thickness 0.1524)
				)
			)
		)
		(property "Device Type" "R603H22"
			(at -0.0254 -4.0386 0)
			(unlocked yes)
			(layer "F.Fab")
			(hide yes)
			(effects
				(font
					(size 1.016 1.016)
					(thickness 0.1524)
				)
			)
		)
		(duplicate_pad_numbers_are_jumpers no)
		(fp_line
			(start -0.4826 0)
			(end -0.2032 0)
			(stroke
				(width 0.2032)
				(type default)
			)
			(layer "F.SilkS")
		)
		(fp_line
			(start 0.2032 0)
			(end 0.4826 0)
			(stroke
				(width 0.2032)
				(type default)
			)
			(layer "F.SilkS")
		)
		(fp_rect
			(start -0.5842 1.3335)
			(end 0.5842 -1.3335)
			(stroke
				(width 0)
				(type default)
			)
			(fill no)
			(layer "F.CrtYd")
		)
		(fp_rect
			(start -0.5842 1.3335)
			(end 0.5842 -1.3335)
			(stroke
				(width 0)
				(type default)
			)
			(fill no)
			(layer "F.Fab")
		)
		(pad "1" smd custom
			(at 0 -0.762)
			(size 0.2159 0.2159)
			(layers "F.Cu" "F.Mask" "F.Paste")
			(net "P5V_A_4")
			(options
				(clearance outline)
				(anchor circle)
			)
			(primitives
				(gr_poly
					(pts
						(arc
							(start -0.3302 -0.4318)
							(mid -0.402042 -0.402042)
							(end -0.4318 -0.3302)
						)
						(arc
							(start -0.4318 0.3302)
							(mid -0.402042 0.402042)
							(end -0.3302 0.4318)
						)
						(arc
							(start 0.3302 0.4318)
							(mid 0.402042 0.402042)
							(end 0.4318 0.3302)
						)
						(arc
							(start 0.4318 -0.3302)
							(mid 0.402042 -0.402042)
							(end 0.3302 -0.4318)
						)
					)
					(width 0)
					(fill yes)
				)
			)
		)
		(pad "2" smd custom
			(at 0 0.762)
			(size 0.2159 0.2159)
			(layers "F.Cu" "F.Mask" "F.Paste")
			(net "FLT_HDD22")
			(options
				(clearance outline)
				(anchor circle)
			)
			(primitives
				(gr_poly
					(pts
						(arc
							(start -0.3302 -0.4318)
							(mid -0.402042 -0.402042)
							(end -0.4318 -0.3302)
						)
						(arc
							(start -0.4318 0.3302)
							(mid -0.402042 0.402042)
							(end -0.3302 0.4318)
						)
						(arc
							(start 0.3302 0.4318)
							(mid 0.402042 0.402042)
							(end 0.4318 0.3302)
						)
						(arc
							(start 0.4318 -0.3302)
							(mid 0.402042 -0.402042)
							(end 0.3302 -0.4318)
						)
					)
					(width 0)
					(fill yes)
				)
			)
		)
	)
	(footprint ""
		(layer "F.Cu")
		(at 241.00663 -237.9345)
		(property "Reference" "C26"
			(at 0 0 0)
			(layer "F.SilkS")
			(hide yes)
			(effects
				(font
					(size 1.27 1.27)
				)
			)
		)
		(property "Value" "SCD1U16V2KX-3GP"
			(at 1.1811 -2.7051 0)
			(unlocked yes)
			(layer "F.Fab")
			(hide yes)
			(effects
				(font
					(size 1.016 1.016)
					(thickness 0.1524)
				)
			)
		)
		(property "Device Type" "C402H22"
			(at 1.1811 -4.2291 0)
			(unlocked yes)
			(layer "F.Fab")
			(hide yes)
			(effects
				(font
					(size 1.016 1.016)
					(thickness 0.1524)
				)
			)
		)
		(duplicate_pad_numbers_are_jumpers no)
		(fp_rect
			(start -0.4318 0.9525)
			(end 0.4318 -0.9525)
			(stroke
				(width 0)
				(type default)
			)
			(fill no)
			(layer "F.CrtYd")
		)
		(fp_rect
			(start -0.4318 0.9525)
			(end 0.4318 -0.9525)
			(stroke
				(width 0)
				(type default)
			)
			(fill no)
			(layer "F.Fab")
		)
		(pad "1" smd custom
			(at 0 -0.4445)
			(size 0.1524 0.1524)
			(layers "F.Cu" "F.Mask" "F.Paste")
			(net "GPIO_VCC_U8")
			(options
				(clearance outline)
				(anchor circle)
			)
			(primitives
				(gr_poly
					(pts
						(arc
							(start 0.3048 -0.2032)
							(mid 0.275042 -0.275042)
							(end 0.2032 -0.3048)
						)
						(arc
							(start -0.2032 -0.3048)
							(mid -0.275042 -0.275042)
							(end -0.3048 -0.2032)
						)
						(arc
							(start -0.3048 0.2032)
							(mid -0.275042 0.275042)
							(end -0.2032 0.3048)
						)
						(arc
							(start 0.2032 0.3048)
							(mid 0.275042 0.275042)
							(end 0.3048 0.2032)
						)
					)
					(width 0)
					(fill yes)
				)
			)
		)
		(pad "2" smd custom
			(at 0 0.4445)
			(size 0.1524 0.1524)
			(layers "F.Cu" "F.Mask" "F.Paste")
			(net "GND")
			(options
				(clearance outline)
				(anchor circle)
			)
			(primitives
				(gr_poly
					(pts
						(arc
							(start 0.3048 -0.2032)
							(mid 0.275042 -0.275042)
							(end 0.2032 -0.3048)
						)
						(arc
							(start -0.2032 -0.3048)
							(mid -0.275042 -0.275042)
							(end -0.3048 -0.2032)
						)
						(arc
							(start -0.3048 0.2032)
							(mid -0.275042 0.275042)
							(end -0.2032 0.3048)
						)
						(arc
							(start 0.2032 0.3048)
							(mid 0.275042 0.275042)
							(end 0.3048 0.2032)
						)
					)
					(width 0)
					(fill yes)
				)
			)
		)
	)
	(footprint ""
		(layer "F.Cu")
		(at 113.065052 -127.254)
		(property "Reference" "R296"
			(at 0 0 0)
			(layer "F.SilkS")
			(hide yes)
			(effects
				(font
					(size 1.27 1.27)
				)
			)
		)
		(property "Value" "91R3F-1-GP"
			(at -0.0254 -2.5146 0)
			(unlocked yes)
			(layer "F.Fab")
			(hide yes)
			(effects
				(font
					(size 1.016 1.016)
					(thickness 0.1524)
				)
			)
		)
		(property "Device Type" "R603H22"
			(at -0.0254 -4.0386 0)
			(unlocked yes)
			(layer "F.Fab")
			(hide yes)
			(effects
				(font
					(size 1.016 1.016)
					(thickness 0.1524)
				)
			)
		)
		(duplicate_pad_numbers_are_jumpers no)
		(fp_line
			(start -0.4826 0)
			(end -0.2032 0)
			(stroke
				(width 0.2032)
				(type default)
			)
			(layer "F.SilkS")
		)
		(fp_line
			(start 0.2032 0)
			(end 0.4826 0)
			(stroke
				(width 0.2032)
				(type default)
			)
			(layer "F.SilkS")
		)
		(fp_rect
			(start -0.5842 1.3335)
			(end 0.5842 -1.3335)
			(stroke
				(width 0)
				(type default)
			)
			(fill no)
			(layer "F.CrtYd")
		)
		(fp_rect
			(start -0.5842 1.3335)
			(end 0.5842 -1.3335)
			(stroke
				(width 0)
				(type default)
			)
			(fill no)
			(layer "F.Fab")
		)
		(pad "1" smd custom
			(at 0 -0.762)
			(size 0.2159 0.2159)
			(layers "F.Cu" "F.Mask" "F.Paste")
			(net "P5V_A_2")
			(options
				(clearance outline)
				(anchor circle)
			)
			(primitives
				(gr_poly
					(pts
						(arc
							(start -0.3302 -0.4318)
							(mid -0.402042 -0.402042)
							(end -0.4318 -0.3302)
						)
						(arc
							(start -0.4318 0.3302)
							(mid -0.402042 0.402042)
							(end -0.3302 0.4318)
						)
						(arc
							(start 0.3302 0.4318)
							(mid 0.402042 0.402042)
							(end 0.4318 0.3302)
						)
						(arc
							(start 0.4318 -0.3302)
							(mid 0.402042 -0.402042)
							(end 0.3302 -0.4318)
						)
					)
					(width 0)
					(fill yes)
				)
			)
		)
		(pad "2" smd custom
			(at 0 0.762)
			(size 0.2159 0.2159)
			(layers "F.Cu" "F.Mask" "F.Paste")
			(net "DRV_ACT_15")
			(options
				(clearance outline)
				(anchor circle)
			)
			(primitives
				(gr_poly
					(pts
						(arc
							(start -0.3302 -0.4318)
							(mid -0.402042 -0.402042)
							(end -0.4318 -0.3302)
						)
						(arc
							(start -0.4318 0.3302)
							(mid -0.402042 0.402042)
							(end -0.3302 0.4318)
						)
						(arc
							(start 0.3302 0.4318)
							(mid 0.402042 0.402042)
							(end 0.4318 0.3302)
						)
						(arc
							(start 0.4318 -0.3302)
							(mid 0.402042 -0.402042)
							(end 0.3302 -0.4318)
						)
					)
					(width 0)
					(fill yes)
				)
			)
		)
	)
	(footprint ""
		(layer "F.Cu")
		(at 22.071584 -159.926274 90)
		(property "Reference" "R417"
			(at 0 0 90)
			(layer "F.SilkS")
			(hide yes)
			(effects
				(font
					(size 1.27 1.27)
				)
			)
		)
		(property "Value" "0R2J-2-GP"
			(at 0.064008 -3.993896 90)
			(unlocked yes)
			(layer "F.Fab")
			(hide yes)
			(effects
				(font
					(size 1.016 1.016)
					(thickness 0.1524)
				)
			)
		)
		(property "Device Type" "R402H16"
			(at 0.064008 -5.517896 90)
			(unlocked yes)
			(layer "F.Fab")
			(hide yes)
			(effects
				(font
					(size 1.016 1.016)
					(thickness 0.1524)
				)
			)
		)
		(duplicate_pad_numbers_are_jumpers no)
		(fp_line
			(start 0.508 -0.9398)
			(end -0.508 -0.9398)
			(stroke
				(width 0.1524)
				(type default)
			)
			(layer "F.SilkS")
		)
		(fp_line
			(start -0.508 -0.9398)
			(end -0.508 0.9398)
			(stroke
				(width 0.1524)
				(type default)
			)
			(layer "F.SilkS")
		)
		(fp_rect
			(start -0.508 0.9398)
			(end 0.508 -0.9398)
			(stroke
				(width 0)
				(type default)
			)
			(fill no)
			(layer "F.CrtYd")
		)
		(fp_rect
			(start -0.508 0.9398)
			(end 0.508 -0.9398)
			(stroke
				(width 0)
				(type default)
			)
			(fill no)
			(layer "F.Fab")
		)
		(pad "1" smd custom
			(at 0 -0.4445 90)
			(size 0.1397 0.1397)
			(layers "F.Cu" "F.Mask" "F.Paste")
			(net "DRIVE_A_12_PWR")
			(options
				(clearance outline)
				(anchor circle)
			)
			(primitives
				(gr_poly
					(pts
						(arc
							(start -0.1778 -0.2794)
							(mid -0.249642 -0.249642)
							(end -0.2794 -0.1778)
						)
						(arc
							(start -0.2794 0.1778)
							(mid -0.249642 0.249642)
							(end -0.1778 0.2794)
						)
						(arc
							(start 0.1778 0.2794)
							(mid 0.249642 0.249642)
							(end 0.2794 0.1778)
						)
						(arc
							(start 0.2794 -0.1778)
							(mid 0.249642 -0.249642)
							(end 0.1778 -0.2794)
						)
					)
					(width 0)
					(fill yes)
				)
			)
		)
		(pad "2" smd custom
			(at 0 0.4445 90)
			(size 0.1397 0.1397)
			(layers "F.Cu" "F.Mask" "F.Paste")
			(net "SW_PWR_R_HDD12")
			(options
				(clearance outline)
				(anchor circle)
			)
			(primitives
				(gr_poly
					(pts
						(arc
							(start -0.1778 -0.2794)
							(mid -0.249642 -0.249642)
							(end -0.2794 -0.1778)
						)
						(arc
							(start -0.2794 0.1778)
							(mid -0.249642 0.249642)
							(end -0.1778 0.2794)
						)
						(arc
							(start 0.1778 0.2794)
							(mid 0.249642 0.249642)
							(end 0.2794 0.1778)
						)
						(arc
							(start 0.2794 -0.1778)
							(mid 0.249642 -0.249642)
							(end 0.1778 -0.2794)
						)
					)
					(width 0)
					(fill yes)
				)
			)
		)
	)
	(footprint ""
		(layer "F.Cu")
		(at 400.41195 -47.792894 90)
		(property "Reference" "D32"
			(at 0 0 90)
			(layer "F.SilkS")
			(hide yes)
			(effects
				(font
					(size 1.27 1.27)
				)
			)
		)
		(property "Value" "RB551V30-GP"
			(at 0 -6.7818 90)
			(unlocked yes)
			(layer "F.Fab")
			(hide yes)
			(effects
				(font
					(size 1.016 1.016)
					(thickness 0.1524)
				)
			)
		)
		(property "Device Type" "SOD323AKH38"
			(at 0 -8.6868 90)
			(unlocked yes)
			(layer "F.Fab")
			(hide yes)
			(effects
				(font
					(size 1.016 1.016)
					(thickness 0.1524)
				)
			)
		)
		(duplicate_pad_numbers_are_jumpers no)
		(fp_line
			(start 0.889 -1.9304)
			(end 0.889 2.159)
			(stroke
				(width 0.1524)
				(type default)
			)
			(layer "F.SilkS")
		)
		(fp_line
			(start -0.889 -1.9304)
			(end 0.889 -1.9304)
			(stroke
				(width 0.1524)
				(type default)
			)
			(layer "F.SilkS")
		)
		(fp_line
			(start 0.762 2.0574)
			(end -0.762 2.0574)
			(stroke
				(width 0.508)
				(type default)
			)
			(layer "F.SilkS")
		)
		(fp_line
			(start 0.889 2.159)
			(end -0.889 2.159)
			(stroke
				(width 0.1524)
				(type default)
			)
			(layer "F.SilkS")
		)
		(fp_line
			(start -0.889 2.159)
			(end -0.889 -1.9304)
			(stroke
				(width 0.1524)
				(type default)
			)
			(layer "F.SilkS")
		)
		(fp_rect
			(start -1.016 2.3114)
			(end 1.016 -2.0066)
			(stroke
				(width 0)
				(type default)
			)
			(fill no)
			(layer "F.CrtYd")
		)
		(fp_poly
			(pts
				(xy -1.016 -2.0066) (xy 1.016 -2.0066) (xy 1.016 2.3114) (xy -1.016 2.3114)
			)
			(stroke
				(width 0)
				(type default)
			)
			(fill no)
			(layer "F.Fab")
		)
		(pad "A" smd rect
			(at 0 -1.143 90)
			(size 0.5588 1.016)
			(layers "F.Cu" "F.Mask" "F.Paste")
			(net "SW_HDD_R32")
		)
		(pad "K" smd rect
			(at 0 1.143 90)
			(size 0.5588 1.016)
			(layers "F.Cu" "F.Mask" "F.Paste")
			(net "SW_HDD_N32")
		)
	)
	(footprint ""
		(layer "F.Cu")
		(at 236.819694 -244.146578)
		(property "Reference" "R73"
			(at 0 0 0)
			(layer "F.SilkS")
			(hide yes)
			(effects
				(font
					(size 1.27 1.27)
				)
			)
		)
		(property "Value" "4K7R2F-GP"
			(at 0.064008 -3.993896 0)
			(unlocked yes)
			(layer "F.Fab")
			(hide yes)
			(effects
				(font
					(size 1.016 1.016)
					(thickness 0.1524)
				)
			)
		)
		(property "Device Type" "R402H16"
			(at 0.064008 -5.517896 0)
			(unlocked yes)
			(layer "F.Fab")
			(hide yes)
			(effects
				(font
					(size 1.016 1.016)
					(thickness 0.1524)
				)
			)
		)
		(duplicate_pad_numbers_are_jumpers no)
		(fp_line
			(start -0.508 -0.9398)
			(end -0.508 0.9398)
			(stroke
				(width 0.1524)
				(type default)
			)
			(layer "F.SilkS")
		)
		(fp_line
			(start 0.508 -0.9398)
			(end -0.508 -0.9398)
			(stroke
				(width 0.1524)
				(type default)
			)
			(layer "F.SilkS")
		)
		(fp_rect
			(start -0.508 0.9398)
			(end 0.508 -0.9398)
			(stroke
				(width 0)
				(type default)
			)
			(fill no)
			(layer "F.CrtYd")
		)
		(fp_rect
			(start -0.508 0.9398)
			(end 0.508 -0.9398)
			(stroke
				(width 0)
				(type default)
			)
			(fill no)
			(layer "F.Fab")
		)
		(pad "1" smd custom
			(at 0 -0.4445)
			(size 0.1397 0.1397)
			(layers "F.Cu" "F.Mask" "F.Paste")
			(net "P3V3_STBY_A")
			(options
				(clearance outline)
				(anchor circle)
			)
			(primitives
				(gr_poly
					(pts
						(arc
							(start -0.1778 -0.2794)
							(mid -0.249642 -0.249642)
							(end -0.2794 -0.1778)
						)
						(arc
							(start -0.2794 0.1778)
							(mid -0.249642 0.249642)
							(end -0.1778 0.2794)
						)
						(arc
							(start 0.1778 0.2794)
							(mid 0.249642 0.249642)
							(end 0.2794 0.1778)
						)
						(arc
							(start 0.2794 -0.1778)
							(mid 0.249642 -0.249642)
							(end 0.1778 -0.2794)
						)
					)
					(width 0)
					(fill yes)
				)
			)
		)
		(pad "2" smd custom
			(at 0 0.4445)
			(size 0.1397 0.1397)
			(layers "F.Cu" "F.Mask" "F.Paste")
			(net "IO_EXP1_A1")
			(options
				(clearance outline)
				(anchor circle)
			)
			(primitives
				(gr_poly
					(pts
						(arc
							(start -0.1778 -0.2794)
							(mid -0.249642 -0.249642)
							(end -0.2794 -0.1778)
						)
						(arc
							(start -0.2794 0.1778)
							(mid -0.249642 0.249642)
							(end -0.1778 0.2794)
						)
						(arc
							(start 0.1778 0.2794)
							(mid 0.249642 0.249642)
							(end 0.2794 0.1778)
						)
						(arc
							(start 0.2794 -0.1778)
							(mid 0.249642 -0.249642)
							(end 0.1778 -0.2794)
						)
					)
					(width 0)
					(fill yes)
				)
			)
		)
	)
	(footprint ""
		(layer "F.Cu")
		(at 159.043878 -130.184398 -90)
		(property "Reference" "R523"
			(at 0 0 270)
			(layer "F.SilkS")
			(hide yes)
			(effects
				(font
					(size 1.27 1.27)
				)
			)
		)
		(property "Value" "4K7R2J-2-GP"
			(at 0.064008 -3.993896 270)
			(unlocked yes)
			(layer "F.Fab")
			(hide yes)
			(effects
				(font
					(size 1.016 1.016)
					(thickness 0.1524)
				)
			)
		)
		(property "Device Type" "R402H16"
			(at 0.064008 -5.517896 270)
			(unlocked yes)
			(layer "F.Fab")
			(hide yes)
			(effects
				(font
					(size 1.016 1.016)
					(thickness 0.1524)
				)
			)
		)
		(duplicate_pad_numbers_are_jumpers no)
		(fp_line
			(start -0.508 -0.9398)
			(end -0.508 0.9398)
			(stroke
				(width 0.1524)
				(type default)
			)
			(layer "F.SilkS")
		)
		(fp_line
			(start 0.508 -0.9398)
			(end -0.508 -0.9398)
			(stroke
				(width 0.1524)
				(type default)
			)
			(layer "F.SilkS")
		)
		(fp_rect
			(start -0.508 0.9398)
			(end 0.508 -0.9398)
			(stroke
				(width 0)
				(type default)
			)
			(fill no)
			(layer "F.CrtYd")
		)
		(fp_rect
			(start -0.508 0.9398)
			(end 0.508 -0.9398)
			(stroke
				(width 0)
				(type default)
			)
			(fill no)
			(layer "F.Fab")
		)
		(pad "1" smd custom
			(at 0 -0.4445 270)
			(size 0.1397 0.1397)
			(layers "F.Cu" "F.Mask" "F.Paste")
			(net "DRIVE_A_17_ACT")
			(options
				(clearance outline)
				(anchor circle)
			)
			(primitives
				(gr_poly
					(pts
						(arc
							(start -0.1778 -0.2794)
							(mid -0.249642 -0.249642)
							(end -0.2794 -0.1778)
						)
						(arc
							(start -0.2794 0.1778)
							(mid -0.249642 0.249642)
							(end -0.1778 0.2794)
						)
						(arc
							(start 0.1778 0.2794)
							(mid 0.249642 0.249642)
							(end 0.2794 0.1778)
						)
						(arc
							(start 0.2794 -0.1778)
							(mid 0.249642 -0.249642)
							(end 0.1778 -0.2794)
						)
					)
					(width 0)
					(fill yes)
				)
			)
		)
		(pad "2" smd custom
			(at 0 0.4445 270)
			(size 0.1397 0.1397)
			(layers "F.Cu" "F.Mask" "F.Paste")
			(net "GND")
			(options
				(clearance outline)
				(anchor circle)
			)
			(primitives
				(gr_poly
					(pts
						(arc
							(start -0.1778 -0.2794)
							(mid -0.249642 -0.249642)
							(end -0.2794 -0.1778)
						)
						(arc
							(start -0.2794 0.1778)
							(mid -0.249642 0.249642)
							(end -0.1778 0.2794)
						)
						(arc
							(start 0.1778 0.2794)
							(mid 0.249642 0.249642)
							(end 0.2794 0.1778)
						)
						(arc
							(start 0.2794 -0.1778)
							(mid 0.249642 -0.249642)
							(end 0.1778 -0.2794)
						)
					)
					(width 0)
					(fill yes)
				)
			)
		)
	)
	(footprint ""
		(layer "F.Cu")
		(at 266.987274 -148.925534 90)
		(property "Reference" "TP187"
			(at 0 0 90)
			(layer "F.SilkS")
			(hide yes)
			(effects
				(font
					(size 1.27 1.27)
				)
			)
		)
		(property "Value" "TPAD32-GP"
			(at -0.0508 -1.6764 90)
			(unlocked yes)
			(layer "F.Fab")
			(hide yes)
			(effects
				(font
					(size 1.016 1.016)
					(thickness 0.1524)
				)
			)
		)
		(property "Device Type" "TPAD32"
			(at -0.0508 -3.2004 90)
			(unlocked yes)
			(layer "F.Fab")
			(hide yes)
			(effects
				(font
					(size 1.016 1.016)
					(thickness 0.1524)
				)
			)
		)
		(duplicate_pad_numbers_are_jumpers no)
		(fp_poly
			(pts
				(arc
					(start 0 0.4064)
					(mid 0 -0.4064)
					(end 0 0.4064)
				)
			)
			(stroke
				(width 0)
				(type default)
			)
			(fill no)
			(layer "F.CrtYd")
		)
		(fp_poly
			(pts
				(arc
					(start 0 0.7112)
					(mid 0 -0.7112)
					(end 0 0.7112)
				)
			)
			(stroke
				(width 0)
				(type default)
			)
			(fill no)
			(layer "F.Fab")
		)
		(pad "1" smd circle
			(at 0 0 90)
			(size 0.8128 0.8128)
			(layers "F.Cu" "F.Mask" "F.Paste")
			(net "TP_COMP_B_KR_P0_RX_DP")
		)
	)
	(footprint ""
		(layer "F.Cu")
		(at 257.1496 -16.1544 90)
		(property "Reference" "R1044"
			(at 0 0 90)
			(layer "F.SilkS")
			(hide yes)
			(effects
				(font
					(size 1.27 1.27)
				)
			)
		)
		(property "Value" "100KR2F-L1-GP"
			(at 0.064008 -3.993896 90)
			(unlocked yes)
			(layer "F.Fab")
			(hide yes)
			(effects
				(font
					(size 1.016 1.016)
					(thickness 0.1524)
				)
			)
		)
		(property "Device Type" "R402H16"
			(at 0.064008 -5.517896 90)
			(unlocked yes)
			(layer "F.Fab")
			(hide yes)
			(effects
				(font
					(size 1.016 1.016)
					(thickness 0.1524)
				)
			)
		)
		(duplicate_pad_numbers_are_jumpers no)
		(fp_line
			(start 0.508 -0.9398)
			(end -0.508 -0.9398)
			(stroke
				(width 0.1524)
				(type default)
			)
			(layer "F.SilkS")
		)
		(fp_line
			(start -0.508 -0.9398)
			(end -0.508 0.9398)
			(stroke
				(width 0.1524)
				(type default)
			)
			(layer "F.SilkS")
		)
		(fp_rect
			(start -0.508 0.9398)
			(end 0.508 -0.9398)
			(stroke
				(width 0)
				(type default)
			)
			(fill no)
			(layer "F.CrtYd")
		)
		(fp_rect
			(start -0.508 0.9398)
			(end 0.508 -0.9398)
			(stroke
				(width 0)
				(type default)
			)
			(fill no)
			(layer "F.Fab")
		)
		(pad "1" smd custom
			(at 0 -0.4445 90)
			(size 0.1397 0.1397)
			(layers "F.Cu" "F.Mask" "F.Paste")
			(net "PCIE_COMP_A_TO_IOM_A_RST_4")
			(options
				(clearance outline)
				(anchor circle)
			)
			(primitives
				(gr_poly
					(pts
						(arc
							(start -0.1778 -0.2794)
							(mid -0.249642 -0.249642)
							(end -0.2794 -0.1778)
						)
						(arc
							(start -0.2794 0.1778)
							(mid -0.249642 0.249642)
							(end -0.1778 0.2794)
						)
						(arc
							(start 0.1778 0.2794)
							(mid 0.249642 0.249642)
							(end 0.2794 0.1778)
						)
						(arc
							(start 0.2794 -0.1778)
							(mid 0.249642 -0.249642)
							(end 0.1778 -0.2794)
						)
					)
					(width 0)
					(fill yes)
				)
			)
		)
		(pad "2" smd custom
			(at 0 0.4445 90)
			(size 0.1397 0.1397)
			(layers "F.Cu" "F.Mask" "F.Paste")
			(net "GND")
			(options
				(clearance outline)
				(anchor circle)
			)
			(primitives
				(gr_poly
					(pts
						(arc
							(start -0.1778 -0.2794)
							(mid -0.249642 -0.249642)
							(end -0.2794 -0.1778)
						)
						(arc
							(start -0.2794 0.1778)
							(mid -0.249642 0.249642)
							(end -0.1778 0.2794)
						)
						(arc
							(start 0.1778 0.2794)
							(mid 0.249642 0.249642)
							(end 0.2794 0.1778)
						)
						(arc
							(start 0.2794 -0.1778)
							(mid 0.249642 -0.249642)
							(end 0.1778 -0.2794)
						)
					)
					(width 0)
					(fill yes)
				)
			)
		)
	)
	(footprint ""
		(layer "F.Cu")
		(at 336.804 -62.016894)
		(property "Reference" "Q182"
			(at 0 0 0)
			(layer "F.SilkS")
			(hide yes)
			(effects
				(font
					(size 1.27 1.27)
				)
			)
		)
		(property "Value" "AO4407AL-GP"
			(at -3.707384 -1.5367 0)
			(unlocked yes)
			(layer "F.Fab")
			(hide yes)
			(effects
				(font
					(size 1.016 1.016)
					(thickness 0.1524)
				)
			)
		)
		(property "Device Type" "SOIC8H69"
			(at -3.707384 -3.0607 0)
			(unlocked yes)
			(layer "F.Fab")
			(hide yes)
			(effects
				(font
					(size 1.016 1.016)
					(thickness 0.1524)
				)
			)
		)
		(duplicate_pad_numbers_are_jumpers no)
		(fp_line
			(start -2.7432 -1.4224)
			(end -2.7432 1.4224)
			(stroke
				(width 0.1524)
				(type default)
			)
			(layer "F.SilkS")
		)
		(fp_line
			(start -2.7432 1.4224)
			(end -2.6416 1.4224)
			(stroke
				(width 0.1524)
				(type default)
			)
			(layer "F.SilkS")
		)
		(fp_line
			(start -2.7432 1.4224)
			(end 2.1336 1.4224)
			(stroke
				(width 0.1524)
				(type default)
			)
			(layer "F.SilkS")
		)
		(fp_line
			(start -2.7178 -0.508)
			(end -2.1844 -0.0508)
			(stroke
				(width 0.1524)
				(type default)
			)
			(layer "F.SilkS")
		)
		(fp_line
			(start -2.6289 3.4417)
			(end -2.6289 1.4732)
			(stroke
				(width 0.381)
				(type default)
			)
			(layer "F.SilkS")
		)
		(fp_line
			(start -2.1844 -0.0508)
			(end -2.7178 0.508)
			(stroke
				(width 0.1524)
				(type default)
			)
			(layer "F.SilkS")
		)
		(fp_line
			(start 2.1336 -1.4224)
			(end -2.7432 -1.4224)
			(stroke
				(width 0.1524)
				(type default)
			)
			(layer "F.SilkS")
		)
		(fp_line
			(start 2.1336 1.4224)
			(end 2.1336 -1.4224)
			(stroke
				(width 0.1524)
				(type default)
			)
			(layer "F.SilkS")
		)
		(fp_poly
			(pts
				(xy -2.2098 -1.4224) (xy -2.2098 1.4224) (xy 2.2098 1.4224) (xy 2.2098 -1.4224)
			)
			(stroke
				(width 0)
				(type default)
			)
			(fill yes)
			(layer "F.SilkS")
		)
		(fp_rect
			(start -2.450084 2.999994)
			(end 2.450084 -2.999994)
			(stroke
				(width 0)
				(type default)
			)
			(fill no)
			(layer "F.CrtYd")
		)
		(fp_poly
			(pts
				(xy -2.8194 3.6322) (xy -2.8194 -3.6322) (xy 2.8194 -3.6322) (xy 2.8194 1.18364) (xy 2.450084 1.18364)
				(xy 2.450084 -2.999994) (xy -2.450084 -2.999994) (xy -2.450084 2.999994) (xy 2.450084 2.999994)
				(xy 2.450084 1.18618) (xy 2.8194 1.18618) (xy 2.8194 3.6322)
			)
			(stroke
				(width 0)
				(type default)
			)
			(fill no)
			(layer "F.CrtYd")
		)
		(fp_rect
			(start -2.8194 3.6322)
			(end 2.8194 -3.6322)
			(stroke
				(width 0)
				(type default)
			)
			(fill no)
			(layer "F.Fab")
		)
		(pad "1" smd rect
			(at -1.905 2.54)
			(size 0.635 1.651)
			(layers "F.Cu" "F.Mask" "F.Paste")
			(net "P12V_A")
		)
		(pad "2" smd rect
			(at -0.635 2.54)
			(size 0.635 1.651)
			(layers "F.Cu" "F.Mask" "F.Paste")
			(net "P12V_A")
		)
		(pad "3" smd rect
			(at 0.635 2.54)
			(size 0.635 1.651)
			(layers "F.Cu" "F.Mask" "F.Paste")
			(net "P12V_A")
		)
		(pad "4" smd rect
			(at 1.905 2.54)
			(size 0.635 1.651)
			(layers "F.Cu" "F.Mask" "F.Paste")
			(net "SW_HDD_N30")
		)
		(pad "5" smd rect
			(at 1.905 -2.54)
			(size 0.635 1.651)
			(layers "F.Cu" "F.Mask" "F.Paste")
			(net "P12V_HDD30")
		)
		(pad "6" smd rect
			(at 0.635 -2.54)
			(size 0.635 1.651)
			(layers "F.Cu" "F.Mask" "F.Paste")
			(net "P12V_HDD30")
		)
		(pad "7" smd rect
			(at -0.635 -2.54)
			(size 0.635 1.651)
			(layers "F.Cu" "F.Mask" "F.Paste")
			(net "P12V_HDD30")
		)
		(pad "8" smd rect
			(at -1.905 -2.54)
			(size 0.635 1.651)
			(layers "F.Cu" "F.Mask" "F.Paste")
			(net "P12V_HDD30")
		)
	)
	(footprint ""
		(layer "F.Cu")
		(at 116.121942 -272.726404)
		(property "Reference" "R212"
			(at 0 0 0)
			(layer "F.SilkS")
			(hide yes)
			(effects
				(font
					(size 1.27 1.27)
				)
			)
		)
		(property "Value" "4K7R2J-2-GP"
			(at 0.064008 -3.993896 0)
			(unlocked yes)
			(layer "F.Fab")
			(hide yes)
			(effects
				(font
					(size 1.016 1.016)
					(thickness 0.1524)
				)
			)
		)
		(property "Device Type" "R402H16"
			(at 0.064008 -5.517896 0)
			(unlocked yes)
			(layer "F.Fab")
			(hide yes)
			(effects
				(font
					(size 1.016 1.016)
					(thickness 0.1524)
				)
			)
		)
		(duplicate_pad_numbers_are_jumpers no)
		(fp_line
			(start -0.508 -0.9398)
			(end -0.508 0.9398)
			(stroke
				(width 0.1524)
				(type default)
			)
			(layer "F.SilkS")
		)
		(fp_line
			(start 0.508 -0.9398)
			(end -0.508 -0.9398)
			(stroke
				(width 0.1524)
				(type default)
			)
			(layer "F.SilkS")
		)
		(fp_rect
			(start -0.508 0.9398)
			(end 0.508 -0.9398)
			(stroke
				(width 0)
				(type default)
			)
			(fill no)
			(layer "F.CrtYd")
		)
		(fp_rect
			(start -0.508 0.9398)
			(end 0.508 -0.9398)
			(stroke
				(width 0)
				(type default)
			)
			(fill no)
			(layer "F.Fab")
		)
		(pad "1" smd custom
			(at 0 -0.4445)
			(size 0.1397 0.1397)
			(layers "F.Cu" "F.Mask" "F.Paste")
			(net "SW_PWR_R_HDD3")
			(options
				(clearance outline)
				(anchor circle)
			)
			(primitives
				(gr_poly
					(pts
						(arc
							(start -0.1778 -0.2794)
							(mid -0.249642 -0.249642)
							(end -0.2794 -0.1778)
						)
						(arc
							(start -0.2794 0.1778)
							(mid -0.249642 0.249642)
							(end -0.1778 0.2794)
						)
						(arc
							(start 0.1778 0.2794)
							(mid 0.249642 0.249642)
							(end 0.2794 0.1778)
						)
						(arc
							(start 0.2794 -0.1778)
							(mid 0.249642 -0.249642)
							(end 0.1778 -0.2794)
						)
					)
					(width 0)
					(fill yes)
				)
			)
		)
		(pad "2" smd custom
			(at 0 0.4445)
			(size 0.1397 0.1397)
			(layers "F.Cu" "F.Mask" "F.Paste")
			(net "GND")
			(options
				(clearance outline)
				(anchor circle)
			)
			(primitives
				(gr_poly
					(pts
						(arc
							(start -0.1778 -0.2794)
							(mid -0.249642 -0.249642)
							(end -0.2794 -0.1778)
						)
						(arc
							(start -0.2794 0.1778)
							(mid -0.249642 0.249642)
							(end -0.1778 0.2794)
						)
						(arc
							(start 0.1778 0.2794)
							(mid 0.249642 0.249642)
							(end 0.2794 0.1778)
						)
						(arc
							(start 0.2794 -0.1778)
							(mid 0.249642 -0.249642)
							(end 0.1778 -0.2794)
						)
					)
					(width 0)
					(fill yes)
				)
			)
		)
	)
	(footprint ""
		(layer "F.Cu")
		(at 415.909252 -292.169342 90)
		(property "Reference" "R337"
			(at 0 0 90)
			(layer "F.SilkS")
			(hide yes)
			(effects
				(font
					(size 1.27 1.27)
				)
			)
		)
		(property "Value" "10KR2F-2-GP"
			(at 0.064008 -3.993896 90)
			(unlocked yes)
			(layer "F.Fab")
			(hide yes)
			(effects
				(font
					(size 1.016 1.016)
					(thickness 0.1524)
				)
			)
		)
		(property "Device Type" "R402H16"
			(at 0.064008 -5.517896 90)
			(unlocked yes)
			(layer "F.Fab")
			(hide yes)
			(effects
				(font
					(size 1.016 1.016)
					(thickness 0.1524)
				)
			)
		)
		(duplicate_pad_numbers_are_jumpers no)
		(fp_line
			(start 0.508 -0.9398)
			(end -0.508 -0.9398)
			(stroke
				(width 0.1524)
				(type default)
			)
			(layer "F.SilkS")
		)
		(fp_line
			(start -0.508 -0.9398)
			(end -0.508 0.9398)
			(stroke
				(width 0.1524)
				(type default)
			)
			(layer "F.SilkS")
		)
		(fp_rect
			(start -0.508 0.9398)
			(end 0.508 -0.9398)
			(stroke
				(width 0)
				(type default)
			)
			(fill no)
			(layer "F.CrtYd")
		)
		(fp_rect
			(start -0.508 0.9398)
			(end 0.508 -0.9398)
			(stroke
				(width 0)
				(type default)
			)
			(fill no)
			(layer "F.Fab")
		)
		(pad "1" smd custom
			(at 0 -0.4445 90)
			(size 0.1397 0.1397)
			(layers "F.Cu" "F.Mask" "F.Paste")
			(net "P3V3_STBY_A")
			(options
				(clearance outline)
				(anchor circle)
			)
			(primitives
				(gr_poly
					(pts
						(arc
							(start -0.1778 -0.2794)
							(mid -0.249642 -0.249642)
							(end -0.2794 -0.1778)
						)
						(arc
							(start -0.2794 0.1778)
							(mid -0.249642 0.249642)
							(end -0.1778 0.2794)
						)
						(arc
							(start 0.1778 0.2794)
							(mid 0.249642 0.249642)
							(end 0.2794 0.1778)
						)
						(arc
							(start 0.2794 -0.1778)
							(mid 0.249642 -0.249642)
							(end 0.1778 -0.2794)
						)
					)
					(width 0)
					(fill yes)
				)
			)
		)
		(pad "2" smd custom
			(at 0 0.4445 90)
			(size 0.1397 0.1397)
			(layers "F.Cu" "F.Mask" "F.Paste")
			(net "HDD_PRSNT_9")
			(options
				(clearance outline)
				(anchor circle)
			)
			(primitives
				(gr_poly
					(pts
						(arc
							(start -0.1778 -0.2794)
							(mid -0.249642 -0.249642)
							(end -0.2794 -0.1778)
						)
						(arc
							(start -0.2794 0.1778)
							(mid -0.249642 0.249642)
							(end -0.1778 0.2794)
						)
						(arc
							(start 0.1778 0.2794)
							(mid 0.249642 0.249642)
							(end 0.2794 0.1778)
						)
						(arc
							(start 0.2794 -0.1778)
							(mid 0.249642 -0.249642)
							(end 0.1778 -0.2794)
						)
					)
					(width 0)
					(fill yes)
				)
			)
		)
	)
	(footprint ""
		(layer "F.Cu")
		(at 431.962052 -47.792894 90)
		(property "Reference" "D33"
			(at 0 0 90)
			(layer "F.SilkS")
			(hide yes)
			(effects
				(font
					(size 1.27 1.27)
				)
			)
		)
		(property "Value" "RB551V30-GP"
			(at 0 -6.7818 90)
			(unlocked yes)
			(layer "F.Fab")
			(hide yes)
			(effects
				(font
					(size 1.016 1.016)
					(thickness 0.1524)
				)
			)
		)
		(property "Device Type" "SOD323AKH38"
			(at 0 -8.6868 90)
			(unlocked yes)
			(layer "F.Fab")
			(hide yes)
			(effects
				(font
					(size 1.016 1.016)
					(thickness 0.1524)
				)
			)
		)
		(duplicate_pad_numbers_are_jumpers no)
		(fp_line
			(start 0.889 -1.9304)
			(end 0.889 2.159)
			(stroke
				(width 0.1524)
				(type default)
			)
			(layer "F.SilkS")
		)
		(fp_line
			(start -0.889 -1.9304)
			(end 0.889 -1.9304)
			(stroke
				(width 0.1524)
				(type default)
			)
			(layer "F.SilkS")
		)
		(fp_line
			(start 0.762 2.0574)
			(end -0.762 2.0574)
			(stroke
				(width 0.508)
				(type default)
			)
			(layer "F.SilkS")
		)
		(fp_line
			(start 0.889 2.159)
			(end -0.889 2.159)
			(stroke
				(width 0.1524)
				(type default)
			)
			(layer "F.SilkS")
		)
		(fp_line
			(start -0.889 2.159)
			(end -0.889 -1.9304)
			(stroke
				(width 0.1524)
				(type default)
			)
			(layer "F.SilkS")
		)
		(fp_rect
			(start -1.016 2.3114)
			(end 1.016 -2.0066)
			(stroke
				(width 0)
				(type default)
			)
			(fill no)
			(layer "F.CrtYd")
		)
		(fp_poly
			(pts
				(xy -1.016 -2.0066) (xy 1.016 -2.0066) (xy 1.016 2.3114) (xy -1.016 2.3114)
			)
			(stroke
				(width 0)
				(type default)
			)
			(fill no)
			(layer "F.Fab")
		)
		(pad "A" smd rect
			(at 0 -1.143 90)
			(size 0.5588 1.016)
			(layers "F.Cu" "F.Mask" "F.Paste")
			(net "SW_HDD_R33")
		)
		(pad "K" smd rect
			(at 0 1.143 90)
			(size 0.5588 1.016)
			(layers "F.Cu" "F.Mask" "F.Paste")
			(net "SW_HDD_N33")
		)
	)
	(footprint ""
		(layer "F.Cu")
		(at 223.500442 -212.700362)
		(property "Reference" "U16"
			(at 0 0 0)
			(layer "F.SilkS")
			(hide yes)
			(effects
				(font
					(size 1.27 1.27)
				)
			)
		)
		(property "Value" "PCA9511ADP-T-GP"
			(at 0 -13.1572 0)
			(unlocked yes)
			(layer "F.Fab")
			(hide yes)
			(effects
				(font
					(size 1.016 1.016)
					(thickness 0.1524)
				)
			)
		)
		(property "Device Type" "SSOIC8-2H44"
			(at 0 -15.1892 0)
			(unlocked yes)
			(layer "F.Fab")
			(hide yes)
			(effects
				(font
					(size 1.016 1.016)
					(thickness 0.1524)
				)
			)
		)
		(duplicate_pad_numbers_are_jumpers no)
		(fp_line
			(start -1.9304 -1.016)
			(end 1.0922 -1.016)
			(stroke
				(width 0.1524)
				(type default)
			)
			(layer "F.SilkS")
		)
		(fp_line
			(start -1.9304 1.016)
			(end -1.9304 -1.016)
			(stroke
				(width 0.1524)
				(type default)
			)
			(layer "F.SilkS")
		)
		(fp_line
			(start -1.7018 1.0414)
			(end -1.7018 2.9718)
			(stroke
				(width 0.635)
				(type default)
			)
			(layer "F.SilkS")
		)
		(fp_line
			(start -1.524 0)
			(end -1.9304 -0.4064)
			(stroke
				(width 0.1524)
				(type default)
			)
			(layer "F.SilkS")
		)
		(fp_line
			(start -1.524 0)
			(end -1.9304 0.4064)
			(stroke
				(width 0.1524)
				(type default)
			)
			(layer "F.SilkS")
		)
		(fp_line
			(start 1.0922 -1.016)
			(end 1.0922 1.016)
			(stroke
				(width 0.1524)
				(type default)
			)
			(layer "F.SilkS")
		)
		(fp_line
			(start 1.0922 1.016)
			(end -1.9304 1.016)
			(stroke
				(width 0.1524)
				(type default)
			)
			(layer "F.SilkS")
		)
		(fp_poly
			(pts
				(xy -1.1938 -1.016) (xy 1.0922 -1.016) (xy 1.0922 1.016) (xy -1.1938 1.016)
			)
			(stroke
				(width 0)
				(type default)
			)
			(fill yes)
			(layer "F.SilkS")
		)
		(fp_rect
			(start -2.0066 3.3401)
			(end 2.0066 -3.3401)
			(stroke
				(width 0)
				(type default)
			)
			(fill no)
			(layer "F.CrtYd")
		)
		(fp_poly
			(pts
				(xy -2.0066 -3.3401) (xy 2.0066 -3.3401) (xy 2.0066 3.3401) (xy -2.0066 3.3401)
			)
			(stroke
				(width 0)
				(type default)
			)
			(fill no)
			(layer "F.Fab")
		)
		(pad "1" smd rect
			(at -0.97536 2.0701)
			(size 0.4064 1.524)
			(layers "F.Cu" "F.Mask" "F.Paste")
			(net "I2C_SCC_BUFF_EN")
		)
		(pad "2" smd rect
			(at -0.32512 2.0701)
			(size 0.4064 1.524)
			(layers "F.Cu" "F.Mask" "F.Paste")
			(net "I2C_SCC_A_SCL_BUF")
		)
		(pad "3" smd rect
			(at 0.32512 2.0701)
			(size 0.4064 1.524)
			(layers "F.Cu" "F.Mask" "F.Paste")
			(net "I2C_SCC_A_SCL")
		)
		(pad "4" smd rect
			(at 0.97536 2.0701)
			(size 0.4064 1.524)
			(layers "F.Cu" "F.Mask" "F.Paste")
			(net "GND")
		)
		(pad "5" smd rect
			(at 0.97536 -2.0701)
			(size 0.4064 1.524)
			(layers "F.Cu" "F.Mask" "F.Paste")
			(net "I2C_SCC_BUFF_READY")
		)
		(pad "6" smd rect
			(at 0.32512 -2.0701)
			(size 0.4064 1.524)
			(layers "F.Cu" "F.Mask" "F.Paste")
			(net "I2C_SCC_A_SDA")
		)
		(pad "7" smd rect
			(at -0.32512 -2.0701)
			(size 0.4064 1.524)
			(layers "F.Cu" "F.Mask" "F.Paste")
			(net "I2C_SCC_A_SDA_BUF")
		)
		(pad "8" smd rect
			(at -0.97536 -2.0701)
			(size 0.4064 1.524)
			(layers "F.Cu" "F.Mask" "F.Paste")
			(net "P3V3_STBY_A")
		)
	)
	(footprint ""
		(layer "F.Cu")
		(at 336.804 -177.016918)
		(property "Reference" "Q110"
			(at 0 0 0)
			(layer "F.SilkS")
			(hide yes)
			(effects
				(font
					(size 1.27 1.27)
				)
			)
		)
		(property "Value" "AO4407AL-GP"
			(at -3.707384 -1.5367 0)
			(unlocked yes)
			(layer "F.Fab")
			(hide yes)
			(effects
				(font
					(size 1.016 1.016)
					(thickness 0.1524)
				)
			)
		)
		(property "Device Type" "SOIC8H69"
			(at -3.707384 -3.0607 0)
			(unlocked yes)
			(layer "F.Fab")
			(hide yes)
			(effects
				(font
					(size 1.016 1.016)
					(thickness 0.1524)
				)
			)
		)
		(duplicate_pad_numbers_are_jumpers no)
		(fp_line
			(start -2.7432 -1.4224)
			(end -2.7432 1.4224)
			(stroke
				(width 0.1524)
				(type default)
			)
			(layer "F.SilkS")
		)
		(fp_line
			(start -2.7432 1.4224)
			(end -2.6416 1.4224)
			(stroke
				(width 0.1524)
				(type default)
			)
			(layer "F.SilkS")
		)
		(fp_line
			(start -2.7432 1.4224)
			(end 2.1336 1.4224)
			(stroke
				(width 0.1524)
				(type default)
			)
			(layer "F.SilkS")
		)
		(fp_line
			(start -2.7178 -0.508)
			(end -2.1844 -0.0508)
			(stroke
				(width 0.1524)
				(type default)
			)
			(layer "F.SilkS")
		)
		(fp_line
			(start -2.6289 3.4417)
			(end -2.6289 1.4732)
			(stroke
				(width 0.381)
				(type default)
			)
			(layer "F.SilkS")
		)
		(fp_line
			(start -2.1844 -0.0508)
			(end -2.7178 0.508)
			(stroke
				(width 0.1524)
				(type default)
			)
			(layer "F.SilkS")
		)
		(fp_line
			(start 2.1336 -1.4224)
			(end -2.7432 -1.4224)
			(stroke
				(width 0.1524)
				(type default)
			)
			(layer "F.SilkS")
		)
		(fp_line
			(start 2.1336 1.4224)
			(end 2.1336 -1.4224)
			(stroke
				(width 0.1524)
				(type default)
			)
			(layer "F.SilkS")
		)
		(fp_poly
			(pts
				(xy -2.2098 -1.4224) (xy -2.2098 1.4224) (xy 2.2098 1.4224) (xy 2.2098 -1.4224)
			)
			(stroke
				(width 0)
				(type default)
			)
			(fill yes)
			(layer "F.SilkS")
		)
		(fp_rect
			(start -2.450084 2.999994)
			(end 2.450084 -2.999994)
			(stroke
				(width 0)
				(type default)
			)
			(fill no)
			(layer "F.CrtYd")
		)
		(fp_poly
			(pts
				(xy -2.8194 3.6322) (xy -2.8194 -3.6322) (xy 2.8194 -3.6322) (xy 2.8194 1.18364) (xy 2.450084 1.18364)
				(xy 2.450084 -2.999994) (xy -2.450084 -2.999994) (xy -2.450084 2.999994) (xy 2.450084 2.999994)
				(xy 2.450084 1.18618) (xy 2.8194 1.18618) (xy 2.8194 3.6322)
			)
			(stroke
				(width 0)
				(type default)
			)
			(fill no)
			(layer "F.CrtYd")
		)
		(fp_rect
			(start -2.8194 3.6322)
			(end 2.8194 -3.6322)
			(stroke
				(width 0)
				(type default)
			)
			(fill no)
			(layer "F.Fab")
		)
		(pad "1" smd rect
			(at -1.905 2.54)
			(size 0.635 1.651)
			(layers "F.Cu" "F.Mask" "F.Paste")
			(net "P12V_A")
		)
		(pad "2" smd rect
			(at -0.635 2.54)
			(size 0.635 1.651)
			(layers "F.Cu" "F.Mask" "F.Paste")
			(net "P12V_A")
		)
		(pad "3" smd rect
			(at 0.635 2.54)
			(size 0.635 1.651)
			(layers "F.Cu" "F.Mask" "F.Paste")
			(net "P12V_A")
		)
		(pad "4" smd rect
			(at 1.905 2.54)
			(size 0.635 1.651)
			(layers "F.Cu" "F.Mask" "F.Paste")
			(net "SW_HDD_N18")
		)
		(pad "5" smd rect
			(at 1.905 -2.54)
			(size 0.635 1.651)
			(layers "F.Cu" "F.Mask" "F.Paste")
			(net "P12V_HDD18")
		)
		(pad "6" smd rect
			(at 0.635 -2.54)
			(size 0.635 1.651)
			(layers "F.Cu" "F.Mask" "F.Paste")
			(net "P12V_HDD18")
		)
		(pad "7" smd rect
			(at -0.635 -2.54)
			(size 0.635 1.651)
			(layers "F.Cu" "F.Mask" "F.Paste")
			(net "P12V_HDD18")
		)
		(pad "8" smd rect
			(at -1.905 -2.54)
			(size 0.635 1.651)
			(layers "F.Cu" "F.Mask" "F.Paste")
			(net "P12V_HDD18")
		)
	)
	(footprint ""
		(layer "F.Cu")
		(at 428.192184 -69.434964 -90)
		(property "Reference" "R890"
			(at 0 0 270)
			(layer "F.SilkS")
			(hide yes)
			(effects
				(font
					(size 1.27 1.27)
				)
			)
		)
		(property "Value" "2R6F-GP"
			(at -0.0508 -4.8514 270)
			(unlocked yes)
			(layer "F.Fab")
			(hide yes)
			(effects
				(font
					(size 1.016 1.016)
					(thickness 0.1524)
				)
			)
		)
		(property "Device Type" "R1206H26"
			(at 0 -6.3754 270)
			(unlocked yes)
			(layer "F.Fab")
			(hide yes)
			(effects
				(font
					(size 1.016 1.016)
					(thickness 0.1524)
				)
			)
		)
		(duplicate_pad_numbers_are_jumpers no)
		(fp_line
			(start -1.016 2.2352)
			(end -1.016 -2.2352)
			(stroke
				(width 0.1524)
				(type default)
			)
			(layer "F.SilkS")
		)
		(fp_line
			(start 1.016 2.2352)
			(end -1.016 2.2352)
			(stroke
				(width 0.1524)
				(type default)
			)
			(layer "F.SilkS")
		)
		(fp_line
			(start -1.016 -2.2352)
			(end 1.016 -2.2352)
			(stroke
				(width 0.1524)
				(type default)
			)
			(layer "F.SilkS")
		)
		(fp_line
			(start 1.016 -2.2352)
			(end 1.016 2.2352)
			(stroke
				(width 0.1524)
				(type default)
			)
			(layer "F.SilkS")
		)
		(fp_rect
			(start -1.0922 2.3114)
			(end 1.0922 -2.3114)
			(stroke
				(width 0)
				(type default)
			)
			(fill no)
			(layer "F.CrtYd")
		)
		(fp_poly
			(pts
				(xy -1.0922 -2.3114) (xy 1.0922 -2.3114) (xy 1.0922 2.3114) (xy -1.0922 2.3114)
			)
			(stroke
				(width 0)
				(type default)
			)
			(fill no)
			(layer "F.Fab")
		)
		(pad "1" smd rect
			(at 0 -1.397 270)
			(size 1.651 1.27)
			(layers "F.Cu" "F.Mask" "F.Paste")
			(net "P12V_HDD33")
		)
		(pad "2" smd rect
			(at 0 1.397 270)
			(size 1.651 1.27)
			(layers "F.Cu" "F.Mask" "F.Paste")
			(net "12V_PRE_33")
		)
	)
	(footprint ""
		(layer "F.Cu")
		(at 361.369102 -181.842918 180)
		(property "Reference" "C287"
			(at 0 0 180)
			(layer "F.SilkS")
			(hide yes)
			(effects
				(font
					(size 1.27 1.27)
				)
			)
		)
		(property "Value" "SC1U16V3KX-5GP"
			(at 0 -2.8194 180)
			(unlocked yes)
			(layer "F.Fab")
			(hide yes)
			(effects
				(font
					(size 1.016 1.016)
					(thickness 0.1524)
				)
			)
		)
		(property "Device Type" "C603H36"
			(at 0 -4.3434 180)
			(unlocked yes)
			(layer "F.Fab")
			(hide yes)
			(effects
				(font
					(size 1.016 1.016)
					(thickness 0.1524)
				)
			)
		)
		(duplicate_pad_numbers_are_jumpers no)
		(fp_line
			(start 0.508 0)
			(end -0.508 0)
			(stroke
				(width 0.2032)
				(type default)
			)
			(layer "F.SilkS")
		)
		(fp_rect
			(start -0.5842 1.3335)
			(end 0.5842 -1.3335)
			(stroke
				(width 0)
				(type default)
			)
			(fill no)
			(layer "F.CrtYd")
		)
		(fp_rect
			(start -0.5842 1.3335)
			(end 0.5842 -1.3335)
			(stroke
				(width 0)
				(type default)
			)
			(fill no)
			(layer "F.Fab")
		)
		(pad "1" smd custom
			(at 0 -0.762 180)
			(size 0.2159 0.2159)
			(layers "F.Cu" "F.Mask" "F.Paste")
			(net "P5V_HDD19")
			(options
				(clearance outline)
				(anchor circle)
			)
			(primitives
				(gr_poly
					(pts
						(arc
							(start -0.3302 -0.4318)
							(mid -0.402042 -0.402042)
							(end -0.4318 -0.3302)
						)
						(arc
							(start -0.4318 0.3302)
							(mid -0.402042 0.402042)
							(end -0.3302 0.4318)
						)
						(arc
							(start 0.3302 0.4318)
							(mid 0.402042 0.402042)
							(end 0.4318 0.3302)
						)
						(arc
							(start 0.4318 -0.3302)
							(mid 0.402042 -0.402042)
							(end 0.3302 -0.4318)
						)
					)
					(width 0)
					(fill yes)
				)
			)
		)
		(pad "2" smd custom
			(at 0 0.762 180)
			(size 0.2159 0.2159)
			(layers "F.Cu" "F.Mask" "F.Paste")
			(net "GND")
			(options
				(clearance outline)
				(anchor circle)
			)
			(primitives
				(gr_poly
					(pts
						(arc
							(start -0.3302 -0.4318)
							(mid -0.402042 -0.402042)
							(end -0.4318 -0.3302)
						)
						(arc
							(start -0.4318 0.3302)
							(mid -0.402042 0.402042)
							(end -0.3302 0.4318)
						)
						(arc
							(start 0.3302 0.4318)
							(mid 0.402042 0.402042)
							(end 0.4318 0.3302)
						)
						(arc
							(start 0.4318 -0.3302)
							(mid 0.402042 -0.402042)
							(end 0.3302 -0.4318)
						)
					)
					(width 0)
					(fill yes)
				)
			)
		)
	)
	(footprint ""
		(layer "F.Cu")
		(at 477.739202 -158.939992 90)
		(property "Reference" "VIA11"
			(at 0 0 90)
			(layer "F.SilkS")
			(hide yes)
			(effects
				(font
					(size 1.27 1.27)
				)
			)
		)
		(property "Value" "100OHM-8L-1D6MM-L18L16-GP"
			(at -3.7211 -4.5085 90)
			(unlocked yes)
			(layer "F.Fab")
			(hide yes)
			(effects
				(font
					(size 1.016 1.016)
					(thickness 0.1524)
				)
			)
		)
		(property "Device Type" "VIA-PCIE-4P-394076"
			(at -3.7211 -6.0325 90)
			(unlocked yes)
			(layer "F.Fab")
			(hide yes)
			(effects
				(font
					(size 1.016 1.016)
					(thickness 0.1524)
				)
			)
		)
		(duplicate_pad_numbers_are_jumpers no)
		(fp_rect
			(start -1.9685 0.381)
			(end 1.9685 -0.381)
			(stroke
				(width 0)
				(type default)
			)
			(fill no)
			(layer "F.CrtYd")
		)
		(fp_rect
			(start -1.9685 0.381)
			(end 1.9685 -0.381)
			(stroke
				(width 0)
				(type default)
			)
			(fill no)
			(layer "F.Fab")
		)
		(pad "1" thru_hole circle
			(at -1.5875 0 90)
			(size 0.508 0.508)
			(drill 0.254)
			(layers "*.Cu" "*.Mask")
			(remove_unused_layers no)
			(net "GND")
			(clearance 0.127)
			(thermal_gap 0.127)
		)
		(pad "2" thru_hole circle
			(at -0.5715 0 90)
			(size 0.508 0.508)
			(drill 0.254)
			(layers "*.Cu" "*.Mask")
			(remove_unused_layers no)
			(net "PHY_SCC_A_TO_DRV_A_23_DP")
			(clearance 0.127)
			(thermal_gap 0.127)
		)
		(pad "3" thru_hole circle
			(at 0.5715 0 90)
			(size 0.508 0.508)
			(drill 0.254)
			(layers "*.Cu" "*.Mask")
			(remove_unused_layers no)
			(net "PHY_SCC_A_TO_DRV_A_23_DN")
			(clearance 0.127)
			(thermal_gap 0.127)
		)
		(pad "4" thru_hole circle
			(at 1.5875 0 90)
			(size 0.508 0.508)
			(drill 0.254)
			(layers "*.Cu" "*.Mask")
			(remove_unused_layers no)
			(net "GND")
			(clearance 0.127)
			(thermal_gap 0.127)
		)
	)
	(footprint ""
		(layer "F.Cu")
		(at 444.541402 -256.34315 180)
		(property "Reference" "R1260"
			(at 0 0 180)
			(layer "F.SilkS")
			(hide yes)
			(effects
				(font
					(size 1.27 1.27)
				)
			)
		)
		(property "Value" "619KR2F-GP"
			(at 0.064008 -3.993896 180)
			(unlocked yes)
			(layer "F.Fab")
			(hide yes)
			(effects
				(font
					(size 1.016 1.016)
					(thickness 0.1524)
				)
			)
		)
		(property "Device Type" "R402H16"
			(at 0.064008 -5.517896 180)
			(unlocked yes)
			(layer "F.Fab")
			(hide yes)
			(effects
				(font
					(size 1.016 1.016)
					(thickness 0.1524)
				)
			)
		)
		(duplicate_pad_numbers_are_jumpers no)
		(fp_line
			(start 0.508 -0.9398)
			(end -0.508 -0.9398)
			(stroke
				(width 0.1524)
				(type default)
			)
			(layer "F.SilkS")
		)
		(fp_line
			(start -0.508 -0.9398)
			(end -0.508 0.9398)
			(stroke
				(width 0.1524)
				(type default)
			)
			(layer "F.SilkS")
		)
		(fp_rect
			(start -0.508 0.9398)
			(end 0.508 -0.9398)
			(stroke
				(width 0)
				(type default)
			)
			(fill no)
			(layer "F.CrtYd")
		)
		(fp_rect
			(start -0.508 0.9398)
			(end 0.508 -0.9398)
			(stroke
				(width 0)
				(type default)
			)
			(fill no)
			(layer "F.Fab")
		)
		(pad "1" smd custom
			(at 0 -0.4445 180)
			(size 0.1397 0.1397)
			(layers "F.Cu" "F.Mask" "F.Paste")
			(net "P5V_C_RF")
			(options
				(clearance outline)
				(anchor circle)
			)
			(primitives
				(gr_poly
					(pts
						(arc
							(start -0.1778 -0.2794)
							(mid -0.249642 -0.249642)
							(end -0.2794 -0.1778)
						)
						(arc
							(start -0.2794 0.1778)
							(mid -0.249642 0.249642)
							(end -0.1778 0.2794)
						)
						(arc
							(start 0.1778 0.2794)
							(mid 0.249642 0.249642)
							(end 0.2794 0.1778)
						)
						(arc
							(start 0.2794 -0.1778)
							(mid 0.249642 -0.249642)
							(end 0.1778 -0.2794)
						)
					)
					(width 0)
					(fill yes)
				)
			)
		)
		(pad "2" smd custom
			(at 0 0.4445 180)
			(size 0.1397 0.1397)
			(layers "F.Cu" "F.Mask" "F.Paste")
			(net "AGND_P5V_C")
			(options
				(clearance outline)
				(anchor circle)
			)
			(primitives
				(gr_poly
					(pts
						(arc
							(start -0.1778 -0.2794)
							(mid -0.249642 -0.249642)
							(end -0.2794 -0.1778)
						)
						(arc
							(start -0.2794 0.1778)
							(mid -0.249642 0.249642)
							(end -0.1778 0.2794)
						)
						(arc
							(start 0.1778 0.2794)
							(mid 0.249642 0.249642)
							(end 0.2794 0.1778)
						)
						(arc
							(start 0.2794 -0.1778)
							(mid 0.249642 -0.249642)
							(end 0.1778 -0.2794)
						)
					)
					(width 0)
					(fill yes)
				)
			)
		)
	)
	(footprint ""
		(layer "F.Cu")
		(at 244.221 -231.14)
		(property "Reference" "R78"
			(at 0 0 0)
			(layer "F.SilkS")
			(hide yes)
			(effects
				(font
					(size 1.27 1.27)
				)
			)
		)
		(property "Value" "4K7R2F-GP"
			(at 0.064008 -3.993896 0)
			(unlocked yes)
			(layer "F.Fab")
			(hide yes)
			(effects
				(font
					(size 1.016 1.016)
					(thickness 0.1524)
				)
			)
		)
		(property "Device Type" "R402H16"
			(at 0.064008 -5.517896 0)
			(unlocked yes)
			(layer "F.Fab")
			(hide yes)
			(effects
				(font
					(size 1.016 1.016)
					(thickness 0.1524)
				)
			)
		)
		(duplicate_pad_numbers_are_jumpers no)
		(fp_line
			(start -0.508 -0.9398)
			(end -0.508 0.9398)
			(stroke
				(width 0.1524)
				(type default)
			)
			(layer "F.SilkS")
		)
		(fp_line
			(start 0.508 -0.9398)
			(end -0.508 -0.9398)
			(stroke
				(width 0.1524)
				(type default)
			)
			(layer "F.SilkS")
		)
		(fp_rect
			(start -0.508 0.9398)
			(end 0.508 -0.9398)
			(stroke
				(width 0)
				(type default)
			)
			(fill no)
			(layer "F.CrtYd")
		)
		(fp_rect
			(start -0.508 0.9398)
			(end 0.508 -0.9398)
			(stroke
				(width 0)
				(type default)
			)
			(fill no)
			(layer "F.Fab")
		)
		(pad "1" smd custom
			(at 0 -0.4445)
			(size 0.1397 0.1397)
			(layers "F.Cu" "F.Mask" "F.Paste")
			(net "IO_EXP2_A1")
			(options
				(clearance outline)
				(anchor circle)
			)
			(primitives
				(gr_poly
					(pts
						(arc
							(start -0.1778 -0.2794)
							(mid -0.249642 -0.249642)
							(end -0.2794 -0.1778)
						)
						(arc
							(start -0.2794 0.1778)
							(mid -0.249642 0.249642)
							(end -0.1778 0.2794)
						)
						(arc
							(start 0.1778 0.2794)
							(mid 0.249642 0.249642)
							(end 0.2794 0.1778)
						)
						(arc
							(start 0.2794 -0.1778)
							(mid 0.249642 -0.249642)
							(end 0.1778 -0.2794)
						)
					)
					(width 0)
					(fill yes)
				)
			)
		)
		(pad "2" smd custom
			(at 0 0.4445)
			(size 0.1397 0.1397)
			(layers "F.Cu" "F.Mask" "F.Paste")
			(net "GND")
			(options
				(clearance outline)
				(anchor circle)
			)
			(primitives
				(gr_poly
					(pts
						(arc
							(start -0.1778 -0.2794)
							(mid -0.249642 -0.249642)
							(end -0.2794 -0.1778)
						)
						(arc
							(start -0.2794 0.1778)
							(mid -0.249642 0.249642)
							(end -0.1778 0.2794)
						)
						(arc
							(start 0.1778 0.2794)
							(mid 0.249642 0.249642)
							(end 0.2794 0.1778)
						)
						(arc
							(start 0.2794 -0.1778)
							(mid 0.249642 -0.249642)
							(end 0.1778 -0.2794)
						)
					)
					(width 0)
					(fill yes)
				)
			)
		)
	)
	(footprint ""
		(layer "F.Cu")
		(at 458.5589 -180.826918 180)
		(property "Reference" "C327"
			(at 0 0 180)
			(layer "F.SilkS")
			(hide yes)
			(effects
				(font
					(size 1.27 1.27)
				)
			)
		)
		(property "Value" "SC10U16V6KX-2GP"
			(at -0.0762 -5.1308 180)
			(unlocked yes)
			(layer "F.Fab")
			(hide yes)
			(effects
				(font
					(size 1.016 1.016)
					(thickness 0.1524)
				)
			)
		)
		(property "Device Type" "C1206H71"
			(at -0.127 -6.6548 180)
			(unlocked yes)
			(layer "F.Fab")
			(hide yes)
			(effects
				(font
					(size 1.016 1.016)
					(thickness 0.1524)
				)
			)
		)
		(duplicate_pad_numbers_are_jumpers no)
		(fp_line
			(start 1.016 2.2352)
			(end -1.016 2.2352)
			(stroke
				(width 0.1524)
				(type default)
			)
			(layer "F.SilkS")
		)
		(fp_line
			(start 1.016 0.8382)
			(end 1.016 2.2352)
			(stroke
				(width 0.1524)
				(type default)
			)
			(layer "F.SilkS")
		)
		(fp_line
			(start 1.016 -2.2352)
			(end 1.016 -0.8382)
			(stroke
				(width 0.1524)
				(type default)
			)
			(layer "F.SilkS")
		)
		(fp_line
			(start -1.016 2.2352)
			(end -1.016 0.8382)
			(stroke
				(width 0.1524)
				(type default)
			)
			(layer "F.SilkS")
		)
		(fp_line
			(start -1.016 -0.8382)
			(end -1.016 -2.2352)
			(stroke
				(width 0.1524)
				(type default)
			)
			(layer "F.SilkS")
		)
		(fp_line
			(start -1.016 -2.2352)
			(end 1.016 -2.2352)
			(stroke
				(width 0.1524)
				(type default)
			)
			(layer "F.SilkS")
		)
		(fp_rect
			(start -1.0922 2.3114)
			(end 1.0922 -2.3114)
			(stroke
				(width 0)
				(type default)
			)
			(fill no)
			(layer "F.CrtYd")
		)
		(fp_poly
			(pts
				(xy 1.0922 -2.3114) (xy 1.0922 2.3114) (xy -1.0922 2.3114) (xy -1.0922 -2.3114)
			)
			(stroke
				(width 0)
				(type default)
			)
			(fill no)
			(layer "F.Fab")
		)
		(pad "1" smd rect
			(at 0 -1.397 180)
			(size 1.651 1.27)
			(layers "F.Cu" "F.Mask" "F.Paste")
			(net "P5V_HDD22")
		)
		(pad "2" smd rect
			(at 0 1.397 180)
			(size 1.651 1.27)
			(layers "F.Cu" "F.Mask" "F.Paste")
			(net "GND")
		)
	)
	(footprint ""
		(layer "F.Cu")
		(at 261.932166 -336.350864 90)
		(property "Reference" "R386"
			(at 0 0 90)
			(layer "F.SilkS")
			(hide yes)
			(effects
				(font
					(size 1.27 1.27)
				)
			)
		)
		(property "Value" "10KR2F-2-GP"
			(at 0.064008 -3.993896 90)
			(unlocked yes)
			(layer "F.Fab")
			(hide yes)
			(effects
				(font
					(size 1.016 1.016)
					(thickness 0.1524)
				)
			)
		)
		(property "Device Type" "R402H16"
			(at 0.064008 -5.517896 90)
			(unlocked yes)
			(layer "F.Fab")
			(hide yes)
			(effects
				(font
					(size 1.016 1.016)
					(thickness 0.1524)
				)
			)
		)
		(duplicate_pad_numbers_are_jumpers no)
		(fp_line
			(start 0.508 -0.9398)
			(end -0.508 -0.9398)
			(stroke
				(width 0.1524)
				(type default)
			)
			(layer "F.SilkS")
		)
		(fp_line
			(start -0.508 -0.9398)
			(end -0.508 0.9398)
			(stroke
				(width 0.1524)
				(type default)
			)
			(layer "F.SilkS")
		)
		(fp_rect
			(start -0.508 0.9398)
			(end 0.508 -0.9398)
			(stroke
				(width 0)
				(type default)
			)
			(fill no)
			(layer "F.CrtYd")
		)
		(fp_rect
			(start -0.508 0.9398)
			(end 0.508 -0.9398)
			(stroke
				(width 0)
				(type default)
			)
			(fill no)
			(layer "F.Fab")
		)
		(pad "1" smd custom
			(at 0 -0.4445 90)
			(size 0.1397 0.1397)
			(layers "F.Cu" "F.Mask" "F.Paste")
			(net "P3V3_STBY_A")
			(options
				(clearance outline)
				(anchor circle)
			)
			(primitives
				(gr_poly
					(pts
						(arc
							(start -0.1778 -0.2794)
							(mid -0.249642 -0.249642)
							(end -0.2794 -0.1778)
						)
						(arc
							(start -0.2794 0.1778)
							(mid -0.249642 0.249642)
							(end -0.1778 0.2794)
						)
						(arc
							(start 0.1778 0.2794)
							(mid 0.249642 0.249642)
							(end 0.2794 0.1778)
						)
						(arc
							(start 0.2794 -0.1778)
							(mid 0.249642 -0.249642)
							(end 0.1778 -0.2794)
						)
					)
					(width 0)
					(fill yes)
				)
			)
		)
		(pad "2" smd custom
			(at 0 0.4445 90)
			(size 0.1397 0.1397)
			(layers "F.Cu" "F.Mask" "F.Paste")
			(net "SCC_A_TYPE_2")
			(options
				(clearance outline)
				(anchor circle)
			)
			(primitives
				(gr_poly
					(pts
						(arc
							(start -0.1778 -0.2794)
							(mid -0.249642 -0.249642)
							(end -0.2794 -0.1778)
						)
						(arc
							(start -0.2794 0.1778)
							(mid -0.249642 0.249642)
							(end -0.1778 0.2794)
						)
						(arc
							(start 0.1778 0.2794)
							(mid 0.249642 0.249642)
							(end 0.2794 0.1778)
						)
						(arc
							(start 0.2794 -0.1778)
							(mid 0.249642 -0.249642)
							(end 0.1778 -0.2794)
						)
					)
					(width 0)
					(fill yes)
				)
			)
		)
	)
	(footprint ""
		(layer "F.Cu")
		(at 86.832948 -177.270918)
		(property "Reference" "R451"
			(at 0 0 0)
			(layer "F.SilkS")
			(hide yes)
			(effects
				(font
					(size 1.27 1.27)
				)
			)
		)
		(property "Value" "2R6F-GP"
			(at -0.0508 -4.8514 0)
			(unlocked yes)
			(layer "F.Fab")
			(hide yes)
			(effects
				(font
					(size 1.016 1.016)
					(thickness 0.1524)
				)
			)
		)
		(property "Device Type" "R1206H26"
			(at 0 -6.3754 0)
			(unlocked yes)
			(layer "F.Fab")
			(hide yes)
			(effects
				(font
					(size 1.016 1.016)
					(thickness 0.1524)
				)
			)
		)
		(duplicate_pad_numbers_are_jumpers no)
		(fp_line
			(start -1.016 -2.2352)
			(end 1.016 -2.2352)
			(stroke
				(width 0.1524)
				(type default)
			)
			(layer "F.SilkS")
		)
		(fp_line
			(start -1.016 2.2352)
			(end -1.016 -2.2352)
			(stroke
				(width 0.1524)
				(type default)
			)
			(layer "F.SilkS")
		)
		(fp_line
			(start 1.016 -2.2352)
			(end 1.016 2.2352)
			(stroke
				(width 0.1524)
				(type default)
			)
			(layer "F.SilkS")
		)
		(fp_line
			(start 1.016 2.2352)
			(end -1.016 2.2352)
			(stroke
				(width 0.1524)
				(type default)
			)
			(layer "F.SilkS")
		)
		(fp_rect
			(start -1.0922 2.3114)
			(end 1.0922 -2.3114)
			(stroke
				(width 0)
				(type default)
			)
			(fill no)
			(layer "F.CrtYd")
		)
		(fp_poly
			(pts
				(xy -1.0922 -2.3114) (xy 1.0922 -2.3114) (xy 1.0922 2.3114) (xy -1.0922 2.3114)
			)
			(stroke
				(width 0)
				(type default)
			)
			(fill no)
			(layer "F.Fab")
		)
		(pad "1" smd rect
			(at 0 -1.397)
			(size 1.651 1.27)
			(layers "F.Cu" "F.Mask" "F.Paste")
			(net "P5V_HDD14")
		)
		(pad "2" smd rect
			(at 0 1.397)
			(size 1.651 1.27)
			(layers "F.Cu" "F.Mask" "F.Paste")
			(net "5V_PRE_14")
		)
	)
	(footprint ""
		(layer "F.Cu")
		(at 154.399996 -287.910016 -90)
		(property "Reference" "HDDSAS4"
			(at 0 0 270)
			(layer "F.SilkS")
			(hide yes)
			(effects
				(font
					(size 1.27 1.27)
				)
			)
		)
		(property "Value" "SKT-SAS15P-14P-45-GP"
			(at -20.7645 -8.9789 270)
			(unlocked yes)
			(layer "F.Fab")
			(hide yes)
			(effects
				(font
					(size 1.016 1.016)
					(thickness 0.1524)
				)
			)
		)
		(property "Device Type" "10120818-001C-TRLF"
			(at -20.7645 -10.5029 270)
			(unlocked yes)
			(layer "F.Fab")
			(hide yes)
			(effects
				(font
					(size 1.016 1.016)
					(thickness 0.1524)
				)
			)
		)
		(duplicate_pad_numbers_are_jumpers no)
		(fp_line
			(start 1.651 4.2926)
			(end 1.651 3.0099)
			(stroke
				(width 0.1524)
				(type default)
			)
			(layer "F.SilkS")
		)
		(fp_line
			(start 8.509 4.2926)
			(end 1.651 4.2926)
			(stroke
				(width 0.1524)
				(type default)
			)
			(layer "F.SilkS")
		)
		(fp_line
			(start -23.4188 3.0099)
			(end -23.4188 -3.2512)
			(stroke
				(width 0.1524)
				(type default)
			)
			(layer "F.SilkS")
		)
		(fp_line
			(start 1.651 3.0099)
			(end -23.4188 3.0099)
			(stroke
				(width 0.1524)
				(type default)
			)
			(layer "F.SilkS")
		)
		(fp_line
			(start 8.509 3.0099)
			(end 8.509 4.2926)
			(stroke
				(width 0.1524)
				(type default)
			)
			(layer "F.SilkS")
		)
		(fp_line
			(start 23.4188 3.0099)
			(end 8.509 3.0099)
			(stroke
				(width 0.1524)
				(type default)
			)
			(layer "F.SilkS")
		)
		(fp_line
			(start -23.4188 -3.2512)
			(end 23.4188 -3.2512)
			(stroke
				(width 0.1524)
				(type default)
			)
			(layer "F.SilkS")
		)
		(fp_line
			(start 23.4188 -3.2512)
			(end 23.4188 3.0099)
			(stroke
				(width 0.1524)
				(type default)
			)
			(layer "F.SilkS")
		)
		(fp_line
			(start 15.5067 -3.3401)
			(end 16.2687 -3.3401)
			(stroke
				(width 0.3302)
				(type default)
			)
			(layer "F.SilkS")
		)
		(fp_poly
			(pts
				(xy 15.868904 -3.230372) (xy 16.503904 -3.865372) (xy 15.233904 -3.865372)
			)
			(stroke
				(width 0)
				(type default)
			)
			(fill yes)
			(layer "F.SilkS")
		)
		(fp_poly
			(pts
				(xy -22.8727 -2.7559) (xy 22.8727 -2.7559) (xy 22.8727 2.7559) (xy 8.255 2.7559) (xy 8.255 3.5179)
				(xy 1.905 3.5179) (xy 1.905 2.7559) (xy -22.8727 2.7559)
			)
			(stroke
				(width 0)
				(type default)
			)
			(fill no)
			(layer "F.CrtYd")
		)
		(fp_poly
			(pts
				(xy 1.397 4.5466) (xy 1.397 3.2639) (xy -23.6728 3.2639) (xy -23.6728 -3.5052) (xy 23.6728 -3.5052)
				(xy 23.6728 -0.00635) (xy 22.8727 -0.00635) (xy 22.8727 -2.7559) (xy -22.8727 -2.7559) (xy -22.8727 2.7559)
				(xy 1.905 2.7559) (xy 1.905 3.5179) (xy 8.255 3.5179) (xy 8.255 2.7559) (xy 22.8727 2.7559) (xy 22.8727 0.00635)
				(xy 23.6728 0.00635) (xy 23.6728 3.2639) (xy 8.763 3.2639) (xy 8.763 4.5466)
			)
			(stroke
				(width 0)
				(type default)
			)
			(fill no)
			(layer "F.CrtYd")
		)
		(fp_poly
			(pts
				(xy 1.397 4.5466) (xy 1.397 3.2639) (xy -23.6728 3.2639) (xy -23.6728 -3.5052) (xy 23.6728 -3.5052)
				(xy 23.6728 3.2639) (xy 8.763 3.2639) (xy 8.763 4.5466)
			)
			(stroke
				(width 0)
				(type default)
			)
			(fill no)
			(layer "F.Fab")
		)
		(pad "" np_thru_hole circle
			(at -18.874994 0 270)
			(size 0.254 0.254)
			(drill 1.3462)
			(layers "*.Cu" "*.Mask")
			(clearance 0.9017)
			(thermal_gap 0.9017)
		)
		(pad "" np_thru_hole circle
			(at 18.874994 0 270)
			(size 0.254 0.254)
			(drill 0.9398)
			(layers "*.Cu" "*.Mask")
			(clearance 0.6985)
			(thermal_gap 0.6985)
		)
		(pad "G1" smd rect
			(at 21.874988 0 270)
			(size 2.5908 2.5908)
			(layers "F.Cu" "F.Mask" "F.Paste")
			(net "GND")
		)
		(pad "G2" smd rect
			(at -21.874988 0 270)
			(size 2.5908 2.5908)
			(layers "F.Cu" "F.Mask" "F.Paste")
			(net "GND")
		)
		(pad "P1" smd rect
			(at 1.905 -1.82499 270)
			(size 0.6096 2.3622)
			(layers "F.Cu" "F.Mask" "F.Paste")
			(net "Net_2021")
		)
		(pad "P2" smd rect
			(at 0.635 -1.82499 270)
			(size 0.6096 2.3622)
			(layers "F.Cu" "F.Mask" "F.Paste")
			(net "Net_2022")
		)
		(pad "P3" smd rect
			(at -0.635 -1.82499 270)
			(size 0.6096 2.3622)
			(layers "F.Cu" "F.Mask" "F.Paste")
			(net "Net_2023")
		)
		(pad "P4" smd rect
			(at -1.905 -1.82499 270)
			(size 0.6096 2.3622)
			(layers "F.Cu" "F.Mask" "F.Paste")
			(net "GND")
		)
		(pad "P5" smd rect
			(at -3.175 -1.82499 270)
			(size 0.6096 2.3622)
			(layers "F.Cu" "F.Mask" "F.Paste")
			(net "HDD_PRSNT_4")
		)
		(pad "P6" smd rect
			(at -4.445 -1.82499 270)
			(size 0.6096 2.3622)
			(layers "F.Cu" "F.Mask" "F.Paste")
			(net "GND")
		)
		(pad "P7" smd rect
			(at -5.715 -1.82499 270)
			(size 0.6096 2.3622)
			(layers "F.Cu" "F.Mask" "F.Paste")
			(net "5V_PRE_4")
		)
		(pad "P8" smd rect
			(at -6.985 -1.82499 270)
			(size 0.6096 2.3622)
			(layers "F.Cu" "F.Mask" "F.Paste")
			(net "P5V_HDD4")
		)
		(pad "P9" smd rect
			(at -8.255 -1.82499 270)
			(size 0.6096 2.3622)
			(layers "F.Cu" "F.Mask" "F.Paste")
			(net "P5V_HDD4")
		)
		(pad "P10" smd rect
			(at -9.525 -1.82499 270)
			(size 0.6096 2.3622)
			(layers "F.Cu" "F.Mask" "F.Paste")
			(net "GND")
		)
		(pad "P11" smd rect
			(at -10.795 -1.82499 270)
			(size 0.6096 2.3622)
			(layers "F.Cu" "F.Mask" "F.Paste")
			(net "ACT_HDD_4")
		)
		(pad "P12" smd rect
			(at -12.065 -1.82499 270)
			(size 0.6096 2.3622)
			(layers "F.Cu" "F.Mask" "F.Paste")
			(net "GND")
		)
		(pad "P13" smd rect
			(at -13.335 -1.82499 270)
			(size 0.6096 2.3622)
			(layers "F.Cu" "F.Mask" "F.Paste")
			(net "12V_PRE_4")
		)
		(pad "P14" smd rect
			(at -14.605 -1.82499 270)
			(size 0.6096 2.3622)
			(layers "F.Cu" "F.Mask" "F.Paste")
			(net "P12V_HDD4")
		)
		(pad "P15" smd rect
			(at -15.875 -1.82499 270)
			(size 0.6096 2.3622)
			(layers "F.Cu" "F.Mask" "F.Paste")
			(net "P12V_HDD4")
		)
		(pad "S1" smd rect
			(at 15.875 -1.82499 270)
			(size 0.6096 2.3622)
			(layers "F.Cu" "F.Mask" "F.Paste")
			(net "GND")
		)
		(pad "S2" smd rect
			(at 14.605 -1.82499 270)
			(size 0.6096 2.3622)
			(layers "F.Cu" "F.Mask" "F.Paste")
			(net "SAS_HDD_RX_P4")
		)
		(pad "S3" smd rect
			(at 13.335 -1.82499 270)
			(size 0.6096 2.3622)
			(layers "F.Cu" "F.Mask" "F.Paste")
			(net "SAS_HDD_RX_N4")
		)
		(pad "S4" smd rect
			(at 12.065 -1.82499 270)
			(size 0.6096 2.3622)
			(layers "F.Cu" "F.Mask" "F.Paste")
			(net "GND")
		)
		(pad "S5" smd rect
			(at 10.795 -1.82499 270)
			(size 0.6096 2.3622)
			(layers "F.Cu" "F.Mask" "F.Paste")
			(net "PHY_DRV_A_TO_SCC_A_4_DN")
		)
		(pad "S6" smd rect
			(at 9.525 -1.82499 270)
			(size 0.6096 2.3622)
			(layers "F.Cu" "F.Mask" "F.Paste")
			(net "PHY_DRV_A_TO_SCC_A_4_DP")
		)
		(pad "S7" smd rect
			(at 8.255 -1.82499 270)
			(size 0.6096 2.3622)
			(layers "F.Cu" "F.Mask" "F.Paste")
			(net "GND")
		)
		(pad "S8" smd rect
			(at 7.480046 2.845054 270)
			(size 0.508 2.3622)
			(layers "F.Cu" "F.Mask" "F.Paste")
			(net "GND")
		)
		(pad "S9" smd rect
			(at 6.679946 2.845054 270)
			(size 0.508 2.3622)
			(layers "F.Cu" "F.Mask" "F.Paste")
			(net "Net_476")
		)
		(pad "S10" smd rect
			(at 5.8801 2.845054 270)
			(size 0.508 2.3622)
			(layers "F.Cu" "F.Mask" "F.Paste")
			(net "Net_368")
		)
		(pad "S11" smd rect
			(at 5.08 2.845054 270)
			(size 0.508 2.3622)
			(layers "F.Cu" "F.Mask" "F.Paste")
			(net "GND")
		)
		(pad "S12" smd rect
			(at 4.2799 2.845054 270)
			(size 0.508 2.3622)
			(layers "F.Cu" "F.Mask" "F.Paste")
			(net "Net_404")
		)
		(pad "S13" smd rect
			(at 3.480054 2.845054 270)
			(size 0.508 2.3622)
			(layers "F.Cu" "F.Mask" "F.Paste")
			(net "Net_440")
		)
		(pad "S14" smd rect
			(at 2.679954 2.845054 270)
			(size 0.508 2.3622)
			(layers "F.Cu" "F.Mask" "F.Paste")
			(net "GND")
		)
		(zone
			(layer "F.Cu")
			(hatch none 0.5)
			(connect_pads
				(clearance 0)
			)
			(min_thickness 0.25)
			(keepout
				(tracks not_allowed)
				(vias allowed)
				(pads allowed)
				(copperpour not_allowed)
				(footprints allowed)
			)
			(placement
				(enabled no)
				(sheetname "")
			)
			(fill
				(thermal_gap 0.5)
				(thermal_bridge_width 0.5)
				(island_removal_mode 0)
			)
			(polygon
				(pts
					(xy 158.057596 -304.648616) (xy 150.983696 -304.648616) (xy 150.983696 -311.582816) (xy 152.088596 -311.582816)
					(xy 152.088596 -307.468016) (xy 156.711396 -307.468016) (xy 156.711396 -311.582816) (xy 158.057596 -311.582816)
				)
			)
		)
		(zone
			(layer "F.Cu")
			(hatch none 0.5)
			(connect_pads
				(clearance 0)
			)
			(min_thickness 0.25)
			(keepout
				(tracks allowed)
				(vias not_allowed)
				(pads allowed)
				(copperpour not_allowed)
				(footprints allowed)
			)
			(placement
				(enabled no)
				(sheetname "")
			)
			(fill
				(thermal_gap 0.5)
				(thermal_bridge_width 0.5)
				(island_removal_mode 0)
			)
			(polygon
				(pts
					(xy 158.057596 -304.648616) (xy 150.983696 -304.648616) (xy 150.983696 -311.582816) (xy 152.088596 -311.582816)
					(xy 152.088596 -307.468016) (xy 156.711396 -307.468016) (xy 156.711396 -311.582816) (xy 158.057596 -311.582816)
				)
			)
		)
		(zone
			(layer "F.Cu")
			(hatch none 0.5)
			(connect_pads
				(clearance 0)
			)
			(min_thickness 0.25)
			(keepout
				(tracks allowed)
				(vias not_allowed)
				(pads allowed)
				(copperpour not_allowed)
				(footprints allowed)
			)
			(placement
				(enabled no)
				(sheetname "")
			)
			(fill
				(thermal_gap 0.5)
				(thermal_bridge_width 0.5)
				(island_removal_mode 0)
			)
			(polygon
				(pts
					(xy 158.057596 -271.171416) (xy 150.983696 -271.171416) (xy 150.983696 -264.237216) (xy 152.088596 -264.237216)
					(xy 152.088596 -268.352016) (xy 156.711396 -268.352016) (xy 156.711396 -264.237216) (xy 158.057596 -264.237216)
				)
			)
		)
		(zone
			(layer "F.Cu")
			(hatch none 0.5)
			(connect_pads
				(clearance 0)
			)
			(min_thickness 0.25)
			(keepout
				(tracks not_allowed)
				(vias allowed)
				(pads allowed)
				(copperpour not_allowed)
				(footprints allowed)
			)
			(placement
				(enabled no)
				(sheetname "")
			)
			(fill
				(thermal_gap 0.5)
				(thermal_bridge_width 0.5)
				(island_removal_mode 0)
			)
			(polygon
				(pts
					(xy 158.057596 -271.171416) (xy 150.983696 -271.171416) (xy 150.983696 -264.237216) (xy 152.088596 -264.237216)
					(xy 152.088596 -268.352016) (xy 156.711396 -268.352016) (xy 156.711396 -264.237216) (xy 158.057596 -264.237216)
				)
			)
		)
		(zone
			(layers "F.Cu" "B.Cu" "In1.Cu" "In2.Cu" "In3.Cu" "In4.Cu" "In5.Cu" "In6.Cu"
				"In7.Cu" "In8.Cu" "In9.Cu" "In10.Cu"
			)
			(hatch none 0.5)
			(connect_pads
				(clearance 0)
			)
			(min_thickness 0.25)
			(keepout
				(tracks not_allowed)
				(vias allowed)
				(pads allowed)
				(copperpour not_allowed)
				(footprints allowed)
			)
			(placement
				(enabled no)
				(sheetname "")
			)
			(fill
				(thermal_gap 0.5)
				(thermal_bridge_width 0.5)
				(island_removal_mode 0)
			)
			(polygon
				(pts
					(arc
						(start 155.174696 -269.035022)
						(mid 153.625296 -269.035022)
						(end 155.174696 -269.035022)
					)
				)
			)
		)
		(zone
			(layers "F.Cu" "B.Cu" "In1.Cu" "In2.Cu" "In3.Cu" "In4.Cu" "In5.Cu" "In6.Cu"
				"In7.Cu" "In8.Cu" "In9.Cu" "In10.Cu"
			)
			(hatch none 0.5)
			(connect_pads
				(clearance 0)
			)
			(min_thickness 0.25)
			(keepout
				(tracks not_allowed)
				(vias allowed)
				(pads allowed)
				(copperpour not_allowed)
				(footprints allowed)
			)
			(placement
				(enabled no)
				(sheetname "")
			)
			(fill
				(thermal_gap 0.5)
				(thermal_bridge_width 0.5)
				(island_removal_mode 0)
			)
			(polygon
				(pts
					(arc
						(start 155.377896 -306.78501)
						(mid 153.422096 -306.78501)
						(end 155.377896 -306.78501)
					)
				)
			)
		)
	)
	(footprint ""
		(layer "F.Cu")
		(at 314.898532 -127.800354 180)
		(property "Reference" "Q281"
			(at 0 0 180)
			(layer "F.SilkS")
			(hide yes)
			(effects
				(font
					(size 1.27 1.27)
				)
			)
		)
		(property "Value" "SSM3K324R-GP"
			(at 0.127 -8.9662 180)
			(unlocked yes)
			(layer "F.Fab")
			(hide yes)
			(effects
				(font
					(size 1.016 1.016)
					(thickness 0.1524)
				)
			)
		)
		(property "Device Type" "SOT23DGS2D4H35"
			(at 0.127 -10.4902 180)
			(unlocked yes)
			(layer "F.Fab")
			(hide yes)
			(effects
				(font
					(size 1.016 1.016)
					(thickness 0.1524)
				)
			)
		)
		(duplicate_pad_numbers_are_jumpers no)
		(fp_line
			(start 1.651 1.778)
			(end 1.651 -1.778)
			(stroke
				(width 0.1524)
				(type default)
			)
			(layer "F.SilkS")
		)
		(fp_line
			(start 1.651 -1.778)
			(end -1.651 -1.778)
			(stroke
				(width 0.1524)
				(type default)
			)
			(layer "F.SilkS")
		)
		(fp_line
			(start -1.651 1.778)
			(end 1.651 1.778)
			(stroke
				(width 0.1524)
				(type default)
			)
			(layer "F.SilkS")
		)
		(fp_line
			(start -1.651 -1.778)
			(end -1.651 1.778)
			(stroke
				(width 0.1524)
				(type default)
			)
			(layer "F.SilkS")
		)
		(fp_poly
			(pts
				(xy -1.778 1.8796) (xy -1.778 -1.8796) (xy 1.778 -1.8796) (xy 1.778 1.8796)
			)
			(stroke
				(width 0)
				(type default)
			)
			(fill no)
			(layer "F.CrtYd")
		)
		(fp_poly
			(pts
				(xy -1.778 1.8796) (xy -1.778 -1.8796) (xy 1.778 -1.8796) (xy 1.778 1.8796)
			)
			(stroke
				(width 0)
				(type default)
			)
			(fill no)
			(layer "F.Fab")
		)
		(pad "D" smd custom
			(at 0 -0.9525 180)
			(size 0.1905 0.1905)
			(layers "F.Cu" "F.Mask" "F.Paste")
			(net "DRV_ACT_18_N")
			(options
				(clearance outline)
				(anchor circle)
			)
			(primitives
				(gr_poly
					(pts
						(arc
							(start -0.1778 0.5715)
							(mid -0.321484 0.511984)
							(end -0.381 0.3683)
						)
						(arc
							(start -0.381 -0.3683)
							(mid -0.321484 -0.511984)
							(end -0.1778 -0.5715)
						)
						(arc
							(start 0.1778 -0.5715)
							(mid 0.321484 -0.511984)
							(end 0.381 -0.3683)
						)
						(arc
							(start 0.381 0.3683)
							(mid 0.321484 0.511984)
							(end 0.1778 0.5715)
						)
					)
					(width 0)
					(fill yes)
				)
			)
		)
		(pad "G" smd custom
			(at -0.98425 0.9525 180)
			(size 0.1905 0.1905)
			(layers "F.Cu" "F.Mask" "F.Paste")
			(net "DRIVE_A_18_ACT")
			(options
				(clearance outline)
				(anchor circle)
			)
			(primitives
				(gr_poly
					(pts
						(arc
							(start -0.1778 0.5715)
							(mid -0.321484 0.511984)
							(end -0.381 0.3683)
						)
						(arc
							(start -0.381 -0.3683)
							(mid -0.321484 -0.511984)
							(end -0.1778 -0.5715)
						)
						(arc
							(start 0.1778 -0.5715)
							(mid 0.321484 -0.511984)
							(end 0.381 -0.3683)
						)
						(arc
							(start 0.381 0.3683)
							(mid 0.321484 0.511984)
							(end 0.1778 0.5715)
						)
					)
					(width 0)
					(fill yes)
				)
			)
		)
		(pad "S" smd custom
			(at 0.98425 0.9525 180)
			(size 0.1905 0.1905)
			(layers "F.Cu" "F.Mask" "F.Paste")
			(net "GND")
			(options
				(clearance outline)
				(anchor circle)
			)
			(primitives
				(gr_poly
					(pts
						(arc
							(start -0.1778 0.5715)
							(mid -0.321484 0.511984)
							(end -0.381 0.3683)
						)
						(arc
							(start -0.381 -0.3683)
							(mid -0.321484 -0.511984)
							(end -0.1778 -0.5715)
						)
						(arc
							(start 0.1778 -0.5715)
							(mid 0.321484 -0.511984)
							(end 0.381 -0.3683)
						)
						(arc
							(start 0.381 0.3683)
							(mid 0.321484 0.511984)
							(end 0.1778 0.5715)
						)
					)
					(width 0)
					(fill yes)
				)
			)
		)
	)
	(footprint ""
		(layer "F.Cu")
		(at 449.037202 -251.16155)
		(property "Reference" "R1247"
			(at 0 0 0)
			(layer "F.SilkS")
			(hide yes)
			(effects
				(font
					(size 1.27 1.27)
				)
			)
		)
		(property "Value" "0R3J-0-U-GP"
			(at -0.0254 -2.5146 0)
			(unlocked yes)
			(layer "F.Fab")
			(hide yes)
			(effects
				(font
					(size 1.016 1.016)
					(thickness 0.1524)
				)
			)
		)
		(property "Device Type" "R603H22"
			(at -0.0254 -4.0386 0)
			(unlocked yes)
			(layer "F.Fab")
			(hide yes)
			(effects
				(font
					(size 1.016 1.016)
					(thickness 0.1524)
				)
			)
		)
		(duplicate_pad_numbers_are_jumpers no)
		(fp_line
			(start -0.4826 0)
			(end -0.2032 0)
			(stroke
				(width 0.2032)
				(type default)
			)
			(layer "F.SilkS")
		)
		(fp_line
			(start 0.2032 0)
			(end 0.4826 0)
			(stroke
				(width 0.2032)
				(type default)
			)
			(layer "F.SilkS")
		)
		(fp_rect
			(start -0.5842 1.3335)
			(end 0.5842 -1.3335)
			(stroke
				(width 0)
				(type default)
			)
			(fill no)
			(layer "F.CrtYd")
		)
		(fp_rect
			(start -0.5842 1.3335)
			(end 0.5842 -1.3335)
			(stroke
				(width 0)
				(type default)
			)
			(fill no)
			(layer "F.Fab")
		)
		(pad "1" smd custom
			(at 0 -0.762)
			(size 0.2159 0.2159)
			(layers "F.Cu" "F.Mask" "F.Paste")
			(net "P5V_C_VBST")
			(options
				(clearance outline)
				(anchor circle)
			)
			(primitives
				(gr_poly
					(pts
						(arc
							(start -0.3302 -0.4318)
							(mid -0.402042 -0.402042)
							(end -0.4318 -0.3302)
						)
						(arc
							(start -0.4318 0.3302)
							(mid -0.402042 0.402042)
							(end -0.3302 0.4318)
						)
						(arc
							(start 0.3302 0.4318)
							(mid 0.402042 0.402042)
							(end 0.4318 0.3302)
						)
						(arc
							(start 0.4318 -0.3302)
							(mid 0.402042 -0.402042)
							(end 0.3302 -0.4318)
						)
					)
					(width 0)
					(fill yes)
				)
			)
		)
		(pad "2" smd custom
			(at 0 0.762)
			(size 0.2159 0.2159)
			(layers "F.Cu" "F.Mask" "F.Paste")
			(net "P5V_C_VBST_RC")
			(options
				(clearance outline)
				(anchor circle)
			)
			(primitives
				(gr_poly
					(pts
						(arc
							(start -0.3302 -0.4318)
							(mid -0.402042 -0.402042)
							(end -0.4318 -0.3302)
						)
						(arc
							(start -0.4318 0.3302)
							(mid -0.402042 0.402042)
							(end -0.3302 0.4318)
						)
						(arc
							(start 0.3302 0.4318)
							(mid 0.402042 0.402042)
							(end 0.4318 0.3302)
						)
						(arc
							(start 0.4318 -0.3302)
							(mid 0.402042 -0.402042)
							(end 0.3302 -0.4318)
						)
					)
					(width 0)
					(fill yes)
				)
			)
		)
	)
	(footprint ""
		(layer "F.Cu")
		(at 318.77 -61.127894 -90)
		(property "Reference" "C432"
			(at 0 0 270)
			(layer "F.SilkS")
			(hide yes)
			(effects
				(font
					(size 1.27 1.27)
				)
			)
		)
		(property "Value" "SCD01U50V2KX-1GP"
			(at 1.1811 -2.7051 270)
			(unlocked yes)
			(layer "F.Fab")
			(hide yes)
			(effects
				(font
					(size 1.016 1.016)
					(thickness 0.1524)
				)
			)
		)
		(property "Device Type" "C402H22"
			(at 1.1811 -4.2291 270)
			(unlocked yes)
			(layer "F.Fab")
			(hide yes)
			(effects
				(font
					(size 1.016 1.016)
					(thickness 0.1524)
				)
			)
		)
		(duplicate_pad_numbers_are_jumpers no)
		(fp_rect
			(start -0.4318 0.9525)
			(end 0.4318 -0.9525)
			(stroke
				(width 0)
				(type default)
			)
			(fill no)
			(layer "F.CrtYd")
		)
		(fp_rect
			(start -0.4318 0.9525)
			(end 0.4318 -0.9525)
			(stroke
				(width 0)
				(type default)
			)
			(fill no)
			(layer "F.Fab")
		)
		(pad "1" smd custom
			(at 0 -0.4445 270)
			(size 0.1524 0.1524)
			(layers "F.Cu" "F.Mask" "F.Paste")
			(net "HDD_PRSNT_30")
			(options
				(clearance outline)
				(anchor circle)
			)
			(primitives
				(gr_poly
					(pts
						(arc
							(start 0.3048 -0.2032)
							(mid 0.275042 -0.275042)
							(end 0.2032 -0.3048)
						)
						(arc
							(start -0.2032 -0.3048)
							(mid -0.275042 -0.275042)
							(end -0.3048 -0.2032)
						)
						(arc
							(start -0.3048 0.2032)
							(mid -0.275042 0.275042)
							(end -0.2032 0.3048)
						)
						(arc
							(start 0.2032 0.3048)
							(mid 0.275042 0.275042)
							(end 0.3048 0.2032)
						)
					)
					(width 0)
					(fill yes)
				)
			)
		)
		(pad "2" smd custom
			(at 0 0.4445 270)
			(size 0.1524 0.1524)
			(layers "F.Cu" "F.Mask" "F.Paste")
			(net "GND")
			(options
				(clearance outline)
				(anchor circle)
			)
			(primitives
				(gr_poly
					(pts
						(arc
							(start 0.3048 -0.2032)
							(mid 0.275042 -0.275042)
							(end 0.2032 -0.3048)
						)
						(arc
							(start -0.2032 -0.3048)
							(mid -0.275042 -0.275042)
							(end -0.3048 -0.2032)
						)
						(arc
							(start -0.3048 0.2032)
							(mid -0.275042 0.275042)
							(end -0.2032 0.3048)
						)
						(arc
							(start 0.2032 0.3048)
							(mid 0.275042 0.275042)
							(end 0.3048 0.2032)
						)
					)
					(width 0)
					(fill yes)
				)
			)
		)
	)
	(footprint ""
		(layer "F.Cu")
		(at 366.174274 -146.66341 180)
		(property "Reference" "R1103"
			(at 0 0 180)
			(layer "F.SilkS")
			(hide yes)
			(effects
				(font
					(size 1.27 1.27)
				)
			)
		)
		(property "Value" "0R5J-5-GP"
			(at 0 -8.9535 180)
			(unlocked yes)
			(layer "F.Fab")
			(hide yes)
			(effects
				(font
					(size 1.27 1.016)
					(thickness 0.1524)
				)
			)
		)
		(property "Device Type" "R805H24"
			(at 0 -10.6299 180)
			(unlocked yes)
			(layer "F.Fab")
			(hide yes)
			(effects
				(font
					(size 1.27 1.016)
					(thickness 0.1524)
				)
			)
		)
		(duplicate_pad_numbers_are_jumpers no)
		(fp_line
			(start 0.889 1.7018)
			(end 0.889 -0.508)
			(stroke
				(width 0.1524)
				(type default)
			)
			(layer "F.SilkS")
		)
		(fp_line
			(start 0.889 -1.7018)
			(end 0.889 -0.381)
			(stroke
				(width 0.1524)
				(type default)
			)
			(layer "F.SilkS")
		)
		(fp_line
			(start 0.889 -1.7018)
			(end -0.889 -1.7018)
			(stroke
				(width 0.1524)
				(type default)
			)
			(layer "F.SilkS")
		)
		(fp_line
			(start -0.889 1.7018)
			(end 0.889 1.7018)
			(stroke
				(width 0.1524)
				(type default)
			)
			(layer "F.SilkS")
		)
		(fp_line
			(start -0.889 0.0762)
			(end -0.889 1.7018)
			(stroke
				(width 0.1524)
				(type default)
			)
			(layer "F.SilkS")
		)
		(fp_line
			(start -0.889 -1.7018)
			(end -0.889 0.2794)
			(stroke
				(width 0.1524)
				(type default)
			)
			(layer "F.SilkS")
		)
		(fp_poly
			(pts
				(xy 0.9652 -1.778) (xy 0.9652 1.778) (xy -0.9652 1.778) (xy -0.9652 -1.778)
			)
			(stroke
				(width 0)
				(type default)
			)
			(fill no)
			(layer "F.CrtYd")
		)
		(fp_rect
			(start -0.9652 1.778)
			(end 0.9652 -1.778)
			(stroke
				(width 0)
				(type default)
			)
			(fill no)
			(layer "F.Fab")
		)
		(pad "1" smd rect
			(at 0 -0.9652 180)
			(size 1.397 1.143)
			(layers "F.Cu" "F.Mask" "F.Paste")
			(net "MB1_CM_GATE")
		)
		(pad "2" smd rect
			(at 0 0.9652 180)
			(size 1.397 1.143)
			(layers "F.Cu" "F.Mask" "F.Paste")
			(net "MB1_CM_GATE_R")
		)
	)
	(footprint ""
		(layer "F.Cu")
		(at 35.617912 -245.55069 -90)
		(property "Reference" "C607"
			(at 0 0 270)
			(layer "F.SilkS")
			(hide yes)
			(effects
				(font
					(size 1.27 1.27)
				)
			)
		)
		(property "Value" "SC2200P50V2KX-2GP"
			(at 1.1811 -2.7051 270)
			(unlocked yes)
			(layer "F.Fab")
			(hide yes)
			(effects
				(font
					(size 1.016 1.016)
					(thickness 0.1524)
				)
			)
		)
		(property "Device Type" "C402H22"
			(at 1.1811 -4.2291 270)
			(unlocked yes)
			(layer "F.Fab")
			(hide yes)
			(effects
				(font
					(size 1.016 1.016)
					(thickness 0.1524)
				)
			)
		)
		(duplicate_pad_numbers_are_jumpers no)
		(fp_rect
			(start -0.4318 0.9525)
			(end 0.4318 -0.9525)
			(stroke
				(width 0)
				(type default)
			)
			(fill no)
			(layer "F.CrtYd")
		)
		(fp_rect
			(start -0.4318 0.9525)
			(end 0.4318 -0.9525)
			(stroke
				(width 0)
				(type default)
			)
			(fill no)
			(layer "F.Fab")
		)
		(pad "1" smd custom
			(at 0 -0.4445 270)
			(size 0.1524 0.1524)
			(layers "F.Cu" "F.Mask" "F.Paste")
			(net "P5V_A_LL")
			(options
				(clearance outline)
				(anchor circle)
			)
			(primitives
				(gr_poly
					(pts
						(arc
							(start 0.3048 -0.2032)
							(mid 0.275042 -0.275042)
							(end 0.2032 -0.3048)
						)
						(arc
							(start -0.2032 -0.3048)
							(mid -0.275042 -0.275042)
							(end -0.3048 -0.2032)
						)
						(arc
							(start -0.3048 0.2032)
							(mid -0.275042 0.275042)
							(end -0.2032 0.3048)
						)
						(arc
							(start 0.2032 0.3048)
							(mid 0.275042 0.275042)
							(end 0.3048 0.2032)
						)
					)
					(width 0)
					(fill yes)
				)
			)
		)
		(pad "2" smd custom
			(at 0 0.4445 270)
			(size 0.1524 0.1524)
			(layers "F.Cu" "F.Mask" "F.Paste")
			(net "P5V_SNB")
			(options
				(clearance outline)
				(anchor circle)
			)
			(primitives
				(gr_poly
					(pts
						(arc
							(start 0.3048 -0.2032)
							(mid 0.275042 -0.275042)
							(end 0.2032 -0.3048)
						)
						(arc
							(start -0.2032 -0.3048)
							(mid -0.275042 -0.275042)
							(end -0.3048 -0.2032)
						)
						(arc
							(start -0.3048 0.2032)
							(mid -0.275042 0.275042)
							(end -0.2032 0.3048)
						)
						(arc
							(start 0.2032 0.3048)
							(mid 0.275042 0.275042)
							(end 0.3048 0.2032)
						)
					)
					(width 0)
					(fill yes)
				)
			)
		)
	)
	(footprint ""
		(layer "F.Cu")
		(at 95.608902 -47.749968 -90)
		(property "Reference" "VIA68"
			(at 0 0 270)
			(layer "F.SilkS")
			(hide yes)
			(effects
				(font
					(size 1.27 1.27)
				)
			)
		)
		(property "Value" "100OHM-8L-1D6MM-L18L16-GP"
			(at -3.7211 -4.5085 270)
			(unlocked yes)
			(layer "F.Fab")
			(hide yes)
			(effects
				(font
					(size 1.016 1.016)
					(thickness 0.1524)
				)
			)
		)
		(property "Device Type" "VIA-PCIE-4P-394076"
			(at -3.7211 -6.0325 270)
			(unlocked yes)
			(layer "F.Fab")
			(hide yes)
			(effects
				(font
					(size 1.016 1.016)
					(thickness 0.1524)
				)
			)
		)
		(duplicate_pad_numbers_are_jumpers no)
		(fp_rect
			(start -1.9685 0.381)
			(end 1.9685 -0.381)
			(stroke
				(width 0)
				(type default)
			)
			(fill no)
			(layer "F.CrtYd")
		)
		(fp_rect
			(start -1.9685 0.381)
			(end 1.9685 -0.381)
			(stroke
				(width 0)
				(type default)
			)
			(fill no)
			(layer "F.Fab")
		)
		(pad "1" thru_hole circle
			(at -1.5875 0 270)
			(size 0.508 0.508)
			(drill 0.254)
			(layers "*.Cu" "*.Mask")
			(remove_unused_layers no)
			(net "GND")
			(clearance 0.127)
			(thermal_gap 0.127)
		)
		(pad "2" thru_hole circle
			(at -0.5715 0 270)
			(size 0.508 0.508)
			(drill 0.254)
			(layers "*.Cu" "*.Mask")
			(remove_unused_layers no)
			(net "PHY_DRV_A_TO_SCC_A_26_DP")
			(clearance 0.127)
			(thermal_gap 0.127)
		)
		(pad "3" thru_hole circle
			(at 0.5715 0 270)
			(size 0.508 0.508)
			(drill 0.254)
			(layers "*.Cu" "*.Mask")
			(remove_unused_layers no)
			(net "PHY_DRV_A_TO_SCC_A_26_DN")
			(clearance 0.127)
			(thermal_gap 0.127)
		)
		(pad "4" thru_hole circle
			(at 1.5875 0 270)
			(size 0.508 0.508)
			(drill 0.254)
			(layers "*.Cu" "*.Mask")
			(remove_unused_layers no)
			(net "GND")
			(clearance 0.127)
			(thermal_gap 0.127)
		)
	)
	(footprint ""
		(layer "F.Cu")
		(at 464.2739 -164.443918 90)
		(property "Reference" "R652"
			(at 0 0 90)
			(layer "F.SilkS")
			(hide yes)
			(effects
				(font
					(size 1.27 1.27)
				)
			)
		)
		(property "Value" "200KR2F-L-GP"
			(at 0.064008 -3.993896 90)
			(unlocked yes)
			(layer "F.Fab")
			(hide yes)
			(effects
				(font
					(size 1.016 1.016)
					(thickness 0.1524)
				)
			)
		)
		(property "Device Type" "R402H16"
			(at 0.064008 -5.517896 90)
			(unlocked yes)
			(layer "F.Fab")
			(hide yes)
			(effects
				(font
					(size 1.016 1.016)
					(thickness 0.1524)
				)
			)
		)
		(duplicate_pad_numbers_are_jumpers no)
		(fp_line
			(start 0.508 -0.9398)
			(end -0.508 -0.9398)
			(stroke
				(width 0.1524)
				(type default)
			)
			(layer "F.SilkS")
		)
		(fp_line
			(start -0.508 -0.9398)
			(end -0.508 0.9398)
			(stroke
				(width 0.1524)
				(type default)
			)
			(layer "F.SilkS")
		)
		(fp_rect
			(start -0.508 0.9398)
			(end 0.508 -0.9398)
			(stroke
				(width 0)
				(type default)
			)
			(fill no)
			(layer "F.CrtYd")
		)
		(fp_rect
			(start -0.508 0.9398)
			(end 0.508 -0.9398)
			(stroke
				(width 0)
				(type default)
			)
			(fill no)
			(layer "F.Fab")
		)
		(pad "1" smd custom
			(at 0 -0.4445 90)
			(size 0.1397 0.1397)
			(layers "F.Cu" "F.Mask" "F.Paste")
			(net "SW_HDD_R22")
			(options
				(clearance outline)
				(anchor circle)
			)
			(primitives
				(gr_poly
					(pts
						(arc
							(start -0.1778 -0.2794)
							(mid -0.249642 -0.249642)
							(end -0.2794 -0.1778)
						)
						(arc
							(start -0.2794 0.1778)
							(mid -0.249642 0.249642)
							(end -0.1778 0.2794)
						)
						(arc
							(start 0.1778 0.2794)
							(mid 0.249642 0.249642)
							(end 0.2794 0.1778)
						)
						(arc
							(start 0.2794 -0.1778)
							(mid 0.249642 -0.249642)
							(end 0.1778 -0.2794)
						)
					)
					(width 0)
					(fill yes)
				)
			)
		)
		(pad "2" smd custom
			(at 0 0.4445 90)
			(size 0.1397 0.1397)
			(layers "F.Cu" "F.Mask" "F.Paste")
			(net "SW_HDD_N22")
			(options
				(clearance outline)
				(anchor circle)
			)
			(primitives
				(gr_poly
					(pts
						(arc
							(start -0.1778 -0.2794)
							(mid -0.249642 -0.249642)
							(end -0.2794 -0.1778)
						)
						(arc
							(start -0.2794 0.1778)
							(mid -0.249642 0.249642)
							(end -0.1778 0.2794)
						)
						(arc
							(start 0.1778 0.2794)
							(mid 0.249642 0.249642)
							(end 0.2794 0.1778)
						)
						(arc
							(start 0.2794 -0.1778)
							(mid 0.249642 -0.249642)
							(end 0.1778 -0.2794)
						)
					)
					(width 0)
					(fill yes)
				)
			)
		)
	)
	(footprint ""
		(layer "F.Cu")
		(at 378.249942 -209.399886)
		(property "Reference" "FLED9"
			(at 0 0 0)
			(layer "F.SilkS")
			(hide yes)
			(effects
				(font
					(size 1.27 1.27)
				)
			)
		)
		(property "Value" "LED-BY-19-GP"
			(at -2.132076 1.414018 0)
			(unlocked yes)
			(layer "F.Fab")
			(hide yes)
			(effects
				(font
					(size 1.016 1.016)
					(thickness 0.1524)
				)
			)
		)
		(property "Device Type" "LED-1615-4PH26"
			(at -2.132076 -0.109982 0)
			(unlocked yes)
			(layer "F.Fab")
			(hide yes)
			(effects
				(font
					(size 1.016 1.016)
					(thickness 0.1524)
				)
			)
		)
		(duplicate_pad_numbers_are_jumpers no)
		(fp_line
			(start -1.2954 0.254)
			(end -1.2954 1.6002)
			(stroke
				(width 0.508)
				(type default)
			)
			(layer "F.SilkS")
		)
		(fp_line
			(start -1.2954 1.6002)
			(end 1.2954 1.6002)
			(stroke
				(width 0.508)
				(type default)
			)
			(layer "F.SilkS")
		)
		(fp_line
			(start -1.1176 -1.4224)
			(end 1.1176 -1.4224)
			(stroke
				(width 0.1524)
				(type default)
			)
			(layer "F.SilkS")
		)
		(fp_line
			(start -1.1176 1.4224)
			(end -1.1176 -1.4224)
			(stroke
				(width 0.1524)
				(type default)
			)
			(layer "F.SilkS")
		)
		(fp_line
			(start 1.1176 -1.4224)
			(end 1.1176 1.4224)
			(stroke
				(width 0.1524)
				(type default)
			)
			(layer "F.SilkS")
		)
		(fp_line
			(start 1.1176 1.4224)
			(end -1.1176 1.4224)
			(stroke
				(width 0.1524)
				(type default)
			)
			(layer "F.SilkS")
		)
		(fp_line
			(start 1.2954 1.6002)
			(end 1.2954 0.254)
			(stroke
				(width 0.508)
				(type default)
			)
			(layer "F.SilkS")
		)
		(fp_rect
			(start -0.7493 0.8001)
			(end 0.7493 -0.8001)
			(stroke
				(width 0)
				(type default)
			)
			(fill no)
			(layer "F.CrtYd")
		)
		(fp_poly
			(pts
				(xy -1.3716 1.6764) (xy -1.3716 -1.6764) (xy 1.3716 -1.6764) (xy 1.3716 0.0635) (xy 0.7493 0.0635)
				(xy 0.7493 -0.8001) (xy -0.7493 -0.8001) (xy -0.7493 0.8001) (xy 0.7493 0.8001) (xy 0.7493 0.0762)
				(xy 1.3716 0.0762) (xy 1.3716 1.6764)
			)
			(stroke
				(width 0)
				(type default)
			)
			(fill no)
			(layer "F.CrtYd")
		)
		(fp_rect
			(start -1.3716 1.6764)
			(end 1.3716 -1.6764)
			(stroke
				(width 0)
				(type default)
			)
			(fill no)
			(layer "F.Fab")
		)
		(pad "1" smd rect
			(at 0.50038 -0.73025)
			(size 0.7112 0.8636)
			(layers "F.Cu" "F.Mask" "F.Paste")
			(net "DRV_ACT_8")
		)
		(pad "2" smd rect
			(at -0.50038 -0.73025)
			(size 0.7112 0.8636)
			(layers "F.Cu" "F.Mask" "F.Paste")
			(net "FLT_HDD8")
		)
		(pad "3" smd rect
			(at 0.50038 0.73025)
			(size 0.7112 0.8636)
			(layers "F.Cu" "F.Mask" "F.Paste")
			(net "DRV_ACT_8_N")
		)
		(pad "4" smd rect
			(at -0.50038 0.73025)
			(size 0.7112 0.8636)
			(layers "F.Cu" "F.Mask" "F.Paste")
			(net "FLT_HDD8_N")
		)
	)
	(footprint ""
		(layer "F.Cu")
		(at 127.15875 -162.749992 -90)
		(property "Reference" "VIA52"
			(at 0 0 270)
			(layer "F.SilkS")
			(hide yes)
			(effects
				(font
					(size 1.27 1.27)
				)
			)
		)
		(property "Value" "100OHM-8L-1D6MM-L18L16-GP"
			(at -3.7211 -4.5085 270)
			(unlocked yes)
			(layer "F.Fab")
			(hide yes)
			(effects
				(font
					(size 1.016 1.016)
					(thickness 0.1524)
				)
			)
		)
		(property "Device Type" "VIA-PCIE-4P-394076"
			(at -3.7211 -6.0325 270)
			(unlocked yes)
			(layer "F.Fab")
			(hide yes)
			(effects
				(font
					(size 1.016 1.016)
					(thickness 0.1524)
				)
			)
		)
		(duplicate_pad_numbers_are_jumpers no)
		(fp_rect
			(start -1.9685 0.381)
			(end 1.9685 -0.381)
			(stroke
				(width 0)
				(type default)
			)
			(fill no)
			(layer "F.CrtYd")
		)
		(fp_rect
			(start -1.9685 0.381)
			(end 1.9685 -0.381)
			(stroke
				(width 0)
				(type default)
			)
			(fill no)
			(layer "F.Fab")
		)
		(pad "1" thru_hole circle
			(at -1.5875 0 270)
			(size 0.508 0.508)
			(drill 0.254)
			(layers "*.Cu" "*.Mask")
			(remove_unused_layers no)
			(net "GND")
			(clearance 0.127)
			(thermal_gap 0.127)
		)
		(pad "2" thru_hole circle
			(at -0.5715 0 270)
			(size 0.508 0.508)
			(drill 0.254)
			(layers "*.Cu" "*.Mask")
			(remove_unused_layers no)
			(net "PHY_DRV_A_TO_SCC_A_15_DP")
			(clearance 0.127)
			(thermal_gap 0.127)
		)
		(pad "3" thru_hole circle
			(at 0.5715 0 270)
			(size 0.508 0.508)
			(drill 0.254)
			(layers "*.Cu" "*.Mask")
			(remove_unused_layers no)
			(net "PHY_DRV_A_TO_SCC_A_15_DN")
			(clearance 0.127)
			(thermal_gap 0.127)
		)
		(pad "4" thru_hole circle
			(at 1.5875 0 270)
			(size 0.508 0.508)
			(drill 0.254)
			(layers "*.Cu" "*.Mask")
			(remove_unused_layers no)
			(net "GND")
			(clearance 0.127)
			(thermal_gap 0.127)
		)
	)
	(footprint ""
		(layer "F.Cu")
		(at 177.8 -176.000918 -90)
		(property "Reference" "C262"
			(at 0 0 270)
			(layer "F.SilkS")
			(hide yes)
			(effects
				(font
					(size 1.27 1.27)
				)
			)
		)
		(property "Value" "SC10U16V6KX-2GP"
			(at -0.0762 -5.1308 270)
			(unlocked yes)
			(layer "F.Fab")
			(hide yes)
			(effects
				(font
					(size 1.016 1.016)
					(thickness 0.1524)
				)
			)
		)
		(property "Device Type" "C1206H71"
			(at -0.127 -6.6548 270)
			(unlocked yes)
			(layer "F.Fab")
			(hide yes)
			(effects
				(font
					(size 1.016 1.016)
					(thickness 0.1524)
				)
			)
		)
		(duplicate_pad_numbers_are_jumpers no)
		(fp_line
			(start -1.016 2.2352)
			(end -1.016 0.8382)
			(stroke
				(width 0.1524)
				(type default)
			)
			(layer "F.SilkS")
		)
		(fp_line
			(start 1.016 2.2352)
			(end -1.016 2.2352)
			(stroke
				(width 0.1524)
				(type default)
			)
			(layer "F.SilkS")
		)
		(fp_line
			(start 1.016 0.8382)
			(end 1.016 2.2352)
			(stroke
				(width 0.1524)
				(type default)
			)
			(layer "F.SilkS")
		)
		(fp_line
			(start -1.016 -0.8382)
			(end -1.016 -2.2352)
			(stroke
				(width 0.1524)
				(type default)
			)
			(layer "F.SilkS")
		)
		(fp_line
			(start -1.016 -2.2352)
			(end 1.016 -2.2352)
			(stroke
				(width 0.1524)
				(type default)
			)
			(layer "F.SilkS")
		)
		(fp_line
			(start 1.016 -2.2352)
			(end 1.016 -0.8382)
			(stroke
				(width 0.1524)
				(type default)
			)
			(layer "F.SilkS")
		)
		(fp_rect
			(start -1.0922 2.3114)
			(end 1.0922 -2.3114)
			(stroke
				(width 0)
				(type default)
			)
			(fill no)
			(layer "F.CrtYd")
		)
		(fp_poly
			(pts
				(xy 1.0922 -2.3114) (xy 1.0922 2.3114) (xy -1.0922 2.3114) (xy -1.0922 -2.3114)
			)
			(stroke
				(width 0)
				(type default)
			)
			(fill no)
			(layer "F.Fab")
		)
		(pad "1" smd rect
			(at 0 -1.397 270)
			(size 1.651 1.27)
			(layers "F.Cu" "F.Mask" "F.Paste")
			(net "P5V_HDD17")
		)
		(pad "2" smd rect
			(at 0 1.397 270)
			(size 1.651 1.27)
			(layers "F.Cu" "F.Mask" "F.Paste")
			(net "GND")
		)
	)
	(footprint ""
		(layer "F.Cu")
		(at 141.042898 -53.507894 -90)
		(property "Reference" "R789"
			(at 0 0 270)
			(layer "F.SilkS")
			(hide yes)
			(effects
				(font
					(size 1.27 1.27)
				)
			)
		)
		(property "Value" "300KR2F-GP"
			(at 0.064008 -3.993896 270)
			(unlocked yes)
			(layer "F.Fab")
			(hide yes)
			(effects
				(font
					(size 1.016 1.016)
					(thickness 0.1524)
				)
			)
		)
		(property "Device Type" "R402H16"
			(at 0.064008 -5.517896 270)
			(unlocked yes)
			(layer "F.Fab")
			(hide yes)
			(effects
				(font
					(size 1.016 1.016)
					(thickness 0.1524)
				)
			)
		)
		(duplicate_pad_numbers_are_jumpers no)
		(fp_line
			(start -0.508 -0.9398)
			(end -0.508 0.9398)
			(stroke
				(width 0.1524)
				(type default)
			)
			(layer "F.SilkS")
		)
		(fp_line
			(start 0.508 -0.9398)
			(end -0.508 -0.9398)
			(stroke
				(width 0.1524)
				(type default)
			)
			(layer "F.SilkS")
		)
		(fp_rect
			(start -0.508 0.9398)
			(end 0.508 -0.9398)
			(stroke
				(width 0)
				(type default)
			)
			(fill no)
			(layer "F.CrtYd")
		)
		(fp_rect
			(start -0.508 0.9398)
			(end 0.508 -0.9398)
			(stroke
				(width 0)
				(type default)
			)
			(fill no)
			(layer "F.Fab")
		)
		(pad "1" smd custom
			(at 0 -0.4445 270)
			(size 0.1397 0.1397)
			(layers "F.Cu" "F.Mask" "F.Paste")
			(net "SW_HDD_N28")
			(options
				(clearance outline)
				(anchor circle)
			)
			(primitives
				(gr_poly
					(pts
						(arc
							(start -0.1778 -0.2794)
							(mid -0.249642 -0.249642)
							(end -0.2794 -0.1778)
						)
						(arc
							(start -0.2794 0.1778)
							(mid -0.249642 0.249642)
							(end -0.1778 0.2794)
						)
						(arc
							(start 0.1778 0.2794)
							(mid 0.249642 0.249642)
							(end 0.2794 0.1778)
						)
						(arc
							(start 0.2794 -0.1778)
							(mid 0.249642 -0.249642)
							(end 0.1778 -0.2794)
						)
					)
					(width 0)
					(fill yes)
				)
			)
		)
		(pad "2" smd custom
			(at 0 0.4445 270)
			(size 0.1397 0.1397)
			(layers "F.Cu" "F.Mask" "F.Paste")
			(net "P12V_A")
			(options
				(clearance outline)
				(anchor circle)
			)
			(primitives
				(gr_poly
					(pts
						(arc
							(start -0.1778 -0.2794)
							(mid -0.249642 -0.249642)
							(end -0.2794 -0.1778)
						)
						(arc
							(start -0.2794 0.1778)
							(mid -0.249642 0.249642)
							(end -0.1778 0.2794)
						)
						(arc
							(start 0.1778 0.2794)
							(mid 0.249642 0.249642)
							(end 0.2794 0.1778)
						)
						(arc
							(start 0.2794 -0.1778)
							(mid 0.249642 -0.249642)
							(end 0.1778 -0.2794)
						)
					)
					(width 0)
					(fill yes)
				)
			)
		)
	)
	(footprint ""
		(layer "F.Cu")
		(at 461.0989 -52.872894 -90)
		(property "Reference" "Q203"
			(at 0 0 270)
			(layer "F.SilkS")
			(hide yes)
			(effects
				(font
					(size 1.27 1.27)
				)
			)
		)
		(property "Value" "AO4406AL-GP"
			(at -3.707384 -1.5367 270)
			(unlocked yes)
			(layer "F.Fab")
			(hide yes)
			(effects
				(font
					(size 1.016 1.016)
					(thickness 0.1524)
				)
			)
		)
		(property "Device Type" "SOIC8H69"
			(at -3.707384 -3.0607 270)
			(unlocked yes)
			(layer "F.Fab")
			(hide yes)
			(effects
				(font
					(size 1.016 1.016)
					(thickness 0.1524)
				)
			)
		)
		(duplicate_pad_numbers_are_jumpers no)
		(fp_line
			(start -2.6289 3.4417)
			(end -2.6289 1.4732)
			(stroke
				(width 0.381)
				(type default)
			)
			(layer "F.SilkS")
		)
		(fp_line
			(start -2.7432 1.4224)
			(end -2.6416 1.4224)
			(stroke
				(width 0.1524)
				(type default)
			)
			(layer "F.SilkS")
		)
		(fp_line
			(start -2.7432 1.4224)
			(end 2.1336 1.4224)
			(stroke
				(width 0.1524)
				(type default)
			)
			(layer "F.SilkS")
		)
		(fp_line
			(start 2.1336 1.4224)
			(end 2.1336 -1.4224)
			(stroke
				(width 0.1524)
				(type default)
			)
			(layer "F.SilkS")
		)
		(fp_line
			(start -2.1844 -0.0508)
			(end -2.7178 0.508)
			(stroke
				(width 0.1524)
				(type default)
			)
			(layer "F.SilkS")
		)
		(fp_line
			(start -2.7178 -0.508)
			(end -2.1844 -0.0508)
			(stroke
				(width 0.1524)
				(type default)
			)
			(layer "F.SilkS")
		)
		(fp_line
			(start -2.7432 -1.4224)
			(end -2.7432 1.4224)
			(stroke
				(width 0.1524)
				(type default)
			)
			(layer "F.SilkS")
		)
		(fp_line
			(start 2.1336 -1.4224)
			(end -2.7432 -1.4224)
			(stroke
				(width 0.1524)
				(type default)
			)
			(layer "F.SilkS")
		)
		(fp_poly
			(pts
				(xy -2.2098 -1.4224) (xy -2.2098 1.4224) (xy 2.2098 1.4224) (xy 2.2098 -1.4224)
			)
			(stroke
				(width 0)
				(type default)
			)
			(fill yes)
			(layer "F.SilkS")
		)
		(fp_rect
			(start -2.450084 2.999994)
			(end 2.450084 -2.999994)
			(stroke
				(width 0)
				(type default)
			)
			(fill no)
			(layer "F.CrtYd")
		)
		(fp_poly
			(pts
				(xy -2.8194 3.6322) (xy -2.8194 -3.6322) (xy 2.8194 -3.6322) (xy 2.8194 1.18364) (xy 2.450084 1.18364)
				(xy 2.450084 -2.999994) (xy -2.450084 -2.999994) (xy -2.450084 2.999994) (xy 2.450084 2.999994)
				(xy 2.450084 1.18618) (xy 2.8194 1.18618) (xy 2.8194 3.6322)
			)
			(stroke
				(width 0)
				(type default)
			)
			(fill no)
			(layer "F.CrtYd")
		)
		(fp_rect
			(start -2.8194 3.6322)
			(end 2.8194 -3.6322)
			(stroke
				(width 0)
				(type default)
			)
			(fill no)
			(layer "F.Fab")
		)
		(pad "1" smd rect
			(at -1.905 2.54 270)
			(size 0.635 1.651)
			(layers "F.Cu" "F.Mask" "F.Paste")
			(net "P5V_HDD34")
		)
		(pad "2" smd rect
			(at -0.635 2.54 270)
			(size 0.635 1.651)
			(layers "F.Cu" "F.Mask" "F.Paste")
			(net "P5V_HDD34")
		)
		(pad "3" smd rect
			(at 0.635 2.54 270)
			(size 0.635 1.651)
			(layers "F.Cu" "F.Mask" "F.Paste")
			(net "P5V_HDD34")
		)
		(pad "4" smd rect
			(at 1.905 2.54 270)
			(size 0.635 1.651)
			(layers "F.Cu" "F.Mask" "F.Paste")
			(net "SW_HDD_P34")
		)
		(pad "5" smd rect
			(at 1.905 -2.54 270)
			(size 0.635 1.651)
			(layers "F.Cu" "F.Mask" "F.Paste")
			(net "P5V_A_4")
		)
		(pad "6" smd rect
			(at 0.635 -2.54 270)
			(size 0.635 1.651)
			(layers "F.Cu" "F.Mask" "F.Paste")
			(net "P5V_A_4")
		)
		(pad "7" smd rect
			(at -0.635 -2.54 270)
			(size 0.635 1.651)
			(layers "F.Cu" "F.Mask" "F.Paste")
			(net "P5V_A_4")
		)
		(pad "8" smd rect
			(at -1.905 -2.54 270)
			(size 0.635 1.651)
			(layers "F.Cu" "F.Mask" "F.Paste")
			(net "P5V_A_4")
		)
	)
	(footprint ""
		(layer "F.Cu")
		(at 459.7019 -73.954894 180)
		(property "Reference" "C488"
			(at 0 0 180)
			(layer "F.SilkS")
			(hide yes)
			(effects
				(font
					(size 1.27 1.27)
				)
			)
		)
		(property "Value" "SC4D7U25V5KX-1-GP"
			(at -0.0762 -6.1214 180)
			(unlocked yes)
			(layer "F.Fab")
			(hide yes)
			(effects
				(font
					(size 1.016 1.016)
					(thickness 0.1524)
				)
			)
		)
		(property "Device Type" "C805H58"
			(at -0.0762 -8.1534 180)
			(unlocked yes)
			(layer "F.Fab")
			(hide yes)
			(effects
				(font
					(size 1.016 1.016)
					(thickness 0.1524)
				)
			)
		)
		(duplicate_pad_numbers_are_jumpers no)
		(fp_line
			(start 0.635 0)
			(end -0.635 0)
			(stroke
				(width 0.508)
				(type default)
			)
			(layer "F.SilkS")
		)
		(fp_rect
			(start -0.9652 1.778)
			(end 0.9652 -1.778)
			(stroke
				(width 0)
				(type default)
			)
			(fill no)
			(layer "F.CrtYd")
		)
		(fp_poly
			(pts
				(xy -0.9652 -1.778) (xy 0.9652 -1.778) (xy 0.9652 1.778) (xy -0.9652 1.778)
			)
			(stroke
				(width 0)
				(type default)
			)
			(fill no)
			(layer "F.Fab")
		)
		(pad "1" smd rect
			(at 0 -0.9652 180)
			(size 1.397 1.143)
			(layers "F.Cu" "F.Mask" "F.Paste")
			(net "P12V_HDD34")
		)
		(pad "2" smd rect
			(at 0 0.9652 180)
			(size 1.397 1.143)
			(layers "F.Cu" "F.Mask" "F.Paste")
			(net "GND")
		)
	)
	(footprint ""
		(layer "F.Cu")
		(at 272.542 -332.50505 180)
		(property "Reference" "VIA51"
			(at 0 0 180)
			(layer "F.SilkS")
			(hide yes)
			(effects
				(font
					(size 1.27 1.27)
				)
			)
		)
		(property "Value" "100OHM-8L-1D6MM-L18L16-GP"
			(at -3.7211 -4.5085 180)
			(unlocked yes)
			(layer "F.Fab")
			(hide yes)
			(effects
				(font
					(size 1.016 1.016)
					(thickness 0.1524)
				)
			)
		)
		(property "Device Type" "VIA-PCIE-4P-394076"
			(at -3.7211 -6.0325 180)
			(unlocked yes)
			(layer "F.Fab")
			(hide yes)
			(effects
				(font
					(size 1.016 1.016)
					(thickness 0.1524)
				)
			)
		)
		(duplicate_pad_numbers_are_jumpers no)
		(fp_rect
			(start -1.9685 0.381)
			(end 1.9685 -0.381)
			(stroke
				(width 0)
				(type default)
			)
			(fill no)
			(layer "F.CrtYd")
		)
		(fp_rect
			(start -1.9685 0.381)
			(end 1.9685 -0.381)
			(stroke
				(width 0)
				(type default)
			)
			(fill no)
			(layer "F.Fab")
		)
		(pad "1" thru_hole circle
			(at -1.5875 0 180)
			(size 0.508 0.508)
			(drill 0.254)
			(layers "*.Cu" "*.Mask")
			(remove_unused_layers no)
			(net "GND")
			(clearance 0.127)
			(thermal_gap 0.127)
		)
		(pad "2" thru_hole circle
			(at -0.5715 0 180)
			(size 0.508 0.508)
			(drill 0.254)
			(layers "*.Cu" "*.Mask")
			(remove_unused_layers no)
			(net "PHY_SCC_A_TO_DRV_A_15_DP")
			(clearance 0.127)
			(thermal_gap 0.127)
		)
		(pad "3" thru_hole circle
			(at 0.5715 0 180)
			(size 0.508 0.508)
			(drill 0.254)
			(layers "*.Cu" "*.Mask")
			(remove_unused_layers no)
			(net "PHY_SCC_A_TO_DRV_A_15_DN")
			(clearance 0.127)
			(thermal_gap 0.127)
		)
		(pad "4" thru_hole circle
			(at 1.5875 0 180)
			(size 0.508 0.508)
			(drill 0.254)
			(layers "*.Cu" "*.Mask")
			(remove_unused_layers no)
			(net "GND")
			(clearance 0.127)
			(thermal_gap 0.127)
		)
	)
	(footprint ""
		(layer "F.Cu")
		(at 463.5119 -162.792918 90)
		(property "Reference" "D22"
			(at 0 0 90)
			(layer "F.SilkS")
			(hide yes)
			(effects
				(font
					(size 1.27 1.27)
				)
			)
		)
		(property "Value" "RB551V30-GP"
			(at 0 -6.7818 90)
			(unlocked yes)
			(layer "F.Fab")
			(hide yes)
			(effects
				(font
					(size 1.016 1.016)
					(thickness 0.1524)
				)
			)
		)
		(property "Device Type" "SOD323AKH38"
			(at 0 -8.6868 90)
			(unlocked yes)
			(layer "F.Fab")
			(hide yes)
			(effects
				(font
					(size 1.016 1.016)
					(thickness 0.1524)
				)
			)
		)
		(duplicate_pad_numbers_are_jumpers no)
		(fp_line
			(start 0.889 -1.9304)
			(end 0.889 2.159)
			(stroke
				(width 0.1524)
				(type default)
			)
			(layer "F.SilkS")
		)
		(fp_line
			(start -0.889 -1.9304)
			(end 0.889 -1.9304)
			(stroke
				(width 0.1524)
				(type default)
			)
			(layer "F.SilkS")
		)
		(fp_line
			(start 0.762 2.0574)
			(end -0.762 2.0574)
			(stroke
				(width 0.508)
				(type default)
			)
			(layer "F.SilkS")
		)
		(fp_line
			(start 0.889 2.159)
			(end -0.889 2.159)
			(stroke
				(width 0.1524)
				(type default)
			)
			(layer "F.SilkS")
		)
		(fp_line
			(start -0.889 2.159)
			(end -0.889 -1.9304)
			(stroke
				(width 0.1524)
				(type default)
			)
			(layer "F.SilkS")
		)
		(fp_rect
			(start -1.016 2.3114)
			(end 1.016 -2.0066)
			(stroke
				(width 0)
				(type default)
			)
			(fill no)
			(layer "F.CrtYd")
		)
		(fp_poly
			(pts
				(xy -1.016 -2.0066) (xy 1.016 -2.0066) (xy 1.016 2.3114) (xy -1.016 2.3114)
			)
			(stroke
				(width 0)
				(type default)
			)
			(fill no)
			(layer "F.Fab")
		)
		(pad "A" smd rect
			(at 0 -1.143 90)
			(size 0.5588 1.016)
			(layers "F.Cu" "F.Mask" "F.Paste")
			(net "SW_HDD_R22")
		)
		(pad "K" smd rect
			(at 0 1.143 90)
			(size 0.5588 1.016)
			(layers "F.Cu" "F.Mask" "F.Paste")
			(net "SW_HDD_N22")
		)
	)
	(footprint ""
		(layer "F.Cu")
		(at 479.036126 -186.287918)
		(property "Reference" "C343"
			(at 0 0 0)
			(layer "F.SilkS")
			(hide yes)
			(effects
				(font
					(size 1.27 1.27)
				)
			)
		)
		(property "Value" "SC4D7U25V5KX-1-GP"
			(at -0.0762 -6.1214 0)
			(unlocked yes)
			(layer "F.Fab")
			(hide yes)
			(effects
				(font
					(size 1.016 1.016)
					(thickness 0.1524)
				)
			)
		)
		(property "Device Type" "C805H58"
			(at -0.0762 -8.1534 0)
			(unlocked yes)
			(layer "F.Fab")
			(hide yes)
			(effects
				(font
					(size 1.016 1.016)
					(thickness 0.1524)
				)
			)
		)
		(duplicate_pad_numbers_are_jumpers no)
		(fp_line
			(start 0.635 0)
			(end -0.635 0)
			(stroke
				(width 0.508)
				(type default)
			)
			(layer "F.SilkS")
		)
		(fp_rect
			(start -0.9652 1.778)
			(end 0.9652 -1.778)
			(stroke
				(width 0)
				(type default)
			)
			(fill no)
			(layer "F.CrtYd")
		)
		(fp_poly
			(pts
				(xy -0.9652 -1.778) (xy 0.9652 -1.778) (xy 0.9652 1.778) (xy -0.9652 1.778)
			)
			(stroke
				(width 0)
				(type default)
			)
			(fill no)
			(layer "F.Fab")
		)
		(pad "1" smd rect
			(at 0 -0.9652)
			(size 1.397 1.143)
			(layers "F.Cu" "F.Mask" "F.Paste")
			(net "P12V_HDD23")
		)
		(pad "2" smd rect
			(at 0 0.9652)
			(size 1.397 1.143)
			(layers "F.Cu" "F.Mask" "F.Paste")
			(net "GND")
		)
	)
	(footprint ""
		(layer "F.Cu")
		(at 356.173278 -138.717274 180)
		(property "Reference" "R1101"
			(at 0 0 180)
			(layer "F.SilkS")
			(hide yes)
			(effects
				(font
					(size 1.27 1.27)
				)
			)
		)
		(property "Value" "10R5F-1-GP"
			(at 0 -8.9535 180)
			(unlocked yes)
			(layer "F.Fab")
			(hide yes)
			(effects
				(font
					(size 1.27 1.016)
					(thickness 0.1524)
				)
			)
		)
		(property "Device Type" "R805H24"
			(at 0 -10.6299 180)
			(unlocked yes)
			(layer "F.Fab")
			(hide yes)
			(effects
				(font
					(size 1.27 1.016)
					(thickness 0.1524)
				)
			)
		)
		(duplicate_pad_numbers_are_jumpers no)
		(fp_line
			(start 0.889 1.7018)
			(end 0.889 -0.508)
			(stroke
				(width 0.1524)
				(type default)
			)
			(layer "F.SilkS")
		)
		(fp_line
			(start 0.889 -1.7018)
			(end 0.889 -0.381)
			(stroke
				(width 0.1524)
				(type default)
			)
			(layer "F.SilkS")
		)
		(fp_line
			(start 0.889 -1.7018)
			(end -0.889 -1.7018)
			(stroke
				(width 0.1524)
				(type default)
			)
			(layer "F.SilkS")
		)
		(fp_line
			(start -0.889 1.7018)
			(end 0.889 1.7018)
			(stroke
				(width 0.1524)
				(type default)
			)
			(layer "F.SilkS")
		)
		(fp_line
			(start -0.889 0.0762)
			(end -0.889 1.7018)
			(stroke
				(width 0.1524)
				(type default)
			)
			(layer "F.SilkS")
		)
		(fp_line
			(start -0.889 -1.7018)
			(end -0.889 0.2794)
			(stroke
				(width 0.1524)
				(type default)
			)
			(layer "F.SilkS")
		)
		(fp_poly
			(pts
				(xy 0.9652 -1.778) (xy 0.9652 1.778) (xy -0.9652 1.778) (xy -0.9652 -1.778)
			)
			(stroke
				(width 0)
				(type default)
			)
			(fill no)
			(layer "F.CrtYd")
		)
		(fp_rect
			(start -0.9652 1.778)
			(end 0.9652 -1.778)
			(stroke
				(width 0)
				(type default)
			)
			(fill no)
			(layer "F.Fab")
		)
		(pad "1" smd rect
			(at 0 -0.9652 180)
			(size 1.397 1.143)
			(layers "F.Cu" "F.Mask" "F.Paste")
			(net "MB1_12V_CTRL_GATE1")
		)
		(pad "2" smd rect
			(at 0 0.9652 180)
			(size 1.397 1.143)
			(layers "F.Cu" "F.Mask" "F.Paste")
			(net "MB1_CM_GATE_R")
		)
	)
	(footprint ""
		(layer "F.Cu")
		(at 164.506402 -129.286)
		(property "Reference" "R311"
			(at 0 0 0)
			(layer "F.SilkS")
			(hide yes)
			(effects
				(font
					(size 1.27 1.27)
				)
			)
		)
		(property "Value" "130R3F-GP"
			(at -0.0254 -2.5146 0)
			(unlocked yes)
			(layer "F.Fab")
			(hide yes)
			(effects
				(font
					(size 1.016 1.016)
					(thickness 0.1524)
				)
			)
		)
		(property "Device Type" "R603H22"
			(at -0.0254 -4.0386 0)
			(unlocked yes)
			(layer "F.Fab")
			(hide yes)
			(effects
				(font
					(size 1.016 1.016)
					(thickness 0.1524)
				)
			)
		)
		(duplicate_pad_numbers_are_jumpers no)
		(fp_line
			(start -0.4826 0)
			(end -0.2032 0)
			(stroke
				(width 0.2032)
				(type default)
			)
			(layer "F.SilkS")
		)
		(fp_line
			(start 0.2032 0)
			(end 0.4826 0)
			(stroke
				(width 0.2032)
				(type default)
			)
			(layer "F.SilkS")
		)
		(fp_rect
			(start -0.5842 1.3335)
			(end 0.5842 -1.3335)
			(stroke
				(width 0)
				(type default)
			)
			(fill no)
			(layer "F.CrtYd")
		)
		(fp_rect
			(start -0.5842 1.3335)
			(end 0.5842 -1.3335)
			(stroke
				(width 0)
				(type default)
			)
			(fill no)
			(layer "F.Fab")
		)
		(pad "1" smd custom
			(at 0 -0.762)
			(size 0.2159 0.2159)
			(layers "F.Cu" "F.Mask" "F.Paste")
			(net "P5V_A_2")
			(options
				(clearance outline)
				(anchor circle)
			)
			(primitives
				(gr_poly
					(pts
						(arc
							(start -0.3302 -0.4318)
							(mid -0.402042 -0.402042)
							(end -0.4318 -0.3302)
						)
						(arc
							(start -0.4318 0.3302)
							(mid -0.402042 0.402042)
							(end -0.3302 0.4318)
						)
						(arc
							(start 0.3302 0.4318)
							(mid 0.402042 0.402042)
							(end 0.4318 0.3302)
						)
						(arc
							(start 0.4318 -0.3302)
							(mid 0.402042 -0.402042)
							(end 0.3302 -0.4318)
						)
					)
					(width 0)
					(fill yes)
				)
			)
		)
		(pad "2" smd custom
			(at 0 0.762)
			(size 0.2159 0.2159)
			(layers "F.Cu" "F.Mask" "F.Paste")
			(net "FLT_HDD17")
			(options
				(clearance outline)
				(anchor circle)
			)
			(primitives
				(gr_poly
					(pts
						(arc
							(start -0.3302 -0.4318)
							(mid -0.402042 -0.402042)
							(end -0.4318 -0.3302)
						)
						(arc
							(start -0.4318 0.3302)
							(mid -0.402042 0.402042)
							(end -0.3302 0.4318)
						)
						(arc
							(start 0.3302 0.4318)
							(mid 0.402042 0.402042)
							(end 0.4318 0.3302)
						)
						(arc
							(start 0.4318 -0.3302)
							(mid 0.402042 -0.402042)
							(end 0.3302 -0.4318)
						)
					)
					(width 0)
					(fill yes)
				)
			)
		)
	)
	(footprint ""
		(layer "F.Cu")
		(at 384.734562 -273.660616 -90)
		(property "Reference" "C143"
			(at 0 0 270)
			(layer "F.SilkS")
			(hide yes)
			(effects
				(font
					(size 1.27 1.27)
				)
			)
		)
		(property "Value" "SCD01U16V1KX-GP"
			(at -2.8321 -1.7399 270)
			(unlocked yes)
			(layer "F.Fab")
			(hide yes)
			(effects
				(font
					(size 1.016 1.016)
					(thickness 0.1524)
				)
			)
		)
		(property "Device Type" "C0201H13"
			(at -2.8321 -3.2639 270)
			(unlocked yes)
			(layer "F.Fab")
			(hide yes)
			(effects
				(font
					(size 1.016 1.016)
					(thickness 0.1524)
				)
			)
		)
		(duplicate_pad_numbers_are_jumpers no)
		(fp_rect
			(start -0.2794 0.6477)
			(end 0.2794 -0.6477)
			(stroke
				(width 0)
				(type default)
			)
			(fill no)
			(layer "F.CrtYd")
		)
		(fp_rect
			(start -0.2794 0.6477)
			(end 0.2794 -0.6477)
			(stroke
				(width 0)
				(type default)
			)
			(fill no)
			(layer "F.Fab")
		)
		(pad "1" smd custom
			(at 0 -0.2794 270)
			(size 0.0762 0.0762)
			(layers "F.Cu" "F.Mask" "F.Paste")
			(net "SAS_HDD_RX_P8")
			(options
				(clearance outline)
				(anchor circle)
			)
			(primitives
				(gr_poly
					(pts
						(arc
							(start 0.1524 -0.127)
							(mid 0.137521 -0.162921)
							(end 0.1016 -0.1778)
						)
						(arc
							(start -0.1016 -0.1778)
							(mid -0.137521 -0.162921)
							(end -0.1524 -0.127)
						)
						(arc
							(start -0.1524 0.127)
							(mid -0.137521 0.162921)
							(end -0.1016 0.1778)
						)
						(arc
							(start 0.1016 0.1778)
							(mid 0.137521 0.162921)
							(end 0.1524 0.127)
						)
					)
					(width 0)
					(fill yes)
				)
			)
		)
		(pad "2" smd custom
			(at 0 0.2794 270)
			(size 0.0762 0.0762)
			(layers "F.Cu" "F.Mask" "F.Paste")
			(net "PHY_SCC_A_TO_DRV_A_8_DP")
			(options
				(clearance outline)
				(anchor circle)
			)
			(primitives
				(gr_poly
					(pts
						(arc
							(start 0.1524 -0.127)
							(mid 0.137521 -0.162921)
							(end 0.1016 -0.1778)
						)
						(arc
							(start -0.1016 -0.1778)
							(mid -0.137521 -0.162921)
							(end -0.1524 -0.127)
						)
						(arc
							(start -0.1524 0.127)
							(mid -0.137521 0.162921)
							(end -0.1016 0.1778)
						)
						(arc
							(start 0.1016 0.1778)
							(mid 0.137521 0.162921)
							(end 0.1524 0.127)
						)
					)
					(width 0)
					(fill yes)
				)
			)
		)
	)
	(footprint ""
		(layer "F.Cu")
		(at 377.246134 -287.170114)
		(property "Reference" "Q295"
			(at 0 0 0)
			(layer "F.SilkS")
			(hide yes)
			(effects
				(font
					(size 1.27 1.27)
				)
			)
		)
		(property "Value" "SSM3K324R-GP"
			(at 0.127 -8.9662 0)
			(unlocked yes)
			(layer "F.Fab")
			(hide yes)
			(effects
				(font
					(size 1.016 1.016)
					(thickness 0.1524)
				)
			)
		)
		(property "Device Type" "SOT23DGS2D4H35"
			(at 0.127 -10.4902 0)
			(unlocked yes)
			(layer "F.Fab")
			(hide yes)
			(effects
				(font
					(size 1.016 1.016)
					(thickness 0.1524)
				)
			)
		)
		(duplicate_pad_numbers_are_jumpers no)
		(fp_line
			(start -1.651 -1.778)
			(end -1.651 1.778)
			(stroke
				(width 0.1524)
				(type default)
			)
			(layer "F.SilkS")
		)
		(fp_line
			(start -1.651 1.778)
			(end 1.651 1.778)
			(stroke
				(width 0.1524)
				(type default)
			)
			(layer "F.SilkS")
		)
		(fp_line
			(start 1.651 -1.778)
			(end -1.651 -1.778)
			(stroke
				(width 0.1524)
				(type default)
			)
			(layer "F.SilkS")
		)
		(fp_line
			(start 1.651 1.778)
			(end 1.651 -1.778)
			(stroke
				(width 0.1524)
				(type default)
			)
			(layer "F.SilkS")
		)
		(fp_poly
			(pts
				(xy -1.778 1.8796) (xy -1.778 -1.8796) (xy 1.778 -1.8796) (xy 1.778 1.8796)
			)
			(stroke
				(width 0)
				(type default)
			)
			(fill no)
			(layer "F.CrtYd")
		)
		(fp_poly
			(pts
				(xy -1.778 1.8796) (xy -1.778 -1.8796) (xy 1.778 -1.8796) (xy 1.778 1.8796)
			)
			(stroke
				(width 0)
				(type default)
			)
			(fill no)
			(layer "F.Fab")
		)
		(pad "D" smd custom
			(at 0 -0.9525)
			(size 0.1905 0.1905)
			(layers "F.Cu" "F.Mask" "F.Paste")
			(net "DRV_ACT_32_N")
			(options
				(clearance outline)
				(anchor circle)
			)
			(primitives
				(gr_poly
					(pts
						(arc
							(start -0.1778 0.5715)
							(mid -0.321484 0.511984)
							(end -0.381 0.3683)
						)
						(arc
							(start -0.381 -0.3683)
							(mid -0.321484 -0.511984)
							(end -0.1778 -0.5715)
						)
						(arc
							(start 0.1778 -0.5715)
							(mid 0.321484 -0.511984)
							(end 0.381 -0.3683)
						)
						(arc
							(start 0.381 0.3683)
							(mid 0.321484 0.511984)
							(end 0.1778 0.5715)
						)
					)
					(width 0)
					(fill yes)
				)
			)
		)
		(pad "G" smd custom
			(at -0.98425 0.9525)
			(size 0.1905 0.1905)
			(layers "F.Cu" "F.Mask" "F.Paste")
			(net "DRIVE_B_32_ACT")
			(options
				(clearance outline)
				(anchor circle)
			)
			(primitives
				(gr_poly
					(pts
						(arc
							(start -0.1778 0.5715)
							(mid -0.321484 0.511984)
							(end -0.381 0.3683)
						)
						(arc
							(start -0.381 -0.3683)
							(mid -0.321484 -0.511984)
							(end -0.1778 -0.5715)
						)
						(arc
							(start 0.1778 -0.5715)
							(mid 0.321484 -0.511984)
							(end 0.381 -0.3683)
						)
						(arc
							(start 0.381 0.3683)
							(mid 0.321484 0.511984)
							(end 0.1778 0.5715)
						)
					)
					(width 0)
					(fill yes)
				)
			)
		)
		(pad "S" smd custom
			(at 0.98425 0.9525)
			(size 0.1905 0.1905)
			(layers "F.Cu" "F.Mask" "F.Paste")
			(net "GND")
			(options
				(clearance outline)
				(anchor circle)
			)
			(primitives
				(gr_poly
					(pts
						(arc
							(start -0.1778 0.5715)
							(mid -0.321484 0.511984)
							(end -0.381 0.3683)
						)
						(arc
							(start -0.381 -0.3683)
							(mid -0.321484 -0.511984)
							(end -0.1778 -0.5715)
						)
						(arc
							(start 0.1778 -0.5715)
							(mid 0.321484 -0.511984)
							(end 0.381 -0.3683)
						)
						(arc
							(start 0.381 0.3683)
							(mid 0.321484 0.511984)
							(end 0.1778 0.5715)
						)
					)
					(width 0)
					(fill yes)
				)
			)
		)
	)
	(footprint ""
		(layer "F.Cu")
		(at 447.834512 -44.219368 -90)
		(property "Reference" "C480"
			(at 0 0 270)
			(layer "F.SilkS")
			(hide yes)
			(effects
				(font
					(size 1.27 1.27)
				)
			)
		)
		(property "Value" "SCD01U16V1KX-GP"
			(at -2.8321 -1.7399 270)
			(unlocked yes)
			(layer "F.Fab")
			(hide yes)
			(effects
				(font
					(size 1.016 1.016)
					(thickness 0.1524)
				)
			)
		)
		(property "Device Type" "C0201H13"
			(at -2.8321 -3.2639 270)
			(unlocked yes)
			(layer "F.Fab")
			(hide yes)
			(effects
				(font
					(size 1.016 1.016)
					(thickness 0.1524)
				)
			)
		)
		(duplicate_pad_numbers_are_jumpers no)
		(fp_rect
			(start -0.2794 0.6477)
			(end 0.2794 -0.6477)
			(stroke
				(width 0)
				(type default)
			)
			(fill no)
			(layer "F.CrtYd")
		)
		(fp_rect
			(start -0.2794 0.6477)
			(end 0.2794 -0.6477)
			(stroke
				(width 0)
				(type default)
			)
			(fill no)
			(layer "F.Fab")
		)
		(pad "1" smd custom
			(at 0 -0.2794 270)
			(size 0.0762 0.0762)
			(layers "F.Cu" "F.Mask" "F.Paste")
			(net "SAS_HDD_RX_N34")
			(options
				(clearance outline)
				(anchor circle)
			)
			(primitives
				(gr_poly
					(pts
						(arc
							(start 0.1524 -0.127)
							(mid 0.137521 -0.162921)
							(end 0.1016 -0.1778)
						)
						(arc
							(start -0.1016 -0.1778)
							(mid -0.137521 -0.162921)
							(end -0.1524 -0.127)
						)
						(arc
							(start -0.1524 0.127)
							(mid -0.137521 0.162921)
							(end -0.1016 0.1778)
						)
						(arc
							(start 0.1016 0.1778)
							(mid 0.137521 0.162921)
							(end 0.1524 0.127)
						)
					)
					(width 0)
					(fill yes)
				)
			)
		)
		(pad "2" smd custom
			(at 0 0.2794 270)
			(size 0.0762 0.0762)
			(layers "F.Cu" "F.Mask" "F.Paste")
			(net "PHY_SCC_A_TO_DRV_A_34_DN")
			(options
				(clearance outline)
				(anchor circle)
			)
			(primitives
				(gr_poly
					(pts
						(arc
							(start 0.1524 -0.127)
							(mid 0.137521 -0.162921)
							(end 0.1016 -0.1778)
						)
						(arc
							(start -0.1016 -0.1778)
							(mid -0.137521 -0.162921)
							(end -0.1524 -0.127)
						)
						(arc
							(start -0.1524 0.127)
							(mid -0.137521 0.162921)
							(end -0.1016 0.1778)
						)
						(arc
							(start 0.1016 0.1778)
							(mid 0.137521 0.162921)
							(end 0.1524 0.127)
						)
					)
					(width 0)
					(fill yes)
				)
			)
		)
	)
	(footprint ""
		(layer "F.Cu")
		(at 396.60195 -73.954894 180)
		(property "Reference" "C462"
			(at 0 0 180)
			(layer "F.SilkS")
			(hide yes)
			(effects
				(font
					(size 1.27 1.27)
				)
			)
		)
		(property "Value" "SC4D7U25V5KX-1-GP"
			(at -0.0762 -6.1214 180)
			(unlocked yes)
			(layer "F.Fab")
			(hide yes)
			(effects
				(font
					(size 1.016 1.016)
					(thickness 0.1524)
				)
			)
		)
		(property "Device Type" "C805H58"
			(at -0.0762 -8.1534 180)
			(unlocked yes)
			(layer "F.Fab")
			(hide yes)
			(effects
				(font
					(size 1.016 1.016)
					(thickness 0.1524)
				)
			)
		)
		(duplicate_pad_numbers_are_jumpers no)
		(fp_line
			(start 0.635 0)
			(end -0.635 0)
			(stroke
				(width 0.508)
				(type default)
			)
			(layer "F.SilkS")
		)
		(fp_rect
			(start -0.9652 1.778)
			(end 0.9652 -1.778)
			(stroke
				(width 0)
				(type default)
			)
			(fill no)
			(layer "F.CrtYd")
		)
		(fp_poly
			(pts
				(xy -0.9652 -1.778) (xy 0.9652 -1.778) (xy 0.9652 1.778) (xy -0.9652 1.778)
			)
			(stroke
				(width 0)
				(type default)
			)
			(fill no)
			(layer "F.Fab")
		)
		(pad "1" smd rect
			(at 0 -0.9652 180)
			(size 1.397 1.143)
			(layers "F.Cu" "F.Mask" "F.Paste")
			(net "P12V_HDD32")
		)
		(pad "2" smd rect
			(at 0 0.9652 180)
			(size 1.397 1.143)
			(layers "F.Cu" "F.Mask" "F.Paste")
			(net "GND")
		)
	)
	(footprint ""
		(layer "F.Cu")
		(at 315.149992 -324.39991)
		(property "Reference" "RLED31"
			(at 0 0 0)
			(layer "F.SilkS")
			(hide yes)
			(effects
				(font
					(size 1.27 1.27)
				)
			)
		)
		(property "Value" "LED-BY-19-GP"
			(at -2.132076 1.414018 0)
			(unlocked yes)
			(layer "F.Fab")
			(hide yes)
			(effects
				(font
					(size 1.016 1.016)
					(thickness 0.1524)
				)
			)
		)
		(property "Device Type" "LED-1615-4PH26"
			(at -2.132076 -0.109982 0)
			(unlocked yes)
			(layer "F.Fab")
			(hide yes)
			(effects
				(font
					(size 1.016 1.016)
					(thickness 0.1524)
				)
			)
		)
		(duplicate_pad_numbers_are_jumpers no)
		(fp_line
			(start -1.2954 0.254)
			(end -1.2954 1.6002)
			(stroke
				(width 0.508)
				(type default)
			)
			(layer "F.SilkS")
		)
		(fp_line
			(start -1.2954 1.6002)
			(end 1.2954 1.6002)
			(stroke
				(width 0.508)
				(type default)
			)
			(layer "F.SilkS")
		)
		(fp_line
			(start -1.1176 -1.4224)
			(end 1.1176 -1.4224)
			(stroke
				(width 0.1524)
				(type default)
			)
			(layer "F.SilkS")
		)
		(fp_line
			(start -1.1176 1.4224)
			(end -1.1176 -1.4224)
			(stroke
				(width 0.1524)
				(type default)
			)
			(layer "F.SilkS")
		)
		(fp_line
			(start 1.1176 -1.4224)
			(end 1.1176 1.4224)
			(stroke
				(width 0.1524)
				(type default)
			)
			(layer "F.SilkS")
		)
		(fp_line
			(start 1.1176 1.4224)
			(end -1.1176 1.4224)
			(stroke
				(width 0.1524)
				(type default)
			)
			(layer "F.SilkS")
		)
		(fp_line
			(start 1.2954 1.6002)
			(end 1.2954 0.254)
			(stroke
				(width 0.508)
				(type default)
			)
			(layer "F.SilkS")
		)
		(fp_rect
			(start -0.7493 0.8001)
			(end 0.7493 -0.8001)
			(stroke
				(width 0)
				(type default)
			)
			(fill no)
			(layer "F.CrtYd")
		)
		(fp_poly
			(pts
				(xy -1.3716 1.6764) (xy -1.3716 -1.6764) (xy 1.3716 -1.6764) (xy 1.3716 0.0635) (xy 0.7493 0.0635)
				(xy 0.7493 -0.8001) (xy -0.7493 -0.8001) (xy -0.7493 0.8001) (xy 0.7493 0.8001) (xy 0.7493 0.0762)
				(xy 1.3716 0.0762) (xy 1.3716 1.6764)
			)
			(stroke
				(width 0)
				(type default)
			)
			(fill no)
			(layer "F.CrtYd")
		)
		(fp_rect
			(start -1.3716 1.6764)
			(end 1.3716 -1.6764)
			(stroke
				(width 0)
				(type default)
			)
			(fill no)
			(layer "F.Fab")
		)
		(pad "1" smd rect
			(at 0.50038 -0.73025)
			(size 0.7112 0.8636)
			(layers "F.Cu" "F.Mask" "F.Paste")
			(net "DRV_ACT_30")
		)
		(pad "2" smd rect
			(at -0.50038 -0.73025)
			(size 0.7112 0.8636)
			(layers "F.Cu" "F.Mask" "F.Paste")
			(net "FLT_HDD30")
		)
		(pad "3" smd rect
			(at 0.50038 0.73025)
			(size 0.7112 0.8636)
			(layers "F.Cu" "F.Mask" "F.Paste")
			(net "DRV_ACT_30_N")
		)
		(pad "4" smd rect
			(at -0.50038 0.73025)
			(size 0.7112 0.8636)
			(layers "F.Cu" "F.Mask" "F.Paste")
			(net "FLT_HDD30_N")
		)
	)
	(footprint ""
		(layer "F.Cu")
		(at 157.748732 -137.34923)
		(property "Reference" "C545"
			(at 0 0 0)
			(layer "F.SilkS")
			(hide yes)
			(effects
				(font
					(size 1.27 1.27)
				)
			)
		)
		(property "Value" "SCD015U25V2KX-GP"
			(at 1.1811 -2.7051 0)
			(unlocked yes)
			(layer "F.Fab")
			(hide yes)
			(effects
				(font
					(size 1.016 1.016)
					(thickness 0.1524)
				)
			)
		)
		(property "Device Type" "C402H22"
			(at 1.1811 -4.2291 0)
			(unlocked yes)
			(layer "F.Fab")
			(hide yes)
			(effects
				(font
					(size 1.016 1.016)
					(thickness 0.1524)
				)
			)
		)
		(duplicate_pad_numbers_are_jumpers no)
		(fp_rect
			(start -0.4318 0.9525)
			(end 0.4318 -0.9525)
			(stroke
				(width 0)
				(type default)
			)
			(fill no)
			(layer "F.CrtYd")
		)
		(fp_rect
			(start -0.4318 0.9525)
			(end 0.4318 -0.9525)
			(stroke
				(width 0)
				(type default)
			)
			(fill no)
			(layer "F.Fab")
		)
		(pad "1" smd custom
			(at 0 -0.4445)
			(size 0.1524 0.1524)
			(layers "F.Cu" "F.Mask" "F.Paste")
			(net "MB0_CM_SENSE_P")
			(options
				(clearance outline)
				(anchor circle)
			)
			(primitives
				(gr_poly
					(pts
						(arc
							(start 0.3048 -0.2032)
							(mid 0.275042 -0.275042)
							(end 0.2032 -0.3048)
						)
						(arc
							(start -0.2032 -0.3048)
							(mid -0.275042 -0.275042)
							(end -0.3048 -0.2032)
						)
						(arc
							(start -0.3048 0.2032)
							(mid -0.275042 0.275042)
							(end -0.2032 0.3048)
						)
						(arc
							(start 0.2032 0.3048)
							(mid 0.275042 0.275042)
							(end 0.3048 0.2032)
						)
					)
					(width 0)
					(fill yes)
				)
			)
		)
		(pad "2" smd custom
			(at 0 0.4445)
			(size 0.1524 0.1524)
			(layers "F.Cu" "F.Mask" "F.Paste")
			(net "MB0_CM_SENSE_N")
			(options
				(clearance outline)
				(anchor circle)
			)
			(primitives
				(gr_poly
					(pts
						(arc
							(start 0.3048 -0.2032)
							(mid 0.275042 -0.275042)
							(end 0.2032 -0.3048)
						)
						(arc
							(start -0.2032 -0.3048)
							(mid -0.275042 -0.275042)
							(end -0.3048 -0.2032)
						)
						(arc
							(start -0.3048 0.2032)
							(mid -0.275042 0.275042)
							(end -0.2032 0.3048)
						)
						(arc
							(start 0.2032 0.3048)
							(mid 0.275042 0.275042)
							(end 0.3048 0.2032)
						)
					)
					(width 0)
					(fill yes)
				)
			)
		)
	)
	(footprint ""
		(layer "F.Cu")
		(at 214.568532 -388.795514 90)
		(property "Reference" "U48"
			(at 0 0 90)
			(layer "F.SilkS")
			(hide yes)
			(effects
				(font
					(size 1.27 1.27)
				)
			)
		)
		(property "Value" "SN74LVC1G08DCKR-GP"
			(at -2.3368 -8.6868 90)
			(unlocked yes)
			(layer "F.Fab")
			(hide yes)
			(effects
				(font
					(size 1.016 1.016)
					(thickness 0.1524)
				)
			)
		)
		(property "Device Type" "SC70-5H44"
			(at -2.3114 -10.414 90)
			(unlocked yes)
			(layer "F.Fab")
			(hide yes)
			(effects
				(font
					(size 1.016 1.016)
					(thickness 0.1524)
				)
			)
		)
		(duplicate_pad_numbers_are_jumpers no)
		(fp_line
			(start 1.3843 -1.8034)
			(end 1.3843 -1.1176)
			(stroke
				(width 0.3302)
				(type default)
			)
			(layer "F.SilkS")
		)
		(fp_line
			(start 0.6604 -1.8034)
			(end 1.3843 -1.8034)
			(stroke
				(width 0.3302)
				(type default)
			)
			(layer "F.SilkS")
		)
		(fp_line
			(start 1.27 -1.7018)
			(end 1.27 1.7018)
			(stroke
				(width 0.1524)
				(type default)
			)
			(layer "F.SilkS")
		)
		(fp_line
			(start -1.27 -1.7018)
			(end 1.27 -1.7018)
			(stroke
				(width 0.1524)
				(type default)
			)
			(layer "F.SilkS")
		)
		(fp_line
			(start 1.27 1.7018)
			(end -1.27 1.7018)
			(stroke
				(width 0.1524)
				(type default)
			)
			(layer "F.SilkS")
		)
		(fp_line
			(start -1.27 1.7018)
			(end -1.27 -1.7018)
			(stroke
				(width 0.1524)
				(type default)
			)
			(layer "F.SilkS")
		)
		(fp_rect
			(start -1.524 1.9558)
			(end 1.524 -1.9558)
			(stroke
				(width 0)
				(type default)
			)
			(fill no)
			(layer "F.CrtYd")
		)
		(fp_poly
			(pts
				(xy -1.524 -1.9558) (xy 1.524 -1.9558) (xy 1.524 1.9558) (xy -1.524 1.9558)
			)
			(stroke
				(width 0)
				(type default)
			)
			(fill no)
			(layer "F.Fab")
		)
		(pad "1" smd rect
			(at 0.65024 -0.8255 90)
			(size 0.4064 1.2192)
			(layers "F.Cu" "F.Mask" "F.Paste")
			(net "BMC_B_TO_EXP_B_RESET_N")
		)
		(pad "2" smd rect
			(at 0 -0.8255 90)
			(size 0.4064 1.2192)
			(layers "F.Cu" "F.Mask" "F.Paste")
			(net "RST_BTN_B_N")
		)
		(pad "3" smd rect
			(at -0.65024 -0.8255 90)
			(size 0.4064 1.2192)
			(layers "F.Cu" "F.Mask" "F.Paste")
			(net "GND")
		)
		(pad "4" smd rect
			(at -0.65024 0.8255 90)
			(size 0.4064 1.2192)
			(layers "F.Cu" "F.Mask" "F.Paste")
			(net "SCC_B_RESET_N")
		)
		(pad "5" smd rect
			(at 0.65024 0.8255 90)
			(size 0.4064 1.2192)
			(layers "F.Cu" "F.Mask" "F.Paste")
			(net "P3V3_STBY_B")
		)
	)
	(footprint ""
		(layer "F.Cu")
		(at 482.489002 -47.749968 -90)
		(property "Reference" "VIA29"
			(at 0 0 270)
			(layer "F.SilkS")
			(hide yes)
			(effects
				(font
					(size 1.27 1.27)
				)
			)
		)
		(property "Value" "100OHM-8L-1D6MM-L18L16-GP"
			(at -3.7211 -4.5085 270)
			(unlocked yes)
			(layer "F.Fab")
			(hide yes)
			(effects
				(font
					(size 1.016 1.016)
					(thickness 0.1524)
				)
			)
		)
		(property "Device Type" "VIA-PCIE-4P-394076"
			(at -3.7211 -6.0325 270)
			(unlocked yes)
			(layer "F.Fab")
			(hide yes)
			(effects
				(font
					(size 1.016 1.016)
					(thickness 0.1524)
				)
			)
		)
		(duplicate_pad_numbers_are_jumpers no)
		(fp_rect
			(start -1.9685 0.381)
			(end 1.9685 -0.381)
			(stroke
				(width 0)
				(type default)
			)
			(fill no)
			(layer "F.CrtYd")
		)
		(fp_rect
			(start -1.9685 0.381)
			(end 1.9685 -0.381)
			(stroke
				(width 0)
				(type default)
			)
			(fill no)
			(layer "F.Fab")
		)
		(pad "1" thru_hole circle
			(at -1.5875 0 270)
			(size 0.508 0.508)
			(drill 0.254)
			(layers "*.Cu" "*.Mask")
			(remove_unused_layers no)
			(net "GND")
			(clearance 0.127)
			(thermal_gap 0.127)
		)
		(pad "2" thru_hole circle
			(at -0.5715 0 270)
			(size 0.508 0.508)
			(drill 0.254)
			(layers "*.Cu" "*.Mask")
			(remove_unused_layers no)
			(net "PHY_DRV_A_TO_SCC_A_35_DP")
			(clearance 0.127)
			(thermal_gap 0.127)
		)
		(pad "3" thru_hole circle
			(at 0.5715 0 270)
			(size 0.508 0.508)
			(drill 0.254)
			(layers "*.Cu" "*.Mask")
			(remove_unused_layers no)
			(net "PHY_DRV_A_TO_SCC_A_35_DN")
			(clearance 0.127)
			(thermal_gap 0.127)
		)
		(pad "4" thru_hole circle
			(at 1.5875 0 270)
			(size 0.508 0.508)
			(drill 0.254)
			(layers "*.Cu" "*.Mask")
			(remove_unused_layers no)
			(net "GND")
			(clearance 0.127)
			(thermal_gap 0.127)
		)
	)
	(footprint ""
		(layer "F.Cu")
		(at 191.135 -294.767 180)
		(property "Reference" "R249"
			(at 0 0 180)
			(layer "F.SilkS")
			(hide yes)
			(effects
				(font
					(size 1.27 1.27)
				)
			)
		)
		(property "Value" "220R3F-1-GP"
			(at -0.0254 -2.5146 180)
			(unlocked yes)
			(layer "F.Fab")
			(hide yes)
			(effects
				(font
					(size 1.016 1.016)
					(thickness 0.1524)
				)
			)
		)
		(property "Device Type" "R603H22"
			(at -0.0254 -4.0386 180)
			(unlocked yes)
			(layer "F.Fab")
			(hide yes)
			(effects
				(font
					(size 1.016 1.016)
					(thickness 0.1524)
				)
			)
		)
		(duplicate_pad_numbers_are_jumpers no)
		(fp_line
			(start 0.2032 0)
			(end 0.4826 0)
			(stroke
				(width 0.2032)
				(type default)
			)
			(layer "F.SilkS")
		)
		(fp_line
			(start -0.4826 0)
			(end -0.2032 0)
			(stroke
				(width 0.2032)
				(type default)
			)
			(layer "F.SilkS")
		)
		(fp_rect
			(start -0.5842 1.3335)
			(end 0.5842 -1.3335)
			(stroke
				(width 0)
				(type default)
			)
			(fill no)
			(layer "F.CrtYd")
		)
		(fp_rect
			(start -0.5842 1.3335)
			(end 0.5842 -1.3335)
			(stroke
				(width 0)
				(type default)
			)
			(fill no)
			(layer "F.Fab")
		)
		(pad "1" smd custom
			(at 0 -0.762 180)
			(size 0.2159 0.2159)
			(layers "F.Cu" "F.Mask" "F.Paste")
			(net "HDD_PRSNT_5")
			(options
				(clearance outline)
				(anchor circle)
			)
			(primitives
				(gr_poly
					(pts
						(arc
							(start -0.3302 -0.4318)
							(mid -0.402042 -0.402042)
							(end -0.4318 -0.3302)
						)
						(arc
							(start -0.4318 0.3302)
							(mid -0.402042 0.402042)
							(end -0.3302 0.4318)
						)
						(arc
							(start 0.3302 0.4318)
							(mid 0.402042 0.402042)
							(end 0.4318 0.3302)
						)
						(arc
							(start 0.4318 -0.3302)
							(mid 0.402042 -0.402042)
							(end 0.3302 -0.4318)
						)
					)
					(width 0)
					(fill yes)
				)
			)
		)
		(pad "2" smd custom
			(at 0 0.762 180)
			(size 0.2159 0.2159)
			(layers "F.Cu" "F.Mask" "F.Paste")
			(net "DRIVE_A_5_INS")
			(options
				(clearance outline)
				(anchor circle)
			)
			(primitives
				(gr_poly
					(pts
						(arc
							(start -0.3302 -0.4318)
							(mid -0.402042 -0.402042)
							(end -0.4318 -0.3302)
						)
						(arc
							(start -0.4318 0.3302)
							(mid -0.402042 0.402042)
							(end -0.3302 0.4318)
						)
						(arc
							(start 0.3302 0.4318)
							(mid 0.402042 0.402042)
							(end 0.4318 0.3302)
						)
						(arc
							(start 0.4318 -0.3302)
							(mid 0.402042 -0.402042)
							(end 0.3302 -0.4318)
						)
					)
					(width 0)
					(fill yes)
				)
			)
		)
	)
	(footprint ""
		(layer "F.Cu")
		(at 114.725196 -282.695142 -90)
		(property "Reference" "R214"
			(at 0 0 270)
			(layer "F.SilkS")
			(hide yes)
			(effects
				(font
					(size 1.27 1.27)
				)
			)
		)
		(property "Value" "300KR2F-GP"
			(at 0.064008 -3.993896 270)
			(unlocked yes)
			(layer "F.Fab")
			(hide yes)
			(effects
				(font
					(size 1.016 1.016)
					(thickness 0.1524)
				)
			)
		)
		(property "Device Type" "R402H16"
			(at 0.064008 -5.517896 270)
			(unlocked yes)
			(layer "F.Fab")
			(hide yes)
			(effects
				(font
					(size 1.016 1.016)
					(thickness 0.1524)
				)
			)
		)
		(duplicate_pad_numbers_are_jumpers no)
		(fp_line
			(start -0.508 -0.9398)
			(end -0.508 0.9398)
			(stroke
				(width 0.1524)
				(type default)
			)
			(layer "F.SilkS")
		)
		(fp_line
			(start 0.508 -0.9398)
			(end -0.508 -0.9398)
			(stroke
				(width 0.1524)
				(type default)
			)
			(layer "F.SilkS")
		)
		(fp_rect
			(start -0.508 0.9398)
			(end 0.508 -0.9398)
			(stroke
				(width 0)
				(type default)
			)
			(fill no)
			(layer "F.CrtYd")
		)
		(fp_rect
			(start -0.508 0.9398)
			(end 0.508 -0.9398)
			(stroke
				(width 0)
				(type default)
			)
			(fill no)
			(layer "F.Fab")
		)
		(pad "1" smd custom
			(at 0 -0.4445 270)
			(size 0.1397 0.1397)
			(layers "F.Cu" "F.Mask" "F.Paste")
			(net "SW_HDD_N3")
			(options
				(clearance outline)
				(anchor circle)
			)
			(primitives
				(gr_poly
					(pts
						(arc
							(start -0.1778 -0.2794)
							(mid -0.249642 -0.249642)
							(end -0.2794 -0.1778)
						)
						(arc
							(start -0.2794 0.1778)
							(mid -0.249642 0.249642)
							(end -0.1778 0.2794)
						)
						(arc
							(start 0.1778 0.2794)
							(mid 0.249642 0.249642)
							(end 0.2794 0.1778)
						)
						(arc
							(start 0.2794 -0.1778)
							(mid 0.249642 -0.249642)
							(end 0.1778 -0.2794)
						)
					)
					(width 0)
					(fill yes)
				)
			)
		)
		(pad "2" smd custom
			(at 0 0.4445 270)
			(size 0.1397 0.1397)
			(layers "F.Cu" "F.Mask" "F.Paste")
			(net "P12V_A")
			(options
				(clearance outline)
				(anchor circle)
			)
			(primitives
				(gr_poly
					(pts
						(arc
							(start -0.1778 -0.2794)
							(mid -0.249642 -0.249642)
							(end -0.2794 -0.1778)
						)
						(arc
							(start -0.2794 0.1778)
							(mid -0.249642 0.249642)
							(end -0.1778 0.2794)
						)
						(arc
							(start 0.1778 0.2794)
							(mid 0.249642 0.249642)
							(end 0.2794 0.1778)
						)
						(arc
							(start 0.2794 -0.1778)
							(mid 0.249642 -0.249642)
							(end 0.1778 -0.2794)
						)
					)
					(width 0)
					(fill yes)
				)
			)
		)
	)
	(footprint ""
		(layer "F.Cu")
		(at 458.9399 -49.596294 90)
		(property "Reference" "C490"
			(at 0 0 90)
			(layer "F.SilkS")
			(hide yes)
			(effects
				(font
					(size 1.27 1.27)
				)
			)
		)
		(property "Value" "SCD033U25V2KX-GP"
			(at 1.1811 -2.7051 90)
			(unlocked yes)
			(layer "F.Fab")
			(hide yes)
			(effects
				(font
					(size 1.016 1.016)
					(thickness 0.1524)
				)
			)
		)
		(property "Device Type" "C402H22"
			(at 1.1811 -4.2291 90)
			(unlocked yes)
			(layer "F.Fab")
			(hide yes)
			(effects
				(font
					(size 1.016 1.016)
					(thickness 0.1524)
				)
			)
		)
		(duplicate_pad_numbers_are_jumpers no)
		(fp_rect
			(start -0.4318 0.9525)
			(end 0.4318 -0.9525)
			(stroke
				(width 0)
				(type default)
			)
			(fill no)
			(layer "F.CrtYd")
		)
		(fp_rect
			(start -0.4318 0.9525)
			(end 0.4318 -0.9525)
			(stroke
				(width 0)
				(type default)
			)
			(fill no)
			(layer "F.Fab")
		)
		(pad "1" smd custom
			(at 0 -0.4445 90)
			(size 0.1524 0.1524)
			(layers "F.Cu" "F.Mask" "F.Paste")
			(net "SW_HDD_P34")
			(options
				(clearance outline)
				(anchor circle)
			)
			(primitives
				(gr_poly
					(pts
						(arc
							(start 0.3048 -0.2032)
							(mid 0.275042 -0.275042)
							(end 0.2032 -0.3048)
						)
						(arc
							(start -0.2032 -0.3048)
							(mid -0.275042 -0.275042)
							(end -0.3048 -0.2032)
						)
						(arc
							(start -0.3048 0.2032)
							(mid -0.275042 0.275042)
							(end -0.2032 0.3048)
						)
						(arc
							(start 0.2032 0.3048)
							(mid 0.275042 0.275042)
							(end 0.3048 0.2032)
						)
					)
					(width 0)
					(fill yes)
				)
			)
		)
		(pad "2" smd custom
			(at 0 0.4445 90)
			(size 0.1524 0.1524)
			(layers "F.Cu" "F.Mask" "F.Paste")
			(net "GND")
			(options
				(clearance outline)
				(anchor circle)
			)
			(primitives
				(gr_poly
					(pts
						(arc
							(start 0.3048 -0.2032)
							(mid 0.275042 -0.275042)
							(end 0.2032 -0.3048)
						)
						(arc
							(start -0.2032 -0.3048)
							(mid -0.275042 -0.275042)
							(end -0.3048 -0.2032)
						)
						(arc
							(start -0.3048 0.2032)
							(mid -0.275042 0.275042)
							(end -0.2032 0.3048)
						)
						(arc
							(start 0.2032 0.3048)
							(mid 0.275042 0.275042)
							(end 0.3048 0.2032)
						)
					)
					(width 0)
					(fill yes)
				)
			)
		)
	)
	(footprint ""
		(layer "F.Cu")
		(at 458.838808 -242.78844 180)
		(property "Reference" "Q238"
			(at 0 0 180)
			(layer "F.SilkS")
			(hide yes)
			(effects
				(font
					(size 1.27 1.27)
				)
			)
		)
		(property "Value" "2N7002K-2-GP"
			(at 0.127 -8.9662 180)
			(unlocked yes)
			(layer "F.Fab")
			(hide yes)
			(effects
				(font
					(size 1.016 1.016)
					(thickness 0.1524)
				)
			)
		)
		(property "Device Type" "SOT23DGS2D4H44"
			(at 0.127 -10.4902 180)
			(unlocked yes)
			(layer "F.Fab")
			(hide yes)
			(effects
				(font
					(size 1.016 1.016)
					(thickness 0.1524)
				)
			)
		)
		(duplicate_pad_numbers_are_jumpers no)
		(fp_line
			(start 1.651 1.778)
			(end 1.651 -1.778)
			(stroke
				(width 0.1524)
				(type default)
			)
			(layer "F.SilkS")
		)
		(fp_line
			(start 1.651 -1.778)
			(end -1.651 -1.778)
			(stroke
				(width 0.1524)
				(type default)
			)
			(layer "F.SilkS")
		)
		(fp_line
			(start -1.651 1.778)
			(end 1.651 1.778)
			(stroke
				(width 0.1524)
				(type default)
			)
			(layer "F.SilkS")
		)
		(fp_line
			(start -1.651 -1.778)
			(end -1.651 1.778)
			(stroke
				(width 0.1524)
				(type default)
			)
			(layer "F.SilkS")
		)
		(fp_poly
			(pts
				(xy -1.778 1.8796) (xy -1.778 -1.8796) (xy 1.778 -1.8796) (xy 1.778 1.8796)
			)
			(stroke
				(width 0)
				(type default)
			)
			(fill no)
			(layer "F.CrtYd")
		)
		(fp_poly
			(pts
				(xy -1.778 1.8796) (xy -1.778 -1.8796) (xy 1.778 -1.8796) (xy 1.778 1.8796)
			)
			(stroke
				(width 0)
				(type default)
			)
			(fill no)
			(layer "F.Fab")
		)
		(pad "D" smd custom
			(at 0 -0.9525 180)
			(size 0.1905 0.1905)
			(layers "F.Cu" "F.Mask" "F.Paste")
			(net "FLT_HDD11_N")
			(options
				(clearance outline)
				(anchor circle)
			)
			(primitives
				(gr_poly
					(pts
						(arc
							(start -0.1778 0.5715)
							(mid -0.321484 0.511984)
							(end -0.381 0.3683)
						)
						(arc
							(start -0.381 -0.3683)
							(mid -0.321484 -0.511984)
							(end -0.1778 -0.5715)
						)
						(arc
							(start 0.1778 -0.5715)
							(mid 0.321484 -0.511984)
							(end 0.381 -0.3683)
						)
						(arc
							(start 0.381 0.3683)
							(mid 0.321484 0.511984)
							(end 0.1778 0.5715)
						)
					)
					(width 0)
					(fill yes)
				)
			)
		)
		(pad "G" smd custom
			(at -0.98425 0.9525 180)
			(size 0.1905 0.1905)
			(layers "F.Cu" "F.Mask" "F.Paste")
			(net "DRIVE_A_11_FLT_LED")
			(options
				(clearance outline)
				(anchor circle)
			)
			(primitives
				(gr_poly
					(pts
						(arc
							(start -0.1778 0.5715)
							(mid -0.321484 0.511984)
							(end -0.381 0.3683)
						)
						(arc
							(start -0.381 -0.3683)
							(mid -0.321484 -0.511984)
							(end -0.1778 -0.5715)
						)
						(arc
							(start 0.1778 -0.5715)
							(mid 0.321484 -0.511984)
							(end 0.381 -0.3683)
						)
						(arc
							(start 0.381 0.3683)
							(mid 0.321484 0.511984)
							(end 0.1778 0.5715)
						)
					)
					(width 0)
					(fill yes)
				)
			)
		)
		(pad "S" smd custom
			(at 0.98425 0.9525 180)
			(size 0.1905 0.1905)
			(layers "F.Cu" "F.Mask" "F.Paste")
			(net "GND")
			(options
				(clearance outline)
				(anchor circle)
			)
			(primitives
				(gr_poly
					(pts
						(arc
							(start -0.1778 0.5715)
							(mid -0.321484 0.511984)
							(end -0.381 0.3683)
						)
						(arc
							(start -0.381 -0.3683)
							(mid -0.321484 -0.511984)
							(end -0.1778 -0.5715)
						)
						(arc
							(start 0.1778 -0.5715)
							(mid 0.321484 -0.511984)
							(end 0.381 -0.3683)
						)
						(arc
							(start 0.381 0.3683)
							(mid 0.321484 0.511984)
							(end 0.1778 0.5715)
						)
					)
					(width 0)
					(fill yes)
				)
			)
		)
	)
	(footprint ""
		(layer "F.Cu")
		(at 54.546246 -160.887918 90)
		(property "Reference" "R441"
			(at 0 0 90)
			(layer "F.SilkS")
			(hide yes)
			(effects
				(font
					(size 1.27 1.27)
				)
			)
		)
		(property "Value" "4K7R2J-2-GP"
			(at 0.064008 -3.993896 90)
			(unlocked yes)
			(layer "F.Fab")
			(hide yes)
			(effects
				(font
					(size 1.016 1.016)
					(thickness 0.1524)
				)
			)
		)
		(property "Device Type" "R402H16"
			(at 0.064008 -5.517896 90)
			(unlocked yes)
			(layer "F.Fab")
			(hide yes)
			(effects
				(font
					(size 1.016 1.016)
					(thickness 0.1524)
				)
			)
		)
		(duplicate_pad_numbers_are_jumpers no)
		(fp_line
			(start 0.508 -0.9398)
			(end -0.508 -0.9398)
			(stroke
				(width 0.1524)
				(type default)
			)
			(layer "F.SilkS")
		)
		(fp_line
			(start -0.508 -0.9398)
			(end -0.508 0.9398)
			(stroke
				(width 0.1524)
				(type default)
			)
			(layer "F.SilkS")
		)
		(fp_rect
			(start -0.508 0.9398)
			(end 0.508 -0.9398)
			(stroke
				(width 0)
				(type default)
			)
			(fill no)
			(layer "F.CrtYd")
		)
		(fp_rect
			(start -0.508 0.9398)
			(end 0.508 -0.9398)
			(stroke
				(width 0)
				(type default)
			)
			(fill no)
			(layer "F.Fab")
		)
		(pad "1" smd custom
			(at 0 -0.4445 90)
			(size 0.1397 0.1397)
			(layers "F.Cu" "F.Mask" "F.Paste")
			(net "SW_PWR_R_HDD13")
			(options
				(clearance outline)
				(anchor circle)
			)
			(primitives
				(gr_poly
					(pts
						(arc
							(start -0.1778 -0.2794)
							(mid -0.249642 -0.249642)
							(end -0.2794 -0.1778)
						)
						(arc
							(start -0.2794 0.1778)
							(mid -0.249642 0.249642)
							(end -0.1778 0.2794)
						)
						(arc
							(start 0.1778 0.2794)
							(mid 0.249642 0.249642)
							(end 0.2794 0.1778)
						)
						(arc
							(start 0.2794 -0.1778)
							(mid 0.249642 -0.249642)
							(end 0.1778 -0.2794)
						)
					)
					(width 0)
					(fill yes)
				)
			)
		)
		(pad "2" smd custom
			(at 0 0.4445 90)
			(size 0.1397 0.1397)
			(layers "F.Cu" "F.Mask" "F.Paste")
			(net "GND")
			(options
				(clearance outline)
				(anchor circle)
			)
			(primitives
				(gr_poly
					(pts
						(arc
							(start -0.1778 -0.2794)
							(mid -0.249642 -0.249642)
							(end -0.2794 -0.1778)
						)
						(arc
							(start -0.2794 0.1778)
							(mid -0.249642 0.249642)
							(end -0.1778 0.2794)
						)
						(arc
							(start 0.1778 0.2794)
							(mid 0.249642 0.249642)
							(end 0.2794 0.1778)
						)
						(arc
							(start 0.2794 -0.1778)
							(mid 0.249642 -0.249642)
							(end 0.1778 -0.2794)
						)
					)
					(width 0)
					(fill yes)
				)
			)
		)
	)
	(footprint ""
		(layer "F.Cu")
		(at 432.724052 -49.443894 90)
		(property "Reference" "R905"
			(at 0 0 90)
			(layer "F.SilkS")
			(hide yes)
			(effects
				(font
					(size 1.27 1.27)
				)
			)
		)
		(property "Value" "200KR2F-L-GP"
			(at 0.064008 -3.993896 90)
			(unlocked yes)
			(layer "F.Fab")
			(hide yes)
			(effects
				(font
					(size 1.016 1.016)
					(thickness 0.1524)
				)
			)
		)
		(property "Device Type" "R402H16"
			(at 0.064008 -5.517896 90)
			(unlocked yes)
			(layer "F.Fab")
			(hide yes)
			(effects
				(font
					(size 1.016 1.016)
					(thickness 0.1524)
				)
			)
		)
		(duplicate_pad_numbers_are_jumpers no)
		(fp_line
			(start 0.508 -0.9398)
			(end -0.508 -0.9398)
			(stroke
				(width 0.1524)
				(type default)
			)
			(layer "F.SilkS")
		)
		(fp_line
			(start -0.508 -0.9398)
			(end -0.508 0.9398)
			(stroke
				(width 0.1524)
				(type default)
			)
			(layer "F.SilkS")
		)
		(fp_rect
			(start -0.508 0.9398)
			(end 0.508 -0.9398)
			(stroke
				(width 0)
				(type default)
			)
			(fill no)
			(layer "F.CrtYd")
		)
		(fp_rect
			(start -0.508 0.9398)
			(end 0.508 -0.9398)
			(stroke
				(width 0)
				(type default)
			)
			(fill no)
			(layer "F.Fab")
		)
		(pad "1" smd custom
			(at 0 -0.4445 90)
			(size 0.1397 0.1397)
			(layers "F.Cu" "F.Mask" "F.Paste")
			(net "SW_HDD_R33")
			(options
				(clearance outline)
				(anchor circle)
			)
			(primitives
				(gr_poly
					(pts
						(arc
							(start -0.1778 -0.2794)
							(mid -0.249642 -0.249642)
							(end -0.2794 -0.1778)
						)
						(arc
							(start -0.2794 0.1778)
							(mid -0.249642 0.249642)
							(end -0.1778 0.2794)
						)
						(arc
							(start 0.1778 0.2794)
							(mid 0.249642 0.249642)
							(end 0.2794 0.1778)
						)
						(arc
							(start 0.2794 -0.1778)
							(mid 0.249642 -0.249642)
							(end 0.1778 -0.2794)
						)
					)
					(width 0)
					(fill yes)
				)
			)
		)
		(pad "2" smd custom
			(at 0 0.4445 90)
			(size 0.1397 0.1397)
			(layers "F.Cu" "F.Mask" "F.Paste")
			(net "SW_HDD_N33")
			(options
				(clearance outline)
				(anchor circle)
			)
			(primitives
				(gr_poly
					(pts
						(arc
							(start -0.1778 -0.2794)
							(mid -0.249642 -0.249642)
							(end -0.2794 -0.1778)
						)
						(arc
							(start -0.2794 0.1778)
							(mid -0.249642 0.249642)
							(end -0.1778 0.2794)
						)
						(arc
							(start 0.1778 0.2794)
							(mid 0.249642 0.249642)
							(end 0.2794 0.1778)
						)
						(arc
							(start 0.2794 -0.1778)
							(mid 0.249642 -0.249642)
							(end 0.1778 -0.2794)
						)
					)
					(width 0)
					(fill yes)
				)
			)
		)
	)
	(footprint ""
		(layer "F.Cu")
		(at 221.681802 -207.983074 -90)
		(property "Reference" "C128"
			(at 0 0 270)
			(layer "F.SilkS")
			(hide yes)
			(effects
				(font
					(size 1.27 1.27)
				)
			)
		)
		(property "Value" "SCD1U16V2KX-3GP"
			(at 1.1811 -2.7051 270)
			(unlocked yes)
			(layer "F.Fab")
			(hide yes)
			(effects
				(font
					(size 1.016 1.016)
					(thickness 0.1524)
				)
			)
		)
		(property "Device Type" "C402H22"
			(at 1.1811 -4.2291 270)
			(unlocked yes)
			(layer "F.Fab")
			(hide yes)
			(effects
				(font
					(size 1.016 1.016)
					(thickness 0.1524)
				)
			)
		)
		(duplicate_pad_numbers_are_jumpers no)
		(fp_rect
			(start -0.4318 0.9525)
			(end 0.4318 -0.9525)
			(stroke
				(width 0)
				(type default)
			)
			(fill no)
			(layer "F.CrtYd")
		)
		(fp_rect
			(start -0.4318 0.9525)
			(end 0.4318 -0.9525)
			(stroke
				(width 0)
				(type default)
			)
			(fill no)
			(layer "F.Fab")
		)
		(pad "1" smd custom
			(at 0 -0.4445 270)
			(size 0.1524 0.1524)
			(layers "F.Cu" "F.Mask" "F.Paste")
			(net "I2C_SCC_BUFF_EN")
			(options
				(clearance outline)
				(anchor circle)
			)
			(primitives
				(gr_poly
					(pts
						(arc
							(start 0.3048 -0.2032)
							(mid 0.275042 -0.275042)
							(end 0.2032 -0.3048)
						)
						(arc
							(start -0.2032 -0.3048)
							(mid -0.275042 -0.275042)
							(end -0.3048 -0.2032)
						)
						(arc
							(start -0.3048 0.2032)
							(mid -0.275042 0.275042)
							(end -0.2032 0.3048)
						)
						(arc
							(start 0.2032 0.3048)
							(mid 0.275042 0.275042)
							(end 0.3048 0.2032)
						)
					)
					(width 0)
					(fill yes)
				)
			)
		)
		(pad "2" smd custom
			(at 0 0.4445 270)
			(size 0.1524 0.1524)
			(layers "F.Cu" "F.Mask" "F.Paste")
			(net "GND")
			(options
				(clearance outline)
				(anchor circle)
			)
			(primitives
				(gr_poly
					(pts
						(arc
							(start 0.3048 -0.2032)
							(mid 0.275042 -0.275042)
							(end 0.2032 -0.3048)
						)
						(arc
							(start -0.2032 -0.3048)
							(mid -0.275042 -0.275042)
							(end -0.3048 -0.2032)
						)
						(arc
							(start -0.3048 0.2032)
							(mid -0.275042 0.275042)
							(end -0.2032 0.3048)
						)
						(arc
							(start 0.2032 0.3048)
							(mid 0.275042 0.275042)
							(end 0.3048 0.2032)
						)
					)
					(width 0)
					(fill yes)
				)
			)
		)
	)
	(footprint ""
		(layer "F.Cu")
		(at 35.654488 -187.508896)
		(property "Reference" "R457"
			(at 0 0 0)
			(layer "F.SilkS")
			(hide yes)
			(effects
				(font
					(size 1.27 1.27)
				)
			)
		)
		(property "Value" "4K7R2J-2-GP"
			(at 0.064008 -3.993896 0)
			(unlocked yes)
			(layer "F.Fab")
			(hide yes)
			(effects
				(font
					(size 1.016 1.016)
					(thickness 0.1524)
				)
			)
		)
		(property "Device Type" "R402H16"
			(at 0.064008 -5.517896 0)
			(unlocked yes)
			(layer "F.Fab")
			(hide yes)
			(effects
				(font
					(size 1.016 1.016)
					(thickness 0.1524)
				)
			)
		)
		(duplicate_pad_numbers_are_jumpers no)
		(fp_line
			(start -0.508 -0.9398)
			(end -0.508 0.9398)
			(stroke
				(width 0.1524)
				(type default)
			)
			(layer "F.SilkS")
		)
		(fp_line
			(start 0.508 -0.9398)
			(end -0.508 -0.9398)
			(stroke
				(width 0.1524)
				(type default)
			)
			(layer "F.SilkS")
		)
		(fp_rect
			(start -0.508 0.9398)
			(end 0.508 -0.9398)
			(stroke
				(width 0)
				(type default)
			)
			(fill no)
			(layer "F.CrtYd")
		)
		(fp_rect
			(start -0.508 0.9398)
			(end 0.508 -0.9398)
			(stroke
				(width 0)
				(type default)
			)
			(fill no)
			(layer "F.Fab")
		)
		(pad "1" smd custom
			(at 0 -0.4445)
			(size 0.1397 0.1397)
			(layers "F.Cu" "F.Mask" "F.Paste")
			(net "DRIVE_A_1_FLT_LED")
			(options
				(clearance outline)
				(anchor circle)
			)
			(primitives
				(gr_poly
					(pts
						(arc
							(start -0.1778 -0.2794)
							(mid -0.249642 -0.249642)
							(end -0.2794 -0.1778)
						)
						(arc
							(start -0.2794 0.1778)
							(mid -0.249642 0.249642)
							(end -0.1778 0.2794)
						)
						(arc
							(start 0.1778 0.2794)
							(mid 0.249642 0.249642)
							(end 0.2794 0.1778)
						)
						(arc
							(start 0.2794 -0.1778)
							(mid 0.249642 -0.249642)
							(end 0.1778 -0.2794)
						)
					)
					(width 0)
					(fill yes)
				)
			)
		)
		(pad "2" smd custom
			(at 0 0.4445)
			(size 0.1397 0.1397)
			(layers "F.Cu" "F.Mask" "F.Paste")
			(net "GND")
			(options
				(clearance outline)
				(anchor circle)
			)
			(primitives
				(gr_poly
					(pts
						(arc
							(start -0.1778 -0.2794)
							(mid -0.249642 -0.249642)
							(end -0.2794 -0.1778)
						)
						(arc
							(start -0.2794 0.1778)
							(mid -0.249642 0.249642)
							(end -0.1778 0.2794)
						)
						(arc
							(start 0.1778 0.2794)
							(mid 0.249642 0.249642)
							(end 0.2794 0.1778)
						)
						(arc
							(start 0.2794 -0.1778)
							(mid 0.249642 -0.249642)
							(end 0.1778 -0.2794)
						)
					)
					(width 0)
					(fill yes)
				)
			)
		)
	)
	(footprint ""
		(layer "F.Cu")
		(at 45.5168 -148.66112 180)
		(property "Reference" "R1242"
			(at 0 0 180)
			(layer "F.SilkS")
			(hide yes)
			(effects
				(font
					(size 1.27 1.27)
				)
			)
		)
		(property "Value" "0R2J-2-GP"
			(at 0.064008 -3.993896 180)
			(unlocked yes)
			(layer "F.Fab")
			(hide yes)
			(effects
				(font
					(size 1.016 1.016)
					(thickness 0.1524)
				)
			)
		)
		(property "Device Type" "R402H16"
			(at 0.064008 -5.517896 180)
			(unlocked yes)
			(layer "F.Fab")
			(hide yes)
			(effects
				(font
					(size 1.016 1.016)
					(thickness 0.1524)
				)
			)
		)
		(duplicate_pad_numbers_are_jumpers no)
		(fp_line
			(start 0.508 -0.9398)
			(end -0.508 -0.9398)
			(stroke
				(width 0.1524)
				(type default)
			)
			(layer "F.SilkS")
		)
		(fp_line
			(start -0.508 -0.9398)
			(end -0.508 0.9398)
			(stroke
				(width 0.1524)
				(type default)
			)
			(layer "F.SilkS")
		)
		(fp_rect
			(start -0.508 0.9398)
			(end 0.508 -0.9398)
			(stroke
				(width 0)
				(type default)
			)
			(fill no)
			(layer "F.CrtYd")
		)
		(fp_rect
			(start -0.508 0.9398)
			(end 0.508 -0.9398)
			(stroke
				(width 0)
				(type default)
			)
			(fill no)
			(layer "F.Fab")
		)
		(pad "1" smd custom
			(at 0 -0.4445 180)
			(size 0.1397 0.1397)
			(layers "F.Cu" "F.Mask" "F.Paste")
			(net "P5V_B_ROVP")
			(options
				(clearance outline)
				(anchor circle)
			)
			(primitives
				(gr_poly
					(pts
						(arc
							(start -0.1778 -0.2794)
							(mid -0.249642 -0.249642)
							(end -0.2794 -0.1778)
						)
						(arc
							(start -0.2794 0.1778)
							(mid -0.249642 0.249642)
							(end -0.1778 0.2794)
						)
						(arc
							(start 0.1778 0.2794)
							(mid 0.249642 0.249642)
							(end 0.2794 0.1778)
						)
						(arc
							(start 0.2794 -0.1778)
							(mid 0.249642 -0.249642)
							(end 0.1778 -0.2794)
						)
					)
					(width 0)
					(fill yes)
				)
			)
		)
		(pad "2" smd custom
			(at 0 0.4445 180)
			(size 0.1397 0.1397)
			(layers "F.Cu" "F.Mask" "F.Paste")
			(net "AGND_P5V_B")
			(options
				(clearance outline)
				(anchor circle)
			)
			(primitives
				(gr_poly
					(pts
						(arc
							(start -0.1778 -0.2794)
							(mid -0.249642 -0.249642)
							(end -0.2794 -0.1778)
						)
						(arc
							(start -0.2794 0.1778)
							(mid -0.249642 0.249642)
							(end -0.1778 0.2794)
						)
						(arc
							(start 0.1778 0.2794)
							(mid 0.249642 0.249642)
							(end 0.2794 0.1778)
						)
						(arc
							(start 0.2794 -0.1778)
							(mid 0.249642 -0.249642)
							(end 0.1778 -0.2794)
						)
					)
					(width 0)
					(fill yes)
				)
			)
		)
	)
	(footprint ""
		(layer "F.Cu")
		(at 301.139352 -74.7903)
		(property "Reference" "R358"
			(at 0 0 0)
			(layer "F.SilkS")
			(hide yes)
			(effects
				(font
					(size 1.27 1.27)
				)
			)
		)
		(property "Value" "0R2J-2-GP"
			(at 0.064008 -3.993896 0)
			(unlocked yes)
			(layer "F.Fab")
			(hide yes)
			(effects
				(font
					(size 1.016 1.016)
					(thickness 0.1524)
				)
			)
		)
		(property "Device Type" "R402H16"
			(at 0.064008 -5.517896 0)
			(unlocked yes)
			(layer "F.Fab")
			(hide yes)
			(effects
				(font
					(size 1.016 1.016)
					(thickness 0.1524)
				)
			)
		)
		(duplicate_pad_numbers_are_jumpers no)
		(fp_line
			(start -0.508 -0.9398)
			(end -0.508 0.9398)
			(stroke
				(width 0.1524)
				(type default)
			)
			(layer "F.SilkS")
		)
		(fp_line
			(start 0.508 -0.9398)
			(end -0.508 -0.9398)
			(stroke
				(width 0.1524)
				(type default)
			)
			(layer "F.SilkS")
		)
		(fp_rect
			(start -0.508 0.9398)
			(end 0.508 -0.9398)
			(stroke
				(width 0)
				(type default)
			)
			(fill no)
			(layer "F.CrtYd")
		)
		(fp_rect
			(start -0.508 0.9398)
			(end 0.508 -0.9398)
			(stroke
				(width 0)
				(type default)
			)
			(fill no)
			(layer "F.Fab")
		)
		(pad "1" smd custom
			(at 0 -0.4445)
			(size 0.1397 0.1397)
			(layers "F.Cu" "F.Mask" "F.Paste")
			(net "SLOT1_SVR_ID0_GPIO1")
			(options
				(clearance outline)
				(anchor circle)
			)
			(primitives
				(gr_poly
					(pts
						(arc
							(start -0.1778 -0.2794)
							(mid -0.249642 -0.249642)
							(end -0.2794 -0.1778)
						)
						(arc
							(start -0.2794 0.1778)
							(mid -0.249642 0.249642)
							(end -0.1778 0.2794)
						)
						(arc
							(start 0.1778 0.2794)
							(mid 0.249642 0.249642)
							(end 0.2794 0.1778)
						)
						(arc
							(start 0.2794 -0.1778)
							(mid 0.249642 -0.249642)
							(end 0.1778 -0.2794)
						)
					)
					(width 0)
					(fill yes)
				)
			)
		)
		(pad "2" smd custom
			(at 0 0.4445)
			(size 0.1397 0.1397)
			(layers "F.Cu" "F.Mask" "F.Paste")
			(net "COMP_B_BMC_B_SPARE_1")
			(options
				(clearance outline)
				(anchor circle)
			)
			(primitives
				(gr_poly
					(pts
						(arc
							(start -0.1778 -0.2794)
							(mid -0.249642 -0.249642)
							(end -0.2794 -0.1778)
						)
						(arc
							(start -0.2794 0.1778)
							(mid -0.249642 0.249642)
							(end -0.1778 0.2794)
						)
						(arc
							(start 0.1778 0.2794)
							(mid 0.249642 0.249642)
							(end 0.2794 0.1778)
						)
						(arc
							(start 0.2794 -0.1778)
							(mid 0.249642 -0.249642)
							(end 0.1778 -0.2794)
						)
					)
					(width 0)
					(fill yes)
				)
			)
		)
	)
	(footprint ""
		(layer "F.Cu")
		(at 370.3828 -133.6294 90)
		(property "Reference" "R1094"
			(at 0 0 90)
			(layer "F.SilkS")
			(hide yes)
			(effects
				(font
					(size 1.27 1.27)
				)
			)
		)
		(property "Value" "100KR2F-L1-GP"
			(at 0.064008 -3.993896 90)
			(unlocked yes)
			(layer "F.Fab")
			(hide yes)
			(effects
				(font
					(size 1.016 1.016)
					(thickness 0.1524)
				)
			)
		)
		(property "Device Type" "R402H16"
			(at 0.064008 -5.517896 90)
			(unlocked yes)
			(layer "F.Fab")
			(hide yes)
			(effects
				(font
					(size 1.016 1.016)
					(thickness 0.1524)
				)
			)
		)
		(duplicate_pad_numbers_are_jumpers no)
		(fp_line
			(start 0.508 -0.9398)
			(end -0.508 -0.9398)
			(stroke
				(width 0.1524)
				(type default)
			)
			(layer "F.SilkS")
		)
		(fp_line
			(start -0.508 -0.9398)
			(end -0.508 0.9398)
			(stroke
				(width 0.1524)
				(type default)
			)
			(layer "F.SilkS")
		)
		(fp_rect
			(start -0.508 0.9398)
			(end 0.508 -0.9398)
			(stroke
				(width 0)
				(type default)
			)
			(fill no)
			(layer "F.CrtYd")
		)
		(fp_rect
			(start -0.508 0.9398)
			(end 0.508 -0.9398)
			(stroke
				(width 0)
				(type default)
			)
			(fill no)
			(layer "F.Fab")
		)
		(pad "1" smd custom
			(at 0 -0.4445 90)
			(size 0.1397 0.1397)
			(layers "F.Cu" "F.Mask" "F.Paste")
			(net "MB1_VCAP_R")
			(options
				(clearance outline)
				(anchor circle)
			)
			(primitives
				(gr_poly
					(pts
						(arc
							(start -0.1778 -0.2794)
							(mid -0.249642 -0.249642)
							(end -0.2794 -0.1778)
						)
						(arc
							(start -0.2794 0.1778)
							(mid -0.249642 0.249642)
							(end -0.1778 0.2794)
						)
						(arc
							(start 0.1778 0.2794)
							(mid 0.249642 0.249642)
							(end 0.2794 0.1778)
						)
						(arc
							(start 0.2794 -0.1778)
							(mid 0.249642 -0.249642)
							(end 0.1778 -0.2794)
						)
					)
					(width 0)
					(fill yes)
				)
			)
		)
		(pad "2" smd custom
			(at 0 0.4445 90)
			(size 0.1397 0.1397)
			(layers "F.Cu" "F.Mask" "F.Paste")
			(net "MB1_ISTART_R")
			(options
				(clearance outline)
				(anchor circle)
			)
			(primitives
				(gr_poly
					(pts
						(arc
							(start -0.1778 -0.2794)
							(mid -0.249642 -0.249642)
							(end -0.2794 -0.1778)
						)
						(arc
							(start -0.2794 0.1778)
							(mid -0.249642 0.249642)
							(end -0.1778 0.2794)
						)
						(arc
							(start 0.1778 0.2794)
							(mid 0.249642 0.249642)
							(end 0.2794 0.1778)
						)
						(arc
							(start 0.2794 -0.1778)
							(mid 0.249642 -0.249642)
							(end 0.1778 -0.2794)
						)
					)
					(width 0)
					(fill yes)
				)
			)
		)
	)
	(footprint ""
		(layer "F.Cu")
		(at 330.67498 -322.799964)
		(property "Reference" ""
			(at 0 0 0)
			(layer "F.SilkS")
			(hide yes)
			(effects
				(font
					(size 1.27 1.27)
				)
			)
		)
		(property "Value" "*"
			(at -8.398764 -8.057642 0)
			(unlocked yes)
			(layer "F.Fab")
			(hide yes)
			(effects
				(font
					(size 1.016 1.016)
					(thickness 0.1524)
				)
			)
		)
		(duplicate_pad_numbers_are_jumpers no)
		(fp_poly
			(pts
				(arc
					(start 7.3152 0)
					(mid 0 7.3152)
					(end -7.3152 0)
				)
				(arc
					(start -7.3152 -5.9944)
					(mid 0 -13.3096)
					(end 7.3152 -5.9944)
				)
			)
			(stroke
				(width 0)
				(type default)
			)
			(fill no)
			(layer "B.CrtYd")
		)
		(fp_poly
			(pts
				(arc
					(start 7.3152 0)
					(mid 0 7.3152)
					(end -7.3152 0)
				)
				(arc
					(start -7.3152 -5.9944)
					(mid 0 -13.3096)
					(end 7.3152 -5.9944)
				)
			)
			(stroke
				(width 0)
				(type default)
			)
			(fill no)
			(layer "F.CrtYd")
		)
		(fp_poly
			(pts
				(arc
					(start 7.3152 0)
					(mid 0 7.3152)
					(end -7.3152 0)
				)
				(arc
					(start -7.3152 -5.9944)
					(mid 0 -13.3096)
					(end 7.3152 -5.9944)
				)
			)
			(stroke
				(width 0)
				(type default)
			)
			(fill no)
			(layer "B.Fab")
		)
		(fp_poly
			(pts
				(arc
					(start 7.3152 0)
					(mid 0 7.3152)
					(end -7.3152 0)
				)
				(arc
					(start -7.3152 -5.9944)
					(mid 0 -13.3096)
					(end 7.3152 -5.9944)
				)
			)
			(stroke
				(width 0)
				(type default)
			)
			(fill no)
			(layer "F.Fab")
		)
		(pad "1" thru_hole oval
			(at 0 0)
			(size 14.0208 20.0152)
			(drill 0.0254
				(offset 0 -2.9972)
			)
			(layers "*.Cu" "*.Mask")
			(remove_unused_layers no)
			(net "Net_97")
			(clearance -1.002284)
			(thermal_gap 0.1524)
			(padstack
				(mode front_inner_back)
				(layer "Inner"
					(shape custom)
					(size 2.928012 2.928012)
					(options
						(anchor circle)
					)
					(primitives
						(gr_poly
							(pts
								(arc
									(start 4.571746 -2.084324)
									(mid 0.000333 7.430372)
									(end -4.571492 -2.084324)
								)
								(arc
									(start -4.571492 -2.084324)
									(mid -3.570296 -3.611977)
									(end -2.875026 -5.30098)
								)
								(arc
									(start -2.875026 -5.30098)
									(mid 0.000217 -7.43089)
									(end 2.87528 -5.30098)
								)
								(arc
									(start 2.87528 -5.30098)
									(mid 3.570511 -3.611956)
									(end 4.571746 -2.084324)
								)
							)
							(width 0)
							(fill yes)
						)
					)
					(clearance 0.1524)
				)
				(layer "B.Cu"
					(shape oval)
					(size 14.0208 20.0152)
					(offset 0 -2.9972)
					(clearance -1.002284)
				)
			)
		)
		(zone
			(layers "F.Cu" "B.Cu" "In1.Cu" "In2.Cu" "In3.Cu" "In4.Cu" "In5.Cu" "In6.Cu"
				"In7.Cu" "In8.Cu" "In9.Cu" "In10.Cu"
			)
			(hatch none 0.5)
			(connect_pads
				(clearance 0)
			)
			(min_thickness 0.25)
			(keepout
				(tracks not_allowed)
				(vias allowed)
				(pads allowed)
				(copperpour not_allowed)
				(footprints allowed)
			)
			(placement
				(enabled no)
				(sheetname "")
			)
			(fill
				(thermal_gap 0.5)
				(thermal_bridge_width 0.5)
				(island_removal_mode 0)
			)
			(polygon
				(pts
					(arc
						(start 323.66458 -328.794364)
						(mid 330.67498 -335.804764)
						(end 337.68538 -328.794364)
					)
					(arc
						(start 337.68538 -322.799964)
						(mid 330.67498 -315.789564)
						(end 323.66458 -322.799964)
					)
				)
			)
		)
	)
	(footprint ""
		(layer "F.Cu")
		(at 416.284664 -43.660568 -90)
		(property "Reference" "C468"
			(at 0 0 270)
			(layer "F.SilkS")
			(hide yes)
			(effects
				(font
					(size 1.27 1.27)
				)
			)
		)
		(property "Value" "SCD01U16V1KX-GP"
			(at -2.8321 -1.7399 270)
			(unlocked yes)
			(layer "F.Fab")
			(hide yes)
			(effects
				(font
					(size 1.016 1.016)
					(thickness 0.1524)
				)
			)
		)
		(property "Device Type" "C0201H13"
			(at -2.8321 -3.2639 270)
			(unlocked yes)
			(layer "F.Fab")
			(hide yes)
			(effects
				(font
					(size 1.016 1.016)
					(thickness 0.1524)
				)
			)
		)
		(duplicate_pad_numbers_are_jumpers no)
		(fp_rect
			(start -0.2794 0.6477)
			(end 0.2794 -0.6477)
			(stroke
				(width 0)
				(type default)
			)
			(fill no)
			(layer "F.CrtYd")
		)
		(fp_rect
			(start -0.2794 0.6477)
			(end 0.2794 -0.6477)
			(stroke
				(width 0)
				(type default)
			)
			(fill no)
			(layer "F.Fab")
		)
		(pad "1" smd custom
			(at 0 -0.2794 270)
			(size 0.0762 0.0762)
			(layers "F.Cu" "F.Mask" "F.Paste")
			(net "SAS_HDD_RX_P33")
			(options
				(clearance outline)
				(anchor circle)
			)
			(primitives
				(gr_poly
					(pts
						(arc
							(start 0.1524 -0.127)
							(mid 0.137521 -0.162921)
							(end 0.1016 -0.1778)
						)
						(arc
							(start -0.1016 -0.1778)
							(mid -0.137521 -0.162921)
							(end -0.1524 -0.127)
						)
						(arc
							(start -0.1524 0.127)
							(mid -0.137521 0.162921)
							(end -0.1016 0.1778)
						)
						(arc
							(start 0.1016 0.1778)
							(mid 0.137521 0.162921)
							(end 0.1524 0.127)
						)
					)
					(width 0)
					(fill yes)
				)
			)
		)
		(pad "2" smd custom
			(at 0 0.2794 270)
			(size 0.0762 0.0762)
			(layers "F.Cu" "F.Mask" "F.Paste")
			(net "PHY_SCC_A_TO_DRV_A_33_DP")
			(options
				(clearance outline)
				(anchor circle)
			)
			(primitives
				(gr_poly
					(pts
						(arc
							(start 0.1524 -0.127)
							(mid 0.137521 -0.162921)
							(end 0.1016 -0.1778)
						)
						(arc
							(start -0.1016 -0.1778)
							(mid -0.137521 -0.162921)
							(end -0.1524 -0.127)
						)
						(arc
							(start -0.1524 0.127)
							(mid -0.137521 0.162921)
							(end -0.1016 0.1778)
						)
						(arc
							(start 0.1016 0.1778)
							(mid 0.137521 0.162921)
							(end 0.1524 0.127)
						)
					)
					(width 0)
					(fill yes)
				)
			)
		)
	)
	(footprint ""
		(layer "F.Cu")
		(at 258.8514 13.470128)
		(property "Reference" "Q2"
			(at 0 0 0)
			(layer "F.SilkS")
			(hide yes)
			(effects
				(font
					(size 1.27 1.27)
				)
			)
		)
		(property "Value" "2N7002KDW-GP"
			(at -2.3622 -8.2042 0)
			(unlocked yes)
			(layer "F.Fab")
			(hide yes)
			(effects
				(font
					(size 1.016 1.016)
					(thickness 0.1524)
				)
			)
		)
		(property "Device Type" "SOT-363H44"
			(at -2.3622 -10.1092 0)
			(unlocked yes)
			(layer "F.Fab")
			(hide yes)
			(effects
				(font
					(size 1.016 1.016)
					(thickness 0.1524)
				)
			)
		)
		(duplicate_pad_numbers_are_jumpers no)
		(fp_line
			(start -1.4478 -1.7018)
			(end -1.4478 1.7018)
			(stroke
				(width 0.1524)
				(type default)
			)
			(layer "F.SilkS")
		)
		(fp_line
			(start -1.4478 1.7018)
			(end 1.4478 1.7018)
			(stroke
				(width 0.1524)
				(type default)
			)
			(layer "F.SilkS")
		)
		(fp_line
			(start -1.27 1.524)
			(end -1.27 0.6604)
			(stroke
				(width 0.4826)
				(type default)
			)
			(layer "F.SilkS")
		)
		(fp_line
			(start 1.4478 -1.7018)
			(end -1.4478 -1.7018)
			(stroke
				(width 0.1524)
				(type default)
			)
			(layer "F.SilkS")
		)
		(fp_line
			(start 1.4478 1.7018)
			(end 1.4478 -1.7018)
			(stroke
				(width 0.1524)
				(type default)
			)
			(layer "F.SilkS")
		)
		(fp_poly
			(pts
				(xy -1.524 -1.778) (xy 1.524 -1.778) (xy 1.524 1.778) (xy -1.524 1.778)
			)
			(stroke
				(width 0)
				(type default)
			)
			(fill no)
			(layer "F.CrtYd")
		)
		(fp_poly
			(pts
				(xy -1.524 -1.778) (xy 1.524 -1.778) (xy 1.524 1.778) (xy -1.524 1.778)
			)
			(stroke
				(width 0)
				(type default)
			)
			(fill no)
			(layer "F.Fab")
		)
		(pad "1" smd rect
			(at -0.65024 0.9398)
			(size 0.4064 1.016)
			(layers "F.Cu" "F.Mask" "F.Paste")
			(net "GND")
		)
		(pad "2" smd rect
			(at 0 0.9398)
			(size 0.4064 1.016)
			(layers "F.Cu" "F.Mask" "F.Paste")
			(net "SCC_A_FAULT_LED")
		)
		(pad "3" smd rect
			(at 0.65024 0.9398)
			(size 0.4064 1.016)
			(layers "F.Cu" "F.Mask" "F.Paste")
			(net "ENCL_FAULT_LED_A")
		)
		(pad "4" smd rect
			(at 0.65024 -0.9398)
			(size 0.4064 1.016)
			(layers "F.Cu" "F.Mask" "F.Paste")
			(net "GND")
		)
		(pad "5" smd rect
			(at 0 -0.9398)
			(size 0.4064 1.016)
			(layers "F.Cu" "F.Mask" "F.Paste")
			(net "IOM_A_FAULT_LED")
		)
		(pad "6" smd rect
			(at -0.65024 -0.9398)
			(size 0.4064 1.016)
			(layers "F.Cu" "F.Mask" "F.Paste")
			(net "ENCL_FAULT_LED_A")
		)
	)
	(footprint ""
		(layer "F.Cu")
		(at 148.406866 -144.737074 180)
		(property "Reference" "C549"
			(at 0 0 180)
			(layer "F.SilkS")
			(hide yes)
			(effects
				(font
					(size 1.27 1.27)
				)
			)
		)
		(property "Value" "SC1U16V3KX-5GP"
			(at 0 -2.8194 180)
			(unlocked yes)
			(layer "F.Fab")
			(hide yes)
			(effects
				(font
					(size 1.016 1.016)
					(thickness 0.1524)
				)
			)
		)
		(property "Device Type" "C603H36"
			(at 0 -4.3434 180)
			(unlocked yes)
			(layer "F.Fab")
			(hide yes)
			(effects
				(font
					(size 1.016 1.016)
					(thickness 0.1524)
				)
			)
		)
		(duplicate_pad_numbers_are_jumpers no)
		(fp_line
			(start 0.508 0)
			(end -0.508 0)
			(stroke
				(width 0.2032)
				(type default)
			)
			(layer "F.SilkS")
		)
		(fp_rect
			(start -0.5842 1.3335)
			(end 0.5842 -1.3335)
			(stroke
				(width 0)
				(type default)
			)
			(fill no)
			(layer "F.CrtYd")
		)
		(fp_rect
			(start -0.5842 1.3335)
			(end 0.5842 -1.3335)
			(stroke
				(width 0)
				(type default)
			)
			(fill no)
			(layer "F.Fab")
		)
		(pad "1" smd custom
			(at 0 -0.762 180)
			(size 0.2159 0.2159)
			(layers "F.Cu" "F.Mask" "F.Paste")
			(net "MB0_VCAP_R")
			(options
				(clearance outline)
				(anchor circle)
			)
			(primitives
				(gr_poly
					(pts
						(arc
							(start -0.3302 -0.4318)
							(mid -0.402042 -0.402042)
							(end -0.4318 -0.3302)
						)
						(arc
							(start -0.4318 0.3302)
							(mid -0.402042 0.402042)
							(end -0.3302 0.4318)
						)
						(arc
							(start 0.3302 0.4318)
							(mid 0.402042 0.402042)
							(end 0.4318 0.3302)
						)
						(arc
							(start 0.4318 -0.3302)
							(mid 0.402042 -0.402042)
							(end 0.3302 -0.4318)
						)
					)
					(width 0)
					(fill yes)
				)
			)
		)
		(pad "2" smd custom
			(at 0 0.762 180)
			(size 0.2159 0.2159)
			(layers "F.Cu" "F.Mask" "F.Paste")
			(net "AGND_CURRENT_MONOA")
			(options
				(clearance outline)
				(anchor circle)
			)
			(primitives
				(gr_poly
					(pts
						(arc
							(start -0.3302 -0.4318)
							(mid -0.402042 -0.402042)
							(end -0.4318 -0.3302)
						)
						(arc
							(start -0.4318 0.3302)
							(mid -0.402042 0.402042)
							(end -0.3302 0.4318)
						)
						(arc
							(start 0.3302 0.4318)
							(mid 0.402042 0.402042)
							(end 0.4318 0.3302)
						)
						(arc
							(start 0.4318 -0.3302)
							(mid 0.402042 -0.402042)
							(end 0.3302 -0.4318)
						)
					)
					(width 0)
					(fill yes)
				)
			)
		)
	)
	(footprint ""
		(layer "F.Cu")
		(at 52.234846 -170.285918 180)
		(property "Reference" "Q77"
			(at 0 0 180)
			(layer "F.SilkS")
			(hide yes)
			(effects
				(font
					(size 1.27 1.27)
				)
			)
		)
		(property "Value" "AO4406AL-GP"
			(at -3.707384 -1.5367 180)
			(unlocked yes)
			(layer "F.Fab")
			(hide yes)
			(effects
				(font
					(size 1.016 1.016)
					(thickness 0.1524)
				)
			)
		)
		(property "Device Type" "SOIC8H69"
			(at -3.707384 -3.0607 180)
			(unlocked yes)
			(layer "F.Fab")
			(hide yes)
			(effects
				(font
					(size 1.016 1.016)
					(thickness 0.1524)
				)
			)
		)
		(duplicate_pad_numbers_are_jumpers no)
		(fp_line
			(start 2.1336 1.4224)
			(end 2.1336 -1.4224)
			(stroke
				(width 0.1524)
				(type default)
			)
			(layer "F.SilkS")
		)
		(fp_line
			(start 2.1336 -1.4224)
			(end -2.7432 -1.4224)
			(stroke
				(width 0.1524)
				(type default)
			)
			(layer "F.SilkS")
		)
		(fp_line
			(start -2.1844 -0.0508)
			(end -2.7178 0.508)
			(stroke
				(width 0.1524)
				(type default)
			)
			(layer "F.SilkS")
		)
		(fp_line
			(start -2.6289 3.4417)
			(end -2.6289 1.4732)
			(stroke
				(width 0.381)
				(type default)
			)
			(layer "F.SilkS")
		)
		(fp_line
			(start -2.7178 -0.508)
			(end -2.1844 -0.0508)
			(stroke
				(width 0.1524)
				(type default)
			)
			(layer "F.SilkS")
		)
		(fp_line
			(start -2.7432 1.4224)
			(end 2.1336 1.4224)
			(stroke
				(width 0.1524)
				(type default)
			)
			(layer "F.SilkS")
		)
		(fp_line
			(start -2.7432 1.4224)
			(end -2.6416 1.4224)
			(stroke
				(width 0.1524)
				(type default)
			)
			(layer "F.SilkS")
		)
		(fp_line
			(start -2.7432 -1.4224)
			(end -2.7432 1.4224)
			(stroke
				(width 0.1524)
				(type default)
			)
			(layer "F.SilkS")
		)
		(fp_poly
			(pts
				(xy -2.2098 -1.4224) (xy -2.2098 1.4224) (xy 2.2098 1.4224) (xy 2.2098 -1.4224)
			)
			(stroke
				(width 0)
				(type default)
			)
			(fill yes)
			(layer "F.SilkS")
		)
		(fp_rect
			(start -2.450084 2.999994)
			(end 2.450084 -2.999994)
			(stroke
				(width 0)
				(type default)
			)
			(fill no)
			(layer "F.CrtYd")
		)
		(fp_poly
			(pts
				(xy -2.8194 3.6322) (xy -2.8194 -3.6322) (xy 2.8194 -3.6322) (xy 2.8194 1.18364) (xy 2.450084 1.18364)
				(xy 2.450084 -2.999994) (xy -2.450084 -2.999994) (xy -2.450084 2.999994) (xy 2.450084 2.999994)
				(xy 2.450084 1.18618) (xy 2.8194 1.18618) (xy 2.8194 3.6322)
			)
			(stroke
				(width 0)
				(type default)
			)
			(fill no)
			(layer "F.CrtYd")
		)
		(fp_rect
			(start -2.8194 3.6322)
			(end 2.8194 -3.6322)
			(stroke
				(width 0)
				(type default)
			)
			(fill no)
			(layer "F.Fab")
		)
		(pad "1" smd rect
			(at -1.905 2.54 180)
			(size 0.635 1.651)
			(layers "F.Cu" "F.Mask" "F.Paste")
			(net "P5V_HDD13")
		)
		(pad "2" smd rect
			(at -0.635 2.54 180)
			(size 0.635 1.651)
			(layers "F.Cu" "F.Mask" "F.Paste")
			(net "P5V_HDD13")
		)
		(pad "3" smd rect
			(at 0.635 2.54 180)
			(size 0.635 1.651)
			(layers "F.Cu" "F.Mask" "F.Paste")
			(net "P5V_HDD13")
		)
		(pad "4" smd rect
			(at 1.905 2.54 180)
			(size 0.635 1.651)
			(layers "F.Cu" "F.Mask" "F.Paste")
			(net "SW_HDD_P13")
		)
		(pad "5" smd rect
			(at 1.905 -2.54 180)
			(size 0.635 1.651)
			(layers "F.Cu" "F.Mask" "F.Paste")
			(net "P5V_A_1")
		)
		(pad "6" smd rect
			(at 0.635 -2.54 180)
			(size 0.635 1.651)
			(layers "F.Cu" "F.Mask" "F.Paste")
			(net "P5V_A_1")
		)
		(pad "7" smd rect
			(at -0.635 -2.54 180)
			(size 0.635 1.651)
			(layers "F.Cu" "F.Mask" "F.Paste")
			(net "P5V_A_1")
		)
		(pad "8" smd rect
			(at -1.905 -2.54 180)
			(size 0.635 1.651)
			(layers "F.Cu" "F.Mask" "F.Paste")
			(net "P5V_A_1")
		)
	)
	(footprint ""
		(layer "F.Cu")
		(at 133.933438 -140.520674 -90)
		(property "Reference" "C94"
			(at 0 0 270)
			(layer "F.SilkS")
			(hide yes)
			(effects
				(font
					(size 1.27 1.27)
				)
			)
		)
		(property "Value" "SC1U16V3KX-5GP"
			(at 0 -2.8194 270)
			(unlocked yes)
			(layer "F.Fab")
			(hide yes)
			(effects
				(font
					(size 1.016 1.016)
					(thickness 0.1524)
				)
			)
		)
		(property "Device Type" "C603H36"
			(at 0 -4.3434 270)
			(unlocked yes)
			(layer "F.Fab")
			(hide yes)
			(effects
				(font
					(size 1.016 1.016)
					(thickness 0.1524)
				)
			)
		)
		(duplicate_pad_numbers_are_jumpers no)
		(fp_line
			(start 0.508 0)
			(end -0.508 0)
			(stroke
				(width 0.2032)
				(type default)
			)
			(layer "F.SilkS")
		)
		(fp_rect
			(start -0.5842 1.3335)
			(end 0.5842 -1.3335)
			(stroke
				(width 0)
				(type default)
			)
			(fill no)
			(layer "F.CrtYd")
		)
		(fp_rect
			(start -0.5842 1.3335)
			(end 0.5842 -1.3335)
			(stroke
				(width 0)
				(type default)
			)
			(fill no)
			(layer "F.Fab")
		)
		(pad "1" smd custom
			(at 0 -0.762 270)
			(size 0.2159 0.2159)
			(layers "F.Cu" "F.Mask" "F.Paste")
			(net "P3V3_A_BIAS")
			(options
				(clearance outline)
				(anchor circle)
			)
			(primitives
				(gr_poly
					(pts
						(arc
							(start -0.3302 -0.4318)
							(mid -0.402042 -0.402042)
							(end -0.4318 -0.3302)
						)
						(arc
							(start -0.4318 0.3302)
							(mid -0.402042 0.402042)
							(end -0.3302 0.4318)
						)
						(arc
							(start 0.3302 0.4318)
							(mid 0.402042 0.402042)
							(end 0.4318 0.3302)
						)
						(arc
							(start 0.4318 -0.3302)
							(mid 0.402042 -0.402042)
							(end 0.3302 -0.4318)
						)
					)
					(width 0)
					(fill yes)
				)
			)
		)
		(pad "2" smd custom
			(at 0 0.762 270)
			(size 0.2159 0.2159)
			(layers "F.Cu" "F.Mask" "F.Paste")
			(net "GND")
			(options
				(clearance outline)
				(anchor circle)
			)
			(primitives
				(gr_poly
					(pts
						(arc
							(start -0.3302 -0.4318)
							(mid -0.402042 -0.402042)
							(end -0.4318 -0.3302)
						)
						(arc
							(start -0.4318 0.3302)
							(mid -0.402042 0.402042)
							(end -0.3302 0.4318)
						)
						(arc
							(start 0.3302 0.4318)
							(mid 0.402042 0.402042)
							(end 0.4318 0.3302)
						)
						(arc
							(start 0.4318 -0.3302)
							(mid 0.402042 -0.402042)
							(end 0.3302 -0.4318)
						)
					)
					(width 0)
					(fill yes)
				)
			)
		)
	)
	(footprint ""
		(layer "F.Cu")
		(at 298.7294 -67.183 180)
		(property "Reference" "R631"
			(at 0 0 180)
			(layer "F.SilkS")
			(hide yes)
			(effects
				(font
					(size 1.27 1.27)
				)
			)
		)
		(property "Value" "4K7R2F-GP"
			(at 0.064008 -3.993896 180)
			(unlocked yes)
			(layer "F.Fab")
			(hide yes)
			(effects
				(font
					(size 1.016 1.016)
					(thickness 0.1524)
				)
			)
		)
		(property "Device Type" "R402H16"
			(at 0.064008 -5.517896 180)
			(unlocked yes)
			(layer "F.Fab")
			(hide yes)
			(effects
				(font
					(size 1.016 1.016)
					(thickness 0.1524)
				)
			)
		)
		(duplicate_pad_numbers_are_jumpers no)
		(fp_line
			(start 0.508 -0.9398)
			(end -0.508 -0.9398)
			(stroke
				(width 0.1524)
				(type default)
			)
			(layer "F.SilkS")
		)
		(fp_line
			(start -0.508 -0.9398)
			(end -0.508 0.9398)
			(stroke
				(width 0.1524)
				(type default)
			)
			(layer "F.SilkS")
		)
		(fp_rect
			(start -0.508 0.9398)
			(end 0.508 -0.9398)
			(stroke
				(width 0)
				(type default)
			)
			(fill no)
			(layer "F.CrtYd")
		)
		(fp_rect
			(start -0.508 0.9398)
			(end 0.508 -0.9398)
			(stroke
				(width 0)
				(type default)
			)
			(fill no)
			(layer "F.Fab")
		)
		(pad "1" smd custom
			(at 0 -0.4445 180)
			(size 0.1397 0.1397)
			(layers "F.Cu" "F.Mask" "F.Paste")
			(net "I2C_BMC_B_COMP_B_SDA")
			(options
				(clearance outline)
				(anchor circle)
			)
			(primitives
				(gr_poly
					(pts
						(arc
							(start -0.1778 -0.2794)
							(mid -0.249642 -0.249642)
							(end -0.2794 -0.1778)
						)
						(arc
							(start -0.2794 0.1778)
							(mid -0.249642 0.249642)
							(end -0.1778 0.2794)
						)
						(arc
							(start 0.1778 0.2794)
							(mid 0.249642 0.249642)
							(end 0.2794 0.1778)
						)
						(arc
							(start 0.2794 -0.1778)
							(mid 0.249642 -0.249642)
							(end 0.1778 -0.2794)
						)
					)
					(width 0)
					(fill yes)
				)
			)
		)
		(pad "2" smd custom
			(at 0 0.4445 180)
			(size 0.1397 0.1397)
			(layers "F.Cu" "F.Mask" "F.Paste")
			(net "P3V3_STBY_B")
			(options
				(clearance outline)
				(anchor circle)
			)
			(primitives
				(gr_poly
					(pts
						(arc
							(start -0.1778 -0.2794)
							(mid -0.249642 -0.249642)
							(end -0.2794 -0.1778)
						)
						(arc
							(start -0.2794 0.1778)
							(mid -0.249642 0.249642)
							(end -0.1778 0.2794)
						)
						(arc
							(start 0.1778 0.2794)
							(mid 0.249642 0.249642)
							(end 0.2794 0.1778)
						)
						(arc
							(start 0.2794 -0.1778)
							(mid 0.249642 -0.249642)
							(end 0.1778 -0.2794)
						)
					)
					(width 0)
					(fill yes)
				)
			)
		)
	)
	(footprint ""
		(layer "F.Cu")
		(at 46.773846 -47.183294 180)
		(property "Reference" "R721"
			(at 0 0 180)
			(layer "F.SilkS")
			(hide yes)
			(effects
				(font
					(size 1.27 1.27)
				)
			)
		)
		(property "Value" "200KR2F-L-GP"
			(at 0.064008 -3.993896 180)
			(unlocked yes)
			(layer "F.Fab")
			(hide yes)
			(effects
				(font
					(size 1.016 1.016)
					(thickness 0.1524)
				)
			)
		)
		(property "Device Type" "R402H16"
			(at 0.064008 -5.517896 180)
			(unlocked yes)
			(layer "F.Fab")
			(hide yes)
			(effects
				(font
					(size 1.016 1.016)
					(thickness 0.1524)
				)
			)
		)
		(duplicate_pad_numbers_are_jumpers no)
		(fp_line
			(start 0.508 -0.9398)
			(end -0.508 -0.9398)
			(stroke
				(width 0.1524)
				(type default)
			)
			(layer "F.SilkS")
		)
		(fp_line
			(start -0.508 -0.9398)
			(end -0.508 0.9398)
			(stroke
				(width 0.1524)
				(type default)
			)
			(layer "F.SilkS")
		)
		(fp_rect
			(start -0.508 0.9398)
			(end 0.508 -0.9398)
			(stroke
				(width 0)
				(type default)
			)
			(fill no)
			(layer "F.CrtYd")
		)
		(fp_rect
			(start -0.508 0.9398)
			(end 0.508 -0.9398)
			(stroke
				(width 0)
				(type default)
			)
			(fill no)
			(layer "F.Fab")
		)
		(pad "1" smd custom
			(at 0 -0.4445 180)
			(size 0.1397 0.1397)
			(layers "F.Cu" "F.Mask" "F.Paste")
			(net "SW_HDD_R25")
			(options
				(clearance outline)
				(anchor circle)
			)
			(primitives
				(gr_poly
					(pts
						(arc
							(start -0.1778 -0.2794)
							(mid -0.249642 -0.249642)
							(end -0.2794 -0.1778)
						)
						(arc
							(start -0.2794 0.1778)
							(mid -0.249642 0.249642)
							(end -0.1778 0.2794)
						)
						(arc
							(start 0.1778 0.2794)
							(mid 0.249642 0.249642)
							(end 0.2794 0.1778)
						)
						(arc
							(start 0.2794 -0.1778)
							(mid 0.249642 -0.249642)
							(end 0.1778 -0.2794)
						)
					)
					(width 0)
					(fill yes)
				)
			)
		)
		(pad "2" smd custom
			(at 0 0.4445 180)
			(size 0.1397 0.1397)
			(layers "F.Cu" "F.Mask" "F.Paste")
			(net "SW_HDD_N25")
			(options
				(clearance outline)
				(anchor circle)
			)
			(primitives
				(gr_poly
					(pts
						(arc
							(start -0.1778 -0.2794)
							(mid -0.249642 -0.249642)
							(end -0.2794 -0.1778)
						)
						(arc
							(start -0.2794 0.1778)
							(mid -0.249642 0.249642)
							(end -0.1778 0.2794)
						)
						(arc
							(start 0.1778 0.2794)
							(mid 0.249642 0.249642)
							(end 0.2794 0.1778)
						)
						(arc
							(start 0.2794 -0.1778)
							(mid 0.249642 -0.249642)
							(end 0.1778 -0.2794)
						)
					)
					(width 0)
					(fill yes)
				)
			)
		)
	)
	(footprint ""
		(layer "F.Cu")
		(at 363.909102 -295.826942 180)
		(property "Reference" "C132"
			(at 0 0 180)
			(layer "F.SilkS")
			(hide yes)
			(effects
				(font
					(size 1.27 1.27)
				)
			)
		)
		(property "Value" "SC10U16V6KX-2GP"
			(at -0.0762 -5.1308 180)
			(unlocked yes)
			(layer "F.Fab")
			(hide yes)
			(effects
				(font
					(size 1.016 1.016)
					(thickness 0.1524)
				)
			)
		)
		(property "Device Type" "C1206H71"
			(at -0.127 -6.6548 180)
			(unlocked yes)
			(layer "F.Fab")
			(hide yes)
			(effects
				(font
					(size 1.016 1.016)
					(thickness 0.1524)
				)
			)
		)
		(duplicate_pad_numbers_are_jumpers no)
		(fp_line
			(start 1.016 2.2352)
			(end -1.016 2.2352)
			(stroke
				(width 0.1524)
				(type default)
			)
			(layer "F.SilkS")
		)
		(fp_line
			(start 1.016 0.8382)
			(end 1.016 2.2352)
			(stroke
				(width 0.1524)
				(type default)
			)
			(layer "F.SilkS")
		)
		(fp_line
			(start 1.016 -2.2352)
			(end 1.016 -0.8382)
			(stroke
				(width 0.1524)
				(type default)
			)
			(layer "F.SilkS")
		)
		(fp_line
			(start -1.016 2.2352)
			(end -1.016 0.8382)
			(stroke
				(width 0.1524)
				(type default)
			)
			(layer "F.SilkS")
		)
		(fp_line
			(start -1.016 -0.8382)
			(end -1.016 -2.2352)
			(stroke
				(width 0.1524)
				(type default)
			)
			(layer "F.SilkS")
		)
		(fp_line
			(start -1.016 -2.2352)
			(end 1.016 -2.2352)
			(stroke
				(width 0.1524)
				(type default)
			)
			(layer "F.SilkS")
		)
		(fp_rect
			(start -1.0922 2.3114)
			(end 1.0922 -2.3114)
			(stroke
				(width 0)
				(type default)
			)
			(fill no)
			(layer "F.CrtYd")
		)
		(fp_poly
			(pts
				(xy 1.0922 -2.3114) (xy 1.0922 2.3114) (xy -1.0922 2.3114) (xy -1.0922 -2.3114)
			)
			(stroke
				(width 0)
				(type default)
			)
			(fill no)
			(layer "F.Fab")
		)
		(pad "1" smd rect
			(at 0 -1.397 180)
			(size 1.651 1.27)
			(layers "F.Cu" "F.Mask" "F.Paste")
			(net "P5V_HDD7")
		)
		(pad "2" smd rect
			(at 0 1.397 180)
			(size 1.651 1.27)
			(layers "F.Cu" "F.Mask" "F.Paste")
			(net "GND")
		)
	)
	(footprint ""
		(layer "F.Cu")
		(at 299.962062 -74.79919)
		(property "Reference" "R204"
			(at 0 0 0)
			(layer "F.SilkS")
			(hide yes)
			(effects
				(font
					(size 1.27 1.27)
				)
			)
		)
		(property "Value" "0R2J-2-GP"
			(at 0.064008 -3.993896 0)
			(unlocked yes)
			(layer "F.Fab")
			(hide yes)
			(effects
				(font
					(size 1.016 1.016)
					(thickness 0.1524)
				)
			)
		)
		(property "Device Type" "R402H16"
			(at 0.064008 -5.517896 0)
			(unlocked yes)
			(layer "F.Fab")
			(hide yes)
			(effects
				(font
					(size 1.016 1.016)
					(thickness 0.1524)
				)
			)
		)
		(duplicate_pad_numbers_are_jumpers no)
		(fp_line
			(start -0.508 -0.9398)
			(end -0.508 0.9398)
			(stroke
				(width 0.1524)
				(type default)
			)
			(layer "F.SilkS")
		)
		(fp_line
			(start 0.508 -0.9398)
			(end -0.508 -0.9398)
			(stroke
				(width 0.1524)
				(type default)
			)
			(layer "F.SilkS")
		)
		(fp_rect
			(start -0.508 0.9398)
			(end 0.508 -0.9398)
			(stroke
				(width 0)
				(type default)
			)
			(fill no)
			(layer "F.CrtYd")
		)
		(fp_rect
			(start -0.508 0.9398)
			(end 0.508 -0.9398)
			(stroke
				(width 0)
				(type default)
			)
			(fill no)
			(layer "F.Fab")
		)
		(pad "1" smd custom
			(at 0 -0.4445)
			(size 0.1397 0.1397)
			(layers "F.Cu" "F.Mask" "F.Paste")
			(net "SLOT1_SVR_ID0_GPIO3")
			(options
				(clearance outline)
				(anchor circle)
			)
			(primitives
				(gr_poly
					(pts
						(arc
							(start -0.1778 -0.2794)
							(mid -0.249642 -0.249642)
							(end -0.2794 -0.1778)
						)
						(arc
							(start -0.2794 0.1778)
							(mid -0.249642 0.249642)
							(end -0.1778 0.2794)
						)
						(arc
							(start 0.1778 0.2794)
							(mid 0.249642 0.249642)
							(end 0.2794 0.1778)
						)
						(arc
							(start 0.2794 -0.1778)
							(mid 0.249642 -0.249642)
							(end 0.1778 -0.2794)
						)
					)
					(width 0)
					(fill yes)
				)
			)
		)
		(pad "2" smd custom
			(at 0 0.4445)
			(size 0.1397 0.1397)
			(layers "F.Cu" "F.Mask" "F.Paste")
			(net "COMP_B_TO_BMC_B_RESET_N")
			(options
				(clearance outline)
				(anchor circle)
			)
			(primitives
				(gr_poly
					(pts
						(arc
							(start -0.1778 -0.2794)
							(mid -0.249642 -0.249642)
							(end -0.2794 -0.1778)
						)
						(arc
							(start -0.2794 0.1778)
							(mid -0.249642 0.249642)
							(end -0.1778 0.2794)
						)
						(arc
							(start 0.1778 0.2794)
							(mid 0.249642 0.249642)
							(end 0.2794 0.1778)
						)
						(arc
							(start 0.2794 -0.1778)
							(mid 0.249642 -0.249642)
							(end 0.1778 -0.2794)
						)
					)
					(width 0)
					(fill yes)
				)
			)
		)
	)
	(footprint ""
		(layer "F.Cu")
		(at 299.66031 -71.461122 -90)
		(property "Reference" "C28"
			(at 0 0 270)
			(layer "F.SilkS")
			(hide yes)
			(effects
				(font
					(size 1.27 1.27)
				)
			)
		)
		(property "Value" "SCD1U16V2KX-3GP"
			(at 1.1811 -2.7051 270)
			(unlocked yes)
			(layer "F.Fab")
			(hide yes)
			(effects
				(font
					(size 1.016 1.016)
					(thickness 0.1524)
				)
			)
		)
		(property "Device Type" "C402H22"
			(at 1.1811 -4.2291 270)
			(unlocked yes)
			(layer "F.Fab")
			(hide yes)
			(effects
				(font
					(size 1.016 1.016)
					(thickness 0.1524)
				)
			)
		)
		(duplicate_pad_numbers_are_jumpers no)
		(fp_rect
			(start -0.4318 0.9525)
			(end 0.4318 -0.9525)
			(stroke
				(width 0)
				(type default)
			)
			(fill no)
			(layer "F.CrtYd")
		)
		(fp_rect
			(start -0.4318 0.9525)
			(end 0.4318 -0.9525)
			(stroke
				(width 0)
				(type default)
			)
			(fill no)
			(layer "F.Fab")
		)
		(pad "1" smd custom
			(at 0 -0.4445 270)
			(size 0.1524 0.1524)
			(layers "F.Cu" "F.Mask" "F.Paste")
			(net "P3V3_STBY_B")
			(options
				(clearance outline)
				(anchor circle)
			)
			(primitives
				(gr_poly
					(pts
						(arc
							(start 0.3048 -0.2032)
							(mid 0.275042 -0.275042)
							(end 0.2032 -0.3048)
						)
						(arc
							(start -0.2032 -0.3048)
							(mid -0.275042 -0.275042)
							(end -0.3048 -0.2032)
						)
						(arc
							(start -0.3048 0.2032)
							(mid -0.275042 0.275042)
							(end -0.2032 0.3048)
						)
						(arc
							(start 0.2032 0.3048)
							(mid 0.275042 0.275042)
							(end 0.3048 0.2032)
						)
					)
					(width 0)
					(fill yes)
				)
			)
		)
		(pad "2" smd custom
			(at 0 0.4445 270)
			(size 0.1524 0.1524)
			(layers "F.Cu" "F.Mask" "F.Paste")
			(net "GND")
			(options
				(clearance outline)
				(anchor circle)
			)
			(primitives
				(gr_poly
					(pts
						(arc
							(start 0.3048 -0.2032)
							(mid 0.275042 -0.275042)
							(end 0.2032 -0.3048)
						)
						(arc
							(start -0.2032 -0.3048)
							(mid -0.275042 -0.275042)
							(end -0.3048 -0.2032)
						)
						(arc
							(start -0.3048 0.2032)
							(mid -0.275042 0.275042)
							(end -0.2032 0.3048)
						)
						(arc
							(start 0.2032 0.3048)
							(mid 0.275042 0.275042)
							(end 0.3048 0.2032)
						)
					)
					(width 0)
					(fill yes)
				)
			)
		)
	)
	(footprint ""
		(layer "F.Cu")
		(at 64.0588 -277.750016 -90)
		(property "Reference" "VIA36"
			(at 0 0 270)
			(layer "F.SilkS")
			(hide yes)
			(effects
				(font
					(size 1.27 1.27)
				)
			)
		)
		(property "Value" "100OHM-8L-1D6MM-L18L16-GP"
			(at -3.7211 -4.5085 270)
			(unlocked yes)
			(layer "F.Fab")
			(hide yes)
			(effects
				(font
					(size 1.016 1.016)
					(thickness 0.1524)
				)
			)
		)
		(property "Device Type" "VIA-PCIE-4P-394076"
			(at -3.7211 -6.0325 270)
			(unlocked yes)
			(layer "F.Fab")
			(hide yes)
			(effects
				(font
					(size 1.016 1.016)
					(thickness 0.1524)
				)
			)
		)
		(duplicate_pad_numbers_are_jumpers no)
		(fp_rect
			(start -1.9685 0.381)
			(end 1.9685 -0.381)
			(stroke
				(width 0)
				(type default)
			)
			(fill no)
			(layer "F.CrtYd")
		)
		(fp_rect
			(start -1.9685 0.381)
			(end 1.9685 -0.381)
			(stroke
				(width 0)
				(type default)
			)
			(fill no)
			(layer "F.Fab")
		)
		(pad "1" thru_hole circle
			(at -1.5875 0 270)
			(size 0.508 0.508)
			(drill 0.254)
			(layers "*.Cu" "*.Mask")
			(remove_unused_layers no)
			(net "GND")
			(clearance 0.127)
			(thermal_gap 0.127)
		)
		(pad "2" thru_hole circle
			(at -0.5715 0 270)
			(size 0.508 0.508)
			(drill 0.254)
			(layers "*.Cu" "*.Mask")
			(remove_unused_layers no)
			(net "PHY_DRV_A_TO_SCC_A_1_DP")
			(clearance 0.127)
			(thermal_gap 0.127)
		)
		(pad "3" thru_hole circle
			(at 0.5715 0 270)
			(size 0.508 0.508)
			(drill 0.254)
			(layers "*.Cu" "*.Mask")
			(remove_unused_layers no)
			(net "PHY_DRV_A_TO_SCC_A_1_DN")
			(clearance 0.127)
			(thermal_gap 0.127)
		)
		(pad "4" thru_hole circle
			(at 1.5875 0 270)
			(size 0.508 0.508)
			(drill 0.254)
			(layers "*.Cu" "*.Mask")
			(remove_unused_layers no)
			(net "GND")
			(clearance 0.127)
			(thermal_gap 0.127)
		)
	)
	(footprint ""
		(layer "F.Cu")
		(at 181.6862 -301.287942)
		(property "Reference" "C109"
			(at 0 0 0)
			(layer "F.SilkS")
			(hide yes)
			(effects
				(font
					(size 1.27 1.27)
				)
			)
		)
		(property "Value" "SC4D7U25V5KX-1-GP"
			(at -0.0762 -6.1214 0)
			(unlocked yes)
			(layer "F.Fab")
			(hide yes)
			(effects
				(font
					(size 1.016 1.016)
					(thickness 0.1524)
				)
			)
		)
		(property "Device Type" "C805H58"
			(at -0.0762 -8.1534 0)
			(unlocked yes)
			(layer "F.Fab")
			(hide yes)
			(effects
				(font
					(size 1.016 1.016)
					(thickness 0.1524)
				)
			)
		)
		(duplicate_pad_numbers_are_jumpers no)
		(fp_line
			(start 0.635 0)
			(end -0.635 0)
			(stroke
				(width 0.508)
				(type default)
			)
			(layer "F.SilkS")
		)
		(fp_rect
			(start -0.9652 1.778)
			(end 0.9652 -1.778)
			(stroke
				(width 0)
				(type default)
			)
			(fill no)
			(layer "F.CrtYd")
		)
		(fp_poly
			(pts
				(xy -0.9652 -1.778) (xy 0.9652 -1.778) (xy 0.9652 1.778) (xy -0.9652 1.778)
			)
			(stroke
				(width 0)
				(type default)
			)
			(fill no)
			(layer "F.Fab")
		)
		(pad "1" smd rect
			(at 0 -0.9652)
			(size 1.397 1.143)
			(layers "F.Cu" "F.Mask" "F.Paste")
			(net "P12V_HDD5")
		)
		(pad "2" smd rect
			(at 0 0.9652)
			(size 1.397 1.143)
			(layers "F.Cu" "F.Mask" "F.Paste")
			(net "GND")
		)
	)
	(footprint ""
		(layer "F.Cu")
		(at 79.581248 -26.931874)
		(property "Reference" "C11"
			(at 0 0 0)
			(layer "F.SilkS")
			(hide yes)
			(effects
				(font
					(size 1.27 1.27)
				)
			)
		)
		(property "Value" "SC1U16V3KX-5GP"
			(at 0 -2.8194 0)
			(unlocked yes)
			(layer "F.Fab")
			(hide yes)
			(effects
				(font
					(size 1.016 1.016)
					(thickness 0.1524)
				)
			)
		)
		(property "Device Type" "C603H36"
			(at 0 -4.3434 0)
			(unlocked yes)
			(layer "F.Fab")
			(hide yes)
			(effects
				(font
					(size 1.016 1.016)
					(thickness 0.1524)
				)
			)
		)
		(duplicate_pad_numbers_are_jumpers no)
		(fp_line
			(start 0.508 0)
			(end -0.508 0)
			(stroke
				(width 0.2032)
				(type default)
			)
			(layer "F.SilkS")
		)
		(fp_rect
			(start -0.5842 1.3335)
			(end 0.5842 -1.3335)
			(stroke
				(width 0)
				(type default)
			)
			(fill no)
			(layer "F.CrtYd")
		)
		(fp_rect
			(start -0.5842 1.3335)
			(end 0.5842 -1.3335)
			(stroke
				(width 0)
				(type default)
			)
			(fill no)
			(layer "F.Fab")
		)
		(pad "1" smd custom
			(at 0 -0.762)
			(size 0.2159 0.2159)
			(layers "F.Cu" "F.Mask" "F.Paste")
			(net "P3V3_STBY_A")
			(options
				(clearance outline)
				(anchor circle)
			)
			(primitives
				(gr_poly
					(pts
						(arc
							(start -0.3302 -0.4318)
							(mid -0.402042 -0.402042)
							(end -0.4318 -0.3302)
						)
						(arc
							(start -0.4318 0.3302)
							(mid -0.402042 0.402042)
							(end -0.3302 0.4318)
						)
						(arc
							(start 0.3302 0.4318)
							(mid 0.402042 0.402042)
							(end 0.4318 0.3302)
						)
						(arc
							(start 0.4318 -0.3302)
							(mid 0.402042 -0.402042)
							(end 0.3302 -0.4318)
						)
					)
					(width 0)
					(fill yes)
				)
			)
		)
		(pad "2" smd custom
			(at 0 0.762)
			(size 0.2159 0.2159)
			(layers "F.Cu" "F.Mask" "F.Paste")
			(net "GND")
			(options
				(clearance outline)
				(anchor circle)
			)
			(primitives
				(gr_poly
					(pts
						(arc
							(start -0.3302 -0.4318)
							(mid -0.402042 -0.402042)
							(end -0.4318 -0.3302)
						)
						(arc
							(start -0.4318 0.3302)
							(mid -0.402042 0.402042)
							(end -0.3302 0.4318)
						)
						(arc
							(start 0.3302 0.4318)
							(mid 0.402042 0.402042)
							(end 0.4318 0.3302)
						)
						(arc
							(start 0.4318 -0.3302)
							(mid 0.402042 -0.402042)
							(end 0.3302 -0.4318)
						)
					)
					(width 0)
					(fill yes)
				)
			)
		)
	)
	(footprint ""
		(layer "F.Cu")
		(at 468.735918 -156.522674 180)
		(property "Reference" "R667"
			(at 0 0 180)
			(layer "F.SilkS")
			(hide yes)
			(effects
				(font
					(size 1.27 1.27)
				)
			)
		)
		(property "Value" "1KR2F-3-GP"
			(at 0.064008 -3.993896 180)
			(unlocked yes)
			(layer "F.Fab")
			(hide yes)
			(effects
				(font
					(size 1.016 1.016)
					(thickness 0.1524)
				)
			)
		)
		(property "Device Type" "R402H16"
			(at 0.064008 -5.517896 180)
			(unlocked yes)
			(layer "F.Fab")
			(hide yes)
			(effects
				(font
					(size 1.016 1.016)
					(thickness 0.1524)
				)
			)
		)
		(duplicate_pad_numbers_are_jumpers no)
		(fp_line
			(start 0.508 -0.9398)
			(end -0.508 -0.9398)
			(stroke
				(width 0.1524)
				(type default)
			)
			(layer "F.SilkS")
		)
		(fp_line
			(start -0.508 -0.9398)
			(end -0.508 0.9398)
			(stroke
				(width 0.1524)
				(type default)
			)
			(layer "F.SilkS")
		)
		(fp_rect
			(start -0.508 0.9398)
			(end 0.508 -0.9398)
			(stroke
				(width 0)
				(type default)
			)
			(fill no)
			(layer "F.CrtYd")
		)
		(fp_rect
			(start -0.508 0.9398)
			(end 0.508 -0.9398)
			(stroke
				(width 0)
				(type default)
			)
			(fill no)
			(layer "F.Fab")
		)
		(pad "1" smd custom
			(at 0 -0.4445 180)
			(size 0.1397 0.1397)
			(layers "F.Cu" "F.Mask" "F.Paste")
			(net "P3V3_STBY_A")
			(options
				(clearance outline)
				(anchor circle)
			)
			(primitives
				(gr_poly
					(pts
						(arc
							(start -0.1778 -0.2794)
							(mid -0.249642 -0.249642)
							(end -0.2794 -0.1778)
						)
						(arc
							(start -0.2794 0.1778)
							(mid -0.249642 0.249642)
							(end -0.1778 0.2794)
						)
						(arc
							(start 0.1778 0.2794)
							(mid 0.249642 0.249642)
							(end 0.2794 0.1778)
						)
						(arc
							(start 0.2794 -0.1778)
							(mid 0.249642 -0.249642)
							(end 0.1778 -0.2794)
						)
					)
					(width 0)
					(fill yes)
				)
			)
		)
		(pad "2" smd custom
			(at 0 0.4445 180)
			(size 0.1397 0.1397)
			(layers "F.Cu" "F.Mask" "F.Paste")
			(net "SW_PWR_R_HDD23")
			(options
				(clearance outline)
				(anchor circle)
			)
			(primitives
				(gr_poly
					(pts
						(arc
							(start -0.1778 -0.2794)
							(mid -0.249642 -0.249642)
							(end -0.2794 -0.1778)
						)
						(arc
							(start -0.2794 0.1778)
							(mid -0.249642 0.249642)
							(end -0.1778 0.2794)
						)
						(arc
							(start 0.1778 0.2794)
							(mid 0.249642 0.249642)
							(end 0.2794 0.1778)
						)
						(arc
							(start 0.2794 -0.1778)
							(mid 0.249642 -0.249642)
							(end 0.1778 -0.2794)
						)
					)
					(width 0)
					(fill yes)
				)
			)
		)
	)
	(footprint ""
		(layer "F.Cu")
		(at 424.469052 -181.842918 180)
		(property "Reference" "C313"
			(at 0 0 180)
			(layer "F.SilkS")
			(hide yes)
			(effects
				(font
					(size 1.27 1.27)
				)
			)
		)
		(property "Value" "SC1U16V3KX-5GP"
			(at 0 -2.8194 180)
			(unlocked yes)
			(layer "F.Fab")
			(hide yes)
			(effects
				(font
					(size 1.016 1.016)
					(thickness 0.1524)
				)
			)
		)
		(property "Device Type" "C603H36"
			(at 0 -4.3434 180)
			(unlocked yes)
			(layer "F.Fab")
			(hide yes)
			(effects
				(font
					(size 1.016 1.016)
					(thickness 0.1524)
				)
			)
		)
		(duplicate_pad_numbers_are_jumpers no)
		(fp_line
			(start 0.508 0)
			(end -0.508 0)
			(stroke
				(width 0.2032)
				(type default)
			)
			(layer "F.SilkS")
		)
		(fp_rect
			(start -0.5842 1.3335)
			(end 0.5842 -1.3335)
			(stroke
				(width 0)
				(type default)
			)
			(fill no)
			(layer "F.CrtYd")
		)
		(fp_rect
			(start -0.5842 1.3335)
			(end 0.5842 -1.3335)
			(stroke
				(width 0)
				(type default)
			)
			(fill no)
			(layer "F.Fab")
		)
		(pad "1" smd custom
			(at 0 -0.762 180)
			(size 0.2159 0.2159)
			(layers "F.Cu" "F.Mask" "F.Paste")
			(net "P5V_HDD21")
			(options
				(clearance outline)
				(anchor circle)
			)
			(primitives
				(gr_poly
					(pts
						(arc
							(start -0.3302 -0.4318)
							(mid -0.402042 -0.402042)
							(end -0.4318 -0.3302)
						)
						(arc
							(start -0.4318 0.3302)
							(mid -0.402042 0.402042)
							(end -0.3302 0.4318)
						)
						(arc
							(start 0.3302 0.4318)
							(mid 0.402042 0.402042)
							(end 0.4318 0.3302)
						)
						(arc
							(start 0.4318 -0.3302)
							(mid 0.402042 -0.402042)
							(end 0.3302 -0.4318)
						)
					)
					(width 0)
					(fill yes)
				)
			)
		)
		(pad "2" smd custom
			(at 0 0.762 180)
			(size 0.2159 0.2159)
			(layers "F.Cu" "F.Mask" "F.Paste")
			(net "GND")
			(options
				(clearance outline)
				(anchor circle)
			)
			(primitives
				(gr_poly
					(pts
						(arc
							(start -0.3302 -0.4318)
							(mid -0.402042 -0.402042)
							(end -0.4318 -0.3302)
						)
						(arc
							(start -0.4318 0.3302)
							(mid -0.402042 0.402042)
							(end -0.3302 0.4318)
						)
						(arc
							(start 0.3302 0.4318)
							(mid 0.402042 0.402042)
							(end 0.4318 0.3302)
						)
						(arc
							(start 0.4318 -0.3302)
							(mid 0.402042 -0.402042)
							(end 0.3302 -0.4318)
						)
					)
					(width 0)
					(fill yes)
				)
			)
		)
	)
	(footprint ""
		(layer "F.Cu")
		(at 233.834178 -244.114828)
		(property "Reference" "R74"
			(at 0 0 0)
			(layer "F.SilkS")
			(hide yes)
			(effects
				(font
					(size 1.27 1.27)
				)
			)
		)
		(property "Value" "4K7R2F-GP"
			(at 0.064008 -3.993896 0)
			(unlocked yes)
			(layer "F.Fab")
			(hide yes)
			(effects
				(font
					(size 1.016 1.016)
					(thickness 0.1524)
				)
			)
		)
		(property "Device Type" "R402H16"
			(at 0.064008 -5.517896 0)
			(unlocked yes)
			(layer "F.Fab")
			(hide yes)
			(effects
				(font
					(size 1.016 1.016)
					(thickness 0.1524)
				)
			)
		)
		(duplicate_pad_numbers_are_jumpers no)
		(fp_line
			(start -0.508 -0.9398)
			(end -0.508 0.9398)
			(stroke
				(width 0.1524)
				(type default)
			)
			(layer "F.SilkS")
		)
		(fp_line
			(start 0.508 -0.9398)
			(end -0.508 -0.9398)
			(stroke
				(width 0.1524)
				(type default)
			)
			(layer "F.SilkS")
		)
		(fp_rect
			(start -0.508 0.9398)
			(end 0.508 -0.9398)
			(stroke
				(width 0)
				(type default)
			)
			(fill no)
			(layer "F.CrtYd")
		)
		(fp_rect
			(start -0.508 0.9398)
			(end 0.508 -0.9398)
			(stroke
				(width 0)
				(type default)
			)
			(fill no)
			(layer "F.Fab")
		)
		(pad "1" smd custom
			(at 0 -0.4445)
			(size 0.1397 0.1397)
			(layers "F.Cu" "F.Mask" "F.Paste")
			(net "P3V3_STBY_A")
			(options
				(clearance outline)
				(anchor circle)
			)
			(primitives
				(gr_poly
					(pts
						(arc
							(start -0.1778 -0.2794)
							(mid -0.249642 -0.249642)
							(end -0.2794 -0.1778)
						)
						(arc
							(start -0.2794 0.1778)
							(mid -0.249642 0.249642)
							(end -0.1778 0.2794)
						)
						(arc
							(start 0.1778 0.2794)
							(mid 0.249642 0.249642)
							(end 0.2794 0.1778)
						)
						(arc
							(start 0.2794 -0.1778)
							(mid 0.249642 -0.249642)
							(end 0.1778 -0.2794)
						)
					)
					(width 0)
					(fill yes)
				)
			)
		)
		(pad "2" smd custom
			(at 0 0.4445)
			(size 0.1397 0.1397)
			(layers "F.Cu" "F.Mask" "F.Paste")
			(net "IO_EXP1_A2")
			(options
				(clearance outline)
				(anchor circle)
			)
			(primitives
				(gr_poly
					(pts
						(arc
							(start -0.1778 -0.2794)
							(mid -0.249642 -0.249642)
							(end -0.2794 -0.1778)
						)
						(arc
							(start -0.2794 0.1778)
							(mid -0.249642 0.249642)
							(end -0.1778 0.2794)
						)
						(arc
							(start 0.1778 0.2794)
							(mid 0.249642 0.249642)
							(end 0.2794 0.1778)
						)
						(arc
							(start 0.2794 -0.1778)
							(mid 0.249642 -0.249642)
							(end 0.1778 -0.2794)
						)
					)
					(width 0)
					(fill yes)
				)
			)
		)
	)
	(footprint ""
		(layer "F.Cu")
		(at 232.9434 -248.9708)
		(property "Reference" "R36"
			(at 0 0 0)
			(layer "F.SilkS")
			(hide yes)
			(effects
				(font
					(size 1.27 1.27)
				)
			)
		)
		(property "Value" "4K7R2F-GP"
			(at 0.064008 -3.993896 0)
			(unlocked yes)
			(layer "F.Fab")
			(hide yes)
			(effects
				(font
					(size 1.016 1.016)
					(thickness 0.1524)
				)
			)
		)
		(property "Device Type" "R402H16"
			(at 0.064008 -5.517896 0)
			(unlocked yes)
			(layer "F.Fab")
			(hide yes)
			(effects
				(font
					(size 1.016 1.016)
					(thickness 0.1524)
				)
			)
		)
		(duplicate_pad_numbers_are_jumpers no)
		(fp_line
			(start -0.508 -0.9398)
			(end -0.508 0.9398)
			(stroke
				(width 0.1524)
				(type default)
			)
			(layer "F.SilkS")
		)
		(fp_line
			(start 0.508 -0.9398)
			(end -0.508 -0.9398)
			(stroke
				(width 0.1524)
				(type default)
			)
			(layer "F.SilkS")
		)
		(fp_rect
			(start -0.508 0.9398)
			(end 0.508 -0.9398)
			(stroke
				(width 0)
				(type default)
			)
			(fill no)
			(layer "F.CrtYd")
		)
		(fp_rect
			(start -0.508 0.9398)
			(end 0.508 -0.9398)
			(stroke
				(width 0)
				(type default)
			)
			(fill no)
			(layer "F.Fab")
		)
		(pad "1" smd custom
			(at 0 -0.4445)
			(size 0.1397 0.1397)
			(layers "F.Cu" "F.Mask" "F.Paste")
			(net "IO_EXP4_A0")
			(options
				(clearance outline)
				(anchor circle)
			)
			(primitives
				(gr_poly
					(pts
						(arc
							(start -0.1778 -0.2794)
							(mid -0.249642 -0.249642)
							(end -0.2794 -0.1778)
						)
						(arc
							(start -0.2794 0.1778)
							(mid -0.249642 0.249642)
							(end -0.1778 0.2794)
						)
						(arc
							(start 0.1778 0.2794)
							(mid 0.249642 0.249642)
							(end 0.2794 0.1778)
						)
						(arc
							(start 0.2794 -0.1778)
							(mid 0.249642 -0.249642)
							(end 0.1778 -0.2794)
						)
					)
					(width 0)
					(fill yes)
				)
			)
		)
		(pad "2" smd custom
			(at 0 0.4445)
			(size 0.1397 0.1397)
			(layers "F.Cu" "F.Mask" "F.Paste")
			(net "GND")
			(options
				(clearance outline)
				(anchor circle)
			)
			(primitives
				(gr_poly
					(pts
						(arc
							(start -0.1778 -0.2794)
							(mid -0.249642 -0.249642)
							(end -0.2794 -0.1778)
						)
						(arc
							(start -0.2794 0.1778)
							(mid -0.249642 0.249642)
							(end -0.1778 0.2794)
						)
						(arc
							(start 0.1778 0.2794)
							(mid 0.249642 0.249642)
							(end 0.2794 0.1778)
						)
						(arc
							(start 0.2794 -0.1778)
							(mid 0.249642 -0.249642)
							(end 0.1778 -0.2794)
						)
					)
					(width 0)
					(fill yes)
				)
			)
		)
	)
	(footprint ""
		(layer "F.Cu")
		(at 332.74 -279.596342 90)
		(property "Reference" "C126"
			(at 0 0 90)
			(layer "F.SilkS")
			(hide yes)
			(effects
				(font
					(size 1.27 1.27)
				)
			)
		)
		(property "Value" "SCD033U25V2KX-GP"
			(at 1.1811 -2.7051 90)
			(unlocked yes)
			(layer "F.Fab")
			(hide yes)
			(effects
				(font
					(size 1.016 1.016)
					(thickness 0.1524)
				)
			)
		)
		(property "Device Type" "C402H22"
			(at 1.1811 -4.2291 90)
			(unlocked yes)
			(layer "F.Fab")
			(hide yes)
			(effects
				(font
					(size 1.016 1.016)
					(thickness 0.1524)
				)
			)
		)
		(duplicate_pad_numbers_are_jumpers no)
		(fp_rect
			(start -0.4318 0.9525)
			(end 0.4318 -0.9525)
			(stroke
				(width 0)
				(type default)
			)
			(fill no)
			(layer "F.CrtYd")
		)
		(fp_rect
			(start -0.4318 0.9525)
			(end 0.4318 -0.9525)
			(stroke
				(width 0)
				(type default)
			)
			(fill no)
			(layer "F.Fab")
		)
		(pad "1" smd custom
			(at 0 -0.4445 90)
			(size 0.1524 0.1524)
			(layers "F.Cu" "F.Mask" "F.Paste")
			(net "SW_HDD_P6")
			(options
				(clearance outline)
				(anchor circle)
			)
			(primitives
				(gr_poly
					(pts
						(arc
							(start 0.3048 -0.2032)
							(mid 0.275042 -0.275042)
							(end 0.2032 -0.3048)
						)
						(arc
							(start -0.2032 -0.3048)
							(mid -0.275042 -0.275042)
							(end -0.3048 -0.2032)
						)
						(arc
							(start -0.3048 0.2032)
							(mid -0.275042 0.275042)
							(end -0.2032 0.3048)
						)
						(arc
							(start 0.2032 0.3048)
							(mid 0.275042 0.275042)
							(end 0.3048 0.2032)
						)
					)
					(width 0)
					(fill yes)
				)
			)
		)
		(pad "2" smd custom
			(at 0 0.4445 90)
			(size 0.1524 0.1524)
			(layers "F.Cu" "F.Mask" "F.Paste")
			(net "GND")
			(options
				(clearance outline)
				(anchor circle)
			)
			(primitives
				(gr_poly
					(pts
						(arc
							(start 0.3048 -0.2032)
							(mid 0.275042 -0.275042)
							(end 0.2032 -0.3048)
						)
						(arc
							(start -0.2032 -0.3048)
							(mid -0.275042 -0.275042)
							(end -0.3048 -0.2032)
						)
						(arc
							(start -0.3048 0.2032)
							(mid -0.275042 0.275042)
							(end -0.2032 0.3048)
						)
						(arc
							(start 0.2032 0.3048)
							(mid 0.275042 0.275042)
							(end 0.3048 0.2032)
						)
					)
					(width 0)
					(fill yes)
				)
			)
		)
	)
	(footprint ""
		(layer "F.Cu")
		(at 28.200096 -287.910016 -90)
		(property "Reference" "HDDSAS0"
			(at 0 0 270)
			(layer "F.SilkS")
			(hide yes)
			(effects
				(font
					(size 1.27 1.27)
				)
			)
		)
		(property "Value" "SKT-SAS15P-14P-45-GP"
			(at -20.7645 -8.9789 270)
			(unlocked yes)
			(layer "F.Fab")
			(hide yes)
			(effects
				(font
					(size 1.016 1.016)
					(thickness 0.1524)
				)
			)
		)
		(property "Device Type" "10120818-001C-TRLF"
			(at -20.7645 -10.5029 270)
			(unlocked yes)
			(layer "F.Fab")
			(hide yes)
			(effects
				(font
					(size 1.016 1.016)
					(thickness 0.1524)
				)
			)
		)
		(duplicate_pad_numbers_are_jumpers no)
		(fp_line
			(start 1.651 4.2926)
			(end 1.651 3.0099)
			(stroke
				(width 0.1524)
				(type default)
			)
			(layer "F.SilkS")
		)
		(fp_line
			(start 8.509 4.2926)
			(end 1.651 4.2926)
			(stroke
				(width 0.1524)
				(type default)
			)
			(layer "F.SilkS")
		)
		(fp_line
			(start -23.4188 3.0099)
			(end -23.4188 -3.2512)
			(stroke
				(width 0.1524)
				(type default)
			)
			(layer "F.SilkS")
		)
		(fp_line
			(start 1.651 3.0099)
			(end -23.4188 3.0099)
			(stroke
				(width 0.1524)
				(type default)
			)
			(layer "F.SilkS")
		)
		(fp_line
			(start 8.509 3.0099)
			(end 8.509 4.2926)
			(stroke
				(width 0.1524)
				(type default)
			)
			(layer "F.SilkS")
		)
		(fp_line
			(start 23.4188 3.0099)
			(end 8.509 3.0099)
			(stroke
				(width 0.1524)
				(type default)
			)
			(layer "F.SilkS")
		)
		(fp_line
			(start -23.4188 -3.2512)
			(end 23.4188 -3.2512)
			(stroke
				(width 0.1524)
				(type default)
			)
			(layer "F.SilkS")
		)
		(fp_line
			(start 23.4188 -3.2512)
			(end 23.4188 3.0099)
			(stroke
				(width 0.1524)
				(type default)
			)
			(layer "F.SilkS")
		)
		(fp_line
			(start 15.5067 -3.3401)
			(end 16.2687 -3.3401)
			(stroke
				(width 0.3302)
				(type default)
			)
			(layer "F.SilkS")
		)
		(fp_poly
			(pts
				(xy 15.868904 -3.230372) (xy 16.503904 -3.865372) (xy 15.233904 -3.865372)
			)
			(stroke
				(width 0)
				(type default)
			)
			(fill yes)
			(layer "F.SilkS")
		)
		(fp_poly
			(pts
				(xy -22.8727 -2.7559) (xy 22.8727 -2.7559) (xy 22.8727 2.7559) (xy 8.255 2.7559) (xy 8.255 3.5179)
				(xy 1.905 3.5179) (xy 1.905 2.7559) (xy -22.8727 2.7559)
			)
			(stroke
				(width 0)
				(type default)
			)
			(fill no)
			(layer "F.CrtYd")
		)
		(fp_poly
			(pts
				(xy 1.397 4.5466) (xy 1.397 3.2639) (xy -23.6728 3.2639) (xy -23.6728 -3.5052) (xy 23.6728 -3.5052)
				(xy 23.6728 -0.00635) (xy 22.8727 -0.00635) (xy 22.8727 -2.7559) (xy -22.8727 -2.7559) (xy -22.8727 2.7559)
				(xy 1.905 2.7559) (xy 1.905 3.5179) (xy 8.255 3.5179) (xy 8.255 2.7559) (xy 22.8727 2.7559) (xy 22.8727 0.00635)
				(xy 23.6728 0.00635) (xy 23.6728 3.2639) (xy 8.763 3.2639) (xy 8.763 4.5466)
			)
			(stroke
				(width 0)
				(type default)
			)
			(fill no)
			(layer "F.CrtYd")
		)
		(fp_poly
			(pts
				(xy 1.397 4.5466) (xy 1.397 3.2639) (xy -23.6728 3.2639) (xy -23.6728 -3.5052) (xy 23.6728 -3.5052)
				(xy 23.6728 3.2639) (xy 8.763 3.2639) (xy 8.763 4.5466)
			)
			(stroke
				(width 0)
				(type default)
			)
			(fill no)
			(layer "F.Fab")
		)
		(pad "" np_thru_hole circle
			(at -18.874994 0 270)
			(size 0.254 0.254)
			(drill 1.3462)
			(layers "*.Cu" "*.Mask")
			(clearance 0.9017)
			(thermal_gap 0.9017)
		)
		(pad "" np_thru_hole circle
			(at 18.874994 0 270)
			(size 0.254 0.254)
			(drill 0.9398)
			(layers "*.Cu" "*.Mask")
			(clearance 0.6985)
			(thermal_gap 0.6985)
		)
		(pad "G1" smd rect
			(at 21.874988 0 270)
			(size 2.5908 2.5908)
			(layers "F.Cu" "F.Mask" "F.Paste")
			(net "GND")
		)
		(pad "G2" smd rect
			(at -21.874988 0 270)
			(size 2.5908 2.5908)
			(layers "F.Cu" "F.Mask" "F.Paste")
			(net "GND")
		)
		(pad "P1" smd rect
			(at 1.905 -1.82499 270)
			(size 0.6096 2.3622)
			(layers "F.Cu" "F.Mask" "F.Paste")
			(net "Net_2176")
		)
		(pad "P2" smd rect
			(at 0.635 -1.82499 270)
			(size 0.6096 2.3622)
			(layers "F.Cu" "F.Mask" "F.Paste")
			(net "Net_2177")
		)
		(pad "P3" smd rect
			(at -0.635 -1.82499 270)
			(size 0.6096 2.3622)
			(layers "F.Cu" "F.Mask" "F.Paste")
			(net "Net_2178")
		)
		(pad "P4" smd rect
			(at -1.905 -1.82499 270)
			(size 0.6096 2.3622)
			(layers "F.Cu" "F.Mask" "F.Paste")
			(net "GND")
		)
		(pad "P5" smd rect
			(at -3.175 -1.82499 270)
			(size 0.6096 2.3622)
			(layers "F.Cu" "F.Mask" "F.Paste")
			(net "HDD_PRSNT_0")
		)
		(pad "P6" smd rect
			(at -4.445 -1.82499 270)
			(size 0.6096 2.3622)
			(layers "F.Cu" "F.Mask" "F.Paste")
			(net "GND")
		)
		(pad "P7" smd rect
			(at -5.715 -1.82499 270)
			(size 0.6096 2.3622)
			(layers "F.Cu" "F.Mask" "F.Paste")
			(net "5V_PRE_0")
		)
		(pad "P8" smd rect
			(at -6.985 -1.82499 270)
			(size 0.6096 2.3622)
			(layers "F.Cu" "F.Mask" "F.Paste")
			(net "P5V_HDD0")
		)
		(pad "P9" smd rect
			(at -8.255 -1.82499 270)
			(size 0.6096 2.3622)
			(layers "F.Cu" "F.Mask" "F.Paste")
			(net "P5V_HDD0")
		)
		(pad "P10" smd rect
			(at -9.525 -1.82499 270)
			(size 0.6096 2.3622)
			(layers "F.Cu" "F.Mask" "F.Paste")
			(net "GND")
		)
		(pad "P11" smd rect
			(at -10.795 -1.82499 270)
			(size 0.6096 2.3622)
			(layers "F.Cu" "F.Mask" "F.Paste")
			(net "ACT_HDD_0")
		)
		(pad "P12" smd rect
			(at -12.065 -1.82499 270)
			(size 0.6096 2.3622)
			(layers "F.Cu" "F.Mask" "F.Paste")
			(net "GND")
		)
		(pad "P13" smd rect
			(at -13.335 -1.82499 270)
			(size 0.6096 2.3622)
			(layers "F.Cu" "F.Mask" "F.Paste")
			(net "12V_PRE_0")
		)
		(pad "P14" smd rect
			(at -14.605 -1.82499 270)
			(size 0.6096 2.3622)
			(layers "F.Cu" "F.Mask" "F.Paste")
			(net "P12V_HDD0")
		)
		(pad "P15" smd rect
			(at -15.875 -1.82499 270)
			(size 0.6096 2.3622)
			(layers "F.Cu" "F.Mask" "F.Paste")
			(net "P12V_HDD0")
		)
		(pad "S1" smd rect
			(at 15.875 -1.82499 270)
			(size 0.6096 2.3622)
			(layers "F.Cu" "F.Mask" "F.Paste")
			(net "GND")
		)
		(pad "S2" smd rect
			(at 14.605 -1.82499 270)
			(size 0.6096 2.3622)
			(layers "F.Cu" "F.Mask" "F.Paste")
			(net "SAS_HDD_RX_P0")
		)
		(pad "S3" smd rect
			(at 13.335 -1.82499 270)
			(size 0.6096 2.3622)
			(layers "F.Cu" "F.Mask" "F.Paste")
			(net "SAS_HDD_RX_N0")
		)
		(pad "S4" smd rect
			(at 12.065 -1.82499 270)
			(size 0.6096 2.3622)
			(layers "F.Cu" "F.Mask" "F.Paste")
			(net "GND")
		)
		(pad "S5" smd rect
			(at 10.795 -1.82499 270)
			(size 0.6096 2.3622)
			(layers "F.Cu" "F.Mask" "F.Paste")
			(net "PHY_DRV_A_TO_SCC_A_0_DN")
		)
		(pad "S6" smd rect
			(at 9.525 -1.82499 270)
			(size 0.6096 2.3622)
			(layers "F.Cu" "F.Mask" "F.Paste")
			(net "PHY_DRV_A_TO_SCC_A_0_DP")
		)
		(pad "S7" smd rect
			(at 8.255 -1.82499 270)
			(size 0.6096 2.3622)
			(layers "F.Cu" "F.Mask" "F.Paste")
			(net "GND")
		)
		(pad "S8" smd rect
			(at 7.480046 2.845054 270)
			(size 0.508 2.3622)
			(layers "F.Cu" "F.Mask" "F.Paste")
			(net "GND")
		)
		(pad "S9" smd rect
			(at 6.679946 2.845054 270)
			(size 0.508 2.3622)
			(layers "F.Cu" "F.Mask" "F.Paste")
			(net "Net_445")
		)
		(pad "S10" smd rect
			(at 5.8801 2.845054 270)
			(size 0.508 2.3622)
			(layers "F.Cu" "F.Mask" "F.Paste")
			(net "Net_337")
		)
		(pad "S11" smd rect
			(at 5.08 2.845054 270)
			(size 0.508 2.3622)
			(layers "F.Cu" "F.Mask" "F.Paste")
			(net "GND")
		)
		(pad "S12" smd rect
			(at 4.2799 2.845054 270)
			(size 0.508 2.3622)
			(layers "F.Cu" "F.Mask" "F.Paste")
			(net "Net_373")
		)
		(pad "S13" smd rect
			(at 3.480054 2.845054 270)
			(size 0.508 2.3622)
			(layers "F.Cu" "F.Mask" "F.Paste")
			(net "Net_409")
		)
		(pad "S14" smd rect
			(at 2.679954 2.845054 270)
			(size 0.508 2.3622)
			(layers "F.Cu" "F.Mask" "F.Paste")
			(net "GND")
		)
		(zone
			(layer "F.Cu")
			(hatch none 0.5)
			(connect_pads
				(clearance 0)
			)
			(min_thickness 0.25)
			(keepout
				(tracks not_allowed)
				(vias allowed)
				(pads allowed)
				(copperpour not_allowed)
				(footprints allowed)
			)
			(placement
				(enabled no)
				(sheetname "")
			)
			(fill
				(thermal_gap 0.5)
				(thermal_bridge_width 0.5)
				(island_removal_mode 0)
			)
			(polygon
				(pts
					(xy 31.857696 -304.648616) (xy 24.783796 -304.648616) (xy 24.783796 -311.582816) (xy 25.888696 -311.582816)
					(xy 25.888696 -307.468016) (xy 30.511496 -307.468016) (xy 30.511496 -311.582816) (xy 31.857696 -311.582816)
				)
			)
		)
		(zone
			(layer "F.Cu")
			(hatch none 0.5)
			(connect_pads
				(clearance 0)
			)
			(min_thickness 0.25)
			(keepout
				(tracks allowed)
				(vias not_allowed)
				(pads allowed)
				(copperpour not_allowed)
				(footprints allowed)
			)
			(placement
				(enabled no)
				(sheetname "")
			)
			(fill
				(thermal_gap 0.5)
				(thermal_bridge_width 0.5)
				(island_removal_mode 0)
			)
			(polygon
				(pts
					(xy 31.857696 -304.648616) (xy 24.783796 -304.648616) (xy 24.783796 -311.582816) (xy 25.888696 -311.582816)
					(xy 25.888696 -307.468016) (xy 30.511496 -307.468016) (xy 30.511496 -311.582816) (xy 31.857696 -311.582816)
				)
			)
		)
		(zone
			(layer "F.Cu")
			(hatch none 0.5)
			(connect_pads
				(clearance 0)
			)
			(min_thickness 0.25)
			(keepout
				(tracks not_allowed)
				(vias allowed)
				(pads allowed)
				(copperpour not_allowed)
				(footprints allowed)
			)
			(placement
				(enabled no)
				(sheetname "")
			)
			(fill
				(thermal_gap 0.5)
				(thermal_bridge_width 0.5)
				(island_removal_mode 0)
			)
			(polygon
				(pts
					(xy 31.857696 -271.171416) (xy 24.783796 -271.171416) (xy 24.783796 -264.237216) (xy 25.888696 -264.237216)
					(xy 25.888696 -268.352016) (xy 30.511496 -268.352016) (xy 30.511496 -264.237216) (xy 31.857696 -264.237216)
				)
			)
		)
		(zone
			(layer "F.Cu")
			(hatch none 0.5)
			(connect_pads
				(clearance 0)
			)
			(min_thickness 0.25)
			(keepout
				(tracks allowed)
				(vias not_allowed)
				(pads allowed)
				(copperpour not_allowed)
				(footprints allowed)
			)
			(placement
				(enabled no)
				(sheetname "")
			)
			(fill
				(thermal_gap 0.5)
				(thermal_bridge_width 0.5)
				(island_removal_mode 0)
			)
			(polygon
				(pts
					(xy 31.857696 -271.171416) (xy 24.783796 -271.171416) (xy 24.783796 -264.237216) (xy 25.888696 -264.237216)
					(xy 25.888696 -268.352016) (xy 30.511496 -268.352016) (xy 30.511496 -264.237216) (xy 31.857696 -264.237216)
				)
			)
		)
		(zone
			(layers "F.Cu" "B.Cu" "In1.Cu" "In2.Cu" "In3.Cu" "In4.Cu" "In5.Cu" "In6.Cu"
				"In7.Cu" "In8.Cu" "In9.Cu" "In10.Cu"
			)
			(hatch none 0.5)
			(connect_pads
				(clearance 0)
			)
			(min_thickness 0.25)
			(keepout
				(tracks not_allowed)
				(vias allowed)
				(pads allowed)
				(copperpour not_allowed)
				(footprints allowed)
			)
			(placement
				(enabled no)
				(sheetname "")
			)
			(fill
				(thermal_gap 0.5)
				(thermal_bridge_width 0.5)
				(island_removal_mode 0)
			)
			(polygon
				(pts
					(arc
						(start 28.974796 -269.035022)
						(mid 27.425396 -269.035022)
						(end 28.974796 -269.035022)
					)
				)
			)
		)
		(zone
			(layers "F.Cu" "B.Cu" "In1.Cu" "In2.Cu" "In3.Cu" "In4.Cu" "In5.Cu" "In6.Cu"
				"In7.Cu" "In8.Cu" "In9.Cu" "In10.Cu"
			)
			(hatch none 0.5)
			(connect_pads
				(clearance 0)
			)
			(min_thickness 0.25)
			(keepout
				(tracks not_allowed)
				(vias allowed)
				(pads allowed)
				(copperpour not_allowed)
				(footprints allowed)
			)
			(placement
				(enabled no)
				(sheetname "")
			)
			(fill
				(thermal_gap 0.5)
				(thermal_bridge_width 0.5)
				(island_removal_mode 0)
			)
			(polygon
				(pts
					(arc
						(start 29.177996 -306.78501)
						(mid 27.222196 -306.78501)
						(end 29.177996 -306.78501)
					)
				)
			)
		)
	)
	(footprint ""
		(layer "F.Cu")
		(at 81.600548 -160.633918)
		(property "Reference" "R469"
			(at 0 0 0)
			(layer "F.SilkS")
			(hide yes)
			(effects
				(font
					(size 1.27 1.27)
				)
			)
		)
		(property "Value" "0R2J-2-GP"
			(at 0.064008 -3.993896 0)
			(unlocked yes)
			(layer "F.Fab")
			(hide yes)
			(effects
				(font
					(size 1.016 1.016)
					(thickness 0.1524)
				)
			)
		)
		(property "Device Type" "R402H16"
			(at 0.064008 -5.517896 0)
			(unlocked yes)
			(layer "F.Fab")
			(hide yes)
			(effects
				(font
					(size 1.016 1.016)
					(thickness 0.1524)
				)
			)
		)
		(duplicate_pad_numbers_are_jumpers no)
		(fp_line
			(start -0.508 -0.9398)
			(end -0.508 0.9398)
			(stroke
				(width 0.1524)
				(type default)
			)
			(layer "F.SilkS")
		)
		(fp_line
			(start 0.508 -0.9398)
			(end -0.508 -0.9398)
			(stroke
				(width 0.1524)
				(type default)
			)
			(layer "F.SilkS")
		)
		(fp_rect
			(start -0.508 0.9398)
			(end 0.508 -0.9398)
			(stroke
				(width 0)
				(type default)
			)
			(fill no)
			(layer "F.CrtYd")
		)
		(fp_rect
			(start -0.508 0.9398)
			(end 0.508 -0.9398)
			(stroke
				(width 0)
				(type default)
			)
			(fill no)
			(layer "F.Fab")
		)
		(pad "1" smd custom
			(at 0 -0.4445)
			(size 0.1397 0.1397)
			(layers "F.Cu" "F.Mask" "F.Paste")
			(net "SW_HDD_G14")
			(options
				(clearance outline)
				(anchor circle)
			)
			(primitives
				(gr_poly
					(pts
						(arc
							(start -0.1778 -0.2794)
							(mid -0.249642 -0.249642)
							(end -0.2794 -0.1778)
						)
						(arc
							(start -0.2794 0.1778)
							(mid -0.249642 0.249642)
							(end -0.1778 0.2794)
						)
						(arc
							(start 0.1778 0.2794)
							(mid 0.249642 0.249642)
							(end 0.2794 0.1778)
						)
						(arc
							(start 0.2794 -0.1778)
							(mid 0.249642 -0.249642)
							(end 0.1778 -0.2794)
						)
					)
					(width 0)
					(fill yes)
				)
			)
		)
		(pad "2" smd custom
			(at 0 0.4445)
			(size 0.1397 0.1397)
			(layers "F.Cu" "F.Mask" "F.Paste")
			(net "SW_HDD_R14")
			(options
				(clearance outline)
				(anchor circle)
			)
			(primitives
				(gr_poly
					(pts
						(arc
							(start -0.1778 -0.2794)
							(mid -0.249642 -0.249642)
							(end -0.2794 -0.1778)
						)
						(arc
							(start -0.2794 0.1778)
							(mid -0.249642 0.249642)
							(end -0.1778 0.2794)
						)
						(arc
							(start 0.1778 0.2794)
							(mid 0.249642 0.249642)
							(end 0.2794 0.1778)
						)
						(arc
							(start 0.2794 -0.1778)
							(mid 0.249642 -0.249642)
							(end 0.1778 -0.2794)
						)
					)
					(width 0)
					(fill yes)
				)
			)
		)
	)
	(footprint ""
		(layer "F.Cu")
		(at 143.999966 -94.400116)
		(property "Reference" "FLED17"
			(at 0 0 0)
			(layer "F.SilkS")
			(hide yes)
			(effects
				(font
					(size 1.27 1.27)
				)
			)
		)
		(property "Value" "LED-BY-19-GP"
			(at -2.132076 1.414018 0)
			(unlocked yes)
			(layer "F.Fab")
			(hide yes)
			(effects
				(font
					(size 1.016 1.016)
					(thickness 0.1524)
				)
			)
		)
		(property "Device Type" "LED-1615-4PH26"
			(at -2.132076 -0.109982 0)
			(unlocked yes)
			(layer "F.Fab")
			(hide yes)
			(effects
				(font
					(size 1.016 1.016)
					(thickness 0.1524)
				)
			)
		)
		(duplicate_pad_numbers_are_jumpers no)
		(fp_line
			(start -1.2954 0.254)
			(end -1.2954 1.6002)
			(stroke
				(width 0.508)
				(type default)
			)
			(layer "F.SilkS")
		)
		(fp_line
			(start -1.2954 1.6002)
			(end 1.2954 1.6002)
			(stroke
				(width 0.508)
				(type default)
			)
			(layer "F.SilkS")
		)
		(fp_line
			(start -1.1176 -1.4224)
			(end 1.1176 -1.4224)
			(stroke
				(width 0.1524)
				(type default)
			)
			(layer "F.SilkS")
		)
		(fp_line
			(start -1.1176 1.4224)
			(end -1.1176 -1.4224)
			(stroke
				(width 0.1524)
				(type default)
			)
			(layer "F.SilkS")
		)
		(fp_line
			(start 1.1176 -1.4224)
			(end 1.1176 1.4224)
			(stroke
				(width 0.1524)
				(type default)
			)
			(layer "F.SilkS")
		)
		(fp_line
			(start 1.1176 1.4224)
			(end -1.1176 1.4224)
			(stroke
				(width 0.1524)
				(type default)
			)
			(layer "F.SilkS")
		)
		(fp_line
			(start 1.2954 1.6002)
			(end 1.2954 0.254)
			(stroke
				(width 0.508)
				(type default)
			)
			(layer "F.SilkS")
		)
		(fp_rect
			(start -0.7493 0.8001)
			(end 0.7493 -0.8001)
			(stroke
				(width 0)
				(type default)
			)
			(fill no)
			(layer "F.CrtYd")
		)
		(fp_poly
			(pts
				(xy -1.3716 1.6764) (xy -1.3716 -1.6764) (xy 1.3716 -1.6764) (xy 1.3716 0.0635) (xy 0.7493 0.0635)
				(xy 0.7493 -0.8001) (xy -0.7493 -0.8001) (xy -0.7493 0.8001) (xy 0.7493 0.8001) (xy 0.7493 0.0762)
				(xy 1.3716 0.0762) (xy 1.3716 1.6764)
			)
			(stroke
				(width 0)
				(type default)
			)
			(fill no)
			(layer "F.CrtYd")
		)
		(fp_rect
			(start -1.3716 1.6764)
			(end 1.3716 -1.6764)
			(stroke
				(width 0)
				(type default)
			)
			(fill no)
			(layer "F.Fab")
		)
		(pad "1" smd rect
			(at 0.50038 -0.73025)
			(size 0.7112 0.8636)
			(layers "F.Cu" "F.Mask" "F.Paste")
			(net "DRV_ACT_16")
		)
		(pad "2" smd rect
			(at -0.50038 -0.73025)
			(size 0.7112 0.8636)
			(layers "F.Cu" "F.Mask" "F.Paste")
			(net "FLT_HDD16")
		)
		(pad "3" smd rect
			(at 0.50038 0.73025)
			(size 0.7112 0.8636)
			(layers "F.Cu" "F.Mask" "F.Paste")
			(net "DRV_ACT_16_N")
		)
		(pad "4" smd rect
			(at -0.50038 0.73025)
			(size 0.7112 0.8636)
			(layers "F.Cu" "F.Mask" "F.Paste")
			(net "FLT_HDD16_N")
		)
	)
	(footprint ""
		(layer "F.Cu")
		(at 370.259102 -286.809942 -90)
		(property "Reference" "R306"
			(at 0 0 270)
			(layer "F.SilkS")
			(hide yes)
			(effects
				(font
					(size 1.27 1.27)
				)
			)
		)
		(property "Value" "300KR2F-GP"
			(at 0.064008 -3.993896 270)
			(unlocked yes)
			(layer "F.Fab")
			(hide yes)
			(effects
				(font
					(size 1.016 1.016)
					(thickness 0.1524)
				)
			)
		)
		(property "Device Type" "R402H16"
			(at 0.064008 -5.517896 270)
			(unlocked yes)
			(layer "F.Fab")
			(hide yes)
			(effects
				(font
					(size 1.016 1.016)
					(thickness 0.1524)
				)
			)
		)
		(duplicate_pad_numbers_are_jumpers no)
		(fp_line
			(start -0.508 -0.9398)
			(end -0.508 0.9398)
			(stroke
				(width 0.1524)
				(type default)
			)
			(layer "F.SilkS")
		)
		(fp_line
			(start 0.508 -0.9398)
			(end -0.508 -0.9398)
			(stroke
				(width 0.1524)
				(type default)
			)
			(layer "F.SilkS")
		)
		(fp_rect
			(start -0.508 0.9398)
			(end 0.508 -0.9398)
			(stroke
				(width 0)
				(type default)
			)
			(fill no)
			(layer "F.CrtYd")
		)
		(fp_rect
			(start -0.508 0.9398)
			(end 0.508 -0.9398)
			(stroke
				(width 0)
				(type default)
			)
			(fill no)
			(layer "F.Fab")
		)
		(pad "1" smd custom
			(at 0 -0.4445 270)
			(size 0.1397 0.1397)
			(layers "F.Cu" "F.Mask" "F.Paste")
			(net "SW_HDD_N7")
			(options
				(clearance outline)
				(anchor circle)
			)
			(primitives
				(gr_poly
					(pts
						(arc
							(start -0.1778 -0.2794)
							(mid -0.249642 -0.249642)
							(end -0.2794 -0.1778)
						)
						(arc
							(start -0.2794 0.1778)
							(mid -0.249642 0.249642)
							(end -0.1778 0.2794)
						)
						(arc
							(start 0.1778 0.2794)
							(mid 0.249642 0.249642)
							(end 0.2794 0.1778)
						)
						(arc
							(start 0.2794 -0.1778)
							(mid 0.249642 -0.249642)
							(end 0.1778 -0.2794)
						)
					)
					(width 0)
					(fill yes)
				)
			)
		)
		(pad "2" smd custom
			(at 0 0.4445 270)
			(size 0.1397 0.1397)
			(layers "F.Cu" "F.Mask" "F.Paste")
			(net "P12V_A")
			(options
				(clearance outline)
				(anchor circle)
			)
			(primitives
				(gr_poly
					(pts
						(arc
							(start -0.1778 -0.2794)
							(mid -0.249642 -0.249642)
							(end -0.2794 -0.1778)
						)
						(arc
							(start -0.2794 0.1778)
							(mid -0.249642 0.249642)
							(end -0.1778 0.2794)
						)
						(arc
							(start 0.1778 0.2794)
							(mid 0.249642 0.249642)
							(end 0.2794 0.1778)
						)
						(arc
							(start 0.2794 -0.1778)
							(mid 0.249642 -0.249642)
							(end 0.1778 -0.2794)
						)
					)
					(width 0)
					(fill yes)
				)
			)
		)
	)
	(footprint ""
		(layer "F.Cu")
		(at 176.657 -179.683918 90)
		(property "Reference" "R522"
			(at 0 0 90)
			(layer "F.SilkS")
			(hide yes)
			(effects
				(font
					(size 1.27 1.27)
				)
			)
		)
		(property "Value" "2R6F-GP"
			(at -0.0508 -4.8514 90)
			(unlocked yes)
			(layer "F.Fab")
			(hide yes)
			(effects
				(font
					(size 1.016 1.016)
					(thickness 0.1524)
				)
			)
		)
		(property "Device Type" "R1206H26"
			(at 0 -6.3754 90)
			(unlocked yes)
			(layer "F.Fab")
			(hide yes)
			(effects
				(font
					(size 1.016 1.016)
					(thickness 0.1524)
				)
			)
		)
		(duplicate_pad_numbers_are_jumpers no)
		(fp_line
			(start 1.016 -2.2352)
			(end 1.016 2.2352)
			(stroke
				(width 0.1524)
				(type default)
			)
			(layer "F.SilkS")
		)
		(fp_line
			(start -1.016 -2.2352)
			(end 1.016 -2.2352)
			(stroke
				(width 0.1524)
				(type default)
			)
			(layer "F.SilkS")
		)
		(fp_line
			(start 1.016 2.2352)
			(end -1.016 2.2352)
			(stroke
				(width 0.1524)
				(type default)
			)
			(layer "F.SilkS")
		)
		(fp_line
			(start -1.016 2.2352)
			(end -1.016 -2.2352)
			(stroke
				(width 0.1524)
				(type default)
			)
			(layer "F.SilkS")
		)
		(fp_rect
			(start -1.0922 2.3114)
			(end 1.0922 -2.3114)
			(stroke
				(width 0)
				(type default)
			)
			(fill no)
			(layer "F.CrtYd")
		)
		(fp_poly
			(pts
				(xy -1.0922 -2.3114) (xy 1.0922 -2.3114) (xy 1.0922 2.3114) (xy -1.0922 2.3114)
			)
			(stroke
				(width 0)
				(type default)
			)
			(fill no)
			(layer "F.Fab")
		)
		(pad "1" smd rect
			(at 0 -1.397 90)
			(size 1.651 1.27)
			(layers "F.Cu" "F.Mask" "F.Paste")
			(net "P12V_HDD17")
		)
		(pad "2" smd rect
			(at 0 1.397 90)
			(size 1.651 1.27)
			(layers "F.Cu" "F.Mask" "F.Paste")
			(net "12V_PRE_17")
		)
	)
	(footprint ""
		(layer "F.Cu")
		(at 318.516 -183.620918)
		(property "Reference" "TP92"
			(at 0 0 0)
			(layer "F.SilkS")
			(hide yes)
			(effects
				(font
					(size 1.27 1.27)
				)
			)
		)
		(property "Value" "TPAD32-GP"
			(at -0.0508 -1.6764 0)
			(unlocked yes)
			(layer "F.Fab")
			(hide yes)
			(effects
				(font
					(size 1.016 1.016)
					(thickness 0.1524)
				)
			)
		)
		(property "Device Type" "TPAD32"
			(at -0.0508 -3.2004 0)
			(unlocked yes)
			(layer "F.Fab")
			(hide yes)
			(effects
				(font
					(size 1.016 1.016)
					(thickness 0.1524)
				)
			)
		)
		(duplicate_pad_numbers_are_jumpers no)
		(fp_poly
			(pts
				(arc
					(start 0.4064 0)
					(mid -0.4064 0)
					(end 0.4064 0)
				)
			)
			(stroke
				(width 0)
				(type default)
			)
			(fill no)
			(layer "F.CrtYd")
		)
		(fp_poly
			(pts
				(arc
					(start 0.7112 0)
					(mid -0.7112 0)
					(end 0.7112 0)
				)
			)
			(stroke
				(width 0)
				(type default)
			)
			(fill no)
			(layer "F.Fab")
		)
		(pad "1" smd circle
			(at 0 0)
			(size 0.8128 0.8128)
			(layers "F.Cu" "F.Mask" "F.Paste")
			(net "ACT_HDD_18")
		)
	)
	(footprint ""
		(layer "F.Cu")
		(at 161.997898 -61.127894 90)
		(property "Reference" "C410"
			(at 0 0 90)
			(layer "F.SilkS")
			(hide yes)
			(effects
				(font
					(size 1.27 1.27)
				)
			)
		)
		(property "Value" "SCD01U50V2KX-1GP"
			(at 1.1811 -2.7051 90)
			(unlocked yes)
			(layer "F.Fab")
			(hide yes)
			(effects
				(font
					(size 1.016 1.016)
					(thickness 0.1524)
				)
			)
		)
		(property "Device Type" "C402H22"
			(at 1.1811 -4.2291 90)
			(unlocked yes)
			(layer "F.Fab")
			(hide yes)
			(effects
				(font
					(size 1.016 1.016)
					(thickness 0.1524)
				)
			)
		)
		(duplicate_pad_numbers_are_jumpers no)
		(fp_rect
			(start -0.4318 0.9525)
			(end 0.4318 -0.9525)
			(stroke
				(width 0)
				(type default)
			)
			(fill no)
			(layer "F.CrtYd")
		)
		(fp_rect
			(start -0.4318 0.9525)
			(end 0.4318 -0.9525)
			(stroke
				(width 0)
				(type default)
			)
			(fill no)
			(layer "F.Fab")
		)
		(pad "1" smd custom
			(at 0 -0.4445 90)
			(size 0.1524 0.1524)
			(layers "F.Cu" "F.Mask" "F.Paste")
			(net "HDD_PRSNT_28")
			(options
				(clearance outline)
				(anchor circle)
			)
			(primitives
				(gr_poly
					(pts
						(arc
							(start 0.3048 -0.2032)
							(mid 0.275042 -0.275042)
							(end 0.2032 -0.3048)
						)
						(arc
							(start -0.2032 -0.3048)
							(mid -0.275042 -0.275042)
							(end -0.3048 -0.2032)
						)
						(arc
							(start -0.3048 0.2032)
							(mid -0.275042 0.275042)
							(end -0.2032 0.3048)
						)
						(arc
							(start 0.2032 0.3048)
							(mid 0.275042 0.275042)
							(end 0.3048 0.2032)
						)
					)
					(width 0)
					(fill yes)
				)
			)
		)
		(pad "2" smd custom
			(at 0 0.4445 90)
			(size 0.1524 0.1524)
			(layers "F.Cu" "F.Mask" "F.Paste")
			(net "GND")
			(options
				(clearance outline)
				(anchor circle)
			)
			(primitives
				(gr_poly
					(pts
						(arc
							(start 0.3048 -0.2032)
							(mid 0.275042 -0.275042)
							(end 0.2032 -0.3048)
						)
						(arc
							(start -0.2032 -0.3048)
							(mid -0.275042 -0.275042)
							(end -0.3048 -0.2032)
						)
						(arc
							(start -0.3048 0.2032)
							(mid -0.275042 0.275042)
							(end -0.2032 0.3048)
						)
						(arc
							(start 0.2032 0.3048)
							(mid 0.275042 0.275042)
							(end 0.3048 0.2032)
						)
					)
					(width 0)
					(fill yes)
				)
			)
		)
	)
	(footprint ""
		(layer "F.Cu")
		(at 395.45895 -65.826894 180)
		(property "Reference" "C457"
			(at 0 0 180)
			(layer "F.SilkS")
			(hide yes)
			(effects
				(font
					(size 1.27 1.27)
				)
			)
		)
		(property "Value" "SC10U16V6KX-2GP"
			(at -0.0762 -5.1308 180)
			(unlocked yes)
			(layer "F.Fab")
			(hide yes)
			(effects
				(font
					(size 1.016 1.016)
					(thickness 0.1524)
				)
			)
		)
		(property "Device Type" "C1206H71"
			(at -0.127 -6.6548 180)
			(unlocked yes)
			(layer "F.Fab")
			(hide yes)
			(effects
				(font
					(size 1.016 1.016)
					(thickness 0.1524)
				)
			)
		)
		(duplicate_pad_numbers_are_jumpers no)
		(fp_line
			(start 1.016 2.2352)
			(end -1.016 2.2352)
			(stroke
				(width 0.1524)
				(type default)
			)
			(layer "F.SilkS")
		)
		(fp_line
			(start 1.016 0.8382)
			(end 1.016 2.2352)
			(stroke
				(width 0.1524)
				(type default)
			)
			(layer "F.SilkS")
		)
		(fp_line
			(start 1.016 -2.2352)
			(end 1.016 -0.8382)
			(stroke
				(width 0.1524)
				(type default)
			)
			(layer "F.SilkS")
		)
		(fp_line
			(start -1.016 2.2352)
			(end -1.016 0.8382)
			(stroke
				(width 0.1524)
				(type default)
			)
			(layer "F.SilkS")
		)
		(fp_line
			(start -1.016 -0.8382)
			(end -1.016 -2.2352)
			(stroke
				(width 0.1524)
				(type default)
			)
			(layer "F.SilkS")
		)
		(fp_line
			(start -1.016 -2.2352)
			(end 1.016 -2.2352)
			(stroke
				(width 0.1524)
				(type default)
			)
			(layer "F.SilkS")
		)
		(fp_rect
			(start -1.0922 2.3114)
			(end 1.0922 -2.3114)
			(stroke
				(width 0)
				(type default)
			)
			(fill no)
			(layer "F.CrtYd")
		)
		(fp_poly
			(pts
				(xy 1.0922 -2.3114) (xy 1.0922 2.3114) (xy -1.0922 2.3114) (xy -1.0922 -2.3114)
			)
			(stroke
				(width 0)
				(type default)
			)
			(fill no)
			(layer "F.Fab")
		)
		(pad "1" smd rect
			(at 0 -1.397 180)
			(size 1.651 1.27)
			(layers "F.Cu" "F.Mask" "F.Paste")
			(net "P5V_HDD32")
		)
		(pad "2" smd rect
			(at 0 1.397 180)
			(size 1.651 1.27)
			(layers "F.Cu" "F.Mask" "F.Paste")
			(net "GND")
		)
	)
	(footprint ""
		(layer "F.Cu")
		(at 46.392846 -53.482494 -90)
		(property "Reference" "R720"
			(at 0 0 270)
			(layer "F.SilkS")
			(hide yes)
			(effects
				(font
					(size 1.27 1.27)
				)
			)
		)
		(property "Value" "300KR2F-GP"
			(at 0.064008 -3.993896 270)
			(unlocked yes)
			(layer "F.Fab")
			(hide yes)
			(effects
				(font
					(size 1.016 1.016)
					(thickness 0.1524)
				)
			)
		)
		(property "Device Type" "R402H16"
			(at 0.064008 -5.517896 270)
			(unlocked yes)
			(layer "F.Fab")
			(hide yes)
			(effects
				(font
					(size 1.016 1.016)
					(thickness 0.1524)
				)
			)
		)
		(duplicate_pad_numbers_are_jumpers no)
		(fp_line
			(start -0.508 -0.9398)
			(end -0.508 0.9398)
			(stroke
				(width 0.1524)
				(type default)
			)
			(layer "F.SilkS")
		)
		(fp_line
			(start 0.508 -0.9398)
			(end -0.508 -0.9398)
			(stroke
				(width 0.1524)
				(type default)
			)
			(layer "F.SilkS")
		)
		(fp_rect
			(start -0.508 0.9398)
			(end 0.508 -0.9398)
			(stroke
				(width 0)
				(type default)
			)
			(fill no)
			(layer "F.CrtYd")
		)
		(fp_rect
			(start -0.508 0.9398)
			(end 0.508 -0.9398)
			(stroke
				(width 0)
				(type default)
			)
			(fill no)
			(layer "F.Fab")
		)
		(pad "1" smd custom
			(at 0 -0.4445 270)
			(size 0.1397 0.1397)
			(layers "F.Cu" "F.Mask" "F.Paste")
			(net "SW_HDD_N25")
			(options
				(clearance outline)
				(anchor circle)
			)
			(primitives
				(gr_poly
					(pts
						(arc
							(start -0.1778 -0.2794)
							(mid -0.249642 -0.249642)
							(end -0.2794 -0.1778)
						)
						(arc
							(start -0.2794 0.1778)
							(mid -0.249642 0.249642)
							(end -0.1778 0.2794)
						)
						(arc
							(start 0.1778 0.2794)
							(mid 0.249642 0.249642)
							(end 0.2794 0.1778)
						)
						(arc
							(start 0.2794 -0.1778)
							(mid 0.249642 -0.249642)
							(end 0.1778 -0.2794)
						)
					)
					(width 0)
					(fill yes)
				)
			)
		)
		(pad "2" smd custom
			(at 0 0.4445 270)
			(size 0.1397 0.1397)
			(layers "F.Cu" "F.Mask" "F.Paste")
			(net "P12V_A")
			(options
				(clearance outline)
				(anchor circle)
			)
			(primitives
				(gr_poly
					(pts
						(arc
							(start -0.1778 -0.2794)
							(mid -0.249642 -0.249642)
							(end -0.2794 -0.1778)
						)
						(arc
							(start -0.2794 0.1778)
							(mid -0.249642 0.249642)
							(end -0.1778 0.2794)
						)
						(arc
							(start 0.1778 0.2794)
							(mid 0.249642 0.249642)
							(end 0.2794 0.1778)
						)
						(arc
							(start 0.2794 -0.1778)
							(mid 0.249642 -0.249642)
							(end 0.1778 -0.2794)
						)
					)
					(width 0)
					(fill yes)
				)
			)
		)
	)
	(footprint ""
		(layer "F.Cu")
		(at 213.300056 -4.500118)
		(property "Reference" "LED1"
			(at 0 0 0)
			(layer "F.SilkS")
			(hide yes)
			(effects
				(font
					(size 1.27 1.27)
				)
			)
		)
		(property "Value" "AMP-CONN40D-GP"
			(at -13.74775 -0.720598 0)
			(unlocked yes)
			(layer "F.Fab")
			(hide yes)
			(effects
				(font
					(size 1.016 1.016)
					(thickness 0.1524)
				)
			)
		)
		(property "Device Type" "G846A40120T1HR"
			(at -13.74775 -2.244598 0)
			(unlocked yes)
			(layer "F.Fab")
			(hide yes)
			(effects
				(font
					(size 1.016 1.016)
					(thickness 0.1524)
				)
			)
		)
		(duplicate_pad_numbers_are_jumpers no)
		(fp_line
			(start -12.5095 0.254)
			(end -11.557 0.254)
			(stroke
				(width 0.1524)
				(type default)
			)
			(layer "F.SilkS")
		)
		(fp_line
			(start -12.5095 2.8194)
			(end -12.5095 0.254)
			(stroke
				(width 0.1524)
				(type default)
			)
			(layer "F.SilkS")
		)
		(fp_line
			(start -11.557 -2.5527)
			(end -10.0584 -2.5527)
			(stroke
				(width 0.1524)
				(type default)
			)
			(layer "F.SilkS")
		)
		(fp_line
			(start -11.557 0.254)
			(end -11.557 -2.5527)
			(stroke
				(width 0.1524)
				(type default)
			)
			(layer "F.SilkS")
		)
		(fp_line
			(start -10.1473 -4.1402)
			(end -10.1473 -3.0607)
			(stroke
				(width 0.3302)
				(type default)
			)
			(layer "F.SilkS")
		)
		(fp_line
			(start -10.0584 -4.0513)
			(end 10.0584 -4.0513)
			(stroke
				(width 0.1524)
				(type default)
			)
			(layer "F.SilkS")
		)
		(fp_line
			(start -10.0584 -2.5527)
			(end -10.0584 -4.0513)
			(stroke
				(width 0.1524)
				(type default)
			)
			(layer "F.SilkS")
		)
		(fp_line
			(start -10.0584 2.8194)
			(end -12.5095 2.8194)
			(stroke
				(width 0.1524)
				(type default)
			)
			(layer "F.SilkS")
		)
		(fp_line
			(start -10.0584 4.0513)
			(end -10.0584 2.8194)
			(stroke
				(width 0.1524)
				(type default)
			)
			(layer "F.SilkS")
		)
		(fp_line
			(start -9.1059 -4.1402)
			(end -10.1473 -4.1402)
			(stroke
				(width 0.3302)
				(type default)
			)
			(layer "F.SilkS")
		)
		(fp_line
			(start 10.0584 -4.0513)
			(end 10.0584 -2.5527)
			(stroke
				(width 0.1524)
				(type default)
			)
			(layer "F.SilkS")
		)
		(fp_line
			(start 10.0584 -2.5527)
			(end 10.795 -2.5527)
			(stroke
				(width 0.1524)
				(type default)
			)
			(layer "F.SilkS")
		)
		(fp_line
			(start 10.0584 2.8194)
			(end 10.0584 4.0513)
			(stroke
				(width 0.1524)
				(type default)
			)
			(layer "F.SilkS")
		)
		(fp_line
			(start 10.0584 4.0513)
			(end -10.0584 4.0513)
			(stroke
				(width 0.1524)
				(type default)
			)
			(layer "F.SilkS")
		)
		(fp_line
			(start 10.795 -2.5527)
			(end 11.557 -1.7907)
			(stroke
				(width 0.1524)
				(type default)
			)
			(layer "F.SilkS")
		)
		(fp_line
			(start 11.557 -1.7907)
			(end 11.557 0.254)
			(stroke
				(width 0.1524)
				(type default)
			)
			(layer "F.SilkS")
		)
		(fp_line
			(start 11.557 0.254)
			(end 12.5095 0.254)
			(stroke
				(width 0.1524)
				(type default)
			)
			(layer "F.SilkS")
		)
		(fp_line
			(start 12.5095 0.254)
			(end 12.5095 2.8194)
			(stroke
				(width 0.1524)
				(type default)
			)
			(layer "F.SilkS")
		)
		(fp_line
			(start 12.5095 2.8194)
			(end 10.0584 2.8194)
			(stroke
				(width 0.1524)
				(type default)
			)
			(layer "F.SilkS")
		)
		(fp_poly
			(pts
				(xy -9.500108 -4.1402) (xy -8.865108 -4.7752) (xy -10.135108 -4.7752)
			)
			(stroke
				(width 0)
				(type default)
			)
			(fill yes)
			(layer "F.SilkS")
		)
		(fp_poly
			(pts
				(xy -9.804908 2.097532) (xy 9.804908 2.097532) (xy 9.804908 -2.097532) (xy -9.804908 -2.097532)
			)
			(stroke
				(width 0)
				(type default)
			)
			(fill yes)
			(layer "F.SilkS")
		)
		(fp_poly
			(pts
				(xy -9.8044 3.302) (xy -9.8044 2.2987) (xy -11.938 2.2987) (xy -11.938 0.508) (xy -11.303 0.508)
				(xy -11.303 -2.2987) (xy -9.8044 -2.2987) (xy -9.8044 -3.302) (xy 9.8044 -3.302) (xy 9.8044 -2.2987)
				(xy 11.303 -2.2987) (xy 11.303 0.508) (xy 11.938 0.508) (xy 11.938 2.2987) (xy 9.8044 2.2987) (xy 9.8044 3.302)
			)
			(stroke
				(width 0)
				(type default)
			)
			(fill no)
			(layer "F.CrtYd")
		)
		(fp_poly
			(pts
				(xy -10.3124 4.3053) (xy -10.3124 3.0734) (xy -12.7635 3.0734) (xy -12.7635 0) (xy -11.811 0) (xy -11.811 -2.8067)
				(xy -10.3124 -2.8067) (xy -10.3124 -4.3053) (xy 10.3124 -4.3053) (xy 10.3124 -2.8067) (xy 11.811 -2.8067)
				(xy 11.811 -0.00635) (xy 11.303 -0.00635) (xy 11.303 -2.2987) (xy 9.8044 -2.2987) (xy 9.8044 -3.302)
				(xy -9.8044 -3.302) (xy -9.8044 -2.2987) (xy -11.303 -2.2987) (xy -11.303 0.508) (xy -11.938 0.508)
				(xy -11.938 2.2987) (xy -9.8044 2.2987) (xy -9.8044 3.302) (xy 9.8044 3.302) (xy 9.8044 2.2987)
				(xy 11.938 2.2987) (xy 11.938 0.508) (xy 11.303 0.508) (xy 11.303 0.00635) (xy 12.7635 0.00635)
				(xy 12.7635 3.0734) (xy 10.3124 3.0734) (xy 10.3124 4.3053)
			)
			(stroke
				(width 0)
				(type default)
			)
			(fill no)
			(layer "F.CrtYd")
		)
		(fp_poly
			(pts
				(xy -10.3124 4.3053) (xy -10.3124 3.0734) (xy -12.7635 3.0734) (xy -12.7635 0) (xy -11.811 0) (xy -11.811 -2.8067)
				(xy -10.3124 -2.8067) (xy -10.3124 -4.3053) (xy 10.3124 -4.3053) (xy 10.3124 -2.8067) (xy 11.811 -2.8067)
				(xy 11.811 0) (xy 12.7635 0) (xy 12.7635 3.0734) (xy 10.3124 3.0734) (xy 10.3124 4.3053)
			)
			(stroke
				(width 0)
				(type default)
			)
			(fill no)
			(layer "F.Fab")
		)
		(pad "1" smd rect
			(at -9.500108 -3.050032)
			(size 0.6096 1.4986)
			(layers "F.Cu" "F.Mask" "F.Paste")
			(net "DRIVE_A_26_FLT_LED")
		)
		(pad "2" smd rect
			(at -9.500108 3.050032)
			(size 0.6096 1.4986)
			(layers "F.Cu" "F.Mask" "F.Paste")
			(net "DRIVE_A_27_FLT_LED")
		)
		(pad "3" smd rect
			(at -8.50011 -3.050032)
			(size 0.6096 1.4986)
			(layers "F.Cu" "F.Mask" "F.Paste")
			(net "DRIVE_A_26_ACT")
		)
		(pad "4" smd rect
			(at -8.50011 3.050032)
			(size 0.6096 1.4986)
			(layers "F.Cu" "F.Mask" "F.Paste")
			(net "DRIVE_A_27_ACT")
		)
		(pad "5" smd rect
			(at -7.500112 -3.050032)
			(size 0.6096 1.4986)
			(layers "F.Cu" "F.Mask" "F.Paste")
			(net "Net_56")
		)
		(pad "6" smd rect
			(at -7.500112 3.050032)
			(size 0.6096 1.4986)
			(layers "F.Cu" "F.Mask" "F.Paste")
			(net "DRIVE_A_28_FLT_LED")
		)
		(pad "7" smd rect
			(at -6.500114 -3.050032)
			(size 0.6096 1.4986)
			(layers "F.Cu" "F.Mask" "F.Paste")
			(net "P5V_A_2")
		)
		(pad "8" smd rect
			(at -6.500114 3.050032)
			(size 0.6096 1.4986)
			(layers "F.Cu" "F.Mask" "F.Paste")
			(net "DRIVE_A_28_ACT")
		)
		(pad "9" smd rect
			(at -5.500116 -3.050032)
			(size 0.6096 1.4986)
			(layers "F.Cu" "F.Mask" "F.Paste")
			(net "P5V_A_2")
		)
		(pad "10" smd rect
			(at -5.500116 3.050032)
			(size 0.6096 1.4986)
			(layers "F.Cu" "F.Mask" "F.Paste")
			(net "DRIVE_A_29_FLT_LED")
		)
		(pad "11" smd rect
			(at -4.500118 -3.050032)
			(size 0.6096 1.4986)
			(layers "F.Cu" "F.Mask" "F.Paste")
			(net "P5V_A_2")
		)
		(pad "12" smd rect
			(at -4.500118 3.050032)
			(size 0.6096 1.4986)
			(layers "F.Cu" "F.Mask" "F.Paste")
			(net "DRIVE_A_29_ACT")
		)
		(pad "13" smd rect
			(at -3.50012 -3.050032)
			(size 0.6096 1.4986)
			(layers "F.Cu" "F.Mask" "F.Paste")
			(net "Net_54")
		)
		(pad "14" smd rect
			(at -3.50012 3.050032)
			(size 0.6096 1.4986)
			(layers "F.Cu" "F.Mask" "F.Paste")
			(net "DRIVE_A_24_FLT_LED")
		)
		(pad "15" smd rect
			(at -2.500122 -3.050032)
			(size 0.6096 1.4986)
			(layers "F.Cu" "F.Mask" "F.Paste")
			(net "GND")
		)
		(pad "16" smd rect
			(at -2.500122 3.050032)
			(size 0.6096 1.4986)
			(layers "F.Cu" "F.Mask" "F.Paste")
			(net "DRIVE_A_24_ACT")
		)
		(pad "17" smd rect
			(at -1.500124 -3.050032)
			(size 0.6096 1.4986)
			(layers "F.Cu" "F.Mask" "F.Paste")
			(net "GND")
		)
		(pad "18" smd rect
			(at -1.500124 3.050032)
			(size 0.6096 1.4986)
			(layers "F.Cu" "F.Mask" "F.Paste")
			(net "DRIVE_A_25_FLT_LED")
		)
		(pad "19" smd rect
			(at -0.500126 -3.050032)
			(size 0.6096 1.4986)
			(layers "F.Cu" "F.Mask" "F.Paste")
			(net "GND")
		)
		(pad "20" smd rect
			(at -0.500126 3.050032)
			(size 0.6096 1.4986)
			(layers "F.Cu" "F.Mask" "F.Paste")
			(net "DRIVE_A_25_ACT")
		)
		(pad "21" smd rect
			(at 0.500126 -3.050032)
			(size 0.6096 1.4986)
			(layers "F.Cu" "F.Mask" "F.Paste")
			(net "DRIVE_A_32_FLT_LED")
		)
		(pad "22" smd rect
			(at 0.500126 3.050032)
			(size 0.6096 1.4986)
			(layers "F.Cu" "F.Mask" "F.Paste")
			(net "DRIVE_A_33_FLT_LED")
		)
		(pad "23" smd rect
			(at 1.500124 -3.050032)
			(size 0.6096 1.4986)
			(layers "F.Cu" "F.Mask" "F.Paste")
			(net "DRIVE_A_32_ACT")
		)
		(pad "24" smd rect
			(at 1.500124 3.050032)
			(size 0.6096 1.4986)
			(layers "F.Cu" "F.Mask" "F.Paste")
			(net "DRIVE_A_33_ACT")
		)
		(pad "25" smd rect
			(at 2.500122 -3.050032)
			(size 0.6096 1.4986)
			(layers "F.Cu" "F.Mask" "F.Paste")
			(net "Net_55")
		)
		(pad "26" smd rect
			(at 2.500122 3.050032)
			(size 0.6096 1.4986)
			(layers "F.Cu" "F.Mask" "F.Paste")
			(net "DRIVE_A_34_FLT_LED")
		)
		(pad "27" smd rect
			(at 3.50012 -3.050032)
			(size 0.6096 1.4986)
			(layers "F.Cu" "F.Mask" "F.Paste")
			(net "P5V_A_2")
		)
		(pad "28" smd rect
			(at 3.50012 3.050032)
			(size 0.6096 1.4986)
			(layers "F.Cu" "F.Mask" "F.Paste")
			(net "DRIVE_A_34_ACT")
		)
		(pad "29" smd rect
			(at 4.500118 -3.050032)
			(size 0.6096 1.4986)
			(layers "F.Cu" "F.Mask" "F.Paste")
			(net "P5V_A_2")
		)
		(pad "30" smd rect
			(at 4.500118 3.050032)
			(size 0.6096 1.4986)
			(layers "F.Cu" "F.Mask" "F.Paste")
			(net "DRIVE_A_35_FLT_LED")
		)
		(pad "31" smd rect
			(at 5.500116 -3.050032)
			(size 0.6096 1.4986)
			(layers "F.Cu" "F.Mask" "F.Paste")
			(net "P5V_A_2")
		)
		(pad "32" smd rect
			(at 5.500116 3.050032)
			(size 0.6096 1.4986)
			(layers "F.Cu" "F.Mask" "F.Paste")
			(net "DRIVE_A_35_ACT")
		)
		(pad "33" smd rect
			(at 6.500114 -3.050032)
			(size 0.6096 1.4986)
			(layers "F.Cu" "F.Mask" "F.Paste")
			(net "Net_53")
		)
		(pad "34" smd rect
			(at 6.500114 3.050032)
			(size 0.6096 1.4986)
			(layers "F.Cu" "F.Mask" "F.Paste")
			(net "DRIVE_A_30_FLT_LED")
		)
		(pad "35" smd rect
			(at 7.500112 -3.050032)
			(size 0.6096 1.4986)
			(layers "F.Cu" "F.Mask" "F.Paste")
			(net "GND")
		)
		(pad "36" smd rect
			(at 7.500112 3.050032)
			(size 0.6096 1.4986)
			(layers "F.Cu" "F.Mask" "F.Paste")
			(net "DRIVE_A_30_ACT")
		)
		(pad "37" smd rect
			(at 8.50011 -3.050032)
			(size 0.6096 1.4986)
			(layers "F.Cu" "F.Mask" "F.Paste")
			(net "GND")
		)
		(pad "38" smd rect
			(at 8.50011 3.050032)
			(size 0.6096 1.4986)
			(layers "F.Cu" "F.Mask" "F.Paste")
			(net "DRIVE_A_31_FLT_LED")
		)
		(pad "39" smd rect
			(at 9.500108 -3.050032)
			(size 0.6096 1.4986)
			(layers "F.Cu" "F.Mask" "F.Paste")
			(net "GND")
		)
		(pad "40" smd rect
			(at 9.500108 3.050032)
			(size 0.6096 1.4986)
			(layers "F.Cu" "F.Mask" "F.Paste")
			(net "DRIVE_A_31_ACT")
		)
		(pad "41" smd rect
			(at 11.500104 1.549908)
			(size 1.4986 2.0066)
			(layers "F.Cu" "F.Mask" "F.Paste")
			(net "GND")
		)
		(pad "42" smd rect
			(at -11.500104 1.549908)
			(size 1.4986 2.0066)
			(layers "F.Cu" "F.Mask" "F.Paste")
			(net "GND")
		)
		(zone
			(layer "F.Cu")
			(hatch none 0.5)
			(connect_pads
				(clearance 0)
			)
			(min_thickness 0.25)
			(keepout
				(tracks allowed)
				(vias not_allowed)
				(pads allowed)
				(copperpour not_allowed)
				(footprints allowed)
			)
			(placement
				(enabled no)
				(sheetname "")
			)
			(fill
				(thermal_gap 0.5)
				(thermal_bridge_width 0.5)
				(island_removal_mode 0)
			)
			(polygon
				(pts
					(xy 203.495148 -6.29285) (xy 223.104964 -6.29285) (xy 223.104964 -6.80085) (xy 203.495148 -6.80085)
				)
			)
		)
		(zone
			(layer "F.Cu")
			(hatch none 0.5)
			(connect_pads
				(clearance 0)
			)
			(min_thickness 0.25)
			(keepout
				(tracks allowed)
				(vias not_allowed)
				(pads allowed)
				(copperpour not_allowed)
				(footprints allowed)
			)
			(placement
				(enabled no)
				(sheetname "")
			)
			(fill
				(thermal_gap 0.5)
				(thermal_bridge_width 0.5)
				(island_removal_mode 0)
			)
			(polygon
				(pts
					(xy 203.495148 -2.199386) (xy 223.104964 -2.199386) (xy 223.104964 -6.80085) (xy 203.495148 -6.80085)
				)
			)
		)
		(zone
			(layer "F.Cu")
			(hatch none 0.5)
			(connect_pads
				(clearance 0)
			)
			(min_thickness 0.25)
			(keepout
				(tracks not_allowed)
				(vias allowed)
				(pads allowed)
				(copperpour not_allowed)
				(footprints allowed)
			)
			(placement
				(enabled no)
				(sheetname "")
			)
			(fill
				(thermal_gap 0.5)
				(thermal_bridge_width 0.5)
				(island_removal_mode 0)
			)
			(polygon
				(pts
					(xy 203.495148 -2.199386) (xy 223.104964 -2.199386) (xy 223.104964 -6.80085) (xy 203.495148 -6.80085)
				)
			)
		)
		(zone
			(layer "F.Cu")
			(hatch none 0.5)
			(connect_pads
				(clearance 0)
			)
			(min_thickness 0.25)
			(keepout
				(tracks allowed)
				(vias not_allowed)
				(pads allowed)
				(copperpour not_allowed)
				(footprints allowed)
			)
			(placement
				(enabled no)
				(sheetname "")
			)
			(fill
				(thermal_gap 0.5)
				(thermal_bridge_width 0.5)
				(island_removal_mode 0)
			)
			(polygon
				(pts
					(xy 203.495148 -2.199386) (xy 223.104964 -2.199386) (xy 223.104964 -2.707386) (xy 203.495148 -2.707386)
				)
			)
		)
	)
	(footprint ""
		(layer "F.Cu")
		(at 87.036148 -301.287942)
		(property "Reference" "C72"
			(at 0 0 0)
			(layer "F.SilkS")
			(hide yes)
			(effects
				(font
					(size 1.27 1.27)
				)
			)
		)
		(property "Value" "SC4D7U25V5KX-1-GP"
			(at -0.0762 -6.1214 0)
			(unlocked yes)
			(layer "F.Fab")
			(hide yes)
			(effects
				(font
					(size 1.016 1.016)
					(thickness 0.1524)
				)
			)
		)
		(property "Device Type" "C805H58"
			(at -0.0762 -8.1534 0)
			(unlocked yes)
			(layer "F.Fab")
			(hide yes)
			(effects
				(font
					(size 1.016 1.016)
					(thickness 0.1524)
				)
			)
		)
		(duplicate_pad_numbers_are_jumpers no)
		(fp_line
			(start 0.635 0)
			(end -0.635 0)
			(stroke
				(width 0.508)
				(type default)
			)
			(layer "F.SilkS")
		)
		(fp_rect
			(start -0.9652 1.778)
			(end 0.9652 -1.778)
			(stroke
				(width 0)
				(type default)
			)
			(fill no)
			(layer "F.CrtYd")
		)
		(fp_poly
			(pts
				(xy -0.9652 -1.778) (xy 0.9652 -1.778) (xy 0.9652 1.778) (xy -0.9652 1.778)
			)
			(stroke
				(width 0)
				(type default)
			)
			(fill no)
			(layer "F.Fab")
		)
		(pad "1" smd rect
			(at 0 -0.9652)
			(size 1.397 1.143)
			(layers "F.Cu" "F.Mask" "F.Paste")
			(net "P12V_HDD2")
		)
		(pad "2" smd rect
			(at 0 0.9652)
			(size 1.397 1.143)
			(layers "F.Cu" "F.Mask" "F.Paste")
			(net "GND")
		)
	)
	(footprint ""
		(layer "F.Cu")
		(at 365.052102 -188.954918 180)
		(property "Reference" "C292"
			(at 0 0 180)
			(layer "F.SilkS")
			(hide yes)
			(effects
				(font
					(size 1.27 1.27)
				)
			)
		)
		(property "Value" "SC4D7U25V5KX-1-GP"
			(at -0.0762 -6.1214 180)
			(unlocked yes)
			(layer "F.Fab")
			(hide yes)
			(effects
				(font
					(size 1.016 1.016)
					(thickness 0.1524)
				)
			)
		)
		(property "Device Type" "C805H58"
			(at -0.0762 -8.1534 180)
			(unlocked yes)
			(layer "F.Fab")
			(hide yes)
			(effects
				(font
					(size 1.016 1.016)
					(thickness 0.1524)
				)
			)
		)
		(duplicate_pad_numbers_are_jumpers no)
		(fp_line
			(start 0.635 0)
			(end -0.635 0)
			(stroke
				(width 0.508)
				(type default)
			)
			(layer "F.SilkS")
		)
		(fp_rect
			(start -0.9652 1.778)
			(end 0.9652 -1.778)
			(stroke
				(width 0)
				(type default)
			)
			(fill no)
			(layer "F.CrtYd")
		)
		(fp_poly
			(pts
				(xy -0.9652 -1.778) (xy 0.9652 -1.778) (xy 0.9652 1.778) (xy -0.9652 1.778)
			)
			(stroke
				(width 0)
				(type default)
			)
			(fill no)
			(layer "F.Fab")
		)
		(pad "1" smd rect
			(at 0 -0.9652 180)
			(size 1.397 1.143)
			(layers "F.Cu" "F.Mask" "F.Paste")
			(net "P12V_HDD19")
		)
		(pad "2" smd rect
			(at 0 0.9652 180)
			(size 1.397 1.143)
			(layers "F.Cu" "F.Mask" "F.Paste")
			(net "GND")
		)
	)
	(footprint ""
		(layer "F.Cu")
		(at 172.593 -53.482494 -90)
		(property "Reference" "R812"
			(at 0 0 270)
			(layer "F.SilkS")
			(hide yes)
			(effects
				(font
					(size 1.27 1.27)
				)
			)
		)
		(property "Value" "300KR2F-GP"
			(at 0.064008 -3.993896 270)
			(unlocked yes)
			(layer "F.Fab")
			(hide yes)
			(effects
				(font
					(size 1.016 1.016)
					(thickness 0.1524)
				)
			)
		)
		(property "Device Type" "R402H16"
			(at 0.064008 -5.517896 270)
			(unlocked yes)
			(layer "F.Fab")
			(hide yes)
			(effects
				(font
					(size 1.016 1.016)
					(thickness 0.1524)
				)
			)
		)
		(duplicate_pad_numbers_are_jumpers no)
		(fp_line
			(start -0.508 -0.9398)
			(end -0.508 0.9398)
			(stroke
				(width 0.1524)
				(type default)
			)
			(layer "F.SilkS")
		)
		(fp_line
			(start 0.508 -0.9398)
			(end -0.508 -0.9398)
			(stroke
				(width 0.1524)
				(type default)
			)
			(layer "F.SilkS")
		)
		(fp_rect
			(start -0.508 0.9398)
			(end 0.508 -0.9398)
			(stroke
				(width 0)
				(type default)
			)
			(fill no)
			(layer "F.CrtYd")
		)
		(fp_rect
			(start -0.508 0.9398)
			(end 0.508 -0.9398)
			(stroke
				(width 0)
				(type default)
			)
			(fill no)
			(layer "F.Fab")
		)
		(pad "1" smd custom
			(at 0 -0.4445 270)
			(size 0.1397 0.1397)
			(layers "F.Cu" "F.Mask" "F.Paste")
			(net "SW_HDD_N29")
			(options
				(clearance outline)
				(anchor circle)
			)
			(primitives
				(gr_poly
					(pts
						(arc
							(start -0.1778 -0.2794)
							(mid -0.249642 -0.249642)
							(end -0.2794 -0.1778)
						)
						(arc
							(start -0.2794 0.1778)
							(mid -0.249642 0.249642)
							(end -0.1778 0.2794)
						)
						(arc
							(start 0.1778 0.2794)
							(mid 0.249642 0.249642)
							(end 0.2794 0.1778)
						)
						(arc
							(start 0.2794 -0.1778)
							(mid 0.249642 -0.249642)
							(end 0.1778 -0.2794)
						)
					)
					(width 0)
					(fill yes)
				)
			)
		)
		(pad "2" smd custom
			(at 0 0.4445 270)
			(size 0.1397 0.1397)
			(layers "F.Cu" "F.Mask" "F.Paste")
			(net "P12V_A")
			(options
				(clearance outline)
				(anchor circle)
			)
			(primitives
				(gr_poly
					(pts
						(arc
							(start -0.1778 -0.2794)
							(mid -0.249642 -0.249642)
							(end -0.2794 -0.1778)
						)
						(arc
							(start -0.2794 0.1778)
							(mid -0.249642 0.249642)
							(end -0.1778 0.2794)
						)
						(arc
							(start 0.1778 0.2794)
							(mid 0.249642 0.249642)
							(end 0.2794 0.1778)
						)
						(arc
							(start 0.2794 -0.1778)
							(mid 0.249642 -0.249642)
							(end 0.1778 -0.2794)
						)
					)
					(width 0)
					(fill yes)
				)
			)
		)
	)
	(footprint ""
		(layer "F.Cu")
		(at 159.324802 -322.799964)
		(property "Reference" ""
			(at 0 0 0)
			(layer "F.SilkS")
			(hide yes)
			(effects
				(font
					(size 1.27 1.27)
				)
			)
		)
		(property "Value" "*"
			(at -8.398764 -8.057642 0)
			(unlocked yes)
			(layer "F.Fab")
			(hide yes)
			(effects
				(font
					(size 1.016 1.016)
					(thickness 0.1524)
				)
			)
		)
		(duplicate_pad_numbers_are_jumpers no)
		(fp_poly
			(pts
				(arc
					(start 7.3152 0)
					(mid 0 7.3152)
					(end -7.3152 0)
				)
				(arc
					(start -7.3152 -5.9944)
					(mid 0 -13.3096)
					(end 7.3152 -5.9944)
				)
			)
			(stroke
				(width 0)
				(type default)
			)
			(fill no)
			(layer "B.CrtYd")
		)
		(fp_poly
			(pts
				(arc
					(start 7.3152 0)
					(mid 0 7.3152)
					(end -7.3152 0)
				)
				(arc
					(start -7.3152 -5.9944)
					(mid 0 -13.3096)
					(end 7.3152 -5.9944)
				)
			)
			(stroke
				(width 0)
				(type default)
			)
			(fill no)
			(layer "F.CrtYd")
		)
		(fp_poly
			(pts
				(arc
					(start 7.3152 0)
					(mid 0 7.3152)
					(end -7.3152 0)
				)
				(arc
					(start -7.3152 -5.9944)
					(mid 0 -13.3096)
					(end 7.3152 -5.9944)
				)
			)
			(stroke
				(width 0)
				(type default)
			)
			(fill no)
			(layer "B.Fab")
		)
		(fp_poly
			(pts
				(arc
					(start 7.3152 0)
					(mid 0 7.3152)
					(end -7.3152 0)
				)
				(arc
					(start -7.3152 -5.9944)
					(mid 0 -13.3096)
					(end 7.3152 -5.9944)
				)
			)
			(stroke
				(width 0)
				(type default)
			)
			(fill no)
			(layer "F.Fab")
		)
		(pad "1" thru_hole oval
			(at 0 0)
			(size 14.0208 20.0152)
			(drill 0.0254
				(offset 0 -2.9972)
			)
			(layers "*.Cu" "*.Mask")
			(remove_unused_layers no)
			(net "Net_107")
			(clearance -1.002284)
			(thermal_gap 0.1524)
			(padstack
				(mode front_inner_back)
				(layer "Inner"
					(shape custom)
					(size 2.928012 2.928012)
					(options
						(anchor circle)
					)
					(primitives
						(gr_poly
							(pts
								(arc
									(start 4.571746 -2.084324)
									(mid 0.000333 7.430372)
									(end -4.571492 -2.084324)
								)
								(arc
									(start -4.571492 -2.084324)
									(mid -3.570296 -3.611977)
									(end -2.875026 -5.30098)
								)
								(arc
									(start -2.875026 -5.30098)
									(mid 0.000217 -7.43089)
									(end 2.87528 -5.30098)
								)
								(arc
									(start 2.87528 -5.30098)
									(mid 3.570511 -3.611956)
									(end 4.571746 -2.084324)
								)
							)
							(width 0)
							(fill yes)
						)
					)
					(clearance 0.1524)
				)
				(layer "B.Cu"
					(shape oval)
					(size 14.0208 20.0152)
					(offset 0 -2.9972)
					(clearance -1.002284)
				)
			)
		)
		(zone
			(layers "F.Cu" "B.Cu" "In1.Cu" "In2.Cu" "In3.Cu" "In4.Cu" "In5.Cu" "In6.Cu"
				"In7.Cu" "In8.Cu" "In9.Cu" "In10.Cu"
			)
			(hatch none 0.5)
			(connect_pads
				(clearance 0)
			)
			(min_thickness 0.25)
			(keepout
				(tracks not_allowed)
				(vias allowed)
				(pads allowed)
				(copperpour not_allowed)
				(footprints allowed)
			)
			(placement
				(enabled no)
				(sheetname "")
			)
			(fill
				(thermal_gap 0.5)
				(thermal_bridge_width 0.5)
				(island_removal_mode 0)
			)
			(polygon
				(pts
					(arc
						(start 152.314402 -328.794364)
						(mid 159.324802 -335.804764)
						(end 166.335202 -328.794364)
					)
					(arc
						(start 166.335202 -322.799964)
						(mid 159.324802 -315.789564)
						(end 152.314402 -322.799964)
					)
				)
			)
		)
	)
	(footprint ""
		(layer "F.Cu")
		(at 149.196298 -46.065694 -90)
		(property "Reference" "R782"
			(at 0 0 270)
			(layer "F.SilkS")
			(hide yes)
			(effects
				(font
					(size 1.27 1.27)
				)
			)
		)
		(property "Value" "1KR2F-3-GP"
			(at 0.064008 -3.993896 270)
			(unlocked yes)
			(layer "F.Fab")
			(hide yes)
			(effects
				(font
					(size 1.016 1.016)
					(thickness 0.1524)
				)
			)
		)
		(property "Device Type" "R402H16"
			(at 0.064008 -5.517896 270)
			(unlocked yes)
			(layer "F.Fab")
			(hide yes)
			(effects
				(font
					(size 1.016 1.016)
					(thickness 0.1524)
				)
			)
		)
		(duplicate_pad_numbers_are_jumpers no)
		(fp_line
			(start -0.508 -0.9398)
			(end -0.508 0.9398)
			(stroke
				(width 0.1524)
				(type default)
			)
			(layer "F.SilkS")
		)
		(fp_line
			(start 0.508 -0.9398)
			(end -0.508 -0.9398)
			(stroke
				(width 0.1524)
				(type default)
			)
			(layer "F.SilkS")
		)
		(fp_rect
			(start -0.508 0.9398)
			(end 0.508 -0.9398)
			(stroke
				(width 0)
				(type default)
			)
			(fill no)
			(layer "F.CrtYd")
		)
		(fp_rect
			(start -0.508 0.9398)
			(end 0.508 -0.9398)
			(stroke
				(width 0)
				(type default)
			)
			(fill no)
			(layer "F.Fab")
		)
		(pad "1" smd custom
			(at 0 -0.4445 270)
			(size 0.1397 0.1397)
			(layers "F.Cu" "F.Mask" "F.Paste")
			(net "P3V3_STBY_A")
			(options
				(clearance outline)
				(anchor circle)
			)
			(primitives
				(gr_poly
					(pts
						(arc
							(start -0.1778 -0.2794)
							(mid -0.249642 -0.249642)
							(end -0.2794 -0.1778)
						)
						(arc
							(start -0.2794 0.1778)
							(mid -0.249642 0.249642)
							(end -0.1778 0.2794)
						)
						(arc
							(start 0.1778 0.2794)
							(mid 0.249642 0.249642)
							(end 0.2794 0.1778)
						)
						(arc
							(start 0.2794 -0.1778)
							(mid 0.249642 -0.249642)
							(end 0.1778 -0.2794)
						)
					)
					(width 0)
					(fill yes)
				)
			)
		)
		(pad "2" smd custom
			(at 0 0.4445 270)
			(size 0.1397 0.1397)
			(layers "F.Cu" "F.Mask" "F.Paste")
			(net "SW_PWR_R_HDD28")
			(options
				(clearance outline)
				(anchor circle)
			)
			(primitives
				(gr_poly
					(pts
						(arc
							(start -0.1778 -0.2794)
							(mid -0.249642 -0.249642)
							(end -0.2794 -0.1778)
						)
						(arc
							(start -0.2794 0.1778)
							(mid -0.249642 0.249642)
							(end -0.1778 0.2794)
						)
						(arc
							(start 0.1778 0.2794)
							(mid 0.249642 0.249642)
							(end 0.2794 0.1778)
						)
						(arc
							(start 0.2794 -0.1778)
							(mid 0.249642 -0.249642)
							(end 0.1778 -0.2794)
						)
					)
					(width 0)
					(fill yes)
				)
			)
		)
	)
	(footprint ""
		(layer "F.Cu")
		(at 478.620328 -267.773658 90)
		(property "Reference" "R387"
			(at 0 0 90)
			(layer "F.SilkS")
			(hide yes)
			(effects
				(font
					(size 1.27 1.27)
				)
			)
		)
		(property "Value" "220R3F-1-GP"
			(at -0.0254 -2.5146 90)
			(unlocked yes)
			(layer "F.Fab")
			(hide yes)
			(effects
				(font
					(size 1.016 1.016)
					(thickness 0.1524)
				)
			)
		)
		(property "Device Type" "R603H22"
			(at -0.0254 -4.0386 90)
			(unlocked yes)
			(layer "F.Fab")
			(hide yes)
			(effects
				(font
					(size 1.016 1.016)
					(thickness 0.1524)
				)
			)
		)
		(duplicate_pad_numbers_are_jumpers no)
		(fp_line
			(start 0.2032 0)
			(end 0.4826 0)
			(stroke
				(width 0.2032)
				(type default)
			)
			(layer "F.SilkS")
		)
		(fp_line
			(start -0.4826 0)
			(end -0.2032 0)
			(stroke
				(width 0.2032)
				(type default)
			)
			(layer "F.SilkS")
		)
		(fp_rect
			(start -0.5842 1.3335)
			(end 0.5842 -1.3335)
			(stroke
				(width 0)
				(type default)
			)
			(fill no)
			(layer "F.CrtYd")
		)
		(fp_rect
			(start -0.5842 1.3335)
			(end 0.5842 -1.3335)
			(stroke
				(width 0)
				(type default)
			)
			(fill no)
			(layer "F.Fab")
		)
		(pad "1" smd custom
			(at 0 -0.762 90)
			(size 0.2159 0.2159)
			(layers "F.Cu" "F.Mask" "F.Paste")
			(net "HDD_PRSNT_11")
			(options
				(clearance outline)
				(anchor circle)
			)
			(primitives
				(gr_poly
					(pts
						(arc
							(start -0.3302 -0.4318)
							(mid -0.402042 -0.402042)
							(end -0.4318 -0.3302)
						)
						(arc
							(start -0.4318 0.3302)
							(mid -0.402042 0.402042)
							(end -0.3302 0.4318)
						)
						(arc
							(start 0.3302 0.4318)
							(mid 0.402042 0.402042)
							(end 0.4318 0.3302)
						)
						(arc
							(start 0.4318 -0.3302)
							(mid 0.402042 -0.402042)
							(end 0.3302 -0.4318)
						)
					)
					(width 0)
					(fill yes)
				)
			)
		)
		(pad "2" smd custom
			(at 0 0.762 90)
			(size 0.2159 0.2159)
			(layers "F.Cu" "F.Mask" "F.Paste")
			(net "DRIVE_A_11_INS")
			(options
				(clearance outline)
				(anchor circle)
			)
			(primitives
				(gr_poly
					(pts
						(arc
							(start -0.3302 -0.4318)
							(mid -0.402042 -0.402042)
							(end -0.4318 -0.3302)
						)
						(arc
							(start -0.4318 0.3302)
							(mid -0.402042 0.402042)
							(end -0.3302 0.4318)
						)
						(arc
							(start 0.3302 0.4318)
							(mid 0.402042 0.402042)
							(end 0.4318 0.3302)
						)
						(arc
							(start 0.4318 -0.3302)
							(mid 0.402042 -0.402042)
							(end 0.3302 -0.4318)
						)
					)
					(width 0)
					(fill yes)
				)
			)
		)
	)
	(footprint ""
		(layer "F.Cu")
		(at 393.674854 -207.79994)
		(property "Reference" ""
			(at 0 0 0)
			(layer "F.SilkS")
			(hide yes)
			(effects
				(font
					(size 1.27 1.27)
				)
			)
		)
		(property "Value" "*"
			(at -8.398764 -8.057642 0)
			(unlocked yes)
			(layer "F.Fab")
			(hide yes)
			(effects
				(font
					(size 1.016 1.016)
					(thickness 0.1524)
				)
			)
		)
		(duplicate_pad_numbers_are_jumpers no)
		(fp_poly
			(pts
				(arc
					(start 7.3152 0)
					(mid 0 7.3152)
					(end -7.3152 0)
				)
				(arc
					(start -7.3152 -5.9944)
					(mid 0 -13.3096)
					(end 7.3152 -5.9944)
				)
			)
			(stroke
				(width 0)
				(type default)
			)
			(fill no)
			(layer "B.CrtYd")
		)
		(fp_poly
			(pts
				(arc
					(start 7.3152 0)
					(mid 0 7.3152)
					(end -7.3152 0)
				)
				(arc
					(start -7.3152 -5.9944)
					(mid 0 -13.3096)
					(end 7.3152 -5.9944)
				)
			)
			(stroke
				(width 0)
				(type default)
			)
			(fill no)
			(layer "F.CrtYd")
		)
		(fp_poly
			(pts
				(arc
					(start 7.3152 0)
					(mid 0 7.3152)
					(end -7.3152 0)
				)
				(arc
					(start -7.3152 -5.9944)
					(mid 0 -13.3096)
					(end 7.3152 -5.9944)
				)
			)
			(stroke
				(width 0)
				(type default)
			)
			(fill no)
			(layer "B.Fab")
		)
		(fp_poly
			(pts
				(arc
					(start 7.3152 0)
					(mid 0 7.3152)
					(end -7.3152 0)
				)
				(arc
					(start -7.3152 -5.9944)
					(mid 0 -13.3096)
					(end 7.3152 -5.9944)
				)
			)
			(stroke
				(width 0)
				(type default)
			)
			(fill no)
			(layer "F.Fab")
		)
		(pad "1" thru_hole oval
			(at 0 0)
			(size 14.0208 20.0152)
			(drill 0.0254
				(offset 0 -2.9972)
			)
			(layers "*.Cu" "*.Mask")
			(remove_unused_layers no)
			(net "Net_99")
			(clearance -1.002284)
			(thermal_gap 0.1524)
			(padstack
				(mode front_inner_back)
				(layer "Inner"
					(shape custom)
					(size 2.928012 2.928012)
					(options
						(anchor circle)
					)
					(primitives
						(gr_poly
							(pts
								(arc
									(start 4.571746 -2.084324)
									(mid 0.000333 7.430372)
									(end -4.571492 -2.084324)
								)
								(arc
									(start -4.571492 -2.084324)
									(mid -3.570296 -3.611977)
									(end -2.875026 -5.30098)
								)
								(arc
									(start -2.875026 -5.30098)
									(mid 0.000217 -7.43089)
									(end 2.87528 -5.30098)
								)
								(arc
									(start 2.87528 -5.30098)
									(mid 3.570511 -3.611956)
									(end 4.571746 -2.084324)
								)
							)
							(width 0)
							(fill yes)
						)
					)
					(clearance 0.1524)
				)
				(layer "B.Cu"
					(shape oval)
					(size 14.0208 20.0152)
					(offset 0 -2.9972)
					(clearance -1.002284)
				)
			)
		)
		(zone
			(layers "F.Cu" "B.Cu" "In1.Cu" "In2.Cu" "In3.Cu" "In4.Cu" "In5.Cu" "In6.Cu"
				"In7.Cu" "In8.Cu" "In9.Cu" "In10.Cu"
			)
			(hatch none 0.5)
			(connect_pads
				(clearance 0)
			)
			(min_thickness 0.25)
			(keepout
				(tracks not_allowed)
				(vias allowed)
				(pads allowed)
				(copperpour not_allowed)
				(footprints allowed)
			)
			(placement
				(enabled no)
				(sheetname "")
			)
			(fill
				(thermal_gap 0.5)
				(thermal_bridge_width 0.5)
				(island_removal_mode 0)
			)
			(polygon
				(pts
					(arc
						(start 386.664454 -213.79434)
						(mid 393.674854 -220.80474)
						(end 400.685254 -213.79434)
					)
					(arc
						(start 400.685254 -207.79994)
						(mid 393.674854 -200.78954)
						(end 386.664454 -207.79994)
					)
				)
			)
		)
	)
	(footprint ""
		(layer "F.Cu")
		(at 474.30182 -274.193 90)
		(property "Reference" "Q67"
			(at 0 0 90)
			(layer "F.SilkS")
			(hide yes)
			(effects
				(font
					(size 1.27 1.27)
				)
			)
		)
		(property "Value" "2N7002KDW-GP"
			(at -2.3622 -8.2042 90)
			(unlocked yes)
			(layer "F.Fab")
			(hide yes)
			(effects
				(font
					(size 1.016 1.016)
					(thickness 0.1524)
				)
			)
		)
		(property "Device Type" "SOT-363H44"
			(at -2.3622 -10.1092 90)
			(unlocked yes)
			(layer "F.Fab")
			(hide yes)
			(effects
				(font
					(size 1.016 1.016)
					(thickness 0.1524)
				)
			)
		)
		(duplicate_pad_numbers_are_jumpers no)
		(fp_line
			(start 1.4478 -1.7018)
			(end -1.4478 -1.7018)
			(stroke
				(width 0.1524)
				(type default)
			)
			(layer "F.SilkS")
		)
		(fp_line
			(start -1.4478 -1.7018)
			(end -1.4478 1.7018)
			(stroke
				(width 0.1524)
				(type default)
			)
			(layer "F.SilkS")
		)
		(fp_line
			(start -1.27 1.524)
			(end -1.27 0.6604)
			(stroke
				(width 0.4826)
				(type default)
			)
			(layer "F.SilkS")
		)
		(fp_line
			(start 1.4478 1.7018)
			(end 1.4478 -1.7018)
			(stroke
				(width 0.1524)
				(type default)
			)
			(layer "F.SilkS")
		)
		(fp_line
			(start -1.4478 1.7018)
			(end 1.4478 1.7018)
			(stroke
				(width 0.1524)
				(type default)
			)
			(layer "F.SilkS")
		)
		(fp_poly
			(pts
				(xy -1.524 -1.778) (xy 1.524 -1.778) (xy 1.524 1.778) (xy -1.524 1.778)
			)
			(stroke
				(width 0)
				(type default)
			)
			(fill no)
			(layer "F.CrtYd")
		)
		(fp_poly
			(pts
				(xy -1.524 -1.778) (xy 1.524 -1.778) (xy 1.524 1.778) (xy -1.524 1.778)
			)
			(stroke
				(width 0)
				(type default)
			)
			(fill no)
			(layer "F.Fab")
		)
		(pad "1" smd rect
			(at -0.65024 0.9398 90)
			(size 0.4064 1.016)
			(layers "F.Cu" "F.Mask" "F.Paste")
			(net "GND")
		)
		(pad "2" smd rect
			(at 0 0.9398 90)
			(size 0.4064 1.016)
			(layers "F.Cu" "F.Mask" "F.Paste")
			(net "SW_PWR_R_HDD11")
		)
		(pad "3" smd rect
			(at 0.65024 0.9398 90)
			(size 0.4064 1.016)
			(layers "F.Cu" "F.Mask" "F.Paste")
			(net "SW_HDD_P11")
		)
		(pad "4" smd rect
			(at 0.65024 -0.9398 90)
			(size 0.4064 1.016)
			(layers "F.Cu" "F.Mask" "F.Paste")
			(net "GND")
		)
		(pad "5" smd rect
			(at 0 -0.9398 90)
			(size 0.4064 1.016)
			(layers "F.Cu" "F.Mask" "F.Paste")
			(net "SW_HDD_G11")
		)
		(pad "6" smd rect
			(at -0.65024 -0.9398 90)
			(size 0.4064 1.016)
			(layers "F.Cu" "F.Mask" "F.Paste")
			(net "SW_HDD_R11")
		)
	)
	(footprint ""
		(layer "F.Cu")
		(at 216.027 -381.762 180)
		(property "Reference" "R366"
			(at 0 0 180)
			(layer "F.SilkS")
			(hide yes)
			(effects
				(font
					(size 1.27 1.27)
				)
			)
		)
		(property "Value" "0R2J-2-GP"
			(at 0.064008 -3.993896 180)
			(unlocked yes)
			(layer "F.Fab")
			(hide yes)
			(effects
				(font
					(size 1.016 1.016)
					(thickness 0.1524)
				)
			)
		)
		(property "Device Type" "R402H16"
			(at 0.064008 -5.517896 180)
			(unlocked yes)
			(layer "F.Fab")
			(hide yes)
			(effects
				(font
					(size 1.016 1.016)
					(thickness 0.1524)
				)
			)
		)
		(duplicate_pad_numbers_are_jumpers no)
		(fp_line
			(start 0.508 -0.9398)
			(end -0.508 -0.9398)
			(stroke
				(width 0.1524)
				(type default)
			)
			(layer "F.SilkS")
		)
		(fp_line
			(start -0.508 -0.9398)
			(end -0.508 0.9398)
			(stroke
				(width 0.1524)
				(type default)
			)
			(layer "F.SilkS")
		)
		(fp_rect
			(start -0.508 0.9398)
			(end 0.508 -0.9398)
			(stroke
				(width 0)
				(type default)
			)
			(fill no)
			(layer "F.CrtYd")
		)
		(fp_rect
			(start -0.508 0.9398)
			(end 0.508 -0.9398)
			(stroke
				(width 0)
				(type default)
			)
			(fill no)
			(layer "F.Fab")
		)
		(pad "1" smd custom
			(at 0 -0.4445 180)
			(size 0.1397 0.1397)
			(layers "F.Cu" "F.Mask" "F.Paste")
			(net "SCC_FULL_PWR_EN_5V")
			(options
				(clearance outline)
				(anchor circle)
			)
			(primitives
				(gr_poly
					(pts
						(arc
							(start -0.1778 -0.2794)
							(mid -0.249642 -0.249642)
							(end -0.2794 -0.1778)
						)
						(arc
							(start -0.2794 0.1778)
							(mid -0.249642 0.249642)
							(end -0.1778 0.2794)
						)
						(arc
							(start 0.1778 0.2794)
							(mid 0.249642 0.249642)
							(end 0.2794 0.1778)
						)
						(arc
							(start 0.2794 -0.1778)
							(mid 0.249642 -0.249642)
							(end 0.1778 -0.2794)
						)
					)
					(width 0)
					(fill yes)
				)
			)
		)
		(pad "2" smd custom
			(at 0 0.4445 180)
			(size 0.1397 0.1397)
			(layers "F.Cu" "F.Mask" "F.Paste")
			(net "SCC_FULL_PWR_EN_5V_R")
			(options
				(clearance outline)
				(anchor circle)
			)
			(primitives
				(gr_poly
					(pts
						(arc
							(start -0.1778 -0.2794)
							(mid -0.249642 -0.249642)
							(end -0.2794 -0.1778)
						)
						(arc
							(start -0.2794 0.1778)
							(mid -0.249642 0.249642)
							(end -0.1778 0.2794)
						)
						(arc
							(start 0.1778 0.2794)
							(mid 0.249642 0.249642)
							(end 0.2794 0.1778)
						)
						(arc
							(start 0.2794 -0.1778)
							(mid 0.249642 -0.249642)
							(end 0.1778 -0.2794)
						)
					)
					(width 0)
					(fill yes)
				)
			)
		)
	)
	(footprint ""
		(layer "F.Cu")
		(at 240.23066 -241.849148 180)
		(property "Reference" "R128"
			(at 0 0 180)
			(layer "F.SilkS")
			(hide yes)
			(effects
				(font
					(size 1.27 1.27)
				)
			)
		)
		(property "Value" "100KR2F-L1-GP"
			(at 0.064008 -3.993896 180)
			(unlocked yes)
			(layer "F.Fab")
			(hide yes)
			(effects
				(font
					(size 1.016 1.016)
					(thickness 0.1524)
				)
			)
		)
		(property "Device Type" "R402H16"
			(at 0.064008 -5.517896 180)
			(unlocked yes)
			(layer "F.Fab")
			(hide yes)
			(effects
				(font
					(size 1.016 1.016)
					(thickness 0.1524)
				)
			)
		)
		(duplicate_pad_numbers_are_jumpers no)
		(fp_line
			(start 0.508 -0.9398)
			(end -0.508 -0.9398)
			(stroke
				(width 0.1524)
				(type default)
			)
			(layer "F.SilkS")
		)
		(fp_line
			(start -0.508 -0.9398)
			(end -0.508 0.9398)
			(stroke
				(width 0.1524)
				(type default)
			)
			(layer "F.SilkS")
		)
		(fp_rect
			(start -0.508 0.9398)
			(end 0.508 -0.9398)
			(stroke
				(width 0)
				(type default)
			)
			(fill no)
			(layer "F.CrtYd")
		)
		(fp_rect
			(start -0.508 0.9398)
			(end 0.508 -0.9398)
			(stroke
				(width 0)
				(type default)
			)
			(fill no)
			(layer "F.Fab")
		)
		(pad "1" smd custom
			(at 0 -0.4445 180)
			(size 0.1397 0.1397)
			(layers "F.Cu" "F.Mask" "F.Paste")
			(net "GPIO_VCC_U8")
			(options
				(clearance outline)
				(anchor circle)
			)
			(primitives
				(gr_poly
					(pts
						(arc
							(start -0.1778 -0.2794)
							(mid -0.249642 -0.249642)
							(end -0.2794 -0.1778)
						)
						(arc
							(start -0.2794 0.1778)
							(mid -0.249642 0.249642)
							(end -0.1778 0.2794)
						)
						(arc
							(start 0.1778 0.2794)
							(mid 0.249642 0.249642)
							(end 0.2794 0.1778)
						)
						(arc
							(start 0.2794 -0.1778)
							(mid 0.249642 -0.249642)
							(end 0.1778 -0.2794)
						)
					)
					(width 0)
					(fill yes)
				)
			)
		)
		(pad "2" smd custom
			(at 0 0.4445 180)
			(size 0.1397 0.1397)
			(layers "F.Cu" "F.Mask" "F.Paste")
			(net "GND")
			(options
				(clearance outline)
				(anchor circle)
			)
			(primitives
				(gr_poly
					(pts
						(arc
							(start -0.1778 -0.2794)
							(mid -0.249642 -0.249642)
							(end -0.2794 -0.1778)
						)
						(arc
							(start -0.2794 0.1778)
							(mid -0.249642 0.249642)
							(end -0.1778 0.2794)
						)
						(arc
							(start 0.1778 0.2794)
							(mid 0.249642 0.249642)
							(end 0.2794 0.1778)
						)
						(arc
							(start 0.2794 -0.1778)
							(mid 0.249642 -0.249642)
							(end 0.1778 -0.2794)
						)
					)
					(width 0)
					(fill yes)
				)
			)
		)
	)
	(footprint ""
		(layer "F.Cu")
		(at 383.08915 -158.939992 90)
		(property "Reference" "VIA9"
			(at 0 0 90)
			(layer "F.SilkS")
			(hide yes)
			(effects
				(font
					(size 1.27 1.27)
				)
			)
		)
		(property "Value" "100OHM-8L-1D6MM-L18L16-GP"
			(at -3.7211 -4.5085 90)
			(unlocked yes)
			(layer "F.Fab")
			(hide yes)
			(effects
				(font
					(size 1.016 1.016)
					(thickness 0.1524)
				)
			)
		)
		(property "Device Type" "VIA-PCIE-4P-394076"
			(at -3.7211 -6.0325 90)
			(unlocked yes)
			(layer "F.Fab")
			(hide yes)
			(effects
				(font
					(size 1.016 1.016)
					(thickness 0.1524)
				)
			)
		)
		(duplicate_pad_numbers_are_jumpers no)
		(fp_rect
			(start -1.9685 0.381)
			(end 1.9685 -0.381)
			(stroke
				(width 0)
				(type default)
			)
			(fill no)
			(layer "F.CrtYd")
		)
		(fp_rect
			(start -1.9685 0.381)
			(end 1.9685 -0.381)
			(stroke
				(width 0)
				(type default)
			)
			(fill no)
			(layer "F.Fab")
		)
		(pad "1" thru_hole circle
			(at -1.5875 0 90)
			(size 0.508 0.508)
			(drill 0.254)
			(layers "*.Cu" "*.Mask")
			(remove_unused_layers no)
			(net "GND")
			(clearance 0.127)
			(thermal_gap 0.127)
		)
		(pad "2" thru_hole circle
			(at -0.5715 0 90)
			(size 0.508 0.508)
			(drill 0.254)
			(layers "*.Cu" "*.Mask")
			(remove_unused_layers no)
			(net "PHY_SCC_A_TO_DRV_A_20_DP")
			(clearance 0.127)
			(thermal_gap 0.127)
		)
		(pad "3" thru_hole circle
			(at 0.5715 0 90)
			(size 0.508 0.508)
			(drill 0.254)
			(layers "*.Cu" "*.Mask")
			(remove_unused_layers no)
			(net "PHY_SCC_A_TO_DRV_A_20_DN")
			(clearance 0.127)
			(thermal_gap 0.127)
		)
		(pad "4" thru_hole circle
			(at 1.5875 0 90)
			(size 0.508 0.508)
			(drill 0.254)
			(layers "*.Cu" "*.Mask")
			(remove_unused_layers no)
			(net "GND")
			(clearance 0.127)
			(thermal_gap 0.127)
		)
	)
	(footprint ""
		(layer "F.Cu")
		(at 151.708866 -140.292074 -90)
		(property "Reference" "R1039"
			(at 0 0 270)
			(layer "F.SilkS")
			(hide yes)
			(effects
				(font
					(size 1.27 1.27)
				)
			)
		)
		(property "Value" "10R2F-L-GP"
			(at 0.064008 -3.993896 270)
			(unlocked yes)
			(layer "F.Fab")
			(hide yes)
			(effects
				(font
					(size 1.016 1.016)
					(thickness 0.1524)
				)
			)
		)
		(property "Device Type" "R402H14"
			(at 0.064008 -5.517896 270)
			(unlocked yes)
			(layer "F.Fab")
			(hide yes)
			(effects
				(font
					(size 1.016 1.016)
					(thickness 0.1524)
				)
			)
		)
		(duplicate_pad_numbers_are_jumpers no)
		(fp_line
			(start -0.508 -0.9398)
			(end -0.508 0.9398)
			(stroke
				(width 0.1524)
				(type default)
			)
			(layer "F.SilkS")
		)
		(fp_line
			(start 0.508 -0.9398)
			(end -0.508 -0.9398)
			(stroke
				(width 0.1524)
				(type default)
			)
			(layer "F.SilkS")
		)
		(fp_rect
			(start -0.508 0.9398)
			(end 0.508 -0.9398)
			(stroke
				(width 0)
				(type default)
			)
			(fill no)
			(layer "F.CrtYd")
		)
		(fp_rect
			(start -0.508 0.9398)
			(end 0.508 -0.9398)
			(stroke
				(width 0)
				(type default)
			)
			(fill no)
			(layer "F.Fab")
		)
		(pad "1" smd custom
			(at 0 -0.4445 270)
			(size 0.1397 0.1397)
			(layers "F.Cu" "F.Mask" "F.Paste")
			(net "P12V_A")
			(options
				(clearance outline)
				(anchor circle)
			)
			(primitives
				(gr_poly
					(pts
						(arc
							(start -0.1778 -0.2794)
							(mid -0.249642 -0.249642)
							(end -0.2794 -0.1778)
						)
						(arc
							(start -0.2794 0.1778)
							(mid -0.249642 0.249642)
							(end -0.1778 0.2794)
						)
						(arc
							(start 0.1778 0.2794)
							(mid 0.249642 0.249642)
							(end 0.2794 0.1778)
						)
						(arc
							(start 0.2794 -0.1778)
							(mid 0.249642 -0.249642)
							(end 0.1778 -0.2794)
						)
					)
					(width 0)
					(fill yes)
				)
			)
		)
		(pad "2" smd custom
			(at 0 0.4445 270)
			(size 0.1397 0.1397)
			(layers "F.Cu" "F.Mask" "F.Paste")
			(net "MB0_P12V_HS")
			(options
				(clearance outline)
				(anchor circle)
			)
			(primitives
				(gr_poly
					(pts
						(arc
							(start -0.1778 -0.2794)
							(mid -0.249642 -0.249642)
							(end -0.2794 -0.1778)
						)
						(arc
							(start -0.2794 0.1778)
							(mid -0.249642 0.249642)
							(end -0.1778 0.2794)
						)
						(arc
							(start 0.1778 0.2794)
							(mid 0.249642 0.249642)
							(end 0.2794 0.1778)
						)
						(arc
							(start 0.2794 -0.1778)
							(mid 0.249642 -0.249642)
							(end 0.1778 -0.2794)
						)
					)
					(width 0)
					(fill yes)
				)
			)
		)
	)
	(footprint ""
		(layer "F.Cu")
		(at 143.074898 -161.649918 180)
		(property "Reference" "D16"
			(at 0 0 180)
			(layer "F.SilkS")
			(hide yes)
			(effects
				(font
					(size 1.27 1.27)
				)
			)
		)
		(property "Value" "RB551V30-GP"
			(at 0 -6.7818 180)
			(unlocked yes)
			(layer "F.Fab")
			(hide yes)
			(effects
				(font
					(size 1.016 1.016)
					(thickness 0.1524)
				)
			)
		)
		(property "Device Type" "SOD323AKH38"
			(at 0 -8.6868 180)
			(unlocked yes)
			(layer "F.Fab")
			(hide yes)
			(effects
				(font
					(size 1.016 1.016)
					(thickness 0.1524)
				)
			)
		)
		(duplicate_pad_numbers_are_jumpers no)
		(fp_line
			(start 0.889 2.159)
			(end -0.889 2.159)
			(stroke
				(width 0.1524)
				(type default)
			)
			(layer "F.SilkS")
		)
		(fp_line
			(start 0.889 -1.9304)
			(end 0.889 2.159)
			(stroke
				(width 0.1524)
				(type default)
			)
			(layer "F.SilkS")
		)
		(fp_line
			(start 0.762 2.0574)
			(end -0.762 2.0574)
			(stroke
				(width 0.508)
				(type default)
			)
			(layer "F.SilkS")
		)
		(fp_line
			(start -0.889 2.159)
			(end -0.889 -1.9304)
			(stroke
				(width 0.1524)
				(type default)
			)
			(layer "F.SilkS")
		)
		(fp_line
			(start -0.889 -1.9304)
			(end 0.889 -1.9304)
			(stroke
				(width 0.1524)
				(type default)
			)
			(layer "F.SilkS")
		)
		(fp_rect
			(start -1.016 2.3114)
			(end 1.016 -2.0066)
			(stroke
				(width 0)
				(type default)
			)
			(fill no)
			(layer "F.CrtYd")
		)
		(fp_poly
			(pts
				(xy -1.016 -2.0066) (xy 1.016 -2.0066) (xy 1.016 2.3114) (xy -1.016 2.3114)
			)
			(stroke
				(width 0)
				(type default)
			)
			(fill no)
			(layer "F.Fab")
		)
		(pad "A" smd rect
			(at 0 -1.143 180)
			(size 0.5588 1.016)
			(layers "F.Cu" "F.Mask" "F.Paste")
			(net "SW_HDD_R16")
		)
		(pad "K" smd rect
			(at 0 1.143 180)
			(size 0.5588 1.016)
			(layers "F.Cu" "F.Mask" "F.Paste")
			(net "SW_HDD_N16")
		)
	)
	(footprint ""
		(layer "F.Cu")
		(at 234.0864 -248.9708 180)
		(property "Reference" "R31"
			(at 0 0 180)
			(layer "F.SilkS")
			(hide yes)
			(effects
				(font
					(size 1.27 1.27)
				)
			)
		)
		(property "Value" "4K7R2F-GP"
			(at 0.064008 -3.993896 180)
			(unlocked yes)
			(layer "F.Fab")
			(hide yes)
			(effects
				(font
					(size 1.016 1.016)
					(thickness 0.1524)
				)
			)
		)
		(property "Device Type" "R402H16"
			(at 0.064008 -5.517896 180)
			(unlocked yes)
			(layer "F.Fab")
			(hide yes)
			(effects
				(font
					(size 1.016 1.016)
					(thickness 0.1524)
				)
			)
		)
		(duplicate_pad_numbers_are_jumpers no)
		(fp_line
			(start 0.508 -0.9398)
			(end -0.508 -0.9398)
			(stroke
				(width 0.1524)
				(type default)
			)
			(layer "F.SilkS")
		)
		(fp_line
			(start -0.508 -0.9398)
			(end -0.508 0.9398)
			(stroke
				(width 0.1524)
				(type default)
			)
			(layer "F.SilkS")
		)
		(fp_rect
			(start -0.508 0.9398)
			(end 0.508 -0.9398)
			(stroke
				(width 0)
				(type default)
			)
			(fill no)
			(layer "F.CrtYd")
		)
		(fp_rect
			(start -0.508 0.9398)
			(end 0.508 -0.9398)
			(stroke
				(width 0)
				(type default)
			)
			(fill no)
			(layer "F.Fab")
		)
		(pad "1" smd custom
			(at 0 -0.4445 180)
			(size 0.1397 0.1397)
			(layers "F.Cu" "F.Mask" "F.Paste")
			(net "P3V3_STBY_A")
			(options
				(clearance outline)
				(anchor circle)
			)
			(primitives
				(gr_poly
					(pts
						(arc
							(start -0.1778 -0.2794)
							(mid -0.249642 -0.249642)
							(end -0.2794 -0.1778)
						)
						(arc
							(start -0.2794 0.1778)
							(mid -0.249642 0.249642)
							(end -0.1778 0.2794)
						)
						(arc
							(start 0.1778 0.2794)
							(mid 0.249642 0.249642)
							(end 0.2794 0.1778)
						)
						(arc
							(start 0.2794 -0.1778)
							(mid 0.249642 -0.249642)
							(end 0.1778 -0.2794)
						)
					)
					(width 0)
					(fill yes)
				)
			)
		)
		(pad "2" smd custom
			(at 0 0.4445 180)
			(size 0.1397 0.1397)
			(layers "F.Cu" "F.Mask" "F.Paste")
			(net "IO_EXP4_A0")
			(options
				(clearance outline)
				(anchor circle)
			)
			(primitives
				(gr_poly
					(pts
						(arc
							(start -0.1778 -0.2794)
							(mid -0.249642 -0.249642)
							(end -0.2794 -0.1778)
						)
						(arc
							(start -0.2794 0.1778)
							(mid -0.249642 0.249642)
							(end -0.1778 0.2794)
						)
						(arc
							(start 0.1778 0.2794)
							(mid 0.249642 0.249642)
							(end 0.2794 0.1778)
						)
						(arc
							(start 0.2794 -0.1778)
							(mid 0.249642 -0.249642)
							(end 0.1778 -0.2794)
						)
					)
					(width 0)
					(fill yes)
				)
			)
		)
	)
	(footprint ""
		(layer "F.Cu")
		(at 85.781134 -31.40837)
		(property "Reference" "R44"
			(at 0 0 0)
			(layer "F.SilkS")
			(hide yes)
			(effects
				(font
					(size 1.27 1.27)
				)
			)
		)
		(property "Value" "4K7R2F-GP"
			(at 0.064008 -3.993896 0)
			(unlocked yes)
			(layer "F.Fab")
			(hide yes)
			(effects
				(font
					(size 1.016 1.016)
					(thickness 0.1524)
				)
			)
		)
		(property "Device Type" "R402H16"
			(at 0.064008 -5.517896 0)
			(unlocked yes)
			(layer "F.Fab")
			(hide yes)
			(effects
				(font
					(size 1.016 1.016)
					(thickness 0.1524)
				)
			)
		)
		(duplicate_pad_numbers_are_jumpers no)
		(fp_line
			(start -0.508 -0.9398)
			(end -0.508 0.9398)
			(stroke
				(width 0.1524)
				(type default)
			)
			(layer "F.SilkS")
		)
		(fp_line
			(start 0.508 -0.9398)
			(end -0.508 -0.9398)
			(stroke
				(width 0.1524)
				(type default)
			)
			(layer "F.SilkS")
		)
		(fp_rect
			(start -0.508 0.9398)
			(end 0.508 -0.9398)
			(stroke
				(width 0)
				(type default)
			)
			(fill no)
			(layer "F.CrtYd")
		)
		(fp_rect
			(start -0.508 0.9398)
			(end 0.508 -0.9398)
			(stroke
				(width 0)
				(type default)
			)
			(fill no)
			(layer "F.Fab")
		)
		(pad "1" smd custom
			(at 0 -0.4445)
			(size 0.1397 0.1397)
			(layers "F.Cu" "F.Mask" "F.Paste")
			(net "P3V3_STBY_A")
			(options
				(clearance outline)
				(anchor circle)
			)
			(primitives
				(gr_poly
					(pts
						(arc
							(start -0.1778 -0.2794)
							(mid -0.249642 -0.249642)
							(end -0.2794 -0.1778)
						)
						(arc
							(start -0.2794 0.1778)
							(mid -0.249642 0.249642)
							(end -0.1778 0.2794)
						)
						(arc
							(start 0.1778 0.2794)
							(mid 0.249642 0.249642)
							(end 0.2794 0.1778)
						)
						(arc
							(start 0.2794 -0.1778)
							(mid 0.249642 -0.249642)
							(end 0.1778 -0.2794)
						)
					)
					(width 0)
					(fill yes)
				)
			)
		)
		(pad "2" smd custom
			(at 0 0.4445)
			(size 0.1397 0.1397)
			(layers "F.Cu" "F.Mask" "F.Paste")
			(net "IO_EXP10_A0")
			(options
				(clearance outline)
				(anchor circle)
			)
			(primitives
				(gr_poly
					(pts
						(arc
							(start -0.1778 -0.2794)
							(mid -0.249642 -0.249642)
							(end -0.2794 -0.1778)
						)
						(arc
							(start -0.2794 0.1778)
							(mid -0.249642 0.249642)
							(end -0.1778 0.2794)
						)
						(arc
							(start 0.1778 0.2794)
							(mid 0.249642 0.249642)
							(end 0.2794 0.1778)
						)
						(arc
							(start 0.2794 -0.1778)
							(mid 0.249642 -0.249642)
							(end 0.1778 -0.2794)
						)
					)
					(width 0)
					(fill yes)
				)
			)
		)
	)
	(footprint ""
		(layer "F.Cu")
		(at 129.697734 -127.798068 180)
		(property "Reference" "Q279"
			(at 0 0 180)
			(layer "F.SilkS")
			(hide yes)
			(effects
				(font
					(size 1.27 1.27)
				)
			)
		)
		(property "Value" "SSM3K324R-GP"
			(at 0.127 -8.9662 180)
			(unlocked yes)
			(layer "F.Fab")
			(hide yes)
			(effects
				(font
					(size 1.016 1.016)
					(thickness 0.1524)
				)
			)
		)
		(property "Device Type" "SOT23DGS2D4H35"
			(at 0.127 -10.4902 180)
			(unlocked yes)
			(layer "F.Fab")
			(hide yes)
			(effects
				(font
					(size 1.016 1.016)
					(thickness 0.1524)
				)
			)
		)
		(duplicate_pad_numbers_are_jumpers no)
		(fp_line
			(start 1.651 1.778)
			(end 1.651 -1.778)
			(stroke
				(width 0.1524)
				(type default)
			)
			(layer "F.SilkS")
		)
		(fp_line
			(start 1.651 -1.778)
			(end -1.651 -1.778)
			(stroke
				(width 0.1524)
				(type default)
			)
			(layer "F.SilkS")
		)
		(fp_line
			(start -1.651 1.778)
			(end 1.651 1.778)
			(stroke
				(width 0.1524)
				(type default)
			)
			(layer "F.SilkS")
		)
		(fp_line
			(start -1.651 -1.778)
			(end -1.651 1.778)
			(stroke
				(width 0.1524)
				(type default)
			)
			(layer "F.SilkS")
		)
		(fp_poly
			(pts
				(xy -1.778 1.8796) (xy -1.778 -1.8796) (xy 1.778 -1.8796) (xy 1.778 1.8796)
			)
			(stroke
				(width 0)
				(type default)
			)
			(fill no)
			(layer "F.CrtYd")
		)
		(fp_poly
			(pts
				(xy -1.778 1.8796) (xy -1.778 -1.8796) (xy 1.778 -1.8796) (xy 1.778 1.8796)
			)
			(stroke
				(width 0)
				(type default)
			)
			(fill no)
			(layer "F.Fab")
		)
		(pad "D" smd custom
			(at 0 -0.9525 180)
			(size 0.1905 0.1905)
			(layers "F.Cu" "F.Mask" "F.Paste")
			(net "DRV_ACT_16_N")
			(options
				(clearance outline)
				(anchor circle)
			)
			(primitives
				(gr_poly
					(pts
						(arc
							(start -0.1778 0.5715)
							(mid -0.321484 0.511984)
							(end -0.381 0.3683)
						)
						(arc
							(start -0.381 -0.3683)
							(mid -0.321484 -0.511984)
							(end -0.1778 -0.5715)
						)
						(arc
							(start 0.1778 -0.5715)
							(mid 0.321484 -0.511984)
							(end 0.381 -0.3683)
						)
						(arc
							(start 0.381 0.3683)
							(mid 0.321484 0.511984)
							(end 0.1778 0.5715)
						)
					)
					(width 0)
					(fill yes)
				)
			)
		)
		(pad "G" smd custom
			(at -0.98425 0.9525 180)
			(size 0.1905 0.1905)
			(layers "F.Cu" "F.Mask" "F.Paste")
			(net "DRIVE_A_16_ACT")
			(options
				(clearance outline)
				(anchor circle)
			)
			(primitives
				(gr_poly
					(pts
						(arc
							(start -0.1778 0.5715)
							(mid -0.321484 0.511984)
							(end -0.381 0.3683)
						)
						(arc
							(start -0.381 -0.3683)
							(mid -0.321484 -0.511984)
							(end -0.1778 -0.5715)
						)
						(arc
							(start 0.1778 -0.5715)
							(mid 0.321484 -0.511984)
							(end 0.381 -0.3683)
						)
						(arc
							(start 0.381 0.3683)
							(mid 0.321484 0.511984)
							(end 0.1778 0.5715)
						)
					)
					(width 0)
					(fill yes)
				)
			)
		)
		(pad "S" smd custom
			(at 0.98425 0.9525 180)
			(size 0.1905 0.1905)
			(layers "F.Cu" "F.Mask" "F.Paste")
			(net "GND")
			(options
				(clearance outline)
				(anchor circle)
			)
			(primitives
				(gr_poly
					(pts
						(arc
							(start -0.1778 0.5715)
							(mid -0.321484 0.511984)
							(end -0.381 0.3683)
						)
						(arc
							(start -0.381 -0.3683)
							(mid -0.321484 -0.511984)
							(end -0.1778 -0.5715)
						)
						(arc
							(start 0.1778 -0.5715)
							(mid 0.321484 -0.511984)
							(end 0.381 -0.3683)
						)
						(arc
							(start 0.381 0.3683)
							(mid 0.321484 0.511984)
							(end 0.1778 0.5715)
						)
					)
					(width 0)
					(fill yes)
				)
			)
		)
	)
	(footprint ""
		(layer "F.Cu")
		(at 337.312 -47.792894 90)
		(property "Reference" "D30"
			(at 0 0 90)
			(layer "F.SilkS")
			(hide yes)
			(effects
				(font
					(size 1.27 1.27)
				)
			)
		)
		(property "Value" "RB551V30-GP"
			(at 0 -6.7818 90)
			(unlocked yes)
			(layer "F.Fab")
			(hide yes)
			(effects
				(font
					(size 1.016 1.016)
					(thickness 0.1524)
				)
			)
		)
		(property "Device Type" "SOD323AKH38"
			(at 0 -8.6868 90)
			(unlocked yes)
			(layer "F.Fab")
			(hide yes)
			(effects
				(font
					(size 1.016 1.016)
					(thickness 0.1524)
				)
			)
		)
		(duplicate_pad_numbers_are_jumpers no)
		(fp_line
			(start 0.889 -1.9304)
			(end 0.889 2.159)
			(stroke
				(width 0.1524)
				(type default)
			)
			(layer "F.SilkS")
		)
		(fp_line
			(start -0.889 -1.9304)
			(end 0.889 -1.9304)
			(stroke
				(width 0.1524)
				(type default)
			)
			(layer "F.SilkS")
		)
		(fp_line
			(start 0.762 2.0574)
			(end -0.762 2.0574)
			(stroke
				(width 0.508)
				(type default)
			)
			(layer "F.SilkS")
		)
		(fp_line
			(start 0.889 2.159)
			(end -0.889 2.159)
			(stroke
				(width 0.1524)
				(type default)
			)
			(layer "F.SilkS")
		)
		(fp_line
			(start -0.889 2.159)
			(end -0.889 -1.9304)
			(stroke
				(width 0.1524)
				(type default)
			)
			(layer "F.SilkS")
		)
		(fp_rect
			(start -1.016 2.3114)
			(end 1.016 -2.0066)
			(stroke
				(width 0)
				(type default)
			)
			(fill no)
			(layer "F.CrtYd")
		)
		(fp_poly
			(pts
				(xy -1.016 -2.0066) (xy 1.016 -2.0066) (xy 1.016 2.3114) (xy -1.016 2.3114)
			)
			(stroke
				(width 0)
				(type default)
			)
			(fill no)
			(layer "F.Fab")
		)
		(pad "A" smd rect
			(at 0 -1.143 90)
			(size 0.5588 1.016)
			(layers "F.Cu" "F.Mask" "F.Paste")
			(net "SW_HDD_R30")
		)
		(pad "K" smd rect
			(at 0 1.143 90)
			(size 0.5588 1.016)
			(layers "F.Cu" "F.Mask" "F.Paste")
			(net "SW_HDD_N30")
		)
	)
	(footprint ""
		(layer "F.Cu")
		(at 368.354102 -177.016918)
		(property "Reference" "Q116"
			(at 0 0 0)
			(layer "F.SilkS")
			(hide yes)
			(effects
				(font
					(size 1.27 1.27)
				)
			)
		)
		(property "Value" "AO4407AL-GP"
			(at -3.707384 -1.5367 0)
			(unlocked yes)
			(layer "F.Fab")
			(hide yes)
			(effects
				(font
					(size 1.016 1.016)
					(thickness 0.1524)
				)
			)
		)
		(property "Device Type" "SOIC8H69"
			(at -3.707384 -3.0607 0)
			(unlocked yes)
			(layer "F.Fab")
			(hide yes)
			(effects
				(font
					(size 1.016 1.016)
					(thickness 0.1524)
				)
			)
		)
		(duplicate_pad_numbers_are_jumpers no)
		(fp_line
			(start -2.7432 -1.4224)
			(end -2.7432 1.4224)
			(stroke
				(width 0.1524)
				(type default)
			)
			(layer "F.SilkS")
		)
		(fp_line
			(start -2.7432 1.4224)
			(end -2.6416 1.4224)
			(stroke
				(width 0.1524)
				(type default)
			)
			(layer "F.SilkS")
		)
		(fp_line
			(start -2.7432 1.4224)
			(end 2.1336 1.4224)
			(stroke
				(width 0.1524)
				(type default)
			)
			(layer "F.SilkS")
		)
		(fp_line
			(start -2.7178 -0.508)
			(end -2.1844 -0.0508)
			(stroke
				(width 0.1524)
				(type default)
			)
			(layer "F.SilkS")
		)
		(fp_line
			(start -2.6289 3.4417)
			(end -2.6289 1.4732)
			(stroke
				(width 0.381)
				(type default)
			)
			(layer "F.SilkS")
		)
		(fp_line
			(start -2.1844 -0.0508)
			(end -2.7178 0.508)
			(stroke
				(width 0.1524)
				(type default)
			)
			(layer "F.SilkS")
		)
		(fp_line
			(start 2.1336 -1.4224)
			(end -2.7432 -1.4224)
			(stroke
				(width 0.1524)
				(type default)
			)
			(layer "F.SilkS")
		)
		(fp_line
			(start 2.1336 1.4224)
			(end 2.1336 -1.4224)
			(stroke
				(width 0.1524)
				(type default)
			)
			(layer "F.SilkS")
		)
		(fp_poly
			(pts
				(xy -2.2098 -1.4224) (xy -2.2098 1.4224) (xy 2.2098 1.4224) (xy 2.2098 -1.4224)
			)
			(stroke
				(width 0)
				(type default)
			)
			(fill yes)
			(layer "F.SilkS")
		)
		(fp_rect
			(start -2.450084 2.999994)
			(end 2.450084 -2.999994)
			(stroke
				(width 0)
				(type default)
			)
			(fill no)
			(layer "F.CrtYd")
		)
		(fp_poly
			(pts
				(xy -2.8194 3.6322) (xy -2.8194 -3.6322) (xy 2.8194 -3.6322) (xy 2.8194 1.18364) (xy 2.450084 1.18364)
				(xy 2.450084 -2.999994) (xy -2.450084 -2.999994) (xy -2.450084 2.999994) (xy 2.450084 2.999994)
				(xy 2.450084 1.18618) (xy 2.8194 1.18618) (xy 2.8194 3.6322)
			)
			(stroke
				(width 0)
				(type default)
			)
			(fill no)
			(layer "F.CrtYd")
		)
		(fp_rect
			(start -2.8194 3.6322)
			(end 2.8194 -3.6322)
			(stroke
				(width 0)
				(type default)
			)
			(fill no)
			(layer "F.Fab")
		)
		(pad "1" smd rect
			(at -1.905 2.54)
			(size 0.635 1.651)
			(layers "F.Cu" "F.Mask" "F.Paste")
			(net "P12V_A")
		)
		(pad "2" smd rect
			(at -0.635 2.54)
			(size 0.635 1.651)
			(layers "F.Cu" "F.Mask" "F.Paste")
			(net "P12V_A")
		)
		(pad "3" smd rect
			(at 0.635 2.54)
			(size 0.635 1.651)
			(layers "F.Cu" "F.Mask" "F.Paste")
			(net "P12V_A")
		)
		(pad "4" smd rect
			(at 1.905 2.54)
			(size 0.635 1.651)
			(layers "F.Cu" "F.Mask" "F.Paste")
			(net "SW_HDD_N19")
		)
		(pad "5" smd rect
			(at 1.905 -2.54)
			(size 0.635 1.651)
			(layers "F.Cu" "F.Mask" "F.Paste")
			(net "P12V_HDD19")
		)
		(pad "6" smd rect
			(at 0.635 -2.54)
			(size 0.635 1.651)
			(layers "F.Cu" "F.Mask" "F.Paste")
			(net "P12V_HDD19")
		)
		(pad "7" smd rect
			(at -0.635 -2.54)
			(size 0.635 1.651)
			(layers "F.Cu" "F.Mask" "F.Paste")
			(net "P12V_HDD19")
		)
		(pad "8" smd rect
			(at -1.905 -2.54)
			(size 0.635 1.651)
			(layers "F.Cu" "F.Mask" "F.Paste")
			(net "P12V_HDD19")
		)
	)
	(footprint ""
		(layer "F.Cu")
		(at 263.832848 10.225532 180)
		(property "Reference" "R135"
			(at 0 0 180)
			(layer "F.SilkS")
			(hide yes)
			(effects
				(font
					(size 1.27 1.27)
				)
			)
		)
		(property "Value" "4K7R2F-GP"
			(at 0.064008 -3.993896 180)
			(unlocked yes)
			(layer "F.Fab")
			(hide yes)
			(effects
				(font
					(size 1.016 1.016)
					(thickness 0.1524)
				)
			)
		)
		(property "Device Type" "R402H16"
			(at 0.064008 -5.517896 180)
			(unlocked yes)
			(layer "F.Fab")
			(hide yes)
			(effects
				(font
					(size 1.016 1.016)
					(thickness 0.1524)
				)
			)
		)
		(duplicate_pad_numbers_are_jumpers no)
		(fp_line
			(start 0.508 -0.9398)
			(end -0.508 -0.9398)
			(stroke
				(width 0.1524)
				(type default)
			)
			(layer "F.SilkS")
		)
		(fp_line
			(start -0.508 -0.9398)
			(end -0.508 0.9398)
			(stroke
				(width 0.1524)
				(type default)
			)
			(layer "F.SilkS")
		)
		(fp_rect
			(start -0.508 0.9398)
			(end 0.508 -0.9398)
			(stroke
				(width 0)
				(type default)
			)
			(fill no)
			(layer "F.CrtYd")
		)
		(fp_rect
			(start -0.508 0.9398)
			(end 0.508 -0.9398)
			(stroke
				(width 0)
				(type default)
			)
			(fill no)
			(layer "F.Fab")
		)
		(pad "1" smd custom
			(at 0 -0.4445 180)
			(size 0.1397 0.1397)
			(layers "F.Cu" "F.Mask" "F.Paste")
			(net "USB_EN_1")
			(options
				(clearance outline)
				(anchor circle)
			)
			(primitives
				(gr_poly
					(pts
						(arc
							(start -0.1778 -0.2794)
							(mid -0.249642 -0.249642)
							(end -0.2794 -0.1778)
						)
						(arc
							(start -0.2794 0.1778)
							(mid -0.249642 0.249642)
							(end -0.1778 0.2794)
						)
						(arc
							(start 0.1778 0.2794)
							(mid 0.249642 0.249642)
							(end 0.2794 0.1778)
						)
						(arc
							(start 0.2794 -0.1778)
							(mid 0.249642 -0.249642)
							(end 0.1778 -0.2794)
						)
					)
					(width 0)
					(fill yes)
				)
			)
		)
		(pad "2" smd custom
			(at 0 0.4445 180)
			(size 0.1397 0.1397)
			(layers "F.Cu" "F.Mask" "F.Paste")
			(net "GND")
			(options
				(clearance outline)
				(anchor circle)
			)
			(primitives
				(gr_poly
					(pts
						(arc
							(start -0.1778 -0.2794)
							(mid -0.249642 -0.249642)
							(end -0.2794 -0.1778)
						)
						(arc
							(start -0.2794 0.1778)
							(mid -0.249642 0.249642)
							(end -0.1778 0.2794)
						)
						(arc
							(start 0.1778 0.2794)
							(mid 0.249642 0.249642)
							(end 0.2794 0.1778)
						)
						(arc
							(start 0.2794 -0.1778)
							(mid 0.249642 -0.249642)
							(end 0.1778 -0.2794)
						)
					)
					(width 0)
					(fill yes)
				)
			)
		)
	)
	(footprint ""
		(layer "F.Cu")
		(at 247.849644 -143.49984)
		(property "Reference" ""
			(at 0 0 0)
			(layer "F.SilkS")
			(hide yes)
			(effects
				(font
					(size 1.27 1.27)
				)
			)
		)
		(property "Value" "*"
			(at 5.4229 -0.7239 0)
			(unlocked yes)
			(layer "F.Fab")
			(hide yes)
			(effects
				(font
					(size 1.016 1.016)
					(thickness 0.1524)
				)
			)
		)
		(duplicate_pad_numbers_are_jumpers no)
		(fp_poly
			(pts
				(arc
					(start 4.064 0)
					(mid -4.064 0)
					(end 4.064 0)
				)
			)
			(stroke
				(width 0)
				(type default)
			)
			(fill no)
			(layer "B.CrtYd")
		)
		(fp_poly
			(pts
				(arc
					(start 4.064 0)
					(mid -4.064 0)
					(end 4.064 0)
				)
			)
			(stroke
				(width 0)
				(type default)
			)
			(fill no)
			(layer "F.CrtYd")
		)
		(fp_poly
			(pts
				(arc
					(start 4.064 0)
					(mid -4.064 0)
					(end 4.064 0)
				)
			)
			(stroke
				(width 0)
				(type default)
			)
			(fill no)
			(layer "B.Fab")
		)
		(fp_poly
			(pts
				(arc
					(start 4.064 0)
					(mid -4.064 0)
					(end 4.064 0)
				)
			)
			(stroke
				(width 0)
				(type default)
			)
			(fill no)
			(layer "F.Fab")
		)
		(pad "1" thru_hole circle
			(at 0 0)
			(size 7.5184 7.5184)
			(drill 3.0226)
			(layers "*.Cu" "*.Mask")
			(remove_unused_layers no)
			(net "Net_63")
			(clearance -1.7399)
			(thermal_gap 0.3048)
			(padstack
				(mode front_inner_back)
				(layer "Inner"
					(shape circle)
					(size 3.429 3.429)
					(clearance 0.3048)
				)
				(layer "B.Cu"
					(shape circle)
					(size 7.5184 7.5184)
					(clearance -1.7399)
				)
			)
		)
	)
	(footprint ""
		(layer "F.Cu")
		(at 364.798102 -272.585942 180)
		(property "Reference" "R299"
			(at 0 0 180)
			(layer "F.SilkS")
			(hide yes)
			(effects
				(font
					(size 1.27 1.27)
				)
			)
		)
		(property "Value" "1KR2F-3-GP"
			(at 0.064008 -3.993896 180)
			(unlocked yes)
			(layer "F.Fab")
			(hide yes)
			(effects
				(font
					(size 1.016 1.016)
					(thickness 0.1524)
				)
			)
		)
		(property "Device Type" "R402H16"
			(at 0.064008 -5.517896 180)
			(unlocked yes)
			(layer "F.Fab")
			(hide yes)
			(effects
				(font
					(size 1.016 1.016)
					(thickness 0.1524)
				)
			)
		)
		(duplicate_pad_numbers_are_jumpers no)
		(fp_line
			(start 0.508 -0.9398)
			(end -0.508 -0.9398)
			(stroke
				(width 0.1524)
				(type default)
			)
			(layer "F.SilkS")
		)
		(fp_line
			(start -0.508 -0.9398)
			(end -0.508 0.9398)
			(stroke
				(width 0.1524)
				(type default)
			)
			(layer "F.SilkS")
		)
		(fp_rect
			(start -0.508 0.9398)
			(end 0.508 -0.9398)
			(stroke
				(width 0)
				(type default)
			)
			(fill no)
			(layer "F.CrtYd")
		)
		(fp_rect
			(start -0.508 0.9398)
			(end 0.508 -0.9398)
			(stroke
				(width 0)
				(type default)
			)
			(fill no)
			(layer "F.Fab")
		)
		(pad "1" smd custom
			(at 0 -0.4445 180)
			(size 0.1397 0.1397)
			(layers "F.Cu" "F.Mask" "F.Paste")
			(net "P3V3_STBY_A")
			(options
				(clearance outline)
				(anchor circle)
			)
			(primitives
				(gr_poly
					(pts
						(arc
							(start -0.1778 -0.2794)
							(mid -0.249642 -0.249642)
							(end -0.2794 -0.1778)
						)
						(arc
							(start -0.2794 0.1778)
							(mid -0.249642 0.249642)
							(end -0.1778 0.2794)
						)
						(arc
							(start 0.1778 0.2794)
							(mid 0.249642 0.249642)
							(end 0.2794 0.1778)
						)
						(arc
							(start 0.2794 -0.1778)
							(mid 0.249642 -0.249642)
							(end 0.1778 -0.2794)
						)
					)
					(width 0)
					(fill yes)
				)
			)
		)
		(pad "2" smd custom
			(at 0 0.4445 180)
			(size 0.1397 0.1397)
			(layers "F.Cu" "F.Mask" "F.Paste")
			(net "SW_PWR_R_HDD7")
			(options
				(clearance outline)
				(anchor circle)
			)
			(primitives
				(gr_poly
					(pts
						(arc
							(start -0.1778 -0.2794)
							(mid -0.249642 -0.249642)
							(end -0.2794 -0.1778)
						)
						(arc
							(start -0.2794 0.1778)
							(mid -0.249642 0.249642)
							(end -0.1778 0.2794)
						)
						(arc
							(start 0.1778 0.2794)
							(mid 0.249642 0.249642)
							(end 0.2794 0.1778)
						)
						(arc
							(start 0.2794 -0.1778)
							(mid 0.249642 -0.249642)
							(end 0.1778 -0.2794)
						)
					)
					(width 0)
					(fill yes)
				)
			)
		)
	)
	(footprint ""
		(layer "F.Cu")
		(at 384.734562 -274.219416 -90)
		(property "Reference" "C142"
			(at 0 0 270)
			(layer "F.SilkS")
			(hide yes)
			(effects
				(font
					(size 1.27 1.27)
				)
			)
		)
		(property "Value" "SCD01U16V1KX-GP"
			(at -2.8321 -1.7399 270)
			(unlocked yes)
			(layer "F.Fab")
			(hide yes)
			(effects
				(font
					(size 1.016 1.016)
					(thickness 0.1524)
				)
			)
		)
		(property "Device Type" "C0201H13"
			(at -2.8321 -3.2639 270)
			(unlocked yes)
			(layer "F.Fab")
			(hide yes)
			(effects
				(font
					(size 1.016 1.016)
					(thickness 0.1524)
				)
			)
		)
		(duplicate_pad_numbers_are_jumpers no)
		(fp_rect
			(start -0.2794 0.6477)
			(end 0.2794 -0.6477)
			(stroke
				(width 0)
				(type default)
			)
			(fill no)
			(layer "F.CrtYd")
		)
		(fp_rect
			(start -0.2794 0.6477)
			(end 0.2794 -0.6477)
			(stroke
				(width 0)
				(type default)
			)
			(fill no)
			(layer "F.Fab")
		)
		(pad "1" smd custom
			(at 0 -0.2794 270)
			(size 0.0762 0.0762)
			(layers "F.Cu" "F.Mask" "F.Paste")
			(net "SAS_HDD_RX_N8")
			(options
				(clearance outline)
				(anchor circle)
			)
			(primitives
				(gr_poly
					(pts
						(arc
							(start 0.1524 -0.127)
							(mid 0.137521 -0.162921)
							(end 0.1016 -0.1778)
						)
						(arc
							(start -0.1016 -0.1778)
							(mid -0.137521 -0.162921)
							(end -0.1524 -0.127)
						)
						(arc
							(start -0.1524 0.127)
							(mid -0.137521 0.162921)
							(end -0.1016 0.1778)
						)
						(arc
							(start 0.1016 0.1778)
							(mid 0.137521 0.162921)
							(end 0.1524 0.127)
						)
					)
					(width 0)
					(fill yes)
				)
			)
		)
		(pad "2" smd custom
			(at 0 0.2794 270)
			(size 0.0762 0.0762)
			(layers "F.Cu" "F.Mask" "F.Paste")
			(net "PHY_SCC_A_TO_DRV_A_8_DN")
			(options
				(clearance outline)
				(anchor circle)
			)
			(primitives
				(gr_poly
					(pts
						(arc
							(start 0.1524 -0.127)
							(mid 0.137521 -0.162921)
							(end 0.1016 -0.1778)
						)
						(arc
							(start -0.1016 -0.1778)
							(mid -0.137521 -0.162921)
							(end -0.1524 -0.127)
						)
						(arc
							(start -0.1524 0.127)
							(mid -0.137521 0.162921)
							(end -0.1016 0.1778)
						)
						(arc
							(start 0.1016 0.1778)
							(mid 0.137521 0.162921)
							(end 0.1524 0.127)
						)
					)
					(width 0)
					(fill yes)
				)
			)
		)
	)
	(footprint ""
		(layer "F.Cu")
		(at 321.634612 -44.219368 -90)
		(property "Reference" "C428"
			(at 0 0 270)
			(layer "F.SilkS")
			(hide yes)
			(effects
				(font
					(size 1.27 1.27)
				)
			)
		)
		(property "Value" "SCD01U16V1KX-GP"
			(at -2.8321 -1.7399 270)
			(unlocked yes)
			(layer "F.Fab")
			(hide yes)
			(effects
				(font
					(size 1.016 1.016)
					(thickness 0.1524)
				)
			)
		)
		(property "Device Type" "C0201H13"
			(at -2.8321 -3.2639 270)
			(unlocked yes)
			(layer "F.Fab")
			(hide yes)
			(effects
				(font
					(size 1.016 1.016)
					(thickness 0.1524)
				)
			)
		)
		(duplicate_pad_numbers_are_jumpers no)
		(fp_rect
			(start -0.2794 0.6477)
			(end 0.2794 -0.6477)
			(stroke
				(width 0)
				(type default)
			)
			(fill no)
			(layer "F.CrtYd")
		)
		(fp_rect
			(start -0.2794 0.6477)
			(end 0.2794 -0.6477)
			(stroke
				(width 0)
				(type default)
			)
			(fill no)
			(layer "F.Fab")
		)
		(pad "1" smd custom
			(at 0 -0.2794 270)
			(size 0.0762 0.0762)
			(layers "F.Cu" "F.Mask" "F.Paste")
			(net "SAS_HDD_RX_N30")
			(options
				(clearance outline)
				(anchor circle)
			)
			(primitives
				(gr_poly
					(pts
						(arc
							(start 0.1524 -0.127)
							(mid 0.137521 -0.162921)
							(end 0.1016 -0.1778)
						)
						(arc
							(start -0.1016 -0.1778)
							(mid -0.137521 -0.162921)
							(end -0.1524 -0.127)
						)
						(arc
							(start -0.1524 0.127)
							(mid -0.137521 0.162921)
							(end -0.1016 0.1778)
						)
						(arc
							(start 0.1016 0.1778)
							(mid 0.137521 0.162921)
							(end 0.1524 0.127)
						)
					)
					(width 0)
					(fill yes)
				)
			)
		)
		(pad "2" smd custom
			(at 0 0.2794 270)
			(size 0.0762 0.0762)
			(layers "F.Cu" "F.Mask" "F.Paste")
			(net "PHY_SCC_A_TO_DRV_A_30_DN")
			(options
				(clearance outline)
				(anchor circle)
			)
			(primitives
				(gr_poly
					(pts
						(arc
							(start 0.1524 -0.127)
							(mid 0.137521 -0.162921)
							(end 0.1016 -0.1778)
						)
						(arc
							(start -0.1016 -0.1778)
							(mid -0.137521 -0.162921)
							(end -0.1524 -0.127)
						)
						(arc
							(start -0.1524 0.127)
							(mid -0.137521 0.162921)
							(end -0.1016 0.1778)
						)
						(arc
							(start 0.1016 0.1778)
							(mid 0.137521 0.162921)
							(end 0.1524 0.127)
						)
					)
					(width 0)
					(fill yes)
				)
			)
		)
	)
	(footprint ""
		(layer "F.Cu")
		(at 174.5742 -52.110894 90)
		(property "Reference" "R804"
			(at 0 0 90)
			(layer "F.SilkS")
			(hide yes)
			(effects
				(font
					(size 1.27 1.27)
				)
			)
		)
		(property "Value" "4K7R2J-2-GP"
			(at 0.064008 -3.993896 90)
			(unlocked yes)
			(layer "F.Fab")
			(hide yes)
			(effects
				(font
					(size 1.016 1.016)
					(thickness 0.1524)
				)
			)
		)
		(property "Device Type" "R402H16"
			(at 0.064008 -5.517896 90)
			(unlocked yes)
			(layer "F.Fab")
			(hide yes)
			(effects
				(font
					(size 1.016 1.016)
					(thickness 0.1524)
				)
			)
		)
		(duplicate_pad_numbers_are_jumpers no)
		(fp_line
			(start 0.508 -0.9398)
			(end -0.508 -0.9398)
			(stroke
				(width 0.1524)
				(type default)
			)
			(layer "F.SilkS")
		)
		(fp_line
			(start -0.508 -0.9398)
			(end -0.508 0.9398)
			(stroke
				(width 0.1524)
				(type default)
			)
			(layer "F.SilkS")
		)
		(fp_rect
			(start -0.508 0.9398)
			(end 0.508 -0.9398)
			(stroke
				(width 0)
				(type default)
			)
			(fill no)
			(layer "F.CrtYd")
		)
		(fp_rect
			(start -0.508 0.9398)
			(end 0.508 -0.9398)
			(stroke
				(width 0)
				(type default)
			)
			(fill no)
			(layer "F.Fab")
		)
		(pad "1" smd custom
			(at 0 -0.4445 90)
			(size 0.1397 0.1397)
			(layers "F.Cu" "F.Mask" "F.Paste")
			(net "P12V_A")
			(options
				(clearance outline)
				(anchor circle)
			)
			(primitives
				(gr_poly
					(pts
						(arc
							(start -0.1778 -0.2794)
							(mid -0.249642 -0.249642)
							(end -0.2794 -0.1778)
						)
						(arc
							(start -0.2794 0.1778)
							(mid -0.249642 0.249642)
							(end -0.1778 0.2794)
						)
						(arc
							(start 0.1778 0.2794)
							(mid 0.249642 0.249642)
							(end 0.2794 0.1778)
						)
						(arc
							(start 0.2794 -0.1778)
							(mid 0.249642 -0.249642)
							(end 0.1778 -0.2794)
						)
					)
					(width 0)
					(fill yes)
				)
			)
		)
		(pad "2" smd custom
			(at 0 0.4445 90)
			(size 0.1397 0.1397)
			(layers "F.Cu" "F.Mask" "F.Paste")
			(net "SW_HDD_P29")
			(options
				(clearance outline)
				(anchor circle)
			)
			(primitives
				(gr_poly
					(pts
						(arc
							(start -0.1778 -0.2794)
							(mid -0.249642 -0.249642)
							(end -0.2794 -0.1778)
						)
						(arc
							(start -0.2794 0.1778)
							(mid -0.249642 0.249642)
							(end -0.1778 0.2794)
						)
						(arc
							(start 0.1778 0.2794)
							(mid 0.249642 0.249642)
							(end 0.2794 0.1778)
						)
						(arc
							(start 0.2794 -0.1778)
							(mid 0.249642 -0.249642)
							(end 0.1778 -0.2794)
						)
					)
					(width 0)
					(fill yes)
				)
			)
		)
	)
	(footprint ""
		(layer "F.Cu")
		(at 337.447636 -33.550352 180)
		(property "Reference" "R87"
			(at 0 0 180)
			(layer "F.SilkS")
			(hide yes)
			(effects
				(font
					(size 1.27 1.27)
				)
			)
		)
		(property "Value" "0R2J-2-GP"
			(at 0.064008 -3.993896 180)
			(unlocked yes)
			(layer "F.Fab")
			(hide yes)
			(effects
				(font
					(size 1.016 1.016)
					(thickness 0.1524)
				)
			)
		)
		(property "Device Type" "R402H16"
			(at 0.064008 -5.517896 180)
			(unlocked yes)
			(layer "F.Fab")
			(hide yes)
			(effects
				(font
					(size 1.016 1.016)
					(thickness 0.1524)
				)
			)
		)
		(duplicate_pad_numbers_are_jumpers no)
		(fp_line
			(start 0.508 -0.9398)
			(end -0.508 -0.9398)
			(stroke
				(width 0.1524)
				(type default)
			)
			(layer "F.SilkS")
		)
		(fp_line
			(start -0.508 -0.9398)
			(end -0.508 0.9398)
			(stroke
				(width 0.1524)
				(type default)
			)
			(layer "F.SilkS")
		)
		(fp_rect
			(start -0.508 0.9398)
			(end 0.508 -0.9398)
			(stroke
				(width 0)
				(type default)
			)
			(fill no)
			(layer "F.CrtYd")
		)
		(fp_rect
			(start -0.508 0.9398)
			(end 0.508 -0.9398)
			(stroke
				(width 0)
				(type default)
			)
			(fill no)
			(layer "F.Fab")
		)
		(pad "1" smd custom
			(at 0 -0.4445 180)
			(size 0.1397 0.1397)
			(layers "F.Cu" "F.Mask" "F.Paste")
			(net "IO_EXP11_SCL")
			(options
				(clearance outline)
				(anchor circle)
			)
			(primitives
				(gr_poly
					(pts
						(arc
							(start -0.1778 -0.2794)
							(mid -0.249642 -0.249642)
							(end -0.2794 -0.1778)
						)
						(arc
							(start -0.2794 0.1778)
							(mid -0.249642 0.249642)
							(end -0.1778 0.2794)
						)
						(arc
							(start 0.1778 0.2794)
							(mid 0.249642 0.249642)
							(end 0.2794 0.1778)
						)
						(arc
							(start 0.2794 -0.1778)
							(mid 0.249642 -0.249642)
							(end 0.1778 -0.2794)
						)
					)
					(width 0)
					(fill yes)
				)
			)
		)
		(pad "2" smd custom
			(at 0 0.4445 180)
			(size 0.1397 0.1397)
			(layers "F.Cu" "F.Mask" "F.Paste")
			(net "I2C_BMC_B_MISC_SCL")
			(options
				(clearance outline)
				(anchor circle)
			)
			(primitives
				(gr_poly
					(pts
						(arc
							(start -0.1778 -0.2794)
							(mid -0.249642 -0.249642)
							(end -0.2794 -0.1778)
						)
						(arc
							(start -0.2794 0.1778)
							(mid -0.249642 0.249642)
							(end -0.1778 0.2794)
						)
						(arc
							(start 0.1778 0.2794)
							(mid 0.249642 0.249642)
							(end 0.2794 0.1778)
						)
						(arc
							(start 0.2794 -0.1778)
							(mid 0.249642 -0.249642)
							(end 0.1778 -0.2794)
						)
					)
					(width 0)
					(fill yes)
				)
			)
		)
	)
	(footprint ""
		(layer "F.Cu")
		(at 479.298 -297.372024)
		(property "Reference" "TP57"
			(at 0 0 0)
			(layer "F.SilkS")
			(hide yes)
			(effects
				(font
					(size 1.27 1.27)
				)
			)
		)
		(property "Value" "TPAD32-GP"
			(at -0.0508 -1.6764 0)
			(unlocked yes)
			(layer "F.Fab")
			(hide yes)
			(effects
				(font
					(size 1.016 1.016)
					(thickness 0.1524)
				)
			)
		)
		(property "Device Type" "TPAD32"
			(at -0.0508 -3.2004 0)
			(unlocked yes)
			(layer "F.Fab")
			(hide yes)
			(effects
				(font
					(size 1.016 1.016)
					(thickness 0.1524)
				)
			)
		)
		(duplicate_pad_numbers_are_jumpers no)
		(fp_poly
			(pts
				(arc
					(start 0.4064 0)
					(mid -0.4064 0)
					(end 0.4064 0)
				)
			)
			(stroke
				(width 0)
				(type default)
			)
			(fill no)
			(layer "F.CrtYd")
		)
		(fp_poly
			(pts
				(arc
					(start 0.7112 0)
					(mid -0.7112 0)
					(end 0.7112 0)
				)
			)
			(stroke
				(width 0)
				(type default)
			)
			(fill no)
			(layer "F.Fab")
		)
		(pad "1" smd circle
			(at 0 0)
			(size 0.8128 0.8128)
			(layers "F.Cu" "F.Mask" "F.Paste")
			(net "ACT_HDD_11")
		)
	)
	(footprint ""
		(layer "F.Cu")
		(at 412.323534 -290.148518)
		(property "Reference" "Q262"
			(at 0 0 0)
			(layer "F.SilkS")
			(hide yes)
			(effects
				(font
					(size 1.27 1.27)
				)
			)
		)
		(property "Value" "2N7002K-2-GP"
			(at 0.127 -8.9662 0)
			(unlocked yes)
			(layer "F.Fab")
			(hide yes)
			(effects
				(font
					(size 1.016 1.016)
					(thickness 0.1524)
				)
			)
		)
		(property "Device Type" "SOT23DGS2D4H44"
			(at 0.127 -10.4902 0)
			(unlocked yes)
			(layer "F.Fab")
			(hide yes)
			(effects
				(font
					(size 1.016 1.016)
					(thickness 0.1524)
				)
			)
		)
		(duplicate_pad_numbers_are_jumpers no)
		(fp_line
			(start -1.651 -1.778)
			(end -1.651 1.778)
			(stroke
				(width 0.1524)
				(type default)
			)
			(layer "F.SilkS")
		)
		(fp_line
			(start -1.651 1.778)
			(end 1.651 1.778)
			(stroke
				(width 0.1524)
				(type default)
			)
			(layer "F.SilkS")
		)
		(fp_line
			(start 1.651 -1.778)
			(end -1.651 -1.778)
			(stroke
				(width 0.1524)
				(type default)
			)
			(layer "F.SilkS")
		)
		(fp_line
			(start 1.651 1.778)
			(end 1.651 -1.778)
			(stroke
				(width 0.1524)
				(type default)
			)
			(layer "F.SilkS")
		)
		(fp_poly
			(pts
				(xy -1.778 1.8796) (xy -1.778 -1.8796) (xy 1.778 -1.8796) (xy 1.778 1.8796)
			)
			(stroke
				(width 0)
				(type default)
			)
			(fill no)
			(layer "F.CrtYd")
		)
		(fp_poly
			(pts
				(xy -1.778 1.8796) (xy -1.778 -1.8796) (xy 1.778 -1.8796) (xy 1.778 1.8796)
			)
			(stroke
				(width 0)
				(type default)
			)
			(fill no)
			(layer "F.Fab")
		)
		(pad "D" smd custom
			(at 0 -0.9525)
			(size 0.1905 0.1905)
			(layers "F.Cu" "F.Mask" "F.Paste")
			(net "FLT_HDD33_N")
			(options
				(clearance outline)
				(anchor circle)
			)
			(primitives
				(gr_poly
					(pts
						(arc
							(start -0.1778 0.5715)
							(mid -0.321484 0.511984)
							(end -0.381 0.3683)
						)
						(arc
							(start -0.381 -0.3683)
							(mid -0.321484 -0.511984)
							(end -0.1778 -0.5715)
						)
						(arc
							(start 0.1778 -0.5715)
							(mid 0.321484 -0.511984)
							(end 0.381 -0.3683)
						)
						(arc
							(start 0.381 0.3683)
							(mid 0.321484 0.511984)
							(end 0.1778 0.5715)
						)
					)
					(width 0)
					(fill yes)
				)
			)
		)
		(pad "G" smd custom
			(at -0.98425 0.9525)
			(size 0.1905 0.1905)
			(layers "F.Cu" "F.Mask" "F.Paste")
			(net "DRIVE_B_33_FLT_LED")
			(options
				(clearance outline)
				(anchor circle)
			)
			(primitives
				(gr_poly
					(pts
						(arc
							(start -0.1778 0.5715)
							(mid -0.321484 0.511984)
							(end -0.381 0.3683)
						)
						(arc
							(start -0.381 -0.3683)
							(mid -0.321484 -0.511984)
							(end -0.1778 -0.5715)
						)
						(arc
							(start 0.1778 -0.5715)
							(mid 0.321484 -0.511984)
							(end 0.381 -0.3683)
						)
						(arc
							(start 0.381 0.3683)
							(mid 0.321484 0.511984)
							(end 0.1778 0.5715)
						)
					)
					(width 0)
					(fill yes)
				)
			)
		)
		(pad "S" smd custom
			(at 0.98425 0.9525)
			(size 0.1905 0.1905)
			(layers "F.Cu" "F.Mask" "F.Paste")
			(net "GND")
			(options
				(clearance outline)
				(anchor circle)
			)
			(primitives
				(gr_poly
					(pts
						(arc
							(start -0.1778 0.5715)
							(mid -0.321484 0.511984)
							(end -0.381 0.3683)
						)
						(arc
							(start -0.381 -0.3683)
							(mid -0.321484 -0.511984)
							(end -0.1778 -0.5715)
						)
						(arc
							(start 0.1778 -0.5715)
							(mid 0.321484 -0.511984)
							(end 0.381 -0.3683)
						)
						(arc
							(start 0.381 0.3683)
							(mid 0.321484 0.511984)
							(end 0.1778 0.5715)
						)
					)
					(width 0)
					(fill yes)
				)
			)
		)
	)
	(footprint ""
		(layer "F.Cu")
		(at 224.3836 -205.646528 180)
		(property "Reference" "R609"
			(at 0 0 180)
			(layer "F.SilkS")
			(hide yes)
			(effects
				(font
					(size 1.27 1.27)
				)
			)
		)
		(property "Value" "2K2R2F-GP"
			(at 0.064008 -3.993896 180)
			(unlocked yes)
			(layer "F.Fab")
			(hide yes)
			(effects
				(font
					(size 1.016 1.016)
					(thickness 0.1524)
				)
			)
		)
		(property "Device Type" "R402H16"
			(at 0.064008 -5.517896 180)
			(unlocked yes)
			(layer "F.Fab")
			(hide yes)
			(effects
				(font
					(size 1.016 1.016)
					(thickness 0.1524)
				)
			)
		)
		(duplicate_pad_numbers_are_jumpers no)
		(fp_line
			(start 0.508 -0.9398)
			(end -0.508 -0.9398)
			(stroke
				(width 0.1524)
				(type default)
			)
			(layer "F.SilkS")
		)
		(fp_line
			(start -0.508 -0.9398)
			(end -0.508 0.9398)
			(stroke
				(width 0.1524)
				(type default)
			)
			(layer "F.SilkS")
		)
		(fp_rect
			(start -0.508 0.9398)
			(end 0.508 -0.9398)
			(stroke
				(width 0)
				(type default)
			)
			(fill no)
			(layer "F.CrtYd")
		)
		(fp_rect
			(start -0.508 0.9398)
			(end 0.508 -0.9398)
			(stroke
				(width 0)
				(type default)
			)
			(fill no)
			(layer "F.Fab")
		)
		(pad "1" smd custom
			(at 0 -0.4445 180)
			(size 0.1397 0.1397)
			(layers "F.Cu" "F.Mask" "F.Paste")
			(net "P3V3_STBY_A")
			(options
				(clearance outline)
				(anchor circle)
			)
			(primitives
				(gr_poly
					(pts
						(arc
							(start -0.1778 -0.2794)
							(mid -0.249642 -0.249642)
							(end -0.2794 -0.1778)
						)
						(arc
							(start -0.2794 0.1778)
							(mid -0.249642 0.249642)
							(end -0.1778 0.2794)
						)
						(arc
							(start 0.1778 0.2794)
							(mid 0.249642 0.249642)
							(end 0.2794 0.1778)
						)
						(arc
							(start 0.2794 -0.1778)
							(mid 0.249642 -0.249642)
							(end 0.1778 -0.2794)
						)
					)
					(width 0)
					(fill yes)
				)
			)
		)
		(pad "2" smd custom
			(at 0 0.4445 180)
			(size 0.1397 0.1397)
			(layers "F.Cu" "F.Mask" "F.Paste")
			(net "I2C_SCC_A_SCL")
			(options
				(clearance outline)
				(anchor circle)
			)
			(primitives
				(gr_poly
					(pts
						(arc
							(start -0.1778 -0.2794)
							(mid -0.249642 -0.249642)
							(end -0.2794 -0.1778)
						)
						(arc
							(start -0.2794 0.1778)
							(mid -0.249642 0.249642)
							(end -0.1778 0.2794)
						)
						(arc
							(start 0.1778 0.2794)
							(mid 0.249642 0.249642)
							(end 0.2794 0.1778)
						)
						(arc
							(start 0.2794 -0.1778)
							(mid 0.249642 -0.249642)
							(end 0.1778 -0.2794)
						)
					)
					(width 0)
					(fill yes)
				)
			)
		)
	)
	(footprint ""
		(layer "F.Cu")
		(at 483.300024 -57.909968 -90)
		(property "Reference" "HDDSAS35"
			(at 0 0 270)
			(layer "F.SilkS")
			(hide yes)
			(effects
				(font
					(size 1.27 1.27)
				)
			)
		)
		(property "Value" "SKT-SAS15P-14P-45-GP"
			(at -20.7645 -8.9789 270)
			(unlocked yes)
			(layer "F.Fab")
			(hide yes)
			(effects
				(font
					(size 1.016 1.016)
					(thickness 0.1524)
				)
			)
		)
		(property "Device Type" "10120818-001C-TRLF"
			(at -20.7645 -10.5029 270)
			(unlocked yes)
			(layer "F.Fab")
			(hide yes)
			(effects
				(font
					(size 1.016 1.016)
					(thickness 0.1524)
				)
			)
		)
		(duplicate_pad_numbers_are_jumpers no)
		(fp_line
			(start 1.651 4.2926)
			(end 1.651 3.0099)
			(stroke
				(width 0.1524)
				(type default)
			)
			(layer "F.SilkS")
		)
		(fp_line
			(start 8.509 4.2926)
			(end 1.651 4.2926)
			(stroke
				(width 0.1524)
				(type default)
			)
			(layer "F.SilkS")
		)
		(fp_line
			(start -23.4188 3.0099)
			(end -23.4188 -3.2512)
			(stroke
				(width 0.1524)
				(type default)
			)
			(layer "F.SilkS")
		)
		(fp_line
			(start 1.651 3.0099)
			(end -23.4188 3.0099)
			(stroke
				(width 0.1524)
				(type default)
			)
			(layer "F.SilkS")
		)
		(fp_line
			(start 8.509 3.0099)
			(end 8.509 4.2926)
			(stroke
				(width 0.1524)
				(type default)
			)
			(layer "F.SilkS")
		)
		(fp_line
			(start 23.4188 3.0099)
			(end 8.509 3.0099)
			(stroke
				(width 0.1524)
				(type default)
			)
			(layer "F.SilkS")
		)
		(fp_line
			(start -23.4188 -3.2512)
			(end 23.4188 -3.2512)
			(stroke
				(width 0.1524)
				(type default)
			)
			(layer "F.SilkS")
		)
		(fp_line
			(start 23.4188 -3.2512)
			(end 23.4188 3.0099)
			(stroke
				(width 0.1524)
				(type default)
			)
			(layer "F.SilkS")
		)
		(fp_line
			(start 15.5067 -3.3401)
			(end 16.2687 -3.3401)
			(stroke
				(width 0.3302)
				(type default)
			)
			(layer "F.SilkS")
		)
		(fp_poly
			(pts
				(xy 15.868904 -3.230372) (xy 16.503904 -3.865372) (xy 15.233904 -3.865372)
			)
			(stroke
				(width 0)
				(type default)
			)
			(fill yes)
			(layer "F.SilkS")
		)
		(fp_poly
			(pts
				(xy -22.8727 -2.7559) (xy 22.8727 -2.7559) (xy 22.8727 2.7559) (xy 8.255 2.7559) (xy 8.255 3.5179)
				(xy 1.905 3.5179) (xy 1.905 2.7559) (xy -22.8727 2.7559)
			)
			(stroke
				(width 0)
				(type default)
			)
			(fill no)
			(layer "F.CrtYd")
		)
		(fp_poly
			(pts
				(xy 1.397 4.5466) (xy 1.397 3.2639) (xy -23.6728 3.2639) (xy -23.6728 -3.5052) (xy 23.6728 -3.5052)
				(xy 23.6728 -0.00635) (xy 22.8727 -0.00635) (xy 22.8727 -2.7559) (xy -22.8727 -2.7559) (xy -22.8727 2.7559)
				(xy 1.905 2.7559) (xy 1.905 3.5179) (xy 8.255 3.5179) (xy 8.255 2.7559) (xy 22.8727 2.7559) (xy 22.8727 0.00635)
				(xy 23.6728 0.00635) (xy 23.6728 3.2639) (xy 8.763 3.2639) (xy 8.763 4.5466)
			)
			(stroke
				(width 0)
				(type default)
			)
			(fill no)
			(layer "F.CrtYd")
		)
		(fp_poly
			(pts
				(xy 1.397 4.5466) (xy 1.397 3.2639) (xy -23.6728 3.2639) (xy -23.6728 -3.5052) (xy 23.6728 -3.5052)
				(xy 23.6728 3.2639) (xy 8.763 3.2639) (xy 8.763 4.5466)
			)
			(stroke
				(width 0)
				(type default)
			)
			(fill no)
			(layer "F.Fab")
		)
		(pad "" np_thru_hole circle
			(at -18.874994 0 270)
			(size 0.254 0.254)
			(drill 1.3462)
			(layers "*.Cu" "*.Mask")
			(clearance 0.9017)
			(thermal_gap 0.9017)
		)
		(pad "" np_thru_hole circle
			(at 18.874994 0 270)
			(size 0.254 0.254)
			(drill 0.9398)
			(layers "*.Cu" "*.Mask")
			(clearance 0.6985)
			(thermal_gap 0.6985)
		)
		(pad "G1" smd rect
			(at 21.874988 0 270)
			(size 2.5908 2.5908)
			(layers "F.Cu" "F.Mask" "F.Paste")
			(net "GND")
		)
		(pad "G2" smd rect
			(at -21.874988 0 270)
			(size 2.5908 2.5908)
			(layers "F.Cu" "F.Mask" "F.Paste")
			(net "GND")
		)
		(pad "P1" smd rect
			(at 1.905 -1.82499 270)
			(size 0.6096 2.3622)
			(layers "F.Cu" "F.Mask" "F.Paste")
			(net "Net_2031")
		)
		(pad "P2" smd rect
			(at 0.635 -1.82499 270)
			(size 0.6096 2.3622)
			(layers "F.Cu" "F.Mask" "F.Paste")
			(net "Net_2032")
		)
		(pad "P3" smd rect
			(at -0.635 -1.82499 270)
			(size 0.6096 2.3622)
			(layers "F.Cu" "F.Mask" "F.Paste")
			(net "Net_2033")
		)
		(pad "P4" smd rect
			(at -1.905 -1.82499 270)
			(size 0.6096 2.3622)
			(layers "F.Cu" "F.Mask" "F.Paste")
			(net "GND")
		)
		(pad "P5" smd rect
			(at -3.175 -1.82499 270)
			(size 0.6096 2.3622)
			(layers "F.Cu" "F.Mask" "F.Paste")
			(net "HDD_PRSNT_35")
		)
		(pad "P6" smd rect
			(at -4.445 -1.82499 270)
			(size 0.6096 2.3622)
			(layers "F.Cu" "F.Mask" "F.Paste")
			(net "GND")
		)
		(pad "P7" smd rect
			(at -5.715 -1.82499 270)
			(size 0.6096 2.3622)
			(layers "F.Cu" "F.Mask" "F.Paste")
			(net "5V_PRE_35")
		)
		(pad "P8" smd rect
			(at -6.985 -1.82499 270)
			(size 0.6096 2.3622)
			(layers "F.Cu" "F.Mask" "F.Paste")
			(net "P5V_HDD35")
		)
		(pad "P9" smd rect
			(at -8.255 -1.82499 270)
			(size 0.6096 2.3622)
			(layers "F.Cu" "F.Mask" "F.Paste")
			(net "P5V_HDD35")
		)
		(pad "P10" smd rect
			(at -9.525 -1.82499 270)
			(size 0.6096 2.3622)
			(layers "F.Cu" "F.Mask" "F.Paste")
			(net "GND")
		)
		(pad "P11" smd rect
			(at -10.795 -1.82499 270)
			(size 0.6096 2.3622)
			(layers "F.Cu" "F.Mask" "F.Paste")
			(net "ACT_HDD_35")
		)
		(pad "P12" smd rect
			(at -12.065 -1.82499 270)
			(size 0.6096 2.3622)
			(layers "F.Cu" "F.Mask" "F.Paste")
			(net "GND")
		)
		(pad "P13" smd rect
			(at -13.335 -1.82499 270)
			(size 0.6096 2.3622)
			(layers "F.Cu" "F.Mask" "F.Paste")
			(net "12V_PRE_35")
		)
		(pad "P14" smd rect
			(at -14.605 -1.82499 270)
			(size 0.6096 2.3622)
			(layers "F.Cu" "F.Mask" "F.Paste")
			(net "P12V_HDD35")
		)
		(pad "P15" smd rect
			(at -15.875 -1.82499 270)
			(size 0.6096 2.3622)
			(layers "F.Cu" "F.Mask" "F.Paste")
			(net "P12V_HDD35")
		)
		(pad "S1" smd rect
			(at 15.875 -1.82499 270)
			(size 0.6096 2.3622)
			(layers "F.Cu" "F.Mask" "F.Paste")
			(net "GND")
		)
		(pad "S2" smd rect
			(at 14.605 -1.82499 270)
			(size 0.6096 2.3622)
			(layers "F.Cu" "F.Mask" "F.Paste")
			(net "SAS_HDD_RX_P35")
		)
		(pad "S3" smd rect
			(at 13.335 -1.82499 270)
			(size 0.6096 2.3622)
			(layers "F.Cu" "F.Mask" "F.Paste")
			(net "SAS_HDD_RX_N35")
		)
		(pad "S4" smd rect
			(at 12.065 -1.82499 270)
			(size 0.6096 2.3622)
			(layers "F.Cu" "F.Mask" "F.Paste")
			(net "GND")
		)
		(pad "S5" smd rect
			(at 10.795 -1.82499 270)
			(size 0.6096 2.3622)
			(layers "F.Cu" "F.Mask" "F.Paste")
			(net "PHY_DRV_A_TO_SCC_A_35_DN")
		)
		(pad "S6" smd rect
			(at 9.525 -1.82499 270)
			(size 0.6096 2.3622)
			(layers "F.Cu" "F.Mask" "F.Paste")
			(net "PHY_DRV_A_TO_SCC_A_35_DP")
		)
		(pad "S7" smd rect
			(at 8.255 -1.82499 270)
			(size 0.6096 2.3622)
			(layers "F.Cu" "F.Mask" "F.Paste")
			(net "GND")
		)
		(pad "S8" smd rect
			(at 7.480046 2.845054 270)
			(size 0.508 2.3622)
			(layers "F.Cu" "F.Mask" "F.Paste")
			(net "GND")
		)
		(pad "S9" smd rect
			(at 6.679946 2.845054 270)
			(size 0.508 2.3622)
			(layers "F.Cu" "F.Mask" "F.Paste")
			(net "Net_474")
		)
		(pad "S10" smd rect
			(at 5.8801 2.845054 270)
			(size 0.508 2.3622)
			(layers "F.Cu" "F.Mask" "F.Paste")
			(net "Net_366")
		)
		(pad "S11" smd rect
			(at 5.08 2.845054 270)
			(size 0.508 2.3622)
			(layers "F.Cu" "F.Mask" "F.Paste")
			(net "GND")
		)
		(pad "S12" smd rect
			(at 4.2799 2.845054 270)
			(size 0.508 2.3622)
			(layers "F.Cu" "F.Mask" "F.Paste")
			(net "Net_402")
		)
		(pad "S13" smd rect
			(at 3.480054 2.845054 270)
			(size 0.508 2.3622)
			(layers "F.Cu" "F.Mask" "F.Paste")
			(net "Net_438")
		)
		(pad "S14" smd rect
			(at 2.679954 2.845054 270)
			(size 0.508 2.3622)
			(layers "F.Cu" "F.Mask" "F.Paste")
			(net "GND")
		)
		(zone
			(layer "F.Cu")
			(hatch none 0.5)
			(connect_pads
				(clearance 0)
			)
			(min_thickness 0.25)
			(keepout
				(tracks allowed)
				(vias not_allowed)
				(pads allowed)
				(copperpour not_allowed)
				(footprints allowed)
			)
			(placement
				(enabled no)
				(sheetname "")
			)
			(fill
				(thermal_gap 0.5)
				(thermal_bridge_width 0.5)
				(island_removal_mode 0)
			)
			(polygon
				(pts
					(xy 486.957624 -74.648568) (xy 479.883724 -74.648568) (xy 479.883724 -81.582768) (xy 480.988624 -81.582768)
					(xy 480.988624 -77.467968) (xy 485.611424 -77.467968) (xy 485.611424 -81.582768) (xy 486.957624 -81.582768)
				)
			)
		)
		(zone
			(layer "F.Cu")
			(hatch none 0.5)
			(connect_pads
				(clearance 0)
			)
			(min_thickness 0.25)
			(keepout
				(tracks not_allowed)
				(vias allowed)
				(pads allowed)
				(copperpour not_allowed)
				(footprints allowed)
			)
			(placement
				(enabled no)
				(sheetname "")
			)
			(fill
				(thermal_gap 0.5)
				(thermal_bridge_width 0.5)
				(island_removal_mode 0)
			)
			(polygon
				(pts
					(xy 486.957624 -74.648568) (xy 479.883724 -74.648568) (xy 479.883724 -81.582768) (xy 480.988624 -81.582768)
					(xy 480.988624 -77.467968) (xy 485.611424 -77.467968) (xy 485.611424 -81.582768) (xy 486.957624 -81.582768)
				)
			)
		)
		(zone
			(layer "F.Cu")
			(hatch none 0.5)
			(connect_pads
				(clearance 0)
			)
			(min_thickness 0.25)
			(keepout
				(tracks allowed)
				(vias not_allowed)
				(pads allowed)
				(copperpour not_allowed)
				(footprints allowed)
			)
			(placement
				(enabled no)
				(sheetname "")
			)
			(fill
				(thermal_gap 0.5)
				(thermal_bridge_width 0.5)
				(island_removal_mode 0)
			)
			(polygon
				(pts
					(xy 486.957624 -41.171368) (xy 479.883724 -41.171368) (xy 479.883724 -34.237168) (xy 480.988624 -34.237168)
					(xy 480.988624 -38.351968) (xy 485.611424 -38.351968) (xy 485.611424 -34.237168) (xy 486.957624 -34.237168)
				)
			)
		)
		(zone
			(layer "F.Cu")
			(hatch none 0.5)
			(connect_pads
				(clearance 0)
			)
			(min_thickness 0.25)
			(keepout
				(tracks not_allowed)
				(vias allowed)
				(pads allowed)
				(copperpour not_allowed)
				(footprints allowed)
			)
			(placement
				(enabled no)
				(sheetname "")
			)
			(fill
				(thermal_gap 0.5)
				(thermal_bridge_width 0.5)
				(island_removal_mode 0)
			)
			(polygon
				(pts
					(xy 486.957624 -41.171368) (xy 479.883724 -41.171368) (xy 479.883724 -34.237168) (xy 480.988624 -34.237168)
					(xy 480.988624 -38.351968) (xy 485.611424 -38.351968) (xy 485.611424 -34.237168) (xy 486.957624 -34.237168)
				)
			)
		)
		(zone
			(layers "F.Cu" "B.Cu" "In1.Cu" "In2.Cu" "In3.Cu" "In4.Cu" "In5.Cu" "In6.Cu"
				"In7.Cu" "In8.Cu" "In9.Cu" "In10.Cu"
			)
			(hatch none 0.5)
			(connect_pads
				(clearance 0)
			)
			(min_thickness 0.25)
			(keepout
				(tracks not_allowed)
				(vias allowed)
				(pads allowed)
				(copperpour not_allowed)
				(footprints allowed)
			)
			(placement
				(enabled no)
				(sheetname "")
			)
			(fill
				(thermal_gap 0.5)
				(thermal_bridge_width 0.5)
				(island_removal_mode 0)
			)
			(polygon
				(pts
					(arc
						(start 484.074724 -39.034974)
						(mid 482.525324 -39.034974)
						(end 484.074724 -39.034974)
					)
				)
			)
		)
		(zone
			(layers "F.Cu" "B.Cu" "In1.Cu" "In2.Cu" "In3.Cu" "In4.Cu" "In5.Cu" "In6.Cu"
				"In7.Cu" "In8.Cu" "In9.Cu" "In10.Cu"
			)
			(hatch none 0.5)
			(connect_pads
				(clearance 0)
			)
			(min_thickness 0.25)
			(keepout
				(tracks not_allowed)
				(vias allowed)
				(pads allowed)
				(copperpour not_allowed)
				(footprints allowed)
			)
			(placement
				(enabled no)
				(sheetname "")
			)
			(fill
				(thermal_gap 0.5)
				(thermal_bridge_width 0.5)
				(island_removal_mode 0)
			)
			(polygon
				(pts
					(arc
						(start 484.277924 -76.784962)
						(mid 482.322124 -76.784962)
						(end 484.277924 -76.784962)
					)
				)
			)
		)
	)
	(footprint ""
		(layer "F.Cu")
		(at 161.852102 -149.26437 180)
		(property "Reference" "R1068"
			(at 0 0 180)
			(layer "F.SilkS")
			(hide yes)
			(effects
				(font
					(size 1.27 1.27)
				)
			)
		)
		(property "Value" "1KR2F-3-GP"
			(at 0.064008 -3.993896 180)
			(unlocked yes)
			(layer "F.Fab")
			(hide yes)
			(effects
				(font
					(size 1.016 1.016)
					(thickness 0.1524)
				)
			)
		)
		(property "Device Type" "R402H16"
			(at 0.064008 -5.517896 180)
			(unlocked yes)
			(layer "F.Fab")
			(hide yes)
			(effects
				(font
					(size 1.016 1.016)
					(thickness 0.1524)
				)
			)
		)
		(duplicate_pad_numbers_are_jumpers no)
		(fp_line
			(start 0.508 -0.9398)
			(end -0.508 -0.9398)
			(stroke
				(width 0.1524)
				(type default)
			)
			(layer "F.SilkS")
		)
		(fp_line
			(start -0.508 -0.9398)
			(end -0.508 0.9398)
			(stroke
				(width 0.1524)
				(type default)
			)
			(layer "F.SilkS")
		)
		(fp_rect
			(start -0.508 0.9398)
			(end 0.508 -0.9398)
			(stroke
				(width 0)
				(type default)
			)
			(fill no)
			(layer "F.CrtYd")
		)
		(fp_rect
			(start -0.508 0.9398)
			(end 0.508 -0.9398)
			(stroke
				(width 0)
				(type default)
			)
			(fill no)
			(layer "F.Fab")
		)
		(pad "1" smd custom
			(at 0 -0.4445 180)
			(size 0.1397 0.1397)
			(layers "F.Cu" "F.Mask" "F.Paste")
			(net "MB0_CM_VOUT_R")
			(options
				(clearance outline)
				(anchor circle)
			)
			(primitives
				(gr_poly
					(pts
						(arc
							(start -0.1778 -0.2794)
							(mid -0.249642 -0.249642)
							(end -0.2794 -0.1778)
						)
						(arc
							(start -0.2794 0.1778)
							(mid -0.249642 0.249642)
							(end -0.1778 0.2794)
						)
						(arc
							(start 0.1778 0.2794)
							(mid 0.249642 0.249642)
							(end 0.2794 0.1778)
						)
						(arc
							(start 0.2794 -0.1778)
							(mid 0.249642 -0.249642)
							(end 0.1778 -0.2794)
						)
					)
					(width 0)
					(fill yes)
				)
			)
		)
		(pad "2" smd custom
			(at 0 0.4445 180)
			(size 0.1397 0.1397)
			(layers "F.Cu" "F.Mask" "F.Paste")
			(net "P12V_A_COMP")
			(options
				(clearance outline)
				(anchor circle)
			)
			(primitives
				(gr_poly
					(pts
						(arc
							(start -0.1778 -0.2794)
							(mid -0.249642 -0.249642)
							(end -0.2794 -0.1778)
						)
						(arc
							(start -0.2794 0.1778)
							(mid -0.249642 0.249642)
							(end -0.1778 0.2794)
						)
						(arc
							(start 0.1778 0.2794)
							(mid 0.249642 0.249642)
							(end 0.2794 0.1778)
						)
						(arc
							(start 0.2794 -0.1778)
							(mid 0.249642 -0.249642)
							(end 0.1778 -0.2794)
						)
					)
					(width 0)
					(fill yes)
				)
			)
		)
	)
	(footprint ""
		(layer "F.Cu")
		(at 464.2739 -279.443942 90)
		(property "Reference" "R376"
			(at 0 0 90)
			(layer "F.SilkS")
			(hide yes)
			(effects
				(font
					(size 1.27 1.27)
				)
			)
		)
		(property "Value" "200KR2F-L-GP"
			(at 0.064008 -3.993896 90)
			(unlocked yes)
			(layer "F.Fab")
			(hide yes)
			(effects
				(font
					(size 1.016 1.016)
					(thickness 0.1524)
				)
			)
		)
		(property "Device Type" "R402H16"
			(at 0.064008 -5.517896 90)
			(unlocked yes)
			(layer "F.Fab")
			(hide yes)
			(effects
				(font
					(size 1.016 1.016)
					(thickness 0.1524)
				)
			)
		)
		(duplicate_pad_numbers_are_jumpers no)
		(fp_line
			(start 0.508 -0.9398)
			(end -0.508 -0.9398)
			(stroke
				(width 0.1524)
				(type default)
			)
			(layer "F.SilkS")
		)
		(fp_line
			(start -0.508 -0.9398)
			(end -0.508 0.9398)
			(stroke
				(width 0.1524)
				(type default)
			)
			(layer "F.SilkS")
		)
		(fp_rect
			(start -0.508 0.9398)
			(end 0.508 -0.9398)
			(stroke
				(width 0)
				(type default)
			)
			(fill no)
			(layer "F.CrtYd")
		)
		(fp_rect
			(start -0.508 0.9398)
			(end 0.508 -0.9398)
			(stroke
				(width 0)
				(type default)
			)
			(fill no)
			(layer "F.Fab")
		)
		(pad "1" smd custom
			(at 0 -0.4445 90)
			(size 0.1397 0.1397)
			(layers "F.Cu" "F.Mask" "F.Paste")
			(net "SW_HDD_R10")
			(options
				(clearance outline)
				(anchor circle)
			)
			(primitives
				(gr_poly
					(pts
						(arc
							(start -0.1778 -0.2794)
							(mid -0.249642 -0.249642)
							(end -0.2794 -0.1778)
						)
						(arc
							(start -0.2794 0.1778)
							(mid -0.249642 0.249642)
							(end -0.1778 0.2794)
						)
						(arc
							(start 0.1778 0.2794)
							(mid 0.249642 0.249642)
							(end 0.2794 0.1778)
						)
						(arc
							(start 0.2794 -0.1778)
							(mid 0.249642 -0.249642)
							(end 0.1778 -0.2794)
						)
					)
					(width 0)
					(fill yes)
				)
			)
		)
		(pad "2" smd custom
			(at 0 0.4445 90)
			(size 0.1397 0.1397)
			(layers "F.Cu" "F.Mask" "F.Paste")
			(net "SW_HDD_N10")
			(options
				(clearance outline)
				(anchor circle)
			)
			(primitives
				(gr_poly
					(pts
						(arc
							(start -0.1778 -0.2794)
							(mid -0.249642 -0.249642)
							(end -0.2794 -0.1778)
						)
						(arc
							(start -0.2794 0.1778)
							(mid -0.249642 0.249642)
							(end -0.1778 0.2794)
						)
						(arc
							(start 0.1778 0.2794)
							(mid 0.249642 0.249642)
							(end 0.2794 0.1778)
						)
						(arc
							(start 0.2794 -0.1778)
							(mid 0.249642 -0.249642)
							(end 0.1778 -0.2794)
						)
					)
					(width 0)
					(fill yes)
				)
			)
		)
	)
	(footprint ""
		(layer "F.Cu")
		(at 266.991338 -152.04821)
		(property "Reference" "TP190"
			(at 0 0 0)
			(layer "F.SilkS")
			(hide yes)
			(effects
				(font
					(size 1.27 1.27)
				)
			)
		)
		(property "Value" "TPAD32-GP"
			(at -0.0508 -1.6764 0)
			(unlocked yes)
			(layer "F.Fab")
			(hide yes)
			(effects
				(font
					(size 1.016 1.016)
					(thickness 0.1524)
				)
			)
		)
		(property "Device Type" "TPAD32"
			(at -0.0508 -3.2004 0)
			(unlocked yes)
			(layer "F.Fab")
			(hide yes)
			(effects
				(font
					(size 1.016 1.016)
					(thickness 0.1524)
				)
			)
		)
		(duplicate_pad_numbers_are_jumpers no)
		(fp_poly
			(pts
				(arc
					(start 0.4064 0)
					(mid -0.4064 0)
					(end 0.4064 0)
				)
			)
			(stroke
				(width 0)
				(type default)
			)
			(fill no)
			(layer "F.CrtYd")
		)
		(fp_poly
			(pts
				(arc
					(start 0.7112 0)
					(mid -0.7112 0)
					(end 0.7112 0)
				)
			)
			(stroke
				(width 0)
				(type default)
			)
			(fill no)
			(layer "F.Fab")
		)
		(pad "1" smd circle
			(at 0 0)
			(size 0.8128 0.8128)
			(layers "F.Cu" "F.Mask" "F.Paste")
			(net "TP_COMP_B_KR_P0_TX_DN")
		)
	)
	(footprint ""
		(layer "F.Cu")
		(at 456.674982 -322.799964)
		(property "Reference" ""
			(at 0 0 0)
			(layer "F.SilkS")
			(hide yes)
			(effects
				(font
					(size 1.27 1.27)
				)
			)
		)
		(property "Value" "*"
			(at -8.398764 -8.057642 0)
			(unlocked yes)
			(layer "F.Fab")
			(hide yes)
			(effects
				(font
					(size 1.016 1.016)
					(thickness 0.1524)
				)
			)
		)
		(duplicate_pad_numbers_are_jumpers no)
		(fp_poly
			(pts
				(arc
					(start 7.3152 0)
					(mid 0 7.3152)
					(end -7.3152 0)
				)
				(arc
					(start -7.3152 -5.9944)
					(mid 0 -13.3096)
					(end 7.3152 -5.9944)
				)
			)
			(stroke
				(width 0)
				(type default)
			)
			(fill no)
			(layer "B.CrtYd")
		)
		(fp_poly
			(pts
				(arc
					(start 7.3152 0)
					(mid 0 7.3152)
					(end -7.3152 0)
				)
				(arc
					(start -7.3152 -5.9944)
					(mid 0 -13.3096)
					(end 7.3152 -5.9944)
				)
			)
			(stroke
				(width 0)
				(type default)
			)
			(fill no)
			(layer "F.CrtYd")
		)
		(fp_poly
			(pts
				(arc
					(start 7.3152 0)
					(mid 0 7.3152)
					(end -7.3152 0)
				)
				(arc
					(start -7.3152 -5.9944)
					(mid 0 -13.3096)
					(end 7.3152 -5.9944)
				)
			)
			(stroke
				(width 0)
				(type default)
			)
			(fill no)
			(layer "B.Fab")
		)
		(fp_poly
			(pts
				(arc
					(start 7.3152 0)
					(mid 0 7.3152)
					(end -7.3152 0)
				)
				(arc
					(start -7.3152 -5.9944)
					(mid 0 -13.3096)
					(end 7.3152 -5.9944)
				)
			)
			(stroke
				(width 0)
				(type default)
			)
			(fill no)
			(layer "F.Fab")
		)
		(pad "1" thru_hole oval
			(at 0 0)
			(size 14.0208 20.0152)
			(drill 0.0254
				(offset 0 -2.9972)
			)
			(layers "*.Cu" "*.Mask")
			(remove_unused_layers no)
			(net "Net_38")
			(clearance -1.002284)
			(thermal_gap 0.1524)
			(padstack
				(mode front_inner_back)
				(layer "Inner"
					(shape custom)
					(size 2.928012 2.928012)
					(options
						(anchor circle)
					)
					(primitives
						(gr_poly
							(pts
								(arc
									(start 4.571746 -2.084324)
									(mid 0.000333 7.430372)
									(end -4.571492 -2.084324)
								)
								(arc
									(start -4.571492 -2.084324)
									(mid -3.570296 -3.611977)
									(end -2.875026 -5.30098)
								)
								(arc
									(start -2.875026 -5.30098)
									(mid 0.000217 -7.43089)
									(end 2.87528 -5.30098)
								)
								(arc
									(start 2.87528 -5.30098)
									(mid 3.570511 -3.611956)
									(end 4.571746 -2.084324)
								)
							)
							(width 0)
							(fill yes)
						)
					)
					(clearance 0.1524)
				)
				(layer "B.Cu"
					(shape oval)
					(size 14.0208 20.0152)
					(offset 0 -2.9972)
					(clearance -1.002284)
				)
			)
		)
		(zone
			(layers "F.Cu" "B.Cu" "In1.Cu" "In2.Cu" "In3.Cu" "In4.Cu" "In5.Cu" "In6.Cu"
				"In7.Cu" "In8.Cu" "In9.Cu" "In10.Cu"
			)
			(hatch none 0.5)
			(connect_pads
				(clearance 0)
			)
			(min_thickness 0.25)
			(keepout
				(tracks not_allowed)
				(vias allowed)
				(pads allowed)
				(copperpour not_allowed)
				(footprints allowed)
			)
			(placement
				(enabled no)
				(sheetname "")
			)
			(fill
				(thermal_gap 0.5)
				(thermal_bridge_width 0.5)
				(island_removal_mode 0)
			)
			(polygon
				(pts
					(arc
						(start 449.664582 -328.794364)
						(mid 456.674982 -335.804764)
						(end 463.685382 -328.794364)
					)
					(arc
						(start 463.685382 -322.799964)
						(mid 456.674982 -315.789564)
						(end 449.664582 -322.799964)
					)
				)
			)
		)
	)
	(footprint ""
		(layer "F.Cu")
		(at 430.387252 -160.735518 180)
		(property "Reference" "R630"
			(at 0 0 180)
			(layer "F.SilkS")
			(hide yes)
			(effects
				(font
					(size 1.27 1.27)
				)
			)
		)
		(property "Value" "0R2J-2-GP"
			(at 0.064008 -3.993896 180)
			(unlocked yes)
			(layer "F.Fab")
			(hide yes)
			(effects
				(font
					(size 1.016 1.016)
					(thickness 0.1524)
				)
			)
		)
		(property "Device Type" "R402H16"
			(at 0.064008 -5.517896 180)
			(unlocked yes)
			(layer "F.Fab")
			(hide yes)
			(effects
				(font
					(size 1.016 1.016)
					(thickness 0.1524)
				)
			)
		)
		(duplicate_pad_numbers_are_jumpers no)
		(fp_line
			(start 0.508 -0.9398)
			(end -0.508 -0.9398)
			(stroke
				(width 0.1524)
				(type default)
			)
			(layer "F.SilkS")
		)
		(fp_line
			(start -0.508 -0.9398)
			(end -0.508 0.9398)
			(stroke
				(width 0.1524)
				(type default)
			)
			(layer "F.SilkS")
		)
		(fp_rect
			(start -0.508 0.9398)
			(end 0.508 -0.9398)
			(stroke
				(width 0)
				(type default)
			)
			(fill no)
			(layer "F.CrtYd")
		)
		(fp_rect
			(start -0.508 0.9398)
			(end 0.508 -0.9398)
			(stroke
				(width 0)
				(type default)
			)
			(fill no)
			(layer "F.Fab")
		)
		(pad "1" smd custom
			(at 0 -0.4445 180)
			(size 0.1397 0.1397)
			(layers "F.Cu" "F.Mask" "F.Paste")
			(net "SW_HDD_G21")
			(options
				(clearance outline)
				(anchor circle)
			)
			(primitives
				(gr_poly
					(pts
						(arc
							(start -0.1778 -0.2794)
							(mid -0.249642 -0.249642)
							(end -0.2794 -0.1778)
						)
						(arc
							(start -0.2794 0.1778)
							(mid -0.249642 0.249642)
							(end -0.1778 0.2794)
						)
						(arc
							(start 0.1778 0.2794)
							(mid 0.249642 0.249642)
							(end 0.2794 0.1778)
						)
						(arc
							(start 0.2794 -0.1778)
							(mid 0.249642 -0.249642)
							(end 0.1778 -0.2794)
						)
					)
					(width 0)
					(fill yes)
				)
			)
		)
		(pad "2" smd custom
			(at 0 0.4445 180)
			(size 0.1397 0.1397)
			(layers "F.Cu" "F.Mask" "F.Paste")
			(net "SW_HDD_R21")
			(options
				(clearance outline)
				(anchor circle)
			)
			(primitives
				(gr_poly
					(pts
						(arc
							(start -0.1778 -0.2794)
							(mid -0.249642 -0.249642)
							(end -0.2794 -0.1778)
						)
						(arc
							(start -0.2794 0.1778)
							(mid -0.249642 0.249642)
							(end -0.1778 0.2794)
						)
						(arc
							(start 0.1778 0.2794)
							(mid 0.249642 0.249642)
							(end 0.2794 0.1778)
						)
						(arc
							(start 0.2794 -0.1778)
							(mid 0.249642 -0.249642)
							(end 0.1778 -0.2794)
						)
					)
					(width 0)
					(fill yes)
				)
			)
		)
	)
	(footprint ""
		(layer "F.Cu")
		(at 461.9371 -45.735494 180)
		(property "Reference" "R929"
			(at 0 0 180)
			(layer "F.SilkS")
			(hide yes)
			(effects
				(font
					(size 1.27 1.27)
				)
			)
		)
		(property "Value" "0R2J-2-GP"
			(at 0.064008 -3.993896 180)
			(unlocked yes)
			(layer "F.Fab")
			(hide yes)
			(effects
				(font
					(size 1.016 1.016)
					(thickness 0.1524)
				)
			)
		)
		(property "Device Type" "R402H16"
			(at 0.064008 -5.517896 180)
			(unlocked yes)
			(layer "F.Fab")
			(hide yes)
			(effects
				(font
					(size 1.016 1.016)
					(thickness 0.1524)
				)
			)
		)
		(duplicate_pad_numbers_are_jumpers no)
		(fp_line
			(start 0.508 -0.9398)
			(end -0.508 -0.9398)
			(stroke
				(width 0.1524)
				(type default)
			)
			(layer "F.SilkS")
		)
		(fp_line
			(start -0.508 -0.9398)
			(end -0.508 0.9398)
			(stroke
				(width 0.1524)
				(type default)
			)
			(layer "F.SilkS")
		)
		(fp_rect
			(start -0.508 0.9398)
			(end 0.508 -0.9398)
			(stroke
				(width 0)
				(type default)
			)
			(fill no)
			(layer "F.CrtYd")
		)
		(fp_rect
			(start -0.508 0.9398)
			(end 0.508 -0.9398)
			(stroke
				(width 0)
				(type default)
			)
			(fill no)
			(layer "F.Fab")
		)
		(pad "1" smd custom
			(at 0 -0.4445 180)
			(size 0.1397 0.1397)
			(layers "F.Cu" "F.Mask" "F.Paste")
			(net "SW_HDD_G34")
			(options
				(clearance outline)
				(anchor circle)
			)
			(primitives
				(gr_poly
					(pts
						(arc
							(start -0.1778 -0.2794)
							(mid -0.249642 -0.249642)
							(end -0.2794 -0.1778)
						)
						(arc
							(start -0.2794 0.1778)
							(mid -0.249642 0.249642)
							(end -0.1778 0.2794)
						)
						(arc
							(start 0.1778 0.2794)
							(mid 0.249642 0.249642)
							(end 0.2794 0.1778)
						)
						(arc
							(start 0.2794 -0.1778)
							(mid 0.249642 -0.249642)
							(end 0.1778 -0.2794)
						)
					)
					(width 0)
					(fill yes)
				)
			)
		)
		(pad "2" smd custom
			(at 0 0.4445 180)
			(size 0.1397 0.1397)
			(layers "F.Cu" "F.Mask" "F.Paste")
			(net "SW_HDD_R34")
			(options
				(clearance outline)
				(anchor circle)
			)
			(primitives
				(gr_poly
					(pts
						(arc
							(start -0.1778 -0.2794)
							(mid -0.249642 -0.249642)
							(end -0.2794 -0.1778)
						)
						(arc
							(start -0.2794 0.1778)
							(mid -0.249642 0.249642)
							(end -0.1778 0.2794)
						)
						(arc
							(start 0.1778 0.2794)
							(mid 0.249642 0.249642)
							(end 0.2794 0.1778)
						)
						(arc
							(start 0.2794 -0.1778)
							(mid 0.249642 -0.249642)
							(end 0.1778 -0.2794)
						)
					)
					(width 0)
					(fill yes)
				)
			)
		)
	)
	(footprint ""
		(layer "F.Cu")
		(at 164.964364 -294.84574 90)
		(property "Reference" "R573"
			(at 0 0 90)
			(layer "F.SilkS")
			(hide yes)
			(effects
				(font
					(size 1.27 1.27)
				)
			)
		)
		(property "Value" "4K7R2J-2-GP"
			(at 0.064008 -3.993896 90)
			(unlocked yes)
			(layer "F.Fab")
			(hide yes)
			(effects
				(font
					(size 1.016 1.016)
					(thickness 0.1524)
				)
			)
		)
		(property "Device Type" "R402H16"
			(at 0.064008 -5.517896 90)
			(unlocked yes)
			(layer "F.Fab")
			(hide yes)
			(effects
				(font
					(size 1.016 1.016)
					(thickness 0.1524)
				)
			)
		)
		(duplicate_pad_numbers_are_jumpers no)
		(fp_line
			(start 0.508 -0.9398)
			(end -0.508 -0.9398)
			(stroke
				(width 0.1524)
				(type default)
			)
			(layer "F.SilkS")
		)
		(fp_line
			(start -0.508 -0.9398)
			(end -0.508 0.9398)
			(stroke
				(width 0.1524)
				(type default)
			)
			(layer "F.SilkS")
		)
		(fp_rect
			(start -0.508 0.9398)
			(end 0.508 -0.9398)
			(stroke
				(width 0)
				(type default)
			)
			(fill no)
			(layer "F.CrtYd")
		)
		(fp_rect
			(start -0.508 0.9398)
			(end 0.508 -0.9398)
			(stroke
				(width 0)
				(type default)
			)
			(fill no)
			(layer "F.Fab")
		)
		(pad "1" smd custom
			(at 0 -0.4445 90)
			(size 0.1397 0.1397)
			(layers "F.Cu" "F.Mask" "F.Paste")
			(net "DRIVE_B_29_ACT")
			(options
				(clearance outline)
				(anchor circle)
			)
			(primitives
				(gr_poly
					(pts
						(arc
							(start -0.1778 -0.2794)
							(mid -0.249642 -0.249642)
							(end -0.2794 -0.1778)
						)
						(arc
							(start -0.2794 0.1778)
							(mid -0.249642 0.249642)
							(end -0.1778 0.2794)
						)
						(arc
							(start 0.1778 0.2794)
							(mid 0.249642 0.249642)
							(end 0.2794 0.1778)
						)
						(arc
							(start 0.2794 -0.1778)
							(mid 0.249642 -0.249642)
							(end 0.1778 -0.2794)
						)
					)
					(width 0)
					(fill yes)
				)
			)
		)
		(pad "2" smd custom
			(at 0 0.4445 90)
			(size 0.1397 0.1397)
			(layers "F.Cu" "F.Mask" "F.Paste")
			(net "GND")
			(options
				(clearance outline)
				(anchor circle)
			)
			(primitives
				(gr_poly
					(pts
						(arc
							(start -0.1778 -0.2794)
							(mid -0.249642 -0.249642)
							(end -0.2794 -0.1778)
						)
						(arc
							(start -0.2794 0.1778)
							(mid -0.249642 0.249642)
							(end -0.1778 0.2794)
						)
						(arc
							(start 0.1778 0.2794)
							(mid 0.249642 0.249642)
							(end 0.2794 0.1778)
						)
						(arc
							(start 0.2794 -0.1778)
							(mid 0.249642 -0.249642)
							(end 0.1778 -0.2794)
						)
					)
					(width 0)
					(fill yes)
				)
			)
		)
	)
	(footprint ""
		(layer "F.Cu")
		(at 471.924126 -52.060094 90)
		(property "Reference" "R942"
			(at 0 0 90)
			(layer "F.SilkS")
			(hide yes)
			(effects
				(font
					(size 1.27 1.27)
				)
			)
		)
		(property "Value" "4K7R2J-2-GP"
			(at 0.064008 -3.993896 90)
			(unlocked yes)
			(layer "F.Fab")
			(hide yes)
			(effects
				(font
					(size 1.016 1.016)
					(thickness 0.1524)
				)
			)
		)
		(property "Device Type" "R402H16"
			(at 0.064008 -5.517896 90)
			(unlocked yes)
			(layer "F.Fab")
			(hide yes)
			(effects
				(font
					(size 1.016 1.016)
					(thickness 0.1524)
				)
			)
		)
		(duplicate_pad_numbers_are_jumpers no)
		(fp_line
			(start 0.508 -0.9398)
			(end -0.508 -0.9398)
			(stroke
				(width 0.1524)
				(type default)
			)
			(layer "F.SilkS")
		)
		(fp_line
			(start -0.508 -0.9398)
			(end -0.508 0.9398)
			(stroke
				(width 0.1524)
				(type default)
			)
			(layer "F.SilkS")
		)
		(fp_rect
			(start -0.508 0.9398)
			(end 0.508 -0.9398)
			(stroke
				(width 0)
				(type default)
			)
			(fill no)
			(layer "F.CrtYd")
		)
		(fp_rect
			(start -0.508 0.9398)
			(end 0.508 -0.9398)
			(stroke
				(width 0)
				(type default)
			)
			(fill no)
			(layer "F.Fab")
		)
		(pad "1" smd custom
			(at 0 -0.4445 90)
			(size 0.1397 0.1397)
			(layers "F.Cu" "F.Mask" "F.Paste")
			(net "P12V_A")
			(options
				(clearance outline)
				(anchor circle)
			)
			(primitives
				(gr_poly
					(pts
						(arc
							(start -0.1778 -0.2794)
							(mid -0.249642 -0.249642)
							(end -0.2794 -0.1778)
						)
						(arc
							(start -0.2794 0.1778)
							(mid -0.249642 0.249642)
							(end -0.1778 0.2794)
						)
						(arc
							(start 0.1778 0.2794)
							(mid 0.249642 0.249642)
							(end 0.2794 0.1778)
						)
						(arc
							(start 0.2794 -0.1778)
							(mid 0.249642 -0.249642)
							(end 0.1778 -0.2794)
						)
					)
					(width 0)
					(fill yes)
				)
			)
		)
		(pad "2" smd custom
			(at 0 0.4445 90)
			(size 0.1397 0.1397)
			(layers "F.Cu" "F.Mask" "F.Paste")
			(net "SW_HDD_P35")
			(options
				(clearance outline)
				(anchor circle)
			)
			(primitives
				(gr_poly
					(pts
						(arc
							(start -0.1778 -0.2794)
							(mid -0.249642 -0.249642)
							(end -0.2794 -0.1778)
						)
						(arc
							(start -0.2794 0.1778)
							(mid -0.249642 0.249642)
							(end -0.1778 0.2794)
						)
						(arc
							(start 0.1778 0.2794)
							(mid 0.249642 0.249642)
							(end 0.2794 0.1778)
						)
						(arc
							(start 0.2794 -0.1778)
							(mid 0.249642 -0.249642)
							(end 0.1778 -0.2794)
						)
					)
					(width 0)
					(fill yes)
				)
			)
		)
	)
	(footprint ""
		(layer "F.Cu")
		(at 272.385028 -11.73353 90)
		(property "Reference" "TP194"
			(at 0 0 90)
			(layer "F.SilkS")
			(hide yes)
			(effects
				(font
					(size 1.27 1.27)
				)
			)
		)
		(property "Value" "TPAD32-GP"
			(at -0.0508 -1.6764 90)
			(unlocked yes)
			(layer "F.Fab")
			(hide yes)
			(effects
				(font
					(size 1.016 1.016)
					(thickness 0.1524)
				)
			)
		)
		(property "Device Type" "TPAD32"
			(at -0.0508 -3.2004 90)
			(unlocked yes)
			(layer "F.Fab")
			(hide yes)
			(effects
				(font
					(size 1.016 1.016)
					(thickness 0.1524)
				)
			)
		)
		(duplicate_pad_numbers_are_jumpers no)
		(fp_poly
			(pts
				(arc
					(start 0 0.4064)
					(mid 0 -0.4064)
					(end 0 0.4064)
				)
			)
			(stroke
				(width 0)
				(type default)
			)
			(fill no)
			(layer "F.CrtYd")
		)
		(fp_poly
			(pts
				(arc
					(start 0 0.7112)
					(mid 0 -0.7112)
					(end 0 0.7112)
				)
			)
			(stroke
				(width 0)
				(type default)
			)
			(fill no)
			(layer "F.Fab")
		)
		(pad "1" smd circle
			(at 0 0 90)
			(size 0.8128 0.8128)
			(layers "F.Cu" "F.Mask" "F.Paste")
			(net "TP_COMP_B_NCSI_TXD1")
		)
	)
	(footprint ""
		(layer "F.Cu")
		(at 32.463486 -273.660616 90)
		(property "Reference" "C507"
			(at 0 0 90)
			(layer "F.SilkS")
			(hide yes)
			(effects
				(font
					(size 1.27 1.27)
				)
			)
		)
		(property "Value" "SCD01U16V1KX-GP"
			(at -2.8321 -1.7399 90)
			(unlocked yes)
			(layer "F.Fab")
			(hide yes)
			(effects
				(font
					(size 1.016 1.016)
					(thickness 0.1524)
				)
			)
		)
		(property "Device Type" "C0201H13"
			(at -2.8321 -3.2639 90)
			(unlocked yes)
			(layer "F.Fab")
			(hide yes)
			(effects
				(font
					(size 1.016 1.016)
					(thickness 0.1524)
				)
			)
		)
		(duplicate_pad_numbers_are_jumpers no)
		(fp_rect
			(start -0.2794 0.6477)
			(end 0.2794 -0.6477)
			(stroke
				(width 0)
				(type default)
			)
			(fill no)
			(layer "F.CrtYd")
		)
		(fp_rect
			(start -0.2794 0.6477)
			(end 0.2794 -0.6477)
			(stroke
				(width 0)
				(type default)
			)
			(fill no)
			(layer "F.Fab")
		)
		(pad "1" smd custom
			(at 0 -0.2794 90)
			(size 0.0762 0.0762)
			(layers "F.Cu" "F.Mask" "F.Paste")
			(net "SAS_HDD_RX_P0")
			(options
				(clearance outline)
				(anchor circle)
			)
			(primitives
				(gr_poly
					(pts
						(arc
							(start 0.1524 -0.127)
							(mid 0.137521 -0.162921)
							(end 0.1016 -0.1778)
						)
						(arc
							(start -0.1016 -0.1778)
							(mid -0.137521 -0.162921)
							(end -0.1524 -0.127)
						)
						(arc
							(start -0.1524 0.127)
							(mid -0.137521 0.162921)
							(end -0.1016 0.1778)
						)
						(arc
							(start 0.1016 0.1778)
							(mid 0.137521 0.162921)
							(end 0.1524 0.127)
						)
					)
					(width 0)
					(fill yes)
				)
			)
		)
		(pad "2" smd custom
			(at 0 0.2794 90)
			(size 0.0762 0.0762)
			(layers "F.Cu" "F.Mask" "F.Paste")
			(net "PHY_SCC_A_TO_DRV_A_0_DP")
			(options
				(clearance outline)
				(anchor circle)
			)
			(primitives
				(gr_poly
					(pts
						(arc
							(start 0.1524 -0.127)
							(mid 0.137521 -0.162921)
							(end 0.1016 -0.1778)
						)
						(arc
							(start -0.1016 -0.1778)
							(mid -0.137521 -0.162921)
							(end -0.1524 -0.127)
						)
						(arc
							(start -0.1524 0.127)
							(mid -0.137521 0.162921)
							(end -0.1016 0.1778)
						)
						(arc
							(start 0.1016 0.1778)
							(mid 0.137521 0.162921)
							(end 0.1524 0.127)
						)
					)
					(width 0)
					(fill yes)
				)
			)
		)
	)
	(footprint ""
		(layer "F.Cu")
		(at 333.502 -73.954894 180)
		(property "Reference" "C436"
			(at 0 0 180)
			(layer "F.SilkS")
			(hide yes)
			(effects
				(font
					(size 1.27 1.27)
				)
			)
		)
		(property "Value" "SC4D7U25V5KX-1-GP"
			(at -0.0762 -6.1214 180)
			(unlocked yes)
			(layer "F.Fab")
			(hide yes)
			(effects
				(font
					(size 1.016 1.016)
					(thickness 0.1524)
				)
			)
		)
		(property "Device Type" "C805H58"
			(at -0.0762 -8.1534 180)
			(unlocked yes)
			(layer "F.Fab")
			(hide yes)
			(effects
				(font
					(size 1.016 1.016)
					(thickness 0.1524)
				)
			)
		)
		(duplicate_pad_numbers_are_jumpers no)
		(fp_line
			(start 0.635 0)
			(end -0.635 0)
			(stroke
				(width 0.508)
				(type default)
			)
			(layer "F.SilkS")
		)
		(fp_rect
			(start -0.9652 1.778)
			(end 0.9652 -1.778)
			(stroke
				(width 0)
				(type default)
			)
			(fill no)
			(layer "F.CrtYd")
		)
		(fp_poly
			(pts
				(xy -0.9652 -1.778) (xy 0.9652 -1.778) (xy 0.9652 1.778) (xy -0.9652 1.778)
			)
			(stroke
				(width 0)
				(type default)
			)
			(fill no)
			(layer "F.Fab")
		)
		(pad "1" smd rect
			(at 0 -0.9652 180)
			(size 1.397 1.143)
			(layers "F.Cu" "F.Mask" "F.Paste")
			(net "P12V_HDD30")
		)
		(pad "2" smd rect
			(at 0 0.9652 180)
			(size 1.397 1.143)
			(layers "F.Cu" "F.Mask" "F.Paste")
			(net "GND")
		)
	)
	(footprint ""
		(layer "F.Cu")
		(at 339.47227 -245.31955 -90)
		(property "Reference" "R480"
			(at 0 0 270)
			(layer "F.SilkS")
			(hide yes)
			(effects
				(font
					(size 1.27 1.27)
				)
			)
		)
		(property "Value" "4K7R2J-2-GP"
			(at 0.064008 -3.993896 270)
			(unlocked yes)
			(layer "F.Fab")
			(hide yes)
			(effects
				(font
					(size 1.016 1.016)
					(thickness 0.1524)
				)
			)
		)
		(property "Device Type" "R402H16"
			(at 0.064008 -5.517896 270)
			(unlocked yes)
			(layer "F.Fab")
			(hide yes)
			(effects
				(font
					(size 1.016 1.016)
					(thickness 0.1524)
				)
			)
		)
		(duplicate_pad_numbers_are_jumpers no)
		(fp_line
			(start -0.508 -0.9398)
			(end -0.508 0.9398)
			(stroke
				(width 0.1524)
				(type default)
			)
			(layer "F.SilkS")
		)
		(fp_line
			(start 0.508 -0.9398)
			(end -0.508 -0.9398)
			(stroke
				(width 0.1524)
				(type default)
			)
			(layer "F.SilkS")
		)
		(fp_rect
			(start -0.508 0.9398)
			(end 0.508 -0.9398)
			(stroke
				(width 0)
				(type default)
			)
			(fill no)
			(layer "F.CrtYd")
		)
		(fp_rect
			(start -0.508 0.9398)
			(end 0.508 -0.9398)
			(stroke
				(width 0)
				(type default)
			)
			(fill no)
			(layer "F.Fab")
		)
		(pad "1" smd custom
			(at 0 -0.4445 270)
			(size 0.1397 0.1397)
			(layers "F.Cu" "F.Mask" "F.Paste")
			(net "DRIVE_A_7_ACT")
			(options
				(clearance outline)
				(anchor circle)
			)
			(primitives
				(gr_poly
					(pts
						(arc
							(start -0.1778 -0.2794)
							(mid -0.249642 -0.249642)
							(end -0.2794 -0.1778)
						)
						(arc
							(start -0.2794 0.1778)
							(mid -0.249642 0.249642)
							(end -0.1778 0.2794)
						)
						(arc
							(start 0.1778 0.2794)
							(mid 0.249642 0.249642)
							(end 0.2794 0.1778)
						)
						(arc
							(start 0.2794 -0.1778)
							(mid 0.249642 -0.249642)
							(end 0.1778 -0.2794)
						)
					)
					(width 0)
					(fill yes)
				)
			)
		)
		(pad "2" smd custom
			(at 0 0.4445 270)
			(size 0.1397 0.1397)
			(layers "F.Cu" "F.Mask" "F.Paste")
			(net "GND")
			(options
				(clearance outline)
				(anchor circle)
			)
			(primitives
				(gr_poly
					(pts
						(arc
							(start -0.1778 -0.2794)
							(mid -0.249642 -0.249642)
							(end -0.2794 -0.1778)
						)
						(arc
							(start -0.2794 0.1778)
							(mid -0.249642 0.249642)
							(end -0.1778 0.2794)
						)
						(arc
							(start 0.1778 0.2794)
							(mid 0.249642 0.249642)
							(end 0.2794 0.1778)
						)
						(arc
							(start 0.2794 -0.1778)
							(mid 0.249642 -0.249642)
							(end 0.1778 -0.2794)
						)
					)
					(width 0)
					(fill yes)
				)
			)
		)
	)
	(footprint ""
		(layer "F.Cu")
		(at 298.91609 -155.684728 180)
		(property "Reference" "R994"
			(at 0 0 180)
			(layer "F.SilkS")
			(hide yes)
			(effects
				(font
					(size 1.27 1.27)
				)
			)
		)
		(property "Value" "100KR2F-L1-GP"
			(at 0.064008 -3.993896 180)
			(unlocked yes)
			(layer "F.Fab")
			(hide yes)
			(effects
				(font
					(size 1.016 1.016)
					(thickness 0.1524)
				)
			)
		)
		(property "Device Type" "R402H16"
			(at 0.064008 -5.517896 180)
			(unlocked yes)
			(layer "F.Fab")
			(hide yes)
			(effects
				(font
					(size 1.016 1.016)
					(thickness 0.1524)
				)
			)
		)
		(duplicate_pad_numbers_are_jumpers no)
		(fp_line
			(start 0.508 -0.9398)
			(end -0.508 -0.9398)
			(stroke
				(width 0.1524)
				(type default)
			)
			(layer "F.SilkS")
		)
		(fp_line
			(start -0.508 -0.9398)
			(end -0.508 0.9398)
			(stroke
				(width 0.1524)
				(type default)
			)
			(layer "F.SilkS")
		)
		(fp_rect
			(start -0.508 0.9398)
			(end 0.508 -0.9398)
			(stroke
				(width 0)
				(type default)
			)
			(fill no)
			(layer "F.CrtYd")
		)
		(fp_rect
			(start -0.508 0.9398)
			(end 0.508 -0.9398)
			(stroke
				(width 0)
				(type default)
			)
			(fill no)
			(layer "F.Fab")
		)
		(pad "1" smd custom
			(at 0 -0.4445 180)
			(size 0.1397 0.1397)
			(layers "F.Cu" "F.Mask" "F.Paste")
			(net "PCIE_COMP_B_TO_IOM_B_RST_2")
			(options
				(clearance outline)
				(anchor circle)
			)
			(primitives
				(gr_poly
					(pts
						(arc
							(start -0.1778 -0.2794)
							(mid -0.249642 -0.249642)
							(end -0.2794 -0.1778)
						)
						(arc
							(start -0.2794 0.1778)
							(mid -0.249642 0.249642)
							(end -0.1778 0.2794)
						)
						(arc
							(start 0.1778 0.2794)
							(mid 0.249642 0.249642)
							(end 0.2794 0.1778)
						)
						(arc
							(start 0.2794 -0.1778)
							(mid 0.249642 -0.249642)
							(end 0.1778 -0.2794)
						)
					)
					(width 0)
					(fill yes)
				)
			)
		)
		(pad "2" smd custom
			(at 0 0.4445 180)
			(size 0.1397 0.1397)
			(layers "F.Cu" "F.Mask" "F.Paste")
			(net "GND")
			(options
				(clearance outline)
				(anchor circle)
			)
			(primitives
				(gr_poly
					(pts
						(arc
							(start -0.1778 -0.2794)
							(mid -0.249642 -0.249642)
							(end -0.2794 -0.1778)
						)
						(arc
							(start -0.2794 0.1778)
							(mid -0.249642 0.249642)
							(end -0.1778 0.2794)
						)
						(arc
							(start 0.1778 0.2794)
							(mid 0.249642 0.249642)
							(end 0.2794 0.1778)
						)
						(arc
							(start 0.2794 -0.1778)
							(mid 0.249642 -0.249642)
							(end 0.1778 -0.2794)
						)
					)
					(width 0)
					(fill yes)
				)
			)
		)
	)
	(footprint ""
		(layer "F.Cu")
		(at 333.57185 -69.434964 -90)
		(property "Reference" "R821"
			(at 0 0 270)
			(layer "F.SilkS")
			(hide yes)
			(effects
				(font
					(size 1.27 1.27)
				)
			)
		)
		(property "Value" "2R6F-GP"
			(at -0.0508 -4.8514 270)
			(unlocked yes)
			(layer "F.Fab")
			(hide yes)
			(effects
				(font
					(size 1.016 1.016)
					(thickness 0.1524)
				)
			)
		)
		(property "Device Type" "R1206H26"
			(at 0 -6.3754 270)
			(unlocked yes)
			(layer "F.Fab")
			(hide yes)
			(effects
				(font
					(size 1.016 1.016)
					(thickness 0.1524)
				)
			)
		)
		(duplicate_pad_numbers_are_jumpers no)
		(fp_line
			(start -1.016 2.2352)
			(end -1.016 -2.2352)
			(stroke
				(width 0.1524)
				(type default)
			)
			(layer "F.SilkS")
		)
		(fp_line
			(start 1.016 2.2352)
			(end -1.016 2.2352)
			(stroke
				(width 0.1524)
				(type default)
			)
			(layer "F.SilkS")
		)
		(fp_line
			(start -1.016 -2.2352)
			(end 1.016 -2.2352)
			(stroke
				(width 0.1524)
				(type default)
			)
			(layer "F.SilkS")
		)
		(fp_line
			(start 1.016 -2.2352)
			(end 1.016 2.2352)
			(stroke
				(width 0.1524)
				(type default)
			)
			(layer "F.SilkS")
		)
		(fp_rect
			(start -1.0922 2.3114)
			(end 1.0922 -2.3114)
			(stroke
				(width 0)
				(type default)
			)
			(fill no)
			(layer "F.CrtYd")
		)
		(fp_poly
			(pts
				(xy -1.0922 -2.3114) (xy 1.0922 -2.3114) (xy 1.0922 2.3114) (xy -1.0922 2.3114)
			)
			(stroke
				(width 0)
				(type default)
			)
			(fill no)
			(layer "F.Fab")
		)
		(pad "1" smd rect
			(at 0 -1.397 270)
			(size 1.651 1.27)
			(layers "F.Cu" "F.Mask" "F.Paste")
			(net "P12V_HDD30")
		)
		(pad "2" smd rect
			(at 0 1.397 270)
			(size 1.651 1.27)
			(layers "F.Cu" "F.Mask" "F.Paste")
			(net "12V_PRE_30")
		)
	)
	(footprint ""
		(layer "F.Cu")
		(at 79.974948 -46.649894 180)
		(property "Reference" "D26"
			(at 0 0 180)
			(layer "F.SilkS")
			(hide yes)
			(effects
				(font
					(size 1.27 1.27)
				)
			)
		)
		(property "Value" "RB551V30-GP"
			(at 0 -6.7818 180)
			(unlocked yes)
			(layer "F.Fab")
			(hide yes)
			(effects
				(font
					(size 1.016 1.016)
					(thickness 0.1524)
				)
			)
		)
		(property "Device Type" "SOD323AKH38"
			(at 0 -8.6868 180)
			(unlocked yes)
			(layer "F.Fab")
			(hide yes)
			(effects
				(font
					(size 1.016 1.016)
					(thickness 0.1524)
				)
			)
		)
		(duplicate_pad_numbers_are_jumpers no)
		(fp_line
			(start 0.889 2.159)
			(end -0.889 2.159)
			(stroke
				(width 0.1524)
				(type default)
			)
			(layer "F.SilkS")
		)
		(fp_line
			(start 0.889 -1.9304)
			(end 0.889 2.159)
			(stroke
				(width 0.1524)
				(type default)
			)
			(layer "F.SilkS")
		)
		(fp_line
			(start 0.762 2.0574)
			(end -0.762 2.0574)
			(stroke
				(width 0.508)
				(type default)
			)
			(layer "F.SilkS")
		)
		(fp_line
			(start -0.889 2.159)
			(end -0.889 -1.9304)
			(stroke
				(width 0.1524)
				(type default)
			)
			(layer "F.SilkS")
		)
		(fp_line
			(start -0.889 -1.9304)
			(end 0.889 -1.9304)
			(stroke
				(width 0.1524)
				(type default)
			)
			(layer "F.SilkS")
		)
		(fp_rect
			(start -1.016 2.3114)
			(end 1.016 -2.0066)
			(stroke
				(width 0)
				(type default)
			)
			(fill no)
			(layer "F.CrtYd")
		)
		(fp_poly
			(pts
				(xy -1.016 -2.0066) (xy 1.016 -2.0066) (xy 1.016 2.3114) (xy -1.016 2.3114)
			)
			(stroke
				(width 0)
				(type default)
			)
			(fill no)
			(layer "F.Fab")
		)
		(pad "A" smd rect
			(at 0 -1.143 180)
			(size 0.5588 1.016)
			(layers "F.Cu" "F.Mask" "F.Paste")
			(net "SW_HDD_R26")
		)
		(pad "K" smd rect
			(at 0 1.143 180)
			(size 0.5588 1.016)
			(layers "F.Cu" "F.Mask" "F.Paste")
			(net "SW_HDD_N26")
		)
	)
	(footprint ""
		(layer "F.Cu")
		(at 224.546922 -155.42387 -90)
		(property "Reference" "TP210"
			(at 0 0 270)
			(layer "F.SilkS")
			(hide yes)
			(effects
				(font
					(size 1.27 1.27)
				)
			)
		)
		(property "Value" "TPAD32-GP"
			(at -0.0508 -1.6764 270)
			(unlocked yes)
			(layer "F.Fab")
			(hide yes)
			(effects
				(font
					(size 1.016 1.016)
					(thickness 0.1524)
				)
			)
		)
		(property "Device Type" "TPAD32"
			(at -0.0508 -3.2004 270)
			(unlocked yes)
			(layer "F.Fab")
			(hide yes)
			(effects
				(font
					(size 1.016 1.016)
					(thickness 0.1524)
				)
			)
		)
		(duplicate_pad_numbers_are_jumpers no)
		(fp_poly
			(pts
				(arc
					(start 0 -0.4064)
					(mid 0 0.4064)
					(end 0 -0.4064)
				)
			)
			(stroke
				(width 0)
				(type default)
			)
			(fill no)
			(layer "F.CrtYd")
		)
		(fp_poly
			(pts
				(arc
					(start 0 -0.7112)
					(mid 0 0.7112)
					(end 0 -0.7112)
				)
			)
			(stroke
				(width 0)
				(type default)
			)
			(fill no)
			(layer "F.Fab")
		)
		(pad "1" smd circle
			(at 0 0 270)
			(size 0.8128 0.8128)
			(layers "F.Cu" "F.Mask" "F.Paste")
			(net "TP_COMP_A_KR_P0_TX_DN")
		)
	)
	(footprint ""
		(layer "F.Cu")
		(at 267.00099 -145.858738 90)
		(property "Reference" "TP227"
			(at 0 0 90)
			(layer "F.SilkS")
			(hide yes)
			(effects
				(font
					(size 1.27 1.27)
				)
			)
		)
		(property "Value" "TPAD32-GP"
			(at -0.0508 -1.6764 90)
			(unlocked yes)
			(layer "F.Fab")
			(hide yes)
			(effects
				(font
					(size 1.016 1.016)
					(thickness 0.1524)
				)
			)
		)
		(property "Device Type" "TPAD32"
			(at -0.0508 -3.2004 90)
			(unlocked yes)
			(layer "F.Fab")
			(hide yes)
			(effects
				(font
					(size 1.016 1.016)
					(thickness 0.1524)
				)
			)
		)
		(duplicate_pad_numbers_are_jumpers no)
		(fp_poly
			(pts
				(arc
					(start 0 0.4064)
					(mid 0 -0.4064)
					(end 0 0.4064)
				)
			)
			(stroke
				(width 0)
				(type default)
			)
			(fill no)
			(layer "F.CrtYd")
		)
		(fp_poly
			(pts
				(arc
					(start 0 0.7112)
					(mid 0 -0.7112)
					(end 0 0.7112)
				)
			)
			(stroke
				(width 0)
				(type default)
			)
			(fill no)
			(layer "F.Fab")
		)
		(pad "1" smd circle
			(at 0 0 90)
			(size 0.8128 0.8128)
			(layers "F.Cu" "F.Mask" "F.Paste")
			(net "TP_SMB_COMP_B_NIC_SDA")
		)
	)
	(footprint ""
		(layer "F.Cu")
		(at 282.0162 12.2936 90)
		(property "Reference" "C108"
			(at 0 0 90)
			(layer "F.SilkS")
			(hide yes)
			(effects
				(font
					(size 1.27 1.27)
				)
			)
		)
		(property "Value" "SC1U16V3KX-5GP"
			(at 0 -2.8194 90)
			(unlocked yes)
			(layer "F.Fab")
			(hide yes)
			(effects
				(font
					(size 1.016 1.016)
					(thickness 0.1524)
				)
			)
		)
		(property "Device Type" "C603H36"
			(at 0 -4.3434 90)
			(unlocked yes)
			(layer "F.Fab")
			(hide yes)
			(effects
				(font
					(size 1.016 1.016)
					(thickness 0.1524)
				)
			)
		)
		(duplicate_pad_numbers_are_jumpers no)
		(fp_line
			(start 0.508 0)
			(end -0.508 0)
			(stroke
				(width 0.2032)
				(type default)
			)
			(layer "F.SilkS")
		)
		(fp_rect
			(start -0.5842 1.3335)
			(end 0.5842 -1.3335)
			(stroke
				(width 0)
				(type default)
			)
			(fill no)
			(layer "F.CrtYd")
		)
		(fp_rect
			(start -0.5842 1.3335)
			(end 0.5842 -1.3335)
			(stroke
				(width 0)
				(type default)
			)
			(fill no)
			(layer "F.Fab")
		)
		(pad "1" smd custom
			(at 0 -0.762 90)
			(size 0.2159 0.2159)
			(layers "F.Cu" "F.Mask" "F.Paste")
			(net "P3V3_BIAS")
			(options
				(clearance outline)
				(anchor circle)
			)
			(primitives
				(gr_poly
					(pts
						(arc
							(start -0.3302 -0.4318)
							(mid -0.402042 -0.402042)
							(end -0.4318 -0.3302)
						)
						(arc
							(start -0.4318 0.3302)
							(mid -0.402042 0.402042)
							(end -0.3302 0.4318)
						)
						(arc
							(start 0.3302 0.4318)
							(mid 0.402042 0.402042)
							(end 0.4318 0.3302)
						)
						(arc
							(start 0.4318 -0.3302)
							(mid 0.402042 -0.402042)
							(end 0.3302 -0.4318)
						)
					)
					(width 0)
					(fill yes)
				)
			)
		)
		(pad "2" smd custom
			(at 0 0.762 90)
			(size 0.2159 0.2159)
			(layers "F.Cu" "F.Mask" "F.Paste")
			(net "GND")
			(options
				(clearance outline)
				(anchor circle)
			)
			(primitives
				(gr_poly
					(pts
						(arc
							(start -0.3302 -0.4318)
							(mid -0.402042 -0.402042)
							(end -0.4318 -0.3302)
						)
						(arc
							(start -0.4318 0.3302)
							(mid -0.402042 0.402042)
							(end -0.3302 0.4318)
						)
						(arc
							(start 0.3302 0.4318)
							(mid 0.402042 0.402042)
							(end 0.4318 0.3302)
						)
						(arc
							(start 0.4318 -0.3302)
							(mid 0.402042 -0.402042)
							(end 0.3302 -0.4318)
						)
					)
					(width 0)
					(fill yes)
				)
			)
		)
	)
	(footprint ""
		(layer "F.Cu")
		(at 266.999974 -142.840964 90)
		(property "Reference" "TP242"
			(at 0 0 90)
			(layer "F.SilkS")
			(hide yes)
			(effects
				(font
					(size 1.27 1.27)
				)
			)
		)
		(property "Value" "TPAD32-GP"
			(at -0.0508 -1.6764 90)
			(unlocked yes)
			(layer "F.Fab")
			(hide yes)
			(effects
				(font
					(size 1.016 1.016)
					(thickness 0.1524)
				)
			)
		)
		(property "Device Type" "TPAD32"
			(at -0.0508 -3.2004 90)
			(unlocked yes)
			(layer "F.Fab")
			(hide yes)
			(effects
				(font
					(size 1.016 1.016)
					(thickness 0.1524)
				)
			)
		)
		(duplicate_pad_numbers_are_jumpers no)
		(fp_poly
			(pts
				(arc
					(start 0 0.4064)
					(mid 0 -0.4064)
					(end 0 0.4064)
				)
			)
			(stroke
				(width 0)
				(type default)
			)
			(fill no)
			(layer "F.CrtYd")
		)
		(fp_poly
			(pts
				(arc
					(start 0 0.7112)
					(mid 0 -0.7112)
					(end 0 0.7112)
				)
			)
			(stroke
				(width 0)
				(type default)
			)
			(fill no)
			(layer "F.Fab")
		)
		(pad "1" smd circle
			(at 0 0 90)
			(size 0.8128 0.8128)
			(layers "F.Cu" "F.Mask" "F.Paste")
			(net "TP_SMB_COMP_B_NIC_ALERT_N")
		)
	)
	(footprint ""
		(layer "F.Cu")
		(at 168.501568 -151.304244 -90)
		(property "Reference" "Q220"
			(at 0 0 270)
			(layer "F.SilkS")
			(hide yes)
			(effects
				(font
					(size 1.27 1.27)
				)
			)
		)
		(property "Value" "IRFH8201TRPBF-GP"
			(at -4.2164 -4.3688 270)
			(unlocked yes)
			(layer "F.Fab")
			(hide yes)
			(effects
				(font
					(size 1.016 1.016)
					(thickness 0.1524)
				)
			)
		)
		(property "Device Type" "PPAK-5PH42"
			(at -4.2164 -5.8928 270)
			(unlocked yes)
			(layer "F.Fab")
			(hide yes)
			(effects
				(font
					(size 1.016 1.016)
					(thickness 0.1524)
				)
			)
		)
		(duplicate_pad_numbers_are_jumpers no)
		(fp_line
			(start -3.0353 4.9276)
			(end -3.0353 3.9624)
			(stroke
				(width 0.3302)
				(type default)
			)
			(layer "F.SilkS")
		)
		(fp_line
			(start -1.9431 4.9276)
			(end -3.0353 4.9276)
			(stroke
				(width 0.3302)
				(type default)
			)
			(layer "F.SilkS")
		)
		(fp_line
			(start -2.8956 4.826)
			(end -2.8956 -2.794)
			(stroke
				(width 0.1524)
				(type default)
			)
			(layer "F.SilkS")
		)
		(fp_line
			(start 2.8956 4.826)
			(end -2.8956 4.826)
			(stroke
				(width 0.1524)
				(type default)
			)
			(layer "F.SilkS")
		)
		(fp_line
			(start -2.8956 -2.794)
			(end 2.8956 -2.794)
			(stroke
				(width 0.1524)
				(type default)
			)
			(layer "F.SilkS")
		)
		(fp_line
			(start 2.8956 -2.794)
			(end 2.8956 4.826)
			(stroke
				(width 0.1524)
				(type default)
			)
			(layer "F.SilkS")
		)
		(fp_poly
			(pts
				(xy -2.3622 5.334) (xy -1.4986 5.334) (xy -1.9304 4.9022)
			)
			(stroke
				(width 0)
				(type default)
			)
			(fill yes)
			(layer "F.SilkS")
		)
		(fp_poly
			(pts
				(xy -2.6416 2.54) (xy -0.3556 2.54) (xy -0.3556 0.3556) (xy -2.6416 0.3556)
			)
			(stroke
				(width 0)
				(type default)
			)
			(fill yes)
			(layer "F.Paste")
		)
		(fp_poly
			(pts
				(xy 0.3556 2.54) (xy 2.6416 2.54) (xy 2.6416 0.3556) (xy 0.3556 0.3556)
			)
			(stroke
				(width 0)
				(type default)
			)
			(fill yes)
			(layer "F.Paste")
		)
		(fp_poly
			(pts
				(xy -2.6416 -0.3556) (xy -0.3556 -0.3556) (xy -0.3556 -2.54) (xy -2.6416 -2.54)
			)
			(stroke
				(width 0)
				(type default)
			)
			(fill yes)
			(layer "F.Paste")
		)
		(fp_poly
			(pts
				(xy 0.3556 -0.3556) (xy 2.6416 -0.3556) (xy 2.6416 -2.54) (xy 0.3556 -2.54)
			)
			(stroke
				(width 0)
				(type default)
			)
			(fill yes)
			(layer "F.Paste")
		)
		(fp_rect
			(start -2.5781 3.9878)
			(end 2.5781 -2.1082)
			(stroke
				(width 0)
				(type default)
			)
			(fill no)
			(layer "F.CrtYd")
		)
		(fp_poly
			(pts
				(xy -3.1496 5.08) (xy -3.1496 -3.048) (xy 3.1496 -3.048) (xy 3.1496 3.9751) (xy 2.5781 3.9751) (xy 2.5781 -2.1082)
				(xy -2.5781 -2.1082) (xy -2.5781 3.9878) (xy 3.1496 3.9878) (xy 3.1496 5.08)
			)
			(stroke
				(width 0)
				(type default)
			)
			(fill no)
			(layer "F.CrtYd")
		)
		(fp_rect
			(start -3.1496 5.08)
			(end 3.1496 -3.048)
			(stroke
				(width 0)
				(type default)
			)
			(fill no)
			(layer "F.Fab")
		)
		(pad "1" smd rect
			(at -1.905 3.81 270)
			(size 0.762 1.524)
			(layers "F.Cu" "F.Mask" "F.Paste")
			(net "P12V_A_COMP")
		)
		(pad "2" smd rect
			(at -0.635 3.81 270)
			(size 0.762 1.524)
			(layers "F.Cu" "F.Mask" "F.Paste")
			(net "P12V_A_COMP")
		)
		(pad "3" smd rect
			(at 0.635 3.81 270)
			(size 0.762 1.524)
			(layers "F.Cu" "F.Mask" "F.Paste")
			(net "P12V_A_COMP")
		)
		(pad "4" smd rect
			(at 1.905 3.81 270)
			(size 0.762 1.524)
			(layers "F.Cu" "F.Mask" "F.Paste")
			(net "MB0_12V_CTRL_GATE1")
		)
		(pad "5" smd rect
			(at 0 0 270)
			(size 5.2832 5.08)
			(layers "F.Cu" "F.Mask" "F.Paste")
			(net "MB0_P12V_R")
		)
		(pad "6" smd rect
			(at 0.635 -2.032 270)
			(size 0.0254 0.0254)
			(layers "F.Cu" "F.Mask" "F.Paste")
			(net "MB0_P12V_R")
		)
		(pad "7" smd rect
			(at -0.635 -2.032 270)
			(size 0.0254 0.0254)
			(layers "F.Cu" "F.Mask" "F.Paste")
			(net "MB0_P12V_R")
		)
		(pad "8" smd rect
			(at -1.905 -2.032 270)
			(size 0.0254 0.0254)
			(layers "F.Cu" "F.Mask" "F.Paste")
			(net "MB0_P12V_R")
		)
	)
	(footprint ""
		(layer "F.Cu")
		(at 35.625024 -246.827548 90)
		(property "Reference" "C605"
			(at 0 0 90)
			(layer "F.SilkS")
			(hide yes)
			(effects
				(font
					(size 1.27 1.27)
				)
			)
		)
		(property "Value" "SCD1U16V2KX-3GP"
			(at 1.1811 -2.7051 90)
			(unlocked yes)
			(layer "F.Fab")
			(hide yes)
			(effects
				(font
					(size 1.016 1.016)
					(thickness 0.1524)
				)
			)
		)
		(property "Device Type" "C402H22"
			(at 1.1811 -4.2291 90)
			(unlocked yes)
			(layer "F.Fab")
			(hide yes)
			(effects
				(font
					(size 1.016 1.016)
					(thickness 0.1524)
				)
			)
		)
		(duplicate_pad_numbers_are_jumpers no)
		(fp_rect
			(start -0.4318 0.9525)
			(end 0.4318 -0.9525)
			(stroke
				(width 0)
				(type default)
			)
			(fill no)
			(layer "F.CrtYd")
		)
		(fp_rect
			(start -0.4318 0.9525)
			(end 0.4318 -0.9525)
			(stroke
				(width 0)
				(type default)
			)
			(fill no)
			(layer "F.Fab")
		)
		(pad "1" smd custom
			(at 0 -0.4445 90)
			(size 0.1524 0.1524)
			(layers "F.Cu" "F.Mask" "F.Paste")
			(net "P5V_A_VBST_RC")
			(options
				(clearance outline)
				(anchor circle)
			)
			(primitives
				(gr_poly
					(pts
						(arc
							(start 0.3048 -0.2032)
							(mid 0.275042 -0.275042)
							(end 0.2032 -0.3048)
						)
						(arc
							(start -0.2032 -0.3048)
							(mid -0.275042 -0.275042)
							(end -0.3048 -0.2032)
						)
						(arc
							(start -0.3048 0.2032)
							(mid -0.275042 0.275042)
							(end -0.2032 0.3048)
						)
						(arc
							(start 0.2032 0.3048)
							(mid 0.275042 0.275042)
							(end 0.3048 0.2032)
						)
					)
					(width 0)
					(fill yes)
				)
			)
		)
		(pad "2" smd custom
			(at 0 0.4445 90)
			(size 0.1524 0.1524)
			(layers "F.Cu" "F.Mask" "F.Paste")
			(net "P5V_A_LL")
			(options
				(clearance outline)
				(anchor circle)
			)
			(primitives
				(gr_poly
					(pts
						(arc
							(start 0.3048 -0.2032)
							(mid 0.275042 -0.275042)
							(end 0.2032 -0.3048)
						)
						(arc
							(start -0.2032 -0.3048)
							(mid -0.275042 -0.275042)
							(end -0.3048 -0.2032)
						)
						(arc
							(start -0.3048 0.2032)
							(mid -0.275042 0.275042)
							(end -0.2032 0.3048)
						)
						(arc
							(start 0.2032 0.3048)
							(mid 0.275042 0.275042)
							(end 0.3048 0.2032)
						)
					)
					(width 0)
					(fill yes)
				)
			)
		)
	)
	(footprint ""
		(layer "F.Cu")
		(at 464.9089 -172.851318 90)
		(property "Reference" "C335"
			(at 0 0 90)
			(layer "F.SilkS")
			(hide yes)
			(effects
				(font
					(size 1.27 1.27)
				)
			)
		)
		(property "Value" "SCD033U25V2KX-GP"
			(at 1.1811 -2.7051 90)
			(unlocked yes)
			(layer "F.Fab")
			(hide yes)
			(effects
				(font
					(size 1.016 1.016)
					(thickness 0.1524)
				)
			)
		)
		(property "Device Type" "C402H22"
			(at 1.1811 -4.2291 90)
			(unlocked yes)
			(layer "F.Fab")
			(hide yes)
			(effects
				(font
					(size 1.016 1.016)
					(thickness 0.1524)
				)
			)
		)
		(duplicate_pad_numbers_are_jumpers no)
		(fp_rect
			(start -0.4318 0.9525)
			(end 0.4318 -0.9525)
			(stroke
				(width 0)
				(type default)
			)
			(fill no)
			(layer "F.CrtYd")
		)
		(fp_rect
			(start -0.4318 0.9525)
			(end 0.4318 -0.9525)
			(stroke
				(width 0)
				(type default)
			)
			(fill no)
			(layer "F.Fab")
		)
		(pad "1" smd custom
			(at 0 -0.4445 90)
			(size 0.1524 0.1524)
			(layers "F.Cu" "F.Mask" "F.Paste")
			(net "P12V_A")
			(options
				(clearance outline)
				(anchor circle)
			)
			(primitives
				(gr_poly
					(pts
						(arc
							(start 0.3048 -0.2032)
							(mid 0.275042 -0.275042)
							(end 0.2032 -0.3048)
						)
						(arc
							(start -0.2032 -0.3048)
							(mid -0.275042 -0.275042)
							(end -0.3048 -0.2032)
						)
						(arc
							(start -0.3048 0.2032)
							(mid -0.275042 0.275042)
							(end -0.2032 0.3048)
						)
						(arc
							(start 0.2032 0.3048)
							(mid 0.275042 0.275042)
							(end 0.3048 0.2032)
						)
					)
					(width 0)
					(fill yes)
				)
			)
		)
		(pad "2" smd custom
			(at 0 0.4445 90)
			(size 0.1524 0.1524)
			(layers "F.Cu" "F.Mask" "F.Paste")
			(net "SW_HDD_N22")
			(options
				(clearance outline)
				(anchor circle)
			)
			(primitives
				(gr_poly
					(pts
						(arc
							(start 0.3048 -0.2032)
							(mid 0.275042 -0.275042)
							(end 0.2032 -0.3048)
						)
						(arc
							(start -0.2032 -0.3048)
							(mid -0.275042 -0.275042)
							(end -0.3048 -0.2032)
						)
						(arc
							(start -0.3048 0.2032)
							(mid -0.275042 0.275042)
							(end -0.2032 0.3048)
						)
						(arc
							(start 0.2032 0.3048)
							(mid 0.275042 0.275042)
							(end 0.3048 0.2032)
						)
					)
					(width 0)
					(fill yes)
				)
			)
		)
	)
	(footprint ""
		(layer "F.Cu")
		(at 384.734562 -43.660568 -90)
		(property "Reference" "C455"
			(at 0 0 270)
			(layer "F.SilkS")
			(hide yes)
			(effects
				(font
					(size 1.27 1.27)
				)
			)
		)
		(property "Value" "SCD01U16V1KX-GP"
			(at -2.8321 -1.7399 270)
			(unlocked yes)
			(layer "F.Fab")
			(hide yes)
			(effects
				(font
					(size 1.016 1.016)
					(thickness 0.1524)
				)
			)
		)
		(property "Device Type" "C0201H13"
			(at -2.8321 -3.2639 270)
			(unlocked yes)
			(layer "F.Fab")
			(hide yes)
			(effects
				(font
					(size 1.016 1.016)
					(thickness 0.1524)
				)
			)
		)
		(duplicate_pad_numbers_are_jumpers no)
		(fp_rect
			(start -0.2794 0.6477)
			(end 0.2794 -0.6477)
			(stroke
				(width 0)
				(type default)
			)
			(fill no)
			(layer "F.CrtYd")
		)
		(fp_rect
			(start -0.2794 0.6477)
			(end 0.2794 -0.6477)
			(stroke
				(width 0)
				(type default)
			)
			(fill no)
			(layer "F.Fab")
		)
		(pad "1" smd custom
			(at 0 -0.2794 270)
			(size 0.0762 0.0762)
			(layers "F.Cu" "F.Mask" "F.Paste")
			(net "SAS_HDD_RX_P32")
			(options
				(clearance outline)
				(anchor circle)
			)
			(primitives
				(gr_poly
					(pts
						(arc
							(start 0.1524 -0.127)
							(mid 0.137521 -0.162921)
							(end 0.1016 -0.1778)
						)
						(arc
							(start -0.1016 -0.1778)
							(mid -0.137521 -0.162921)
							(end -0.1524 -0.127)
						)
						(arc
							(start -0.1524 0.127)
							(mid -0.137521 0.162921)
							(end -0.1016 0.1778)
						)
						(arc
							(start 0.1016 0.1778)
							(mid 0.137521 0.162921)
							(end 0.1524 0.127)
						)
					)
					(width 0)
					(fill yes)
				)
			)
		)
		(pad "2" smd custom
			(at 0 0.2794 270)
			(size 0.0762 0.0762)
			(layers "F.Cu" "F.Mask" "F.Paste")
			(net "PHY_SCC_A_TO_DRV_A_32_DP")
			(options
				(clearance outline)
				(anchor circle)
			)
			(primitives
				(gr_poly
					(pts
						(arc
							(start 0.1524 -0.127)
							(mid 0.137521 -0.162921)
							(end 0.1016 -0.1778)
						)
						(arc
							(start -0.1016 -0.1778)
							(mid -0.137521 -0.162921)
							(end -0.1524 -0.127)
						)
						(arc
							(start -0.1524 0.127)
							(mid -0.137521 0.162921)
							(end -0.1016 0.1778)
						)
						(arc
							(start 0.1016 0.1778)
							(mid 0.137521 0.162921)
							(end 0.1524 0.127)
						)
					)
					(width 0)
					(fill yes)
				)
			)
		)
	)
	(footprint ""
		(layer "F.Cu")
		(at 413.016192 -281.115516 90)
		(property "Reference" "R585"
			(at 0 0 90)
			(layer "F.SilkS")
			(hide yes)
			(effects
				(font
					(size 1.27 1.27)
				)
			)
		)
		(property "Value" "4K7R2J-2-GP"
			(at 0.064008 -3.993896 90)
			(unlocked yes)
			(layer "F.Fab")
			(hide yes)
			(effects
				(font
					(size 1.016 1.016)
					(thickness 0.1524)
				)
			)
		)
		(property "Device Type" "R402H16"
			(at 0.064008 -5.517896 90)
			(unlocked yes)
			(layer "F.Fab")
			(hide yes)
			(effects
				(font
					(size 1.016 1.016)
					(thickness 0.1524)
				)
			)
		)
		(duplicate_pad_numbers_are_jumpers no)
		(fp_line
			(start 0.508 -0.9398)
			(end -0.508 -0.9398)
			(stroke
				(width 0.1524)
				(type default)
			)
			(layer "F.SilkS")
		)
		(fp_line
			(start -0.508 -0.9398)
			(end -0.508 0.9398)
			(stroke
				(width 0.1524)
				(type default)
			)
			(layer "F.SilkS")
		)
		(fp_rect
			(start -0.508 0.9398)
			(end 0.508 -0.9398)
			(stroke
				(width 0)
				(type default)
			)
			(fill no)
			(layer "F.CrtYd")
		)
		(fp_rect
			(start -0.508 0.9398)
			(end 0.508 -0.9398)
			(stroke
				(width 0)
				(type default)
			)
			(fill no)
			(layer "F.Fab")
		)
		(pad "1" smd custom
			(at 0 -0.4445 90)
			(size 0.1397 0.1397)
			(layers "F.Cu" "F.Mask" "F.Paste")
			(net "DRIVE_B_33_ACT")
			(options
				(clearance outline)
				(anchor circle)
			)
			(primitives
				(gr_poly
					(pts
						(arc
							(start -0.1778 -0.2794)
							(mid -0.249642 -0.249642)
							(end -0.2794 -0.1778)
						)
						(arc
							(start -0.2794 0.1778)
							(mid -0.249642 0.249642)
							(end -0.1778 0.2794)
						)
						(arc
							(start 0.1778 0.2794)
							(mid 0.249642 0.249642)
							(end 0.2794 0.1778)
						)
						(arc
							(start 0.2794 -0.1778)
							(mid 0.249642 -0.249642)
							(end 0.1778 -0.2794)
						)
					)
					(width 0)
					(fill yes)
				)
			)
		)
		(pad "2" smd custom
			(at 0 0.4445 90)
			(size 0.1397 0.1397)
			(layers "F.Cu" "F.Mask" "F.Paste")
			(net "GND")
			(options
				(clearance outline)
				(anchor circle)
			)
			(primitives
				(gr_poly
					(pts
						(arc
							(start -0.1778 -0.2794)
							(mid -0.249642 -0.249642)
							(end -0.2794 -0.1778)
						)
						(arc
							(start -0.2794 0.1778)
							(mid -0.249642 0.249642)
							(end -0.1778 0.2794)
						)
						(arc
							(start 0.1778 0.2794)
							(mid 0.249642 0.249642)
							(end 0.2794 0.1778)
						)
						(arc
							(start 0.2794 -0.1778)
							(mid 0.249642 -0.249642)
							(end 0.1778 -0.2794)
						)
					)
					(width 0)
					(fill yes)
				)
			)
		)
	)
	(footprint ""
		(layer "F.Cu")
		(at 416.284664 -44.219368 -90)
		(property "Reference" "C467"
			(at 0 0 270)
			(layer "F.SilkS")
			(hide yes)
			(effects
				(font
					(size 1.27 1.27)
				)
			)
		)
		(property "Value" "SCD01U16V1KX-GP"
			(at -2.8321 -1.7399 270)
			(unlocked yes)
			(layer "F.Fab")
			(hide yes)
			(effects
				(font
					(size 1.016 1.016)
					(thickness 0.1524)
				)
			)
		)
		(property "Device Type" "C0201H13"
			(at -2.8321 -3.2639 270)
			(unlocked yes)
			(layer "F.Fab")
			(hide yes)
			(effects
				(font
					(size 1.016 1.016)
					(thickness 0.1524)
				)
			)
		)
		(duplicate_pad_numbers_are_jumpers no)
		(fp_rect
			(start -0.2794 0.6477)
			(end 0.2794 -0.6477)
			(stroke
				(width 0)
				(type default)
			)
			(fill no)
			(layer "F.CrtYd")
		)
		(fp_rect
			(start -0.2794 0.6477)
			(end 0.2794 -0.6477)
			(stroke
				(width 0)
				(type default)
			)
			(fill no)
			(layer "F.Fab")
		)
		(pad "1" smd custom
			(at 0 -0.2794 270)
			(size 0.0762 0.0762)
			(layers "F.Cu" "F.Mask" "F.Paste")
			(net "SAS_HDD_RX_N33")
			(options
				(clearance outline)
				(anchor circle)
			)
			(primitives
				(gr_poly
					(pts
						(arc
							(start 0.1524 -0.127)
							(mid 0.137521 -0.162921)
							(end 0.1016 -0.1778)
						)
						(arc
							(start -0.1016 -0.1778)
							(mid -0.137521 -0.162921)
							(end -0.1524 -0.127)
						)
						(arc
							(start -0.1524 0.127)
							(mid -0.137521 0.162921)
							(end -0.1016 0.1778)
						)
						(arc
							(start 0.1016 0.1778)
							(mid 0.137521 0.162921)
							(end 0.1524 0.127)
						)
					)
					(width 0)
					(fill yes)
				)
			)
		)
		(pad "2" smd custom
			(at 0 0.2794 270)
			(size 0.0762 0.0762)
			(layers "F.Cu" "F.Mask" "F.Paste")
			(net "PHY_SCC_A_TO_DRV_A_33_DN")
			(options
				(clearance outline)
				(anchor circle)
			)
			(primitives
				(gr_poly
					(pts
						(arc
							(start 0.1524 -0.127)
							(mid 0.137521 -0.162921)
							(end 0.1016 -0.1778)
						)
						(arc
							(start -0.1016 -0.1778)
							(mid -0.137521 -0.162921)
							(end -0.1524 -0.127)
						)
						(arc
							(start -0.1524 0.127)
							(mid -0.137521 0.162921)
							(end -0.1016 0.1778)
						)
						(arc
							(start 0.1016 0.1778)
							(mid 0.137521 0.162921)
							(end 0.1524 0.127)
						)
					)
					(width 0)
					(fill yes)
				)
			)
		)
	)
	(footprint ""
		(layer "F.Cu")
		(at 78.323948 -47.183294 180)
		(property "Reference" "R744"
			(at 0 0 180)
			(layer "F.SilkS")
			(hide yes)
			(effects
				(font
					(size 1.27 1.27)
				)
			)
		)
		(property "Value" "200KR2F-L-GP"
			(at 0.064008 -3.993896 180)
			(unlocked yes)
			(layer "F.Fab")
			(hide yes)
			(effects
				(font
					(size 1.016 1.016)
					(thickness 0.1524)
				)
			)
		)
		(property "Device Type" "R402H16"
			(at 0.064008 -5.517896 180)
			(unlocked yes)
			(layer "F.Fab")
			(hide yes)
			(effects
				(font
					(size 1.016 1.016)
					(thickness 0.1524)
				)
			)
		)
		(duplicate_pad_numbers_are_jumpers no)
		(fp_line
			(start 0.508 -0.9398)
			(end -0.508 -0.9398)
			(stroke
				(width 0.1524)
				(type default)
			)
			(layer "F.SilkS")
		)
		(fp_line
			(start -0.508 -0.9398)
			(end -0.508 0.9398)
			(stroke
				(width 0.1524)
				(type default)
			)
			(layer "F.SilkS")
		)
		(fp_rect
			(start -0.508 0.9398)
			(end 0.508 -0.9398)
			(stroke
				(width 0)
				(type default)
			)
			(fill no)
			(layer "F.CrtYd")
		)
		(fp_rect
			(start -0.508 0.9398)
			(end 0.508 -0.9398)
			(stroke
				(width 0)
				(type default)
			)
			(fill no)
			(layer "F.Fab")
		)
		(pad "1" smd custom
			(at 0 -0.4445 180)
			(size 0.1397 0.1397)
			(layers "F.Cu" "F.Mask" "F.Paste")
			(net "SW_HDD_R26")
			(options
				(clearance outline)
				(anchor circle)
			)
			(primitives
				(gr_poly
					(pts
						(arc
							(start -0.1778 -0.2794)
							(mid -0.249642 -0.249642)
							(end -0.2794 -0.1778)
						)
						(arc
							(start -0.2794 0.1778)
							(mid -0.249642 0.249642)
							(end -0.1778 0.2794)
						)
						(arc
							(start 0.1778 0.2794)
							(mid 0.249642 0.249642)
							(end 0.2794 0.1778)
						)
						(arc
							(start 0.2794 -0.1778)
							(mid 0.249642 -0.249642)
							(end 0.1778 -0.2794)
						)
					)
					(width 0)
					(fill yes)
				)
			)
		)
		(pad "2" smd custom
			(at 0 0.4445 180)
			(size 0.1397 0.1397)
			(layers "F.Cu" "F.Mask" "F.Paste")
			(net "SW_HDD_N26")
			(options
				(clearance outline)
				(anchor circle)
			)
			(primitives
				(gr_poly
					(pts
						(arc
							(start -0.1778 -0.2794)
							(mid -0.249642 -0.249642)
							(end -0.2794 -0.1778)
						)
						(arc
							(start -0.2794 0.1778)
							(mid -0.249642 0.249642)
							(end -0.1778 0.2794)
						)
						(arc
							(start 0.1778 0.2794)
							(mid 0.249642 0.249642)
							(end 0.2794 0.1778)
						)
						(arc
							(start 0.2794 -0.1778)
							(mid 0.249642 -0.249642)
							(end 0.1778 -0.2794)
						)
					)
					(width 0)
					(fill yes)
				)
			)
		)
	)
	(footprint ""
		(layer "F.Cu")
		(at 235.823506 -346.789756)
		(property "Reference" "C48"
			(at 0 0 0)
			(layer "F.SilkS")
			(hide yes)
			(effects
				(font
					(size 1.27 1.27)
				)
			)
		)
		(property "Value" "SCD1U16V2KX-3GP"
			(at 1.1811 -2.7051 0)
			(unlocked yes)
			(layer "F.Fab")
			(hide yes)
			(effects
				(font
					(size 1.016 1.016)
					(thickness 0.1524)
				)
			)
		)
		(property "Device Type" "C402H22"
			(at 1.1811 -4.2291 0)
			(unlocked yes)
			(layer "F.Fab")
			(hide yes)
			(effects
				(font
					(size 1.016 1.016)
					(thickness 0.1524)
				)
			)
		)
		(duplicate_pad_numbers_are_jumpers no)
		(fp_rect
			(start -0.4318 0.9525)
			(end 0.4318 -0.9525)
			(stroke
				(width 0)
				(type default)
			)
			(fill no)
			(layer "F.CrtYd")
		)
		(fp_rect
			(start -0.4318 0.9525)
			(end 0.4318 -0.9525)
			(stroke
				(width 0)
				(type default)
			)
			(fill no)
			(layer "F.Fab")
		)
		(pad "1" smd custom
			(at 0 -0.4445)
			(size 0.1524 0.1524)
			(layers "F.Cu" "F.Mask" "F.Paste")
			(net "P5V_A_2_SENSE")
			(options
				(clearance outline)
				(anchor circle)
			)
			(primitives
				(gr_poly
					(pts
						(arc
							(start 0.3048 -0.2032)
							(mid 0.275042 -0.275042)
							(end 0.2032 -0.3048)
						)
						(arc
							(start -0.2032 -0.3048)
							(mid -0.275042 -0.275042)
							(end -0.3048 -0.2032)
						)
						(arc
							(start -0.3048 0.2032)
							(mid -0.275042 0.275042)
							(end -0.2032 0.3048)
						)
						(arc
							(start 0.2032 0.3048)
							(mid 0.275042 0.275042)
							(end 0.3048 0.2032)
						)
					)
					(width 0)
					(fill yes)
				)
			)
		)
		(pad "2" smd custom
			(at 0 0.4445)
			(size 0.1524 0.1524)
			(layers "F.Cu" "F.Mask" "F.Paste")
			(net "GND")
			(options
				(clearance outline)
				(anchor circle)
			)
			(primitives
				(gr_poly
					(pts
						(arc
							(start 0.3048 -0.2032)
							(mid 0.275042 -0.275042)
							(end 0.2032 -0.3048)
						)
						(arc
							(start -0.2032 -0.3048)
							(mid -0.275042 -0.275042)
							(end -0.3048 -0.2032)
						)
						(arc
							(start -0.3048 0.2032)
							(mid -0.275042 0.275042)
							(end -0.2032 0.3048)
						)
						(arc
							(start 0.2032 0.3048)
							(mid 0.275042 0.275042)
							(end 0.3048 0.2032)
						)
					)
					(width 0)
					(fill yes)
				)
			)
		)
	)
	(footprint ""
		(layer "F.Cu")
		(at 279.6032 11.5824)
		(property "Reference" "Q11"
			(at 0 0 0)
			(layer "F.SilkS")
			(hide yes)
			(effects
				(font
					(size 1.27 1.27)
				)
			)
		)
		(property "Value" "MMBT3904TT1G-GP"
			(at 0 -9.7282 0)
			(unlocked yes)
			(layer "F.Fab")
			(hide yes)
			(effects
				(font
					(size 1.016 1.016)
					(thickness 0.1524)
				)
			)
		)
		(property "Device Type" "SC75CBE1D6H36"
			(at 0 -11.6332 0)
			(unlocked yes)
			(layer "F.Fab")
			(hide yes)
			(effects
				(font
					(size 1.016 1.016)
					(thickness 0.1524)
				)
			)
		)
		(duplicate_pad_numbers_are_jumpers no)
		(fp_line
			(start -0.9652 -1.3716)
			(end -0.9652 1.3716)
			(stroke
				(width 0.1524)
				(type default)
			)
			(layer "F.SilkS")
		)
		(fp_line
			(start -0.9652 1.3716)
			(end 0.9652 1.3716)
			(stroke
				(width 0.1524)
				(type default)
			)
			(layer "F.SilkS")
		)
		(fp_line
			(start 0.9652 -1.3716)
			(end -0.9652 -1.3716)
			(stroke
				(width 0.1524)
				(type default)
			)
			(layer "F.SilkS")
		)
		(fp_line
			(start 0.9652 1.3716)
			(end 0.9652 -1.3716)
			(stroke
				(width 0.1524)
				(type default)
			)
			(layer "F.SilkS")
		)
		(fp_rect
			(start -1.0414 1.4478)
			(end 1.0414 -1.4478)
			(stroke
				(width 0)
				(type default)
			)
			(fill no)
			(layer "F.CrtYd")
		)
		(fp_poly
			(pts
				(xy -1.0414 -1.4478) (xy 1.0414 -1.4478) (xy 1.0414 1.4478) (xy -1.0414 1.4478)
			)
			(stroke
				(width 0)
				(type default)
			)
			(fill no)
			(layer "F.Fab")
		)
		(pad "B" smd custom
			(at -0.508 0.7112)
			(size 0.127 0.127)
			(layers "F.Cu" "F.Mask" "F.Paste")
			(net "VCCP")
			(options
				(clearance outline)
				(anchor circle)
			)
			(primitives
				(gr_poly
					(pts
						(arc
							(start -0.044958 0.4572)
							(mid -0.192463 0.399794)
							(end -0.254 0.254)
						)
						(xy -0.254 -0.254)
						(arc
							(start -0.253746 -0.254)
							(mid -0.192968 -0.398936)
							(end -0.04699 -0.4572)
						)
						(arc
							(start 0.04699 -0.4572)
							(mid 0.192989 -0.398958)
							(end 0.253746 -0.254)
						)
						(xy 0.254 -0.254)
						(arc
							(start 0.254 0.254)
							(mid 0.192404 0.399734)
							(end 0.044958 0.4572)
						)
					)
					(width 0)
					(fill yes)
				)
			)
		)
		(pad "C" smd custom
			(at 0 -0.7112)
			(size 0.127 0.127)
			(layers "F.Cu" "F.Mask" "F.Paste")
			(net "P12V_IN")
			(options
				(clearance outline)
				(anchor circle)
			)
			(primitives
				(gr_poly
					(pts
						(arc
							(start -0.044958 0.4572)
							(mid -0.192463 0.399794)
							(end -0.254 0.254)
						)
						(xy -0.254 -0.254)
						(arc
							(start -0.253746 -0.254)
							(mid -0.192968 -0.398936)
							(end -0.04699 -0.4572)
						)
						(arc
							(start 0.04699 -0.4572)
							(mid 0.192989 -0.398958)
							(end 0.253746 -0.254)
						)
						(xy 0.254 -0.254)
						(arc
							(start 0.254 0.254)
							(mid 0.192404 0.399734)
							(end 0.044958 0.4572)
						)
					)
					(width 0)
					(fill yes)
				)
			)
		)
		(pad "E" smd custom
			(at 0.508 0.7112)
			(size 0.127 0.127)
			(layers "F.Cu" "F.Mask" "F.Paste")
			(net "P3V3_BIAS")
			(options
				(clearance outline)
				(anchor circle)
			)
			(primitives
				(gr_poly
					(pts
						(arc
							(start -0.044958 0.4572)
							(mid -0.192463 0.399794)
							(end -0.254 0.254)
						)
						(xy -0.254 -0.254)
						(arc
							(start -0.253746 -0.254)
							(mid -0.192968 -0.398936)
							(end -0.04699 -0.4572)
						)
						(arc
							(start 0.04699 -0.4572)
							(mid 0.192989 -0.398958)
							(end 0.253746 -0.254)
						)
						(xy 0.254 -0.254)
						(arc
							(start 0.254 0.254)
							(mid 0.192404 0.399734)
							(end 0.044958 0.4572)
						)
					)
					(width 0)
					(fill yes)
				)
			)
		)
	)
	(footprint ""
		(layer "F.Cu")
		(at 332.359 -295.826942 180)
		(property "Reference" "C119"
			(at 0 0 180)
			(layer "F.SilkS")
			(hide yes)
			(effects
				(font
					(size 1.27 1.27)
				)
			)
		)
		(property "Value" "SC10U16V6KX-2GP"
			(at -0.0762 -5.1308 180)
			(unlocked yes)
			(layer "F.Fab")
			(hide yes)
			(effects
				(font
					(size 1.016 1.016)
					(thickness 0.1524)
				)
			)
		)
		(property "Device Type" "C1206H71"
			(at -0.127 -6.6548 180)
			(unlocked yes)
			(layer "F.Fab")
			(hide yes)
			(effects
				(font
					(size 1.016 1.016)
					(thickness 0.1524)
				)
			)
		)
		(duplicate_pad_numbers_are_jumpers no)
		(fp_line
			(start 1.016 2.2352)
			(end -1.016 2.2352)
			(stroke
				(width 0.1524)
				(type default)
			)
			(layer "F.SilkS")
		)
		(fp_line
			(start 1.016 0.8382)
			(end 1.016 2.2352)
			(stroke
				(width 0.1524)
				(type default)
			)
			(layer "F.SilkS")
		)
		(fp_line
			(start 1.016 -2.2352)
			(end 1.016 -0.8382)
			(stroke
				(width 0.1524)
				(type default)
			)
			(layer "F.SilkS")
		)
		(fp_line
			(start -1.016 2.2352)
			(end -1.016 0.8382)
			(stroke
				(width 0.1524)
				(type default)
			)
			(layer "F.SilkS")
		)
		(fp_line
			(start -1.016 -0.8382)
			(end -1.016 -2.2352)
			(stroke
				(width 0.1524)
				(type default)
			)
			(layer "F.SilkS")
		)
		(fp_line
			(start -1.016 -2.2352)
			(end 1.016 -2.2352)
			(stroke
				(width 0.1524)
				(type default)
			)
			(layer "F.SilkS")
		)
		(fp_rect
			(start -1.0922 2.3114)
			(end 1.0922 -2.3114)
			(stroke
				(width 0)
				(type default)
			)
			(fill no)
			(layer "F.CrtYd")
		)
		(fp_poly
			(pts
				(xy 1.0922 -2.3114) (xy 1.0922 2.3114) (xy -1.0922 2.3114) (xy -1.0922 -2.3114)
			)
			(stroke
				(width 0)
				(type default)
			)
			(fill no)
			(layer "F.Fab")
		)
		(pad "1" smd rect
			(at 0 -1.397 180)
			(size 1.651 1.27)
			(layers "F.Cu" "F.Mask" "F.Paste")
			(net "P5V_HDD6")
		)
		(pad "2" smd rect
			(at 0 1.397 180)
			(size 1.651 1.27)
			(layers "F.Cu" "F.Mask" "F.Paste")
			(net "GND")
		)
	)
	(footprint ""
		(layer "F.Cu")
		(at 428.152052 -188.954918 180)
		(property "Reference" "C319"
			(at 0 0 180)
			(layer "F.SilkS")
			(hide yes)
			(effects
				(font
					(size 1.27 1.27)
				)
			)
		)
		(property "Value" "SC4D7U25V5KX-1-GP"
			(at -0.0762 -6.1214 180)
			(unlocked yes)
			(layer "F.Fab")
			(hide yes)
			(effects
				(font
					(size 1.016 1.016)
					(thickness 0.1524)
				)
			)
		)
		(property "Device Type" "C805H58"
			(at -0.0762 -8.1534 180)
			(unlocked yes)
			(layer "F.Fab")
			(hide yes)
			(effects
				(font
					(size 1.016 1.016)
					(thickness 0.1524)
				)
			)
		)
		(duplicate_pad_numbers_are_jumpers no)
		(fp_line
			(start 0.635 0)
			(end -0.635 0)
			(stroke
				(width 0.508)
				(type default)
			)
			(layer "F.SilkS")
		)
		(fp_rect
			(start -0.9652 1.778)
			(end 0.9652 -1.778)
			(stroke
				(width 0)
				(type default)
			)
			(fill no)
			(layer "F.CrtYd")
		)
		(fp_poly
			(pts
				(xy -0.9652 -1.778) (xy 0.9652 -1.778) (xy 0.9652 1.778) (xy -0.9652 1.778)
			)
			(stroke
				(width 0)
				(type default)
			)
			(fill no)
			(layer "F.Fab")
		)
		(pad "1" smd rect
			(at 0 -0.9652 180)
			(size 1.397 1.143)
			(layers "F.Cu" "F.Mask" "F.Paste")
			(net "P12V_HDD21")
		)
		(pad "2" smd rect
			(at 0 0.9652 180)
			(size 1.397 1.143)
			(layers "F.Cu" "F.Mask" "F.Paste")
			(net "GND")
		)
	)
	(footprint ""
		(layer "F.Cu")
		(at 331.47 -61.127894 -90)
		(property "Reference" "R819"
			(at 0 0 270)
			(layer "F.SilkS")
			(hide yes)
			(effects
				(font
					(size 1.27 1.27)
				)
			)
		)
		(property "Value" "2R6F-GP"
			(at -0.0508 -4.8514 270)
			(unlocked yes)
			(layer "F.Fab")
			(hide yes)
			(effects
				(font
					(size 1.016 1.016)
					(thickness 0.1524)
				)
			)
		)
		(property "Device Type" "R1206H26"
			(at 0 -6.3754 270)
			(unlocked yes)
			(layer "F.Fab")
			(hide yes)
			(effects
				(font
					(size 1.016 1.016)
					(thickness 0.1524)
				)
			)
		)
		(duplicate_pad_numbers_are_jumpers no)
		(fp_line
			(start -1.016 2.2352)
			(end -1.016 -2.2352)
			(stroke
				(width 0.1524)
				(type default)
			)
			(layer "F.SilkS")
		)
		(fp_line
			(start 1.016 2.2352)
			(end -1.016 2.2352)
			(stroke
				(width 0.1524)
				(type default)
			)
			(layer "F.SilkS")
		)
		(fp_line
			(start -1.016 -2.2352)
			(end 1.016 -2.2352)
			(stroke
				(width 0.1524)
				(type default)
			)
			(layer "F.SilkS")
		)
		(fp_line
			(start 1.016 -2.2352)
			(end 1.016 2.2352)
			(stroke
				(width 0.1524)
				(type default)
			)
			(layer "F.SilkS")
		)
		(fp_rect
			(start -1.0922 2.3114)
			(end 1.0922 -2.3114)
			(stroke
				(width 0)
				(type default)
			)
			(fill no)
			(layer "F.CrtYd")
		)
		(fp_poly
			(pts
				(xy -1.0922 -2.3114) (xy 1.0922 -2.3114) (xy 1.0922 2.3114) (xy -1.0922 2.3114)
			)
			(stroke
				(width 0)
				(type default)
			)
			(fill no)
			(layer "F.Fab")
		)
		(pad "1" smd rect
			(at 0 -1.397 270)
			(size 1.651 1.27)
			(layers "F.Cu" "F.Mask" "F.Paste")
			(net "P5V_HDD30")
		)
		(pad "2" smd rect
			(at 0 1.397 270)
			(size 1.651 1.27)
			(layers "F.Cu" "F.Mask" "F.Paste")
			(net "5V_PRE_30")
		)
	)
	(footprint ""
		(layer "F.Cu")
		(at 67.728846 -180.064918 90)
		(property "Reference" "R433"
			(at 0 0 90)
			(layer "F.SilkS")
			(hide yes)
			(effects
				(font
					(size 1.27 1.27)
				)
			)
		)
		(property "Value" "220R3F-1-GP"
			(at -0.0254 -2.5146 90)
			(unlocked yes)
			(layer "F.Fab")
			(hide yes)
			(effects
				(font
					(size 1.016 1.016)
					(thickness 0.1524)
				)
			)
		)
		(property "Device Type" "R603H22"
			(at -0.0254 -4.0386 90)
			(unlocked yes)
			(layer "F.Fab")
			(hide yes)
			(effects
				(font
					(size 1.016 1.016)
					(thickness 0.1524)
				)
			)
		)
		(duplicate_pad_numbers_are_jumpers no)
		(fp_line
			(start 0.2032 0)
			(end 0.4826 0)
			(stroke
				(width 0.2032)
				(type default)
			)
			(layer "F.SilkS")
		)
		(fp_line
			(start -0.4826 0)
			(end -0.2032 0)
			(stroke
				(width 0.2032)
				(type default)
			)
			(layer "F.SilkS")
		)
		(fp_rect
			(start -0.5842 1.3335)
			(end 0.5842 -1.3335)
			(stroke
				(width 0)
				(type default)
			)
			(fill no)
			(layer "F.CrtYd")
		)
		(fp_rect
			(start -0.5842 1.3335)
			(end 0.5842 -1.3335)
			(stroke
				(width 0)
				(type default)
			)
			(fill no)
			(layer "F.Fab")
		)
		(pad "1" smd custom
			(at 0 -0.762 90)
			(size 0.2159 0.2159)
			(layers "F.Cu" "F.Mask" "F.Paste")
			(net "HDD_PRSNT_13")
			(options
				(clearance outline)
				(anchor circle)
			)
			(primitives
				(gr_poly
					(pts
						(arc
							(start -0.3302 -0.4318)
							(mid -0.402042 -0.402042)
							(end -0.4318 -0.3302)
						)
						(arc
							(start -0.4318 0.3302)
							(mid -0.402042 0.402042)
							(end -0.3302 0.4318)
						)
						(arc
							(start 0.3302 0.4318)
							(mid 0.402042 0.402042)
							(end 0.4318 0.3302)
						)
						(arc
							(start 0.4318 -0.3302)
							(mid 0.402042 -0.402042)
							(end 0.3302 -0.4318)
						)
					)
					(width 0)
					(fill yes)
				)
			)
		)
		(pad "2" smd custom
			(at 0 0.762 90)
			(size 0.2159 0.2159)
			(layers "F.Cu" "F.Mask" "F.Paste")
			(net "DRIVE_A_13_INS")
			(options
				(clearance outline)
				(anchor circle)
			)
			(primitives
				(gr_poly
					(pts
						(arc
							(start -0.3302 -0.4318)
							(mid -0.402042 -0.402042)
							(end -0.4318 -0.3302)
						)
						(arc
							(start -0.4318 0.3302)
							(mid -0.402042 0.402042)
							(end -0.3302 0.4318)
						)
						(arc
							(start 0.3302 0.4318)
							(mid 0.402042 0.402042)
							(end 0.4318 0.3302)
						)
						(arc
							(start 0.4318 -0.3302)
							(mid 0.402042 -0.402042)
							(end 0.3302 -0.4318)
						)
					)
					(width 0)
					(fill yes)
				)
			)
		)
	)
	(footprint ""
		(layer "F.Cu")
		(at 151.327866 -139.149074 -90)
		(property "Reference" "C543"
			(at 0 0 270)
			(layer "F.SilkS")
			(hide yes)
			(effects
				(font
					(size 1.27 1.27)
				)
			)
		)
		(property "Value" "SC1U25V3KX-GP"
			(at 0 -2.8194 270)
			(unlocked yes)
			(layer "F.Fab")
			(hide yes)
			(effects
				(font
					(size 1.016 1.016)
					(thickness 0.1524)
				)
			)
		)
		(property "Device Type" "C603H36"
			(at 0 -4.3434 270)
			(unlocked yes)
			(layer "F.Fab")
			(hide yes)
			(effects
				(font
					(size 1.016 1.016)
					(thickness 0.1524)
				)
			)
		)
		(duplicate_pad_numbers_are_jumpers no)
		(fp_line
			(start 0.508 0)
			(end -0.508 0)
			(stroke
				(width 0.2032)
				(type default)
			)
			(layer "F.SilkS")
		)
		(fp_rect
			(start -0.5842 1.3335)
			(end 0.5842 -1.3335)
			(stroke
				(width 0)
				(type default)
			)
			(fill no)
			(layer "F.CrtYd")
		)
		(fp_rect
			(start -0.5842 1.3335)
			(end 0.5842 -1.3335)
			(stroke
				(width 0)
				(type default)
			)
			(fill no)
			(layer "F.Fab")
		)
		(pad "1" smd custom
			(at 0 -0.762 270)
			(size 0.2159 0.2159)
			(layers "F.Cu" "F.Mask" "F.Paste")
			(net "AGND_CURRENT_MONOA")
			(options
				(clearance outline)
				(anchor circle)
			)
			(primitives
				(gr_poly
					(pts
						(arc
							(start -0.3302 -0.4318)
							(mid -0.402042 -0.402042)
							(end -0.4318 -0.3302)
						)
						(arc
							(start -0.4318 0.3302)
							(mid -0.402042 0.402042)
							(end -0.3302 0.4318)
						)
						(arc
							(start 0.3302 0.4318)
							(mid 0.402042 0.402042)
							(end 0.4318 0.3302)
						)
						(arc
							(start 0.4318 -0.3302)
							(mid 0.402042 -0.402042)
							(end 0.3302 -0.4318)
						)
					)
					(width 0)
					(fill yes)
				)
			)
		)
		(pad "2" smd custom
			(at 0 0.762 270)
			(size 0.2159 0.2159)
			(layers "F.Cu" "F.Mask" "F.Paste")
			(net "MB0_P12V_HS")
			(options
				(clearance outline)
				(anchor circle)
			)
			(primitives
				(gr_poly
					(pts
						(arc
							(start -0.3302 -0.4318)
							(mid -0.402042 -0.402042)
							(end -0.4318 -0.3302)
						)
						(arc
							(start -0.4318 0.3302)
							(mid -0.402042 0.402042)
							(end -0.3302 0.4318)
						)
						(arc
							(start 0.3302 0.4318)
							(mid 0.402042 0.402042)
							(end 0.4318 0.3302)
						)
						(arc
							(start 0.4318 -0.3302)
							(mid 0.402042 -0.402042)
							(end 0.3302 -0.4318)
						)
					)
					(width 0)
					(fill yes)
				)
			)
		)
	)
	(footprint ""
		(layer "F.Cu")
		(at 401.80895 -171.809918 -90)
		(property "Reference" "R605"
			(at 0 0 270)
			(layer "F.SilkS")
			(hide yes)
			(effects
				(font
					(size 1.27 1.27)
				)
			)
		)
		(property "Value" "300KR2F-GP"
			(at 0.064008 -3.993896 270)
			(unlocked yes)
			(layer "F.Fab")
			(hide yes)
			(effects
				(font
					(size 1.016 1.016)
					(thickness 0.1524)
				)
			)
		)
		(property "Device Type" "R402H16"
			(at 0.064008 -5.517896 270)
			(unlocked yes)
			(layer "F.Fab")
			(hide yes)
			(effects
				(font
					(size 1.016 1.016)
					(thickness 0.1524)
				)
			)
		)
		(duplicate_pad_numbers_are_jumpers no)
		(fp_line
			(start -0.508 -0.9398)
			(end -0.508 0.9398)
			(stroke
				(width 0.1524)
				(type default)
			)
			(layer "F.SilkS")
		)
		(fp_line
			(start 0.508 -0.9398)
			(end -0.508 -0.9398)
			(stroke
				(width 0.1524)
				(type default)
			)
			(layer "F.SilkS")
		)
		(fp_rect
			(start -0.508 0.9398)
			(end 0.508 -0.9398)
			(stroke
				(width 0)
				(type default)
			)
			(fill no)
			(layer "F.CrtYd")
		)
		(fp_rect
			(start -0.508 0.9398)
			(end 0.508 -0.9398)
			(stroke
				(width 0)
				(type default)
			)
			(fill no)
			(layer "F.Fab")
		)
		(pad "1" smd custom
			(at 0 -0.4445 270)
			(size 0.1397 0.1397)
			(layers "F.Cu" "F.Mask" "F.Paste")
			(net "SW_HDD_N20")
			(options
				(clearance outline)
				(anchor circle)
			)
			(primitives
				(gr_poly
					(pts
						(arc
							(start -0.1778 -0.2794)
							(mid -0.249642 -0.249642)
							(end -0.2794 -0.1778)
						)
						(arc
							(start -0.2794 0.1778)
							(mid -0.249642 0.249642)
							(end -0.1778 0.2794)
						)
						(arc
							(start 0.1778 0.2794)
							(mid 0.249642 0.249642)
							(end 0.2794 0.1778)
						)
						(arc
							(start 0.2794 -0.1778)
							(mid 0.249642 -0.249642)
							(end 0.1778 -0.2794)
						)
					)
					(width 0)
					(fill yes)
				)
			)
		)
		(pad "2" smd custom
			(at 0 0.4445 270)
			(size 0.1397 0.1397)
			(layers "F.Cu" "F.Mask" "F.Paste")
			(net "P12V_A")
			(options
				(clearance outline)
				(anchor circle)
			)
			(primitives
				(gr_poly
					(pts
						(arc
							(start -0.1778 -0.2794)
							(mid -0.249642 -0.249642)
							(end -0.2794 -0.1778)
						)
						(arc
							(start -0.2794 0.1778)
							(mid -0.249642 0.249642)
							(end -0.1778 0.2794)
						)
						(arc
							(start 0.1778 0.2794)
							(mid 0.249642 0.249642)
							(end 0.2794 0.1778)
						)
						(arc
							(start 0.2794 -0.1778)
							(mid 0.249642 -0.249642)
							(end 0.1778 -0.2794)
						)
					)
					(width 0)
					(fill yes)
				)
			)
		)
	)
	(footprint ""
		(layer "F.Cu")
		(at 95.563436 -273.660616 90)
		(property "Reference" "C65"
			(at 0 0 90)
			(layer "F.SilkS")
			(hide yes)
			(effects
				(font
					(size 1.27 1.27)
				)
			)
		)
		(property "Value" "SCD01U16V1KX-GP"
			(at -2.8321 -1.7399 90)
			(unlocked yes)
			(layer "F.Fab")
			(hide yes)
			(effects
				(font
					(size 1.016 1.016)
					(thickness 0.1524)
				)
			)
		)
		(property "Device Type" "C0201H13"
			(at -2.8321 -3.2639 90)
			(unlocked yes)
			(layer "F.Fab")
			(hide yes)
			(effects
				(font
					(size 1.016 1.016)
					(thickness 0.1524)
				)
			)
		)
		(duplicate_pad_numbers_are_jumpers no)
		(fp_rect
			(start -0.2794 0.6477)
			(end 0.2794 -0.6477)
			(stroke
				(width 0)
				(type default)
			)
			(fill no)
			(layer "F.CrtYd")
		)
		(fp_rect
			(start -0.2794 0.6477)
			(end 0.2794 -0.6477)
			(stroke
				(width 0)
				(type default)
			)
			(fill no)
			(layer "F.Fab")
		)
		(pad "1" smd custom
			(at 0 -0.2794 90)
			(size 0.0762 0.0762)
			(layers "F.Cu" "F.Mask" "F.Paste")
			(net "SAS_HDD_RX_P2")
			(options
				(clearance outline)
				(anchor circle)
			)
			(primitives
				(gr_poly
					(pts
						(arc
							(start 0.1524 -0.127)
							(mid 0.137521 -0.162921)
							(end 0.1016 -0.1778)
						)
						(arc
							(start -0.1016 -0.1778)
							(mid -0.137521 -0.162921)
							(end -0.1524 -0.127)
						)
						(arc
							(start -0.1524 0.127)
							(mid -0.137521 0.162921)
							(end -0.1016 0.1778)
						)
						(arc
							(start 0.1016 0.1778)
							(mid 0.137521 0.162921)
							(end 0.1524 0.127)
						)
					)
					(width 0)
					(fill yes)
				)
			)
		)
		(pad "2" smd custom
			(at 0 0.2794 90)
			(size 0.0762 0.0762)
			(layers "F.Cu" "F.Mask" "F.Paste")
			(net "PHY_SCC_A_TO_DRV_A_2_DP")
			(options
				(clearance outline)
				(anchor circle)
			)
			(primitives
				(gr_poly
					(pts
						(arc
							(start 0.1524 -0.127)
							(mid 0.137521 -0.162921)
							(end 0.1016 -0.1778)
						)
						(arc
							(start -0.1016 -0.1778)
							(mid -0.137521 -0.162921)
							(end -0.1524 -0.127)
						)
						(arc
							(start -0.1524 0.127)
							(mid -0.137521 0.162921)
							(end -0.1016 0.1778)
						)
						(arc
							(start 0.1016 0.1778)
							(mid 0.137521 0.162921)
							(end 0.1524 0.127)
						)
					)
					(width 0)
					(fill yes)
				)
			)
		)
	)
	(footprint ""
		(layer "F.Cu")
		(at 101.765862 -300.992794 90)
		(property "Reference" "R569"
			(at 0 0 90)
			(layer "F.SilkS")
			(hide yes)
			(effects
				(font
					(size 1.27 1.27)
				)
			)
		)
		(property "Value" "4K7R2J-2-GP"
			(at 0.064008 -3.993896 90)
			(unlocked yes)
			(layer "F.Fab")
			(hide yes)
			(effects
				(font
					(size 1.016 1.016)
					(thickness 0.1524)
				)
			)
		)
		(property "Device Type" "R402H16"
			(at 0.064008 -5.517896 90)
			(unlocked yes)
			(layer "F.Fab")
			(hide yes)
			(effects
				(font
					(size 1.016 1.016)
					(thickness 0.1524)
				)
			)
		)
		(duplicate_pad_numbers_are_jumpers no)
		(fp_line
			(start 0.508 -0.9398)
			(end -0.508 -0.9398)
			(stroke
				(width 0.1524)
				(type default)
			)
			(layer "F.SilkS")
		)
		(fp_line
			(start -0.508 -0.9398)
			(end -0.508 0.9398)
			(stroke
				(width 0.1524)
				(type default)
			)
			(layer "F.SilkS")
		)
		(fp_rect
			(start -0.508 0.9398)
			(end 0.508 -0.9398)
			(stroke
				(width 0)
				(type default)
			)
			(fill no)
			(layer "F.CrtYd")
		)
		(fp_rect
			(start -0.508 0.9398)
			(end 0.508 -0.9398)
			(stroke
				(width 0)
				(type default)
			)
			(fill no)
			(layer "F.Fab")
		)
		(pad "1" smd custom
			(at 0 -0.4445 90)
			(size 0.1397 0.1397)
			(layers "F.Cu" "F.Mask" "F.Paste")
			(net "DRIVE_B_27_FLT_LED")
			(options
				(clearance outline)
				(anchor circle)
			)
			(primitives
				(gr_poly
					(pts
						(arc
							(start -0.1778 -0.2794)
							(mid -0.249642 -0.249642)
							(end -0.2794 -0.1778)
						)
						(arc
							(start -0.2794 0.1778)
							(mid -0.249642 0.249642)
							(end -0.1778 0.2794)
						)
						(arc
							(start 0.1778 0.2794)
							(mid 0.249642 0.249642)
							(end 0.2794 0.1778)
						)
						(arc
							(start 0.2794 -0.1778)
							(mid 0.249642 -0.249642)
							(end 0.1778 -0.2794)
						)
					)
					(width 0)
					(fill yes)
				)
			)
		)
		(pad "2" smd custom
			(at 0 0.4445 90)
			(size 0.1397 0.1397)
			(layers "F.Cu" "F.Mask" "F.Paste")
			(net "GND")
			(options
				(clearance outline)
				(anchor circle)
			)
			(primitives
				(gr_poly
					(pts
						(arc
							(start -0.1778 -0.2794)
							(mid -0.249642 -0.249642)
							(end -0.2794 -0.1778)
						)
						(arc
							(start -0.2794 0.1778)
							(mid -0.249642 0.249642)
							(end -0.1778 0.2794)
						)
						(arc
							(start 0.1778 0.2794)
							(mid 0.249642 0.249642)
							(end 0.2794 0.1778)
						)
						(arc
							(start 0.2794 -0.1778)
							(mid 0.249642 -0.249642)
							(end 0.1778 -0.2794)
						)
					)
					(width 0)
					(fill yes)
				)
			)
		)
	)
	(footprint ""
		(layer "F.Cu")
		(at 181.483 -292.270942)
		(property "Reference" "R244"
			(at 0 0 0)
			(layer "F.SilkS")
			(hide yes)
			(effects
				(font
					(size 1.27 1.27)
				)
			)
		)
		(property "Value" "2R6F-GP"
			(at -0.0508 -4.8514 0)
			(unlocked yes)
			(layer "F.Fab")
			(hide yes)
			(effects
				(font
					(size 1.016 1.016)
					(thickness 0.1524)
				)
			)
		)
		(property "Device Type" "R1206H26"
			(at 0 -6.3754 0)
			(unlocked yes)
			(layer "F.Fab")
			(hide yes)
			(effects
				(font
					(size 1.016 1.016)
					(thickness 0.1524)
				)
			)
		)
		(duplicate_pad_numbers_are_jumpers no)
		(fp_line
			(start -1.016 -2.2352)
			(end 1.016 -2.2352)
			(stroke
				(width 0.1524)
				(type default)
			)
			(layer "F.SilkS")
		)
		(fp_line
			(start -1.016 2.2352)
			(end -1.016 -2.2352)
			(stroke
				(width 0.1524)
				(type default)
			)
			(layer "F.SilkS")
		)
		(fp_line
			(start 1.016 -2.2352)
			(end 1.016 2.2352)
			(stroke
				(width 0.1524)
				(type default)
			)
			(layer "F.SilkS")
		)
		(fp_line
			(start 1.016 2.2352)
			(end -1.016 2.2352)
			(stroke
				(width 0.1524)
				(type default)
			)
			(layer "F.SilkS")
		)
		(fp_rect
			(start -1.0922 2.3114)
			(end 1.0922 -2.3114)
			(stroke
				(width 0)
				(type default)
			)
			(fill no)
			(layer "F.CrtYd")
		)
		(fp_poly
			(pts
				(xy -1.0922 -2.3114) (xy 1.0922 -2.3114) (xy 1.0922 2.3114) (xy -1.0922 2.3114)
			)
			(stroke
				(width 0)
				(type default)
			)
			(fill no)
			(layer "F.Fab")
		)
		(pad "1" smd rect
			(at 0 -1.397)
			(size 1.651 1.27)
			(layers "F.Cu" "F.Mask" "F.Paste")
			(net "P5V_HDD5")
		)
		(pad "2" smd rect
			(at 0 1.397)
			(size 1.651 1.27)
			(layers "F.Cu" "F.Mask" "F.Paste")
			(net "5V_PRE_5")
		)
	)
	(footprint ""
		(layer "F.Cu")
		(at 338.074 -49.443894 90)
		(property "Reference" "R836"
			(at 0 0 90)
			(layer "F.SilkS")
			(hide yes)
			(effects
				(font
					(size 1.27 1.27)
				)
			)
		)
		(property "Value" "200KR2F-L-GP"
			(at 0.064008 -3.993896 90)
			(unlocked yes)
			(layer "F.Fab")
			(hide yes)
			(effects
				(font
					(size 1.016 1.016)
					(thickness 0.1524)
				)
			)
		)
		(property "Device Type" "R402H16"
			(at 0.064008 -5.517896 90)
			(unlocked yes)
			(layer "F.Fab")
			(hide yes)
			(effects
				(font
					(size 1.016 1.016)
					(thickness 0.1524)
				)
			)
		)
		(duplicate_pad_numbers_are_jumpers no)
		(fp_line
			(start 0.508 -0.9398)
			(end -0.508 -0.9398)
			(stroke
				(width 0.1524)
				(type default)
			)
			(layer "F.SilkS")
		)
		(fp_line
			(start -0.508 -0.9398)
			(end -0.508 0.9398)
			(stroke
				(width 0.1524)
				(type default)
			)
			(layer "F.SilkS")
		)
		(fp_rect
			(start -0.508 0.9398)
			(end 0.508 -0.9398)
			(stroke
				(width 0)
				(type default)
			)
			(fill no)
			(layer "F.CrtYd")
		)
		(fp_rect
			(start -0.508 0.9398)
			(end 0.508 -0.9398)
			(stroke
				(width 0)
				(type default)
			)
			(fill no)
			(layer "F.Fab")
		)
		(pad "1" smd custom
			(at 0 -0.4445 90)
			(size 0.1397 0.1397)
			(layers "F.Cu" "F.Mask" "F.Paste")
			(net "SW_HDD_R30")
			(options
				(clearance outline)
				(anchor circle)
			)
			(primitives
				(gr_poly
					(pts
						(arc
							(start -0.1778 -0.2794)
							(mid -0.249642 -0.249642)
							(end -0.2794 -0.1778)
						)
						(arc
							(start -0.2794 0.1778)
							(mid -0.249642 0.249642)
							(end -0.1778 0.2794)
						)
						(arc
							(start 0.1778 0.2794)
							(mid 0.249642 0.249642)
							(end 0.2794 0.1778)
						)
						(arc
							(start 0.2794 -0.1778)
							(mid 0.249642 -0.249642)
							(end 0.1778 -0.2794)
						)
					)
					(width 0)
					(fill yes)
				)
			)
		)
		(pad "2" smd custom
			(at 0 0.4445 90)
			(size 0.1397 0.1397)
			(layers "F.Cu" "F.Mask" "F.Paste")
			(net "SW_HDD_N30")
			(options
				(clearance outline)
				(anchor circle)
			)
			(primitives
				(gr_poly
					(pts
						(arc
							(start -0.1778 -0.2794)
							(mid -0.249642 -0.249642)
							(end -0.2794 -0.1778)
						)
						(arc
							(start -0.2794 0.1778)
							(mid -0.249642 0.249642)
							(end -0.1778 0.2794)
						)
						(arc
							(start 0.1778 0.2794)
							(mid 0.249642 0.249642)
							(end 0.2794 0.1778)
						)
						(arc
							(start 0.2794 -0.1778)
							(mid 0.249642 -0.249642)
							(end 0.1778 -0.2794)
						)
					)
					(width 0)
					(fill yes)
				)
			)
		)
	)
	(footprint ""
		(layer "F.Cu")
		(at 51.980846 -62.778894 -90)
		(property "Reference" "C365"
			(at 0 0 270)
			(layer "F.SilkS")
			(hide yes)
			(effects
				(font
					(size 1.27 1.27)
				)
			)
		)
		(property "Value" "SC1U16V3KX-5GP"
			(at 0 -2.8194 270)
			(unlocked yes)
			(layer "F.Fab")
			(hide yes)
			(effects
				(font
					(size 1.016 1.016)
					(thickness 0.1524)
				)
			)
		)
		(property "Device Type" "C603H36"
			(at 0 -4.3434 270)
			(unlocked yes)
			(layer "F.Fab")
			(hide yes)
			(effects
				(font
					(size 1.016 1.016)
					(thickness 0.1524)
				)
			)
		)
		(duplicate_pad_numbers_are_jumpers no)
		(fp_line
			(start 0.508 0)
			(end -0.508 0)
			(stroke
				(width 0.2032)
				(type default)
			)
			(layer "F.SilkS")
		)
		(fp_rect
			(start -0.5842 1.3335)
			(end 0.5842 -1.3335)
			(stroke
				(width 0)
				(type default)
			)
			(fill no)
			(layer "F.CrtYd")
		)
		(fp_rect
			(start -0.5842 1.3335)
			(end 0.5842 -1.3335)
			(stroke
				(width 0)
				(type default)
			)
			(fill no)
			(layer "F.Fab")
		)
		(pad "1" smd custom
			(at 0 -0.762 270)
			(size 0.2159 0.2159)
			(layers "F.Cu" "F.Mask" "F.Paste")
			(net "P5V_HDD25")
			(options
				(clearance outline)
				(anchor circle)
			)
			(primitives
				(gr_poly
					(pts
						(arc
							(start -0.3302 -0.4318)
							(mid -0.402042 -0.402042)
							(end -0.4318 -0.3302)
						)
						(arc
							(start -0.4318 0.3302)
							(mid -0.402042 0.402042)
							(end -0.3302 0.4318)
						)
						(arc
							(start 0.3302 0.4318)
							(mid 0.402042 0.402042)
							(end 0.4318 0.3302)
						)
						(arc
							(start 0.4318 -0.3302)
							(mid 0.402042 -0.402042)
							(end 0.3302 -0.4318)
						)
					)
					(width 0)
					(fill yes)
				)
			)
		)
		(pad "2" smd custom
			(at 0 0.762 270)
			(size 0.2159 0.2159)
			(layers "F.Cu" "F.Mask" "F.Paste")
			(net "GND")
			(options
				(clearance outline)
				(anchor circle)
			)
			(primitives
				(gr_poly
					(pts
						(arc
							(start -0.3302 -0.4318)
							(mid -0.402042 -0.402042)
							(end -0.4318 -0.3302)
						)
						(arc
							(start -0.4318 0.3302)
							(mid -0.402042 0.402042)
							(end -0.3302 0.4318)
						)
						(arc
							(start 0.3302 0.4318)
							(mid 0.402042 0.402042)
							(end 0.4318 0.3302)
						)
						(arc
							(start 0.4318 -0.3302)
							(mid 0.402042 -0.402042)
							(end 0.3302 -0.4318)
						)
					)
					(width 0)
					(fill yes)
				)
			)
		)
	)
	(footprint ""
		(layer "F.Cu")
		(at 363.020102 -303.954942 180)
		(property "Reference" "C135"
			(at 0 0 180)
			(layer "F.SilkS")
			(hide yes)
			(effects
				(font
					(size 1.27 1.27)
				)
			)
		)
		(property "Value" "SC4D7U25V5KX-1-GP"
			(at -0.0762 -6.1214 180)
			(unlocked yes)
			(layer "F.Fab")
			(hide yes)
			(effects
				(font
					(size 1.016 1.016)
					(thickness 0.1524)
				)
			)
		)
		(property "Device Type" "C805H58"
			(at -0.0762 -8.1534 180)
			(unlocked yes)
			(layer "F.Fab")
			(hide yes)
			(effects
				(font
					(size 1.016 1.016)
					(thickness 0.1524)
				)
			)
		)
		(duplicate_pad_numbers_are_jumpers no)
		(fp_line
			(start 0.635 0)
			(end -0.635 0)
			(stroke
				(width 0.508)
				(type default)
			)
			(layer "F.SilkS")
		)
		(fp_rect
			(start -0.9652 1.778)
			(end 0.9652 -1.778)
			(stroke
				(width 0)
				(type default)
			)
			(fill no)
			(layer "F.CrtYd")
		)
		(fp_poly
			(pts
				(xy -0.9652 -1.778) (xy 0.9652 -1.778) (xy 0.9652 1.778) (xy -0.9652 1.778)
			)
			(stroke
				(width 0)
				(type default)
			)
			(fill no)
			(layer "F.Fab")
		)
		(pad "1" smd rect
			(at 0 -0.9652 180)
			(size 1.397 1.143)
			(layers "F.Cu" "F.Mask" "F.Paste")
			(net "P12V_HDD7")
		)
		(pad "2" smd rect
			(at 0 0.9652 180)
			(size 1.397 1.143)
			(layers "F.Cu" "F.Mask" "F.Paste")
			(net "GND")
		)
	)
	(footprint ""
		(layer "F.Cu")
		(at 149.932898 -292.270942)
		(property "Reference" "R221"
			(at 0 0 0)
			(layer "F.SilkS")
			(hide yes)
			(effects
				(font
					(size 1.27 1.27)
				)
			)
		)
		(property "Value" "2R6F-GP"
			(at -0.0508 -4.8514 0)
			(unlocked yes)
			(layer "F.Fab")
			(hide yes)
			(effects
				(font
					(size 1.016 1.016)
					(thickness 0.1524)
				)
			)
		)
		(property "Device Type" "R1206H26"
			(at 0 -6.3754 0)
			(unlocked yes)
			(layer "F.Fab")
			(hide yes)
			(effects
				(font
					(size 1.016 1.016)
					(thickness 0.1524)
				)
			)
		)
		(duplicate_pad_numbers_are_jumpers no)
		(fp_line
			(start -1.016 -2.2352)
			(end 1.016 -2.2352)
			(stroke
				(width 0.1524)
				(type default)
			)
			(layer "F.SilkS")
		)
		(fp_line
			(start -1.016 2.2352)
			(end -1.016 -2.2352)
			(stroke
				(width 0.1524)
				(type default)
			)
			(layer "F.SilkS")
		)
		(fp_line
			(start 1.016 -2.2352)
			(end 1.016 2.2352)
			(stroke
				(width 0.1524)
				(type default)
			)
			(layer "F.SilkS")
		)
		(fp_line
			(start 1.016 2.2352)
			(end -1.016 2.2352)
			(stroke
				(width 0.1524)
				(type default)
			)
			(layer "F.SilkS")
		)
		(fp_rect
			(start -1.0922 2.3114)
			(end 1.0922 -2.3114)
			(stroke
				(width 0)
				(type default)
			)
			(fill no)
			(layer "F.CrtYd")
		)
		(fp_poly
			(pts
				(xy -1.0922 -2.3114) (xy 1.0922 -2.3114) (xy 1.0922 2.3114) (xy -1.0922 2.3114)
			)
			(stroke
				(width 0)
				(type default)
			)
			(fill no)
			(layer "F.Fab")
		)
		(pad "1" smd rect
			(at 0 -1.397)
			(size 1.651 1.27)
			(layers "F.Cu" "F.Mask" "F.Paste")
			(net "P5V_HDD4")
		)
		(pad "2" smd rect
			(at 0 1.397)
			(size 1.651 1.27)
			(layers "F.Cu" "F.Mask" "F.Paste")
			(net "5V_PRE_4")
		)
	)
	(footprint ""
		(layer "F.Cu")
		(at 459.801722 -299.435012 -90)
		(property "Reference" "R363"
			(at 0 0 270)
			(layer "F.SilkS")
			(hide yes)
			(effects
				(font
					(size 1.27 1.27)
				)
			)
		)
		(property "Value" "2R6F-GP"
			(at -0.0508 -4.8514 270)
			(unlocked yes)
			(layer "F.Fab")
			(hide yes)
			(effects
				(font
					(size 1.016 1.016)
					(thickness 0.1524)
				)
			)
		)
		(property "Device Type" "R1206H26"
			(at 0 -6.3754 270)
			(unlocked yes)
			(layer "F.Fab")
			(hide yes)
			(effects
				(font
					(size 1.016 1.016)
					(thickness 0.1524)
				)
			)
		)
		(duplicate_pad_numbers_are_jumpers no)
		(fp_line
			(start -1.016 2.2352)
			(end -1.016 -2.2352)
			(stroke
				(width 0.1524)
				(type default)
			)
			(layer "F.SilkS")
		)
		(fp_line
			(start 1.016 2.2352)
			(end -1.016 2.2352)
			(stroke
				(width 0.1524)
				(type default)
			)
			(layer "F.SilkS")
		)
		(fp_line
			(start -1.016 -2.2352)
			(end 1.016 -2.2352)
			(stroke
				(width 0.1524)
				(type default)
			)
			(layer "F.SilkS")
		)
		(fp_line
			(start 1.016 -2.2352)
			(end 1.016 2.2352)
			(stroke
				(width 0.1524)
				(type default)
			)
			(layer "F.SilkS")
		)
		(fp_rect
			(start -1.0922 2.3114)
			(end 1.0922 -2.3114)
			(stroke
				(width 0)
				(type default)
			)
			(fill no)
			(layer "F.CrtYd")
		)
		(fp_poly
			(pts
				(xy -1.0922 -2.3114) (xy 1.0922 -2.3114) (xy 1.0922 2.3114) (xy -1.0922 2.3114)
			)
			(stroke
				(width 0)
				(type default)
			)
			(fill no)
			(layer "F.Fab")
		)
		(pad "1" smd rect
			(at 0 -1.397 270)
			(size 1.651 1.27)
			(layers "F.Cu" "F.Mask" "F.Paste")
			(net "P12V_HDD10")
		)
		(pad "2" smd rect
			(at 0 1.397 270)
			(size 1.651 1.27)
			(layers "F.Cu" "F.Mask" "F.Paste")
			(net "12V_PRE_10")
		)
	)
	(footprint ""
		(layer "F.Cu")
		(at 109.365796 -64.683894 -90)
		(property "Reference" "C395"
			(at 0 0 270)
			(layer "F.SilkS")
			(hide yes)
			(effects
				(font
					(size 1.27 1.27)
				)
			)
		)
		(property "Value" "SC4D7U25V5KX-1-GP"
			(at -0.0762 -6.1214 270)
			(unlocked yes)
			(layer "F.Fab")
			(hide yes)
			(effects
				(font
					(size 1.016 1.016)
					(thickness 0.1524)
				)
			)
		)
		(property "Device Type" "C805H58"
			(at -0.0762 -8.1534 270)
			(unlocked yes)
			(layer "F.Fab")
			(hide yes)
			(effects
				(font
					(size 1.016 1.016)
					(thickness 0.1524)
				)
			)
		)
		(duplicate_pad_numbers_are_jumpers no)
		(fp_line
			(start 0.635 0)
			(end -0.635 0)
			(stroke
				(width 0.508)
				(type default)
			)
			(layer "F.SilkS")
		)
		(fp_rect
			(start -0.9652 1.778)
			(end 0.9652 -1.778)
			(stroke
				(width 0)
				(type default)
			)
			(fill no)
			(layer "F.CrtYd")
		)
		(fp_poly
			(pts
				(xy -0.9652 -1.778) (xy 0.9652 -1.778) (xy 0.9652 1.778) (xy -0.9652 1.778)
			)
			(stroke
				(width 0)
				(type default)
			)
			(fill no)
			(layer "F.Fab")
		)
		(pad "1" smd rect
			(at 0 -0.9652 270)
			(size 1.397 1.143)
			(layers "F.Cu" "F.Mask" "F.Paste")
			(net "P12V_HDD27")
		)
		(pad "2" smd rect
			(at 0 0.9652 270)
			(size 1.397 1.143)
			(layers "F.Cu" "F.Mask" "F.Paste")
			(net "GND")
		)
	)
	(footprint ""
		(layer "F.Cu")
		(at 461.0735 -272.535142 180)
		(property "Reference" "R372"
			(at 0 0 180)
			(layer "F.SilkS")
			(hide yes)
			(effects
				(font
					(size 1.27 1.27)
				)
			)
		)
		(property "Value" "0R2J-2-GP"
			(at 0.064008 -3.993896 180)
			(unlocked yes)
			(layer "F.Fab")
			(hide yes)
			(effects
				(font
					(size 1.016 1.016)
					(thickness 0.1524)
				)
			)
		)
		(property "Device Type" "R402H16"
			(at 0.064008 -5.517896 180)
			(unlocked yes)
			(layer "F.Fab")
			(hide yes)
			(effects
				(font
					(size 1.016 1.016)
					(thickness 0.1524)
				)
			)
		)
		(duplicate_pad_numbers_are_jumpers no)
		(fp_line
			(start 0.508 -0.9398)
			(end -0.508 -0.9398)
			(stroke
				(width 0.1524)
				(type default)
			)
			(layer "F.SilkS")
		)
		(fp_line
			(start -0.508 -0.9398)
			(end -0.508 0.9398)
			(stroke
				(width 0.1524)
				(type default)
			)
			(layer "F.SilkS")
		)
		(fp_rect
			(start -0.508 0.9398)
			(end 0.508 -0.9398)
			(stroke
				(width 0)
				(type default)
			)
			(fill no)
			(layer "F.CrtYd")
		)
		(fp_rect
			(start -0.508 0.9398)
			(end 0.508 -0.9398)
			(stroke
				(width 0)
				(type default)
			)
			(fill no)
			(layer "F.Fab")
		)
		(pad "1" smd custom
			(at 0 -0.4445 180)
			(size 0.1397 0.1397)
			(layers "F.Cu" "F.Mask" "F.Paste")
			(net "DRIVE_A_10_PWR")
			(options
				(clearance outline)
				(anchor circle)
			)
			(primitives
				(gr_poly
					(pts
						(arc
							(start -0.1778 -0.2794)
							(mid -0.249642 -0.249642)
							(end -0.2794 -0.1778)
						)
						(arc
							(start -0.2794 0.1778)
							(mid -0.249642 0.249642)
							(end -0.1778 0.2794)
						)
						(arc
							(start 0.1778 0.2794)
							(mid 0.249642 0.249642)
							(end 0.2794 0.1778)
						)
						(arc
							(start 0.2794 -0.1778)
							(mid 0.249642 -0.249642)
							(end 0.1778 -0.2794)
						)
					)
					(width 0)
					(fill yes)
				)
			)
		)
		(pad "2" smd custom
			(at 0 0.4445 180)
			(size 0.1397 0.1397)
			(layers "F.Cu" "F.Mask" "F.Paste")
			(net "SW_PWR_R_HDD10")
			(options
				(clearance outline)
				(anchor circle)
			)
			(primitives
				(gr_poly
					(pts
						(arc
							(start -0.1778 -0.2794)
							(mid -0.249642 -0.249642)
							(end -0.2794 -0.1778)
						)
						(arc
							(start -0.2794 0.1778)
							(mid -0.249642 0.249642)
							(end -0.1778 0.2794)
						)
						(arc
							(start 0.1778 0.2794)
							(mid 0.249642 0.249642)
							(end 0.2794 0.1778)
						)
						(arc
							(start 0.2794 -0.1778)
							(mid 0.249642 -0.249642)
							(end 0.1778 -0.2794)
						)
					)
					(width 0)
					(fill yes)
				)
			)
		)
	)
	(footprint ""
		(layer "F.Cu")
		(at 365.16691 -184.40527 -90)
		(property "Reference" "R568"
			(at 0 0 270)
			(layer "F.SilkS")
			(hide yes)
			(effects
				(font
					(size 1.27 1.27)
				)
			)
		)
		(property "Value" "2R6F-GP"
			(at -0.0508 -4.8514 270)
			(unlocked yes)
			(layer "F.Fab")
			(hide yes)
			(effects
				(font
					(size 1.016 1.016)
					(thickness 0.1524)
				)
			)
		)
		(property "Device Type" "R1206H26"
			(at 0 -6.3754 270)
			(unlocked yes)
			(layer "F.Fab")
			(hide yes)
			(effects
				(font
					(size 1.016 1.016)
					(thickness 0.1524)
				)
			)
		)
		(duplicate_pad_numbers_are_jumpers no)
		(fp_line
			(start -1.016 2.2352)
			(end -1.016 -2.2352)
			(stroke
				(width 0.1524)
				(type default)
			)
			(layer "F.SilkS")
		)
		(fp_line
			(start 1.016 2.2352)
			(end -1.016 2.2352)
			(stroke
				(width 0.1524)
				(type default)
			)
			(layer "F.SilkS")
		)
		(fp_line
			(start -1.016 -2.2352)
			(end 1.016 -2.2352)
			(stroke
				(width 0.1524)
				(type default)
			)
			(layer "F.SilkS")
		)
		(fp_line
			(start 1.016 -2.2352)
			(end 1.016 2.2352)
			(stroke
				(width 0.1524)
				(type default)
			)
			(layer "F.SilkS")
		)
		(fp_rect
			(start -1.0922 2.3114)
			(end 1.0922 -2.3114)
			(stroke
				(width 0)
				(type default)
			)
			(fill no)
			(layer "F.CrtYd")
		)
		(fp_poly
			(pts
				(xy -1.0922 -2.3114) (xy 1.0922 -2.3114) (xy 1.0922 2.3114) (xy -1.0922 2.3114)
			)
			(stroke
				(width 0)
				(type default)
			)
			(fill no)
			(layer "F.Fab")
		)
		(pad "1" smd rect
			(at 0 -1.397 270)
			(size 1.651 1.27)
			(layers "F.Cu" "F.Mask" "F.Paste")
			(net "P12V_HDD19")
		)
		(pad "2" smd rect
			(at 0 1.397 270)
			(size 1.651 1.27)
			(layers "F.Cu" "F.Mask" "F.Paste")
			(net "12V_PRE_19")
		)
	)
	(footprint ""
		(layer "F.Cu")
		(at 284.353 -284.5308 180)
		(property "Reference" "R123"
			(at 0 0 180)
			(layer "F.SilkS")
			(hide yes)
			(effects
				(font
					(size 1.27 1.27)
				)
			)
		)
		(property "Value" "0R2J-2-GP"
			(at 0.064008 -3.993896 180)
			(unlocked yes)
			(layer "F.Fab")
			(hide yes)
			(effects
				(font
					(size 1.016 1.016)
					(thickness 0.1524)
				)
			)
		)
		(property "Device Type" "R402H16"
			(at 0.064008 -5.517896 180)
			(unlocked yes)
			(layer "F.Fab")
			(hide yes)
			(effects
				(font
					(size 1.016 1.016)
					(thickness 0.1524)
				)
			)
		)
		(duplicate_pad_numbers_are_jumpers no)
		(fp_line
			(start 0.508 -0.9398)
			(end -0.508 -0.9398)
			(stroke
				(width 0.1524)
				(type default)
			)
			(layer "F.SilkS")
		)
		(fp_line
			(start -0.508 -0.9398)
			(end -0.508 0.9398)
			(stroke
				(width 0.1524)
				(type default)
			)
			(layer "F.SilkS")
		)
		(fp_rect
			(start -0.508 0.9398)
			(end 0.508 -0.9398)
			(stroke
				(width 0)
				(type default)
			)
			(fill no)
			(layer "F.CrtYd")
		)
		(fp_rect
			(start -0.508 0.9398)
			(end 0.508 -0.9398)
			(stroke
				(width 0)
				(type default)
			)
			(fill no)
			(layer "F.Fab")
		)
		(pad "1" smd custom
			(at 0 -0.4445 180)
			(size 0.1397 0.1397)
			(layers "F.Cu" "F.Mask" "F.Paste")
			(net "IO_EXP2_LED_SCL")
			(options
				(clearance outline)
				(anchor circle)
			)
			(primitives
				(gr_poly
					(pts
						(arc
							(start -0.1778 -0.2794)
							(mid -0.249642 -0.249642)
							(end -0.2794 -0.1778)
						)
						(arc
							(start -0.2794 0.1778)
							(mid -0.249642 0.249642)
							(end -0.1778 0.2794)
						)
						(arc
							(start 0.1778 0.2794)
							(mid 0.249642 0.249642)
							(end 0.2794 0.1778)
						)
						(arc
							(start 0.2794 -0.1778)
							(mid 0.249642 -0.249642)
							(end 0.1778 -0.2794)
						)
					)
					(width 0)
					(fill yes)
				)
			)
		)
		(pad "2" smd custom
			(at 0 0.4445 180)
			(size 0.1397 0.1397)
			(layers "F.Cu" "F.Mask" "F.Paste")
			(net "I2C_DRIVE_A_FLT_LED_SCL")
			(options
				(clearance outline)
				(anchor circle)
			)
			(primitives
				(gr_poly
					(pts
						(arc
							(start -0.1778 -0.2794)
							(mid -0.249642 -0.249642)
							(end -0.2794 -0.1778)
						)
						(arc
							(start -0.2794 0.1778)
							(mid -0.249642 0.249642)
							(end -0.1778 0.2794)
						)
						(arc
							(start 0.1778 0.2794)
							(mid 0.249642 0.249642)
							(end 0.2794 0.1778)
						)
						(arc
							(start 0.2794 -0.1778)
							(mid 0.249642 -0.249642)
							(end 0.1778 -0.2794)
						)
					)
					(width 0)
					(fill yes)
				)
			)
		)
	)
	(footprint ""
		(layer "F.Cu")
		(at 49.964848 -127.254)
		(property "Reference" "R288"
			(at 0 0 0)
			(layer "F.SilkS")
			(hide yes)
			(effects
				(font
					(size 1.27 1.27)
				)
			)
		)
		(property "Value" "91R3F-1-GP"
			(at -0.0254 -2.5146 0)
			(unlocked yes)
			(layer "F.Fab")
			(hide yes)
			(effects
				(font
					(size 1.016 1.016)
					(thickness 0.1524)
				)
			)
		)
		(property "Device Type" "R603H22"
			(at -0.0254 -4.0386 0)
			(unlocked yes)
			(layer "F.Fab")
			(hide yes)
			(effects
				(font
					(size 1.016 1.016)
					(thickness 0.1524)
				)
			)
		)
		(duplicate_pad_numbers_are_jumpers no)
		(fp_line
			(start -0.4826 0)
			(end -0.2032 0)
			(stroke
				(width 0.2032)
				(type default)
			)
			(layer "F.SilkS")
		)
		(fp_line
			(start 0.2032 0)
			(end 0.4826 0)
			(stroke
				(width 0.2032)
				(type default)
			)
			(layer "F.SilkS")
		)
		(fp_rect
			(start -0.5842 1.3335)
			(end 0.5842 -1.3335)
			(stroke
				(width 0)
				(type default)
			)
			(fill no)
			(layer "F.CrtYd")
		)
		(fp_rect
			(start -0.5842 1.3335)
			(end 0.5842 -1.3335)
			(stroke
				(width 0)
				(type default)
			)
			(fill no)
			(layer "F.Fab")
		)
		(pad "1" smd custom
			(at 0 -0.762)
			(size 0.2159 0.2159)
			(layers "F.Cu" "F.Mask" "F.Paste")
			(net "P5V_A_1")
			(options
				(clearance outline)
				(anchor circle)
			)
			(primitives
				(gr_poly
					(pts
						(arc
							(start -0.3302 -0.4318)
							(mid -0.402042 -0.402042)
							(end -0.4318 -0.3302)
						)
						(arc
							(start -0.4318 0.3302)
							(mid -0.402042 0.402042)
							(end -0.3302 0.4318)
						)
						(arc
							(start 0.3302 0.4318)
							(mid 0.402042 0.402042)
							(end 0.4318 0.3302)
						)
						(arc
							(start 0.4318 -0.3302)
							(mid 0.402042 -0.402042)
							(end 0.3302 -0.4318)
						)
					)
					(width 0)
					(fill yes)
				)
			)
		)
		(pad "2" smd custom
			(at 0 0.762)
			(size 0.2159 0.2159)
			(layers "F.Cu" "F.Mask" "F.Paste")
			(net "DRV_ACT_13")
			(options
				(clearance outline)
				(anchor circle)
			)
			(primitives
				(gr_poly
					(pts
						(arc
							(start -0.3302 -0.4318)
							(mid -0.402042 -0.402042)
							(end -0.4318 -0.3302)
						)
						(arc
							(start -0.4318 0.3302)
							(mid -0.402042 0.402042)
							(end -0.3302 0.4318)
						)
						(arc
							(start 0.3302 0.4318)
							(mid 0.402042 0.402042)
							(end 0.4318 0.3302)
						)
						(arc
							(start 0.4318 -0.3302)
							(mid 0.402042 -0.402042)
							(end 0.3302 -0.4318)
						)
					)
					(width 0)
					(fill yes)
				)
			)
		)
	)
	(footprint ""
		(layer "F.Cu")
		(at 447.166238 -255.778254 -90)
		(property "Reference" "R1251"
			(at 0 0 270)
			(layer "F.SilkS")
			(hide yes)
			(effects
				(font
					(size 1.27 1.27)
				)
			)
		)
		(property "Value" "200KR2F-L-GP"
			(at 0.064008 -3.993896 270)
			(unlocked yes)
			(layer "F.Fab")
			(hide yes)
			(effects
				(font
					(size 1.016 1.016)
					(thickness 0.1524)
				)
			)
		)
		(property "Device Type" "R402H16"
			(at 0.064008 -5.517896 270)
			(unlocked yes)
			(layer "F.Fab")
			(hide yes)
			(effects
				(font
					(size 1.016 1.016)
					(thickness 0.1524)
				)
			)
		)
		(duplicate_pad_numbers_are_jumpers no)
		(fp_line
			(start -0.508 -0.9398)
			(end -0.508 0.9398)
			(stroke
				(width 0.1524)
				(type default)
			)
			(layer "F.SilkS")
		)
		(fp_line
			(start 0.508 -0.9398)
			(end -0.508 -0.9398)
			(stroke
				(width 0.1524)
				(type default)
			)
			(layer "F.SilkS")
		)
		(fp_rect
			(start -0.508 0.9398)
			(end 0.508 -0.9398)
			(stroke
				(width 0)
				(type default)
			)
			(fill no)
			(layer "F.CrtYd")
		)
		(fp_rect
			(start -0.508 0.9398)
			(end 0.508 -0.9398)
			(stroke
				(width 0)
				(type default)
			)
			(fill no)
			(layer "F.Fab")
		)
		(pad "1" smd custom
			(at 0 -0.4445 270)
			(size 0.1397 0.1397)
			(layers "F.Cu" "F.Mask" "F.Paste")
			(net "P5V_C_MODE")
			(options
				(clearance outline)
				(anchor circle)
			)
			(primitives
				(gr_poly
					(pts
						(arc
							(start -0.1778 -0.2794)
							(mid -0.249642 -0.249642)
							(end -0.2794 -0.1778)
						)
						(arc
							(start -0.2794 0.1778)
							(mid -0.249642 0.249642)
							(end -0.1778 0.2794)
						)
						(arc
							(start 0.1778 0.2794)
							(mid 0.249642 0.249642)
							(end 0.2794 0.1778)
						)
						(arc
							(start 0.2794 -0.1778)
							(mid 0.249642 -0.249642)
							(end 0.1778 -0.2794)
						)
					)
					(width 0)
					(fill yes)
				)
			)
		)
		(pad "2" smd custom
			(at 0 0.4445 270)
			(size 0.1397 0.1397)
			(layers "F.Cu" "F.Mask" "F.Paste")
			(net "P5V_A_3_PGOOD")
			(options
				(clearance outline)
				(anchor circle)
			)
			(primitives
				(gr_poly
					(pts
						(arc
							(start -0.1778 -0.2794)
							(mid -0.249642 -0.249642)
							(end -0.2794 -0.1778)
						)
						(arc
							(start -0.2794 0.1778)
							(mid -0.249642 0.249642)
							(end -0.1778 0.2794)
						)
						(arc
							(start 0.1778 0.2794)
							(mid 0.249642 0.249642)
							(end 0.2794 0.1778)
						)
						(arc
							(start 0.2794 -0.1778)
							(mid 0.249642 -0.249642)
							(end 0.1778 -0.2794)
						)
					)
					(width 0)
					(fill yes)
				)
			)
		)
	)
	(footprint ""
		(layer "F.Cu")
		(at 127.113284 -159.219392 90)
		(property "Reference" "C233"
			(at 0 0 90)
			(layer "F.SilkS")
			(hide yes)
			(effects
				(font
					(size 1.27 1.27)
				)
			)
		)
		(property "Value" "SCD01U16V1KX-GP"
			(at -2.8321 -1.7399 90)
			(unlocked yes)
			(layer "F.Fab")
			(hide yes)
			(effects
				(font
					(size 1.016 1.016)
					(thickness 0.1524)
				)
			)
		)
		(property "Device Type" "C0201H13"
			(at -2.8321 -3.2639 90)
			(unlocked yes)
			(layer "F.Fab")
			(hide yes)
			(effects
				(font
					(size 1.016 1.016)
					(thickness 0.1524)
				)
			)
		)
		(duplicate_pad_numbers_are_jumpers no)
		(fp_rect
			(start -0.2794 0.6477)
			(end 0.2794 -0.6477)
			(stroke
				(width 0)
				(type default)
			)
			(fill no)
			(layer "F.CrtYd")
		)
		(fp_rect
			(start -0.2794 0.6477)
			(end 0.2794 -0.6477)
			(stroke
				(width 0)
				(type default)
			)
			(fill no)
			(layer "F.Fab")
		)
		(pad "1" smd custom
			(at 0 -0.2794 90)
			(size 0.0762 0.0762)
			(layers "F.Cu" "F.Mask" "F.Paste")
			(net "SAS_HDD_RX_N15")
			(options
				(clearance outline)
				(anchor circle)
			)
			(primitives
				(gr_poly
					(pts
						(arc
							(start 0.1524 -0.127)
							(mid 0.137521 -0.162921)
							(end 0.1016 -0.1778)
						)
						(arc
							(start -0.1016 -0.1778)
							(mid -0.137521 -0.162921)
							(end -0.1524 -0.127)
						)
						(arc
							(start -0.1524 0.127)
							(mid -0.137521 0.162921)
							(end -0.1016 0.1778)
						)
						(arc
							(start 0.1016 0.1778)
							(mid 0.137521 0.162921)
							(end 0.1524 0.127)
						)
					)
					(width 0)
					(fill yes)
				)
			)
		)
		(pad "2" smd custom
			(at 0 0.2794 90)
			(size 0.0762 0.0762)
			(layers "F.Cu" "F.Mask" "F.Paste")
			(net "PHY_SCC_A_TO_DRV_A_15_DN")
			(options
				(clearance outline)
				(anchor circle)
			)
			(primitives
				(gr_poly
					(pts
						(arc
							(start 0.1524 -0.127)
							(mid 0.137521 -0.162921)
							(end 0.1016 -0.1778)
						)
						(arc
							(start -0.1016 -0.1778)
							(mid -0.137521 -0.162921)
							(end -0.1524 -0.127)
						)
						(arc
							(start -0.1524 0.127)
							(mid -0.137521 0.162921)
							(end -0.1016 0.1778)
						)
						(arc
							(start 0.1016 0.1778)
							(mid 0.137521 0.162921)
							(end 0.1524 0.127)
						)
					)
					(width 0)
					(fill yes)
				)
			)
		)
	)
	(footprint ""
		(layer "F.Cu")
		(at 46.265846 -64.683894 -90)
		(property "Reference" "C370"
			(at 0 0 270)
			(layer "F.SilkS")
			(hide yes)
			(effects
				(font
					(size 1.27 1.27)
				)
			)
		)
		(property "Value" "SC4D7U25V5KX-1-GP"
			(at -0.0762 -6.1214 270)
			(unlocked yes)
			(layer "F.Fab")
			(hide yes)
			(effects
				(font
					(size 1.016 1.016)
					(thickness 0.1524)
				)
			)
		)
		(property "Device Type" "C805H58"
			(at -0.0762 -8.1534 270)
			(unlocked yes)
			(layer "F.Fab")
			(hide yes)
			(effects
				(font
					(size 1.016 1.016)
					(thickness 0.1524)
				)
			)
		)
		(duplicate_pad_numbers_are_jumpers no)
		(fp_line
			(start 0.635 0)
			(end -0.635 0)
			(stroke
				(width 0.508)
				(type default)
			)
			(layer "F.SilkS")
		)
		(fp_rect
			(start -0.9652 1.778)
			(end 0.9652 -1.778)
			(stroke
				(width 0)
				(type default)
			)
			(fill no)
			(layer "F.CrtYd")
		)
		(fp_poly
			(pts
				(xy -0.9652 -1.778) (xy 0.9652 -1.778) (xy 0.9652 1.778) (xy -0.9652 1.778)
			)
			(stroke
				(width 0)
				(type default)
			)
			(fill no)
			(layer "F.Fab")
		)
		(pad "1" smd rect
			(at 0 -0.9652 270)
			(size 1.397 1.143)
			(layers "F.Cu" "F.Mask" "F.Paste")
			(net "P12V_HDD25")
		)
		(pad "2" smd rect
			(at 0 0.9652 270)
			(size 1.397 1.143)
			(layers "F.Cu" "F.Mask" "F.Paste")
			(net "GND")
		)
	)
	(footprint ""
		(layer "F.Cu")
		(at 172.593 -59.857894)
		(property "Reference" "Q176"
			(at 0 0 0)
			(layer "F.SilkS")
			(hide yes)
			(effects
				(font
					(size 1.27 1.27)
				)
			)
		)
		(property "Value" "AO4407AL-GP"
			(at -3.707384 -1.5367 0)
			(unlocked yes)
			(layer "F.Fab")
			(hide yes)
			(effects
				(font
					(size 1.016 1.016)
					(thickness 0.1524)
				)
			)
		)
		(property "Device Type" "SOIC8H69"
			(at -3.707384 -3.0607 0)
			(unlocked yes)
			(layer "F.Fab")
			(hide yes)
			(effects
				(font
					(size 1.016 1.016)
					(thickness 0.1524)
				)
			)
		)
		(duplicate_pad_numbers_are_jumpers no)
		(fp_line
			(start -2.7432 -1.4224)
			(end -2.7432 1.4224)
			(stroke
				(width 0.1524)
				(type default)
			)
			(layer "F.SilkS")
		)
		(fp_line
			(start -2.7432 1.4224)
			(end -2.6416 1.4224)
			(stroke
				(width 0.1524)
				(type default)
			)
			(layer "F.SilkS")
		)
		(fp_line
			(start -2.7432 1.4224)
			(end 2.1336 1.4224)
			(stroke
				(width 0.1524)
				(type default)
			)
			(layer "F.SilkS")
		)
		(fp_line
			(start -2.7178 -0.508)
			(end -2.1844 -0.0508)
			(stroke
				(width 0.1524)
				(type default)
			)
			(layer "F.SilkS")
		)
		(fp_line
			(start -2.6289 3.4417)
			(end -2.6289 1.4732)
			(stroke
				(width 0.381)
				(type default)
			)
			(layer "F.SilkS")
		)
		(fp_line
			(start -2.1844 -0.0508)
			(end -2.7178 0.508)
			(stroke
				(width 0.1524)
				(type default)
			)
			(layer "F.SilkS")
		)
		(fp_line
			(start 2.1336 -1.4224)
			(end -2.7432 -1.4224)
			(stroke
				(width 0.1524)
				(type default)
			)
			(layer "F.SilkS")
		)
		(fp_line
			(start 2.1336 1.4224)
			(end 2.1336 -1.4224)
			(stroke
				(width 0.1524)
				(type default)
			)
			(layer "F.SilkS")
		)
		(fp_poly
			(pts
				(xy -2.2098 -1.4224) (xy -2.2098 1.4224) (xy 2.2098 1.4224) (xy 2.2098 -1.4224)
			)
			(stroke
				(width 0)
				(type default)
			)
			(fill yes)
			(layer "F.SilkS")
		)
		(fp_rect
			(start -2.450084 2.999994)
			(end 2.450084 -2.999994)
			(stroke
				(width 0)
				(type default)
			)
			(fill no)
			(layer "F.CrtYd")
		)
		(fp_poly
			(pts
				(xy -2.8194 3.6322) (xy -2.8194 -3.6322) (xy 2.8194 -3.6322) (xy 2.8194 1.18364) (xy 2.450084 1.18364)
				(xy 2.450084 -2.999994) (xy -2.450084 -2.999994) (xy -2.450084 2.999994) (xy 2.450084 2.999994)
				(xy 2.450084 1.18618) (xy 2.8194 1.18618) (xy 2.8194 3.6322)
			)
			(stroke
				(width 0)
				(type default)
			)
			(fill no)
			(layer "F.CrtYd")
		)
		(fp_rect
			(start -2.8194 3.6322)
			(end 2.8194 -3.6322)
			(stroke
				(width 0)
				(type default)
			)
			(fill no)
			(layer "F.Fab")
		)
		(pad "1" smd rect
			(at -1.905 2.54)
			(size 0.635 1.651)
			(layers "F.Cu" "F.Mask" "F.Paste")
			(net "P12V_A")
		)
		(pad "2" smd rect
			(at -0.635 2.54)
			(size 0.635 1.651)
			(layers "F.Cu" "F.Mask" "F.Paste")
			(net "P12V_A")
		)
		(pad "3" smd rect
			(at 0.635 2.54)
			(size 0.635 1.651)
			(layers "F.Cu" "F.Mask" "F.Paste")
			(net "P12V_A")
		)
		(pad "4" smd rect
			(at 1.905 2.54)
			(size 0.635 1.651)
			(layers "F.Cu" "F.Mask" "F.Paste")
			(net "SW_HDD_N29")
		)
		(pad "5" smd rect
			(at 1.905 -2.54)
			(size 0.635 1.651)
			(layers "F.Cu" "F.Mask" "F.Paste")
			(net "P12V_HDD29")
		)
		(pad "6" smd rect
			(at 0.635 -2.54)
			(size 0.635 1.651)
			(layers "F.Cu" "F.Mask" "F.Paste")
			(net "P12V_HDD29")
		)
		(pad "7" smd rect
			(at -0.635 -2.54)
			(size 0.635 1.651)
			(layers "F.Cu" "F.Mask" "F.Paste")
			(net "P12V_HDD29")
		)
		(pad "8" smd rect
			(at -1.905 -2.54)
			(size 0.635 1.651)
			(layers "F.Cu" "F.Mask" "F.Paste")
			(net "P12V_HDD29")
		)
	)
	(footprint ""
		(layer "F.Cu")
		(at 16.874998 -276.649942 180)
		(property "Reference" "D36"
			(at 0 0 180)
			(layer "F.SilkS")
			(hide yes)
			(effects
				(font
					(size 1.27 1.27)
				)
			)
		)
		(property "Value" "RB551V30-GP"
			(at 0 -6.7818 180)
			(unlocked yes)
			(layer "F.Fab")
			(hide yes)
			(effects
				(font
					(size 1.016 1.016)
					(thickness 0.1524)
				)
			)
		)
		(property "Device Type" "SOD323AKH38"
			(at 0 -8.6868 180)
			(unlocked yes)
			(layer "F.Fab")
			(hide yes)
			(effects
				(font
					(size 1.016 1.016)
					(thickness 0.1524)
				)
			)
		)
		(duplicate_pad_numbers_are_jumpers no)
		(fp_line
			(start 0.889 2.159)
			(end -0.889 2.159)
			(stroke
				(width 0.1524)
				(type default)
			)
			(layer "F.SilkS")
		)
		(fp_line
			(start 0.889 -1.9304)
			(end 0.889 2.159)
			(stroke
				(width 0.1524)
				(type default)
			)
			(layer "F.SilkS")
		)
		(fp_line
			(start 0.762 2.0574)
			(end -0.762 2.0574)
			(stroke
				(width 0.508)
				(type default)
			)
			(layer "F.SilkS")
		)
		(fp_line
			(start -0.889 2.159)
			(end -0.889 -1.9304)
			(stroke
				(width 0.1524)
				(type default)
			)
			(layer "F.SilkS")
		)
		(fp_line
			(start -0.889 -1.9304)
			(end 0.889 -1.9304)
			(stroke
				(width 0.1524)
				(type default)
			)
			(layer "F.SilkS")
		)
		(fp_rect
			(start -1.016 2.3114)
			(end 1.016 -2.0066)
			(stroke
				(width 0)
				(type default)
			)
			(fill no)
			(layer "F.CrtYd")
		)
		(fp_poly
			(pts
				(xy -1.016 -2.0066) (xy 1.016 -2.0066) (xy 1.016 2.3114) (xy -1.016 2.3114)
			)
			(stroke
				(width 0)
				(type default)
			)
			(fill no)
			(layer "F.Fab")
		)
		(pad "A" smd rect
			(at 0 -1.143 180)
			(size 0.5588 1.016)
			(layers "F.Cu" "F.Mask" "F.Paste")
			(net "SW_HDD_R0")
		)
		(pad "K" smd rect
			(at 0 1.143 180)
			(size 0.5588 1.016)
			(layers "F.Cu" "F.Mask" "F.Paste")
			(net "SW_HDD_N0")
		)
	)
	(footprint ""
		(layer "F.Cu")
		(at 265.77417 -371.731794)
		(property "Reference" "R1173"
			(at 0 0 0)
			(layer "F.SilkS")
			(hide yes)
			(effects
				(font
					(size 1.27 1.27)
				)
			)
		)
		(property "Value" "10R5F-1-GP"
			(at 0 -8.9535 0)
			(unlocked yes)
			(layer "F.Fab")
			(hide yes)
			(effects
				(font
					(size 1.27 1.016)
					(thickness 0.1524)
				)
			)
		)
		(property "Device Type" "R805H24"
			(at 0 -10.6299 0)
			(unlocked yes)
			(layer "F.Fab")
			(hide yes)
			(effects
				(font
					(size 1.27 1.016)
					(thickness 0.1524)
				)
			)
		)
		(duplicate_pad_numbers_are_jumpers no)
		(fp_line
			(start -0.889 -1.7018)
			(end -0.889 0.2794)
			(stroke
				(width 0.1524)
				(type default)
			)
			(layer "F.SilkS")
		)
		(fp_line
			(start -0.889 0.0762)
			(end -0.889 1.7018)
			(stroke
				(width 0.1524)
				(type default)
			)
			(layer "F.SilkS")
		)
		(fp_line
			(start -0.889 1.7018)
			(end 0.889 1.7018)
			(stroke
				(width 0.1524)
				(type default)
			)
			(layer "F.SilkS")
		)
		(fp_line
			(start 0.889 -1.7018)
			(end -0.889 -1.7018)
			(stroke
				(width 0.1524)
				(type default)
			)
			(layer "F.SilkS")
		)
		(fp_line
			(start 0.889 -1.7018)
			(end 0.889 -0.381)
			(stroke
				(width 0.1524)
				(type default)
			)
			(layer "F.SilkS")
		)
		(fp_line
			(start 0.889 1.7018)
			(end 0.889 -0.508)
			(stroke
				(width 0.1524)
				(type default)
			)
			(layer "F.SilkS")
		)
		(fp_poly
			(pts
				(xy 0.9652 -1.778) (xy 0.9652 1.778) (xy -0.9652 1.778) (xy -0.9652 -1.778)
			)
			(stroke
				(width 0)
				(type default)
			)
			(fill no)
			(layer "F.CrtYd")
		)
		(fp_rect
			(start -0.9652 1.778)
			(end 0.9652 -1.778)
			(stroke
				(width 0)
				(type default)
			)
			(fill no)
			(layer "F.Fab")
		)
		(pad "1" smd rect
			(at 0 -0.9652)
			(size 1.397 1.143)
			(layers "F.Cu" "F.Mask" "F.Paste")
			(net "MB3_12V_CTRL_GATE2")
		)
		(pad "2" smd rect
			(at 0 0.9652)
			(size 1.397 1.143)
			(layers "F.Cu" "F.Mask" "F.Paste")
			(net "MB3_CM_GATE_R")
		)
	)
	(footprint ""
		(layer "F.Cu")
		(at 236.855 -381.4318)
		(property "Reference" "C588"
			(at 0 0 0)
			(layer "F.SilkS")
			(hide yes)
			(effects
				(font
					(size 1.27 1.27)
				)
			)
		)
		(property "Value" "SC2D2U25V5KX-2-GP"
			(at -0.0762 -6.1214 0)
			(unlocked yes)
			(layer "F.Fab")
			(hide yes)
			(effects
				(font
					(size 1.016 1.016)
					(thickness 0.1524)
				)
			)
		)
		(property "Device Type" "C805H54"
			(at -0.0762 -8.1534 0)
			(unlocked yes)
			(layer "F.Fab")
			(hide yes)
			(effects
				(font
					(size 1.016 1.016)
					(thickness 0.1524)
				)
			)
		)
		(duplicate_pad_numbers_are_jumpers no)
		(fp_line
			(start 0.635 0)
			(end -0.635 0)
			(stroke
				(width 0.508)
				(type default)
			)
			(layer "F.SilkS")
		)
		(fp_rect
			(start -0.9652 1.778)
			(end 0.9652 -1.778)
			(stroke
				(width 0)
				(type default)
			)
			(fill no)
			(layer "F.CrtYd")
		)
		(fp_poly
			(pts
				(xy -0.9652 -1.778) (xy 0.9652 -1.778) (xy 0.9652 1.778) (xy -0.9652 1.778)
			)
			(stroke
				(width 0)
				(type default)
			)
			(fill no)
			(layer "F.Fab")
		)
		(pad "1" smd rect
			(at 0 -0.9652)
			(size 1.397 1.143)
			(layers "F.Cu" "F.Mask" "F.Paste")
			(net "P12V_A_PGOOD")
		)
		(pad "2" smd rect
			(at 0 0.9652)
			(size 1.397 1.143)
			(layers "F.Cu" "F.Mask" "F.Paste")
			(net "GND")
		)
	)
	(footprint ""
		(layer "F.Cu")
		(at 373.5578 -145.8214 180)
		(property "Reference" "R1089"
			(at 0 0 180)
			(layer "F.SilkS")
			(hide yes)
			(effects
				(font
					(size 1.27 1.27)
				)
			)
		)
		(property "Value" "3K83R2F-GP"
			(at 0.064008 -3.993896 180)
			(unlocked yes)
			(layer "F.Fab")
			(hide yes)
			(effects
				(font
					(size 1.016 1.016)
					(thickness 0.1524)
				)
			)
		)
		(property "Device Type" "R402H16"
			(at 0.064008 -5.517896 180)
			(unlocked yes)
			(layer "F.Fab")
			(hide yes)
			(effects
				(font
					(size 1.016 1.016)
					(thickness 0.1524)
				)
			)
		)
		(duplicate_pad_numbers_are_jumpers no)
		(fp_line
			(start 0.508 -0.9398)
			(end -0.508 -0.9398)
			(stroke
				(width 0.1524)
				(type default)
			)
			(layer "F.SilkS")
		)
		(fp_line
			(start -0.508 -0.9398)
			(end -0.508 0.9398)
			(stroke
				(width 0.1524)
				(type default)
			)
			(layer "F.SilkS")
		)
		(fp_rect
			(start -0.508 0.9398)
			(end 0.508 -0.9398)
			(stroke
				(width 0)
				(type default)
			)
			(fill no)
			(layer "F.CrtYd")
		)
		(fp_rect
			(start -0.508 0.9398)
			(end 0.508 -0.9398)
			(stroke
				(width 0)
				(type default)
			)
			(fill no)
			(layer "F.Fab")
		)
		(pad "1" smd custom
			(at 0 -0.4445 180)
			(size 0.1397 0.1397)
			(layers "F.Cu" "F.Mask" "F.Paste")
			(net "COMP_B_PGOOD")
			(options
				(clearance outline)
				(anchor circle)
			)
			(primitives
				(gr_poly
					(pts
						(arc
							(start -0.1778 -0.2794)
							(mid -0.249642 -0.249642)
							(end -0.2794 -0.1778)
						)
						(arc
							(start -0.2794 0.1778)
							(mid -0.249642 0.249642)
							(end -0.1778 0.2794)
						)
						(arc
							(start 0.1778 0.2794)
							(mid 0.249642 0.249642)
							(end 0.2794 0.1778)
						)
						(arc
							(start 0.2794 -0.1778)
							(mid 0.249642 -0.249642)
							(end 0.1778 -0.2794)
						)
					)
					(width 0)
					(fill yes)
				)
			)
		)
		(pad "2" smd custom
			(at 0 0.4445 180)
			(size 0.1397 0.1397)
			(layers "F.Cu" "F.Mask" "F.Paste")
			(net "GND")
			(options
				(clearance outline)
				(anchor circle)
			)
			(primitives
				(gr_poly
					(pts
						(arc
							(start -0.1778 -0.2794)
							(mid -0.249642 -0.249642)
							(end -0.2794 -0.1778)
						)
						(arc
							(start -0.2794 0.1778)
							(mid -0.249642 0.249642)
							(end -0.1778 0.2794)
						)
						(arc
							(start 0.1778 0.2794)
							(mid 0.249642 0.249642)
							(end 0.2794 0.1778)
						)
						(arc
							(start 0.2794 -0.1778)
							(mid 0.249642 -0.249642)
							(end 0.1778 -0.2794)
						)
					)
					(width 0)
					(fill yes)
				)
			)
		)
	)
	(footprint ""
		(layer "F.Cu")
		(at 146.630898 -278.554942 180)
		(property "Reference" "Q25"
			(at 0 0 180)
			(layer "F.SilkS")
			(hide yes)
			(effects
				(font
					(size 1.27 1.27)
				)
			)
		)
		(property "Value" "2N7002KDW-GP"
			(at -2.3622 -8.2042 180)
			(unlocked yes)
			(layer "F.Fab")
			(hide yes)
			(effects
				(font
					(size 1.016 1.016)
					(thickness 0.1524)
				)
			)
		)
		(property "Device Type" "SOT-363H44"
			(at -2.3622 -10.1092 180)
			(unlocked yes)
			(layer "F.Fab")
			(hide yes)
			(effects
				(font
					(size 1.016 1.016)
					(thickness 0.1524)
				)
			)
		)
		(duplicate_pad_numbers_are_jumpers no)
		(fp_line
			(start 1.4478 1.7018)
			(end 1.4478 -1.7018)
			(stroke
				(width 0.1524)
				(type default)
			)
			(layer "F.SilkS")
		)
		(fp_line
			(start 1.4478 -1.7018)
			(end -1.4478 -1.7018)
			(stroke
				(width 0.1524)
				(type default)
			)
			(layer "F.SilkS")
		)
		(fp_line
			(start -1.27 1.524)
			(end -1.27 0.6604)
			(stroke
				(width 0.4826)
				(type default)
			)
			(layer "F.SilkS")
		)
		(fp_line
			(start -1.4478 1.7018)
			(end 1.4478 1.7018)
			(stroke
				(width 0.1524)
				(type default)
			)
			(layer "F.SilkS")
		)
		(fp_line
			(start -1.4478 -1.7018)
			(end -1.4478 1.7018)
			(stroke
				(width 0.1524)
				(type default)
			)
			(layer "F.SilkS")
		)
		(fp_poly
			(pts
				(xy -1.524 -1.778) (xy 1.524 -1.778) (xy 1.524 1.778) (xy -1.524 1.778)
			)
			(stroke
				(width 0)
				(type default)
			)
			(fill no)
			(layer "F.CrtYd")
		)
		(fp_poly
			(pts
				(xy -1.524 -1.778) (xy 1.524 -1.778) (xy 1.524 1.778) (xy -1.524 1.778)
			)
			(stroke
				(width 0)
				(type default)
			)
			(fill no)
			(layer "F.Fab")
		)
		(pad "1" smd rect
			(at -0.65024 0.9398 180)
			(size 0.4064 1.016)
			(layers "F.Cu" "F.Mask" "F.Paste")
			(net "GND")
		)
		(pad "2" smd rect
			(at 0 0.9398 180)
			(size 0.4064 1.016)
			(layers "F.Cu" "F.Mask" "F.Paste")
			(net "SW_PWR_R_HDD4")
		)
		(pad "3" smd rect
			(at 0.65024 0.9398 180)
			(size 0.4064 1.016)
			(layers "F.Cu" "F.Mask" "F.Paste")
			(net "SW_HDD_P4")
		)
		(pad "4" smd rect
			(at 0.65024 -0.9398 180)
			(size 0.4064 1.016)
			(layers "F.Cu" "F.Mask" "F.Paste")
			(net "GND")
		)
		(pad "5" smd rect
			(at 0 -0.9398 180)
			(size 0.4064 1.016)
			(layers "F.Cu" "F.Mask" "F.Paste")
			(net "SW_HDD_G4")
		)
		(pad "6" smd rect
			(at -0.65024 -0.9398 180)
			(size 0.4064 1.016)
			(layers "F.Cu" "F.Mask" "F.Paste")
			(net "SW_HDD_R4")
		)
	)
	(footprint ""
		(layer "F.Cu")
		(at 111.524796 -46.649894 180)
		(property "Reference" "D27"
			(at 0 0 180)
			(layer "F.SilkS")
			(hide yes)
			(effects
				(font
					(size 1.27 1.27)
				)
			)
		)
		(property "Value" "RB551V30-GP"
			(at 0 -6.7818 180)
			(unlocked yes)
			(layer "F.Fab")
			(hide yes)
			(effects
				(font
					(size 1.016 1.016)
					(thickness 0.1524)
				)
			)
		)
		(property "Device Type" "SOD323AKH38"
			(at 0 -8.6868 180)
			(unlocked yes)
			(layer "F.Fab")
			(hide yes)
			(effects
				(font
					(size 1.016 1.016)
					(thickness 0.1524)
				)
			)
		)
		(duplicate_pad_numbers_are_jumpers no)
		(fp_line
			(start 0.889 2.159)
			(end -0.889 2.159)
			(stroke
				(width 0.1524)
				(type default)
			)
			(layer "F.SilkS")
		)
		(fp_line
			(start 0.889 -1.9304)
			(end 0.889 2.159)
			(stroke
				(width 0.1524)
				(type default)
			)
			(layer "F.SilkS")
		)
		(fp_line
			(start 0.762 2.0574)
			(end -0.762 2.0574)
			(stroke
				(width 0.508)
				(type default)
			)
			(layer "F.SilkS")
		)
		(fp_line
			(start -0.889 2.159)
			(end -0.889 -1.9304)
			(stroke
				(width 0.1524)
				(type default)
			)
			(layer "F.SilkS")
		)
		(fp_line
			(start -0.889 -1.9304)
			(end 0.889 -1.9304)
			(stroke
				(width 0.1524)
				(type default)
			)
			(layer "F.SilkS")
		)
		(fp_rect
			(start -1.016 2.3114)
			(end 1.016 -2.0066)
			(stroke
				(width 0)
				(type default)
			)
			(fill no)
			(layer "F.CrtYd")
		)
		(fp_poly
			(pts
				(xy -1.016 -2.0066) (xy 1.016 -2.0066) (xy 1.016 2.3114) (xy -1.016 2.3114)
			)
			(stroke
				(width 0)
				(type default)
			)
			(fill no)
			(layer "F.Fab")
		)
		(pad "A" smd rect
			(at 0 -1.143 180)
			(size 0.5588 1.016)
			(layers "F.Cu" "F.Mask" "F.Paste")
			(net "SW_HDD_R27")
		)
		(pad "K" smd rect
			(at 0 1.143 180)
			(size 0.5588 1.016)
			(layers "F.Cu" "F.Mask" "F.Paste")
			(net "SW_HDD_N27")
		)
	)
	(footprint ""
		(layer "F.Cu")
		(at 36.178998 -295.064942 90)
		(property "Reference" "R962"
			(at 0 0 90)
			(layer "F.SilkS")
			(hide yes)
			(effects
				(font
					(size 1.27 1.27)
				)
			)
		)
		(property "Value" "220R3F-1-GP"
			(at -0.0254 -2.5146 90)
			(unlocked yes)
			(layer "F.Fab")
			(hide yes)
			(effects
				(font
					(size 1.016 1.016)
					(thickness 0.1524)
				)
			)
		)
		(property "Device Type" "R603H22"
			(at -0.0254 -4.0386 90)
			(unlocked yes)
			(layer "F.Fab")
			(hide yes)
			(effects
				(font
					(size 1.016 1.016)
					(thickness 0.1524)
				)
			)
		)
		(duplicate_pad_numbers_are_jumpers no)
		(fp_line
			(start 0.2032 0)
			(end 0.4826 0)
			(stroke
				(width 0.2032)
				(type default)
			)
			(layer "F.SilkS")
		)
		(fp_line
			(start -0.4826 0)
			(end -0.2032 0)
			(stroke
				(width 0.2032)
				(type default)
			)
			(layer "F.SilkS")
		)
		(fp_rect
			(start -0.5842 1.3335)
			(end 0.5842 -1.3335)
			(stroke
				(width 0)
				(type default)
			)
			(fill no)
			(layer "F.CrtYd")
		)
		(fp_rect
			(start -0.5842 1.3335)
			(end 0.5842 -1.3335)
			(stroke
				(width 0)
				(type default)
			)
			(fill no)
			(layer "F.Fab")
		)
		(pad "1" smd custom
			(at 0 -0.762 90)
			(size 0.2159 0.2159)
			(layers "F.Cu" "F.Mask" "F.Paste")
			(net "HDD_PRSNT_0")
			(options
				(clearance outline)
				(anchor circle)
			)
			(primitives
				(gr_poly
					(pts
						(arc
							(start -0.3302 -0.4318)
							(mid -0.402042 -0.402042)
							(end -0.4318 -0.3302)
						)
						(arc
							(start -0.4318 0.3302)
							(mid -0.402042 0.402042)
							(end -0.3302 0.4318)
						)
						(arc
							(start 0.3302 0.4318)
							(mid 0.402042 0.402042)
							(end 0.4318 0.3302)
						)
						(arc
							(start 0.4318 -0.3302)
							(mid 0.402042 -0.402042)
							(end 0.3302 -0.4318)
						)
					)
					(width 0)
					(fill yes)
				)
			)
		)
		(pad "2" smd custom
			(at 0 0.762 90)
			(size 0.2159 0.2159)
			(layers "F.Cu" "F.Mask" "F.Paste")
			(net "DRIVE_A_0_INS")
			(options
				(clearance outline)
				(anchor circle)
			)
			(primitives
				(gr_poly
					(pts
						(arc
							(start -0.3302 -0.4318)
							(mid -0.402042 -0.402042)
							(end -0.4318 -0.3302)
						)
						(arc
							(start -0.4318 0.3302)
							(mid -0.402042 0.402042)
							(end -0.3302 0.4318)
						)
						(arc
							(start 0.3302 0.4318)
							(mid 0.402042 0.402042)
							(end 0.4318 0.3302)
						)
						(arc
							(start 0.4318 -0.3302)
							(mid 0.402042 -0.402042)
							(end 0.3302 -0.4318)
						)
					)
					(width 0)
					(fill yes)
				)
			)
		)
	)
	(footprint ""
		(layer "F.Cu")
		(at 127.729996 -287.241742 90)
		(property "Reference" "R203"
			(at 0 0 90)
			(layer "F.SilkS")
			(hide yes)
			(effects
				(font
					(size 1.27 1.27)
				)
			)
		)
		(property "Value" "220R3F-1-GP"
			(at -0.0254 -2.5146 90)
			(unlocked yes)
			(layer "F.Fab")
			(hide yes)
			(effects
				(font
					(size 1.016 1.016)
					(thickness 0.1524)
				)
			)
		)
		(property "Device Type" "R603H22"
			(at -0.0254 -4.0386 90)
			(unlocked yes)
			(layer "F.Fab")
			(hide yes)
			(effects
				(font
					(size 1.016 1.016)
					(thickness 0.1524)
				)
			)
		)
		(duplicate_pad_numbers_are_jumpers no)
		(fp_line
			(start 0.2032 0)
			(end 0.4826 0)
			(stroke
				(width 0.2032)
				(type default)
			)
			(layer "F.SilkS")
		)
		(fp_line
			(start -0.4826 0)
			(end -0.2032 0)
			(stroke
				(width 0.2032)
				(type default)
			)
			(layer "F.SilkS")
		)
		(fp_rect
			(start -0.5842 1.3335)
			(end 0.5842 -1.3335)
			(stroke
				(width 0)
				(type default)
			)
			(fill no)
			(layer "F.CrtYd")
		)
		(fp_rect
			(start -0.5842 1.3335)
			(end 0.5842 -1.3335)
			(stroke
				(width 0)
				(type default)
			)
			(fill no)
			(layer "F.Fab")
		)
		(pad "1" smd custom
			(at 0 -0.762 90)
			(size 0.2159 0.2159)
			(layers "F.Cu" "F.Mask" "F.Paste")
			(net "HDD_PRSNT_3")
			(options
				(clearance outline)
				(anchor circle)
			)
			(primitives
				(gr_poly
					(pts
						(arc
							(start -0.3302 -0.4318)
							(mid -0.402042 -0.402042)
							(end -0.4318 -0.3302)
						)
						(arc
							(start -0.4318 0.3302)
							(mid -0.402042 0.402042)
							(end -0.3302 0.4318)
						)
						(arc
							(start 0.3302 0.4318)
							(mid 0.402042 0.402042)
							(end 0.4318 0.3302)
						)
						(arc
							(start 0.4318 -0.3302)
							(mid 0.402042 -0.402042)
							(end 0.3302 -0.4318)
						)
					)
					(width 0)
					(fill yes)
				)
			)
		)
		(pad "2" smd custom
			(at 0 0.762 90)
			(size 0.2159 0.2159)
			(layers "F.Cu" "F.Mask" "F.Paste")
			(net "DRIVE_A_3_INS")
			(options
				(clearance outline)
				(anchor circle)
			)
			(primitives
				(gr_poly
					(pts
						(arc
							(start -0.3302 -0.4318)
							(mid -0.402042 -0.402042)
							(end -0.4318 -0.3302)
						)
						(arc
							(start -0.4318 0.3302)
							(mid -0.402042 0.402042)
							(end -0.3302 0.4318)
						)
						(arc
							(start 0.3302 0.4318)
							(mid 0.402042 0.402042)
							(end 0.4318 0.3302)
						)
						(arc
							(start 0.4318 -0.3302)
							(mid 0.402042 -0.402042)
							(end 0.3302 -0.4318)
						)
					)
					(width 0)
					(fill yes)
				)
			)
		)
	)
	(footprint ""
		(layer "F.Cu")
		(at 172.8216 -279.2222 180)
		(property "Reference" "R261"
			(at 0 0 180)
			(layer "F.SilkS")
			(hide yes)
			(effects
				(font
					(size 1.27 1.27)
				)
			)
		)
		(property "Value" "200KR2F-L-GP"
			(at 0.064008 -3.993896 180)
			(unlocked yes)
			(layer "F.Fab")
			(hide yes)
			(effects
				(font
					(size 1.016 1.016)
					(thickness 0.1524)
				)
			)
		)
		(property "Device Type" "R402H16"
			(at 0.064008 -5.517896 180)
			(unlocked yes)
			(layer "F.Fab")
			(hide yes)
			(effects
				(font
					(size 1.016 1.016)
					(thickness 0.1524)
				)
			)
		)
		(duplicate_pad_numbers_are_jumpers no)
		(fp_line
			(start 0.508 -0.9398)
			(end -0.508 -0.9398)
			(stroke
				(width 0.1524)
				(type default)
			)
			(layer "F.SilkS")
		)
		(fp_line
			(start -0.508 -0.9398)
			(end -0.508 0.9398)
			(stroke
				(width 0.1524)
				(type default)
			)
			(layer "F.SilkS")
		)
		(fp_rect
			(start -0.508 0.9398)
			(end 0.508 -0.9398)
			(stroke
				(width 0)
				(type default)
			)
			(fill no)
			(layer "F.CrtYd")
		)
		(fp_rect
			(start -0.508 0.9398)
			(end 0.508 -0.9398)
			(stroke
				(width 0)
				(type default)
			)
			(fill no)
			(layer "F.Fab")
		)
		(pad "1" smd custom
			(at 0 -0.4445 180)
			(size 0.1397 0.1397)
			(layers "F.Cu" "F.Mask" "F.Paste")
			(net "SW_HDD_R5")
			(options
				(clearance outline)
				(anchor circle)
			)
			(primitives
				(gr_poly
					(pts
						(arc
							(start -0.1778 -0.2794)
							(mid -0.249642 -0.249642)
							(end -0.2794 -0.1778)
						)
						(arc
							(start -0.2794 0.1778)
							(mid -0.249642 0.249642)
							(end -0.1778 0.2794)
						)
						(arc
							(start 0.1778 0.2794)
							(mid 0.249642 0.249642)
							(end 0.2794 0.1778)
						)
						(arc
							(start 0.2794 -0.1778)
							(mid 0.249642 -0.249642)
							(end 0.1778 -0.2794)
						)
					)
					(width 0)
					(fill yes)
				)
			)
		)
		(pad "2" smd custom
			(at 0 0.4445 180)
			(size 0.1397 0.1397)
			(layers "F.Cu" "F.Mask" "F.Paste")
			(net "SW_HDD_N5")
			(options
				(clearance outline)
				(anchor circle)
			)
			(primitives
				(gr_poly
					(pts
						(arc
							(start -0.1778 -0.2794)
							(mid -0.249642 -0.249642)
							(end -0.2794 -0.1778)
						)
						(arc
							(start -0.2794 0.1778)
							(mid -0.249642 0.249642)
							(end -0.1778 0.2794)
						)
						(arc
							(start 0.1778 0.2794)
							(mid 0.249642 0.249642)
							(end 0.2794 0.1778)
						)
						(arc
							(start 0.2794 -0.1778)
							(mid 0.249642 -0.249642)
							(end 0.1778 -0.2794)
						)
					)
					(width 0)
					(fill yes)
				)
			)
		)
	)
	(footprint ""
		(layer "F.Cu")
		(at 469.492584 -277.472902 90)
		(property "Reference" "D11"
			(at 0 0 90)
			(layer "F.SilkS")
			(hide yes)
			(effects
				(font
					(size 1.27 1.27)
				)
			)
		)
		(property "Value" "RB551V30-GP"
			(at 0 -6.7818 90)
			(unlocked yes)
			(layer "F.Fab")
			(hide yes)
			(effects
				(font
					(size 1.016 1.016)
					(thickness 0.1524)
				)
			)
		)
		(property "Device Type" "SOD323AKH38"
			(at 0 -8.6868 90)
			(unlocked yes)
			(layer "F.Fab")
			(hide yes)
			(effects
				(font
					(size 1.016 1.016)
					(thickness 0.1524)
				)
			)
		)
		(duplicate_pad_numbers_are_jumpers no)
		(fp_line
			(start 0.889 -1.9304)
			(end 0.889 2.159)
			(stroke
				(width 0.1524)
				(type default)
			)
			(layer "F.SilkS")
		)
		(fp_line
			(start -0.889 -1.9304)
			(end 0.889 -1.9304)
			(stroke
				(width 0.1524)
				(type default)
			)
			(layer "F.SilkS")
		)
		(fp_line
			(start 0.762 2.0574)
			(end -0.762 2.0574)
			(stroke
				(width 0.508)
				(type default)
			)
			(layer "F.SilkS")
		)
		(fp_line
			(start 0.889 2.159)
			(end -0.889 2.159)
			(stroke
				(width 0.1524)
				(type default)
			)
			(layer "F.SilkS")
		)
		(fp_line
			(start -0.889 2.159)
			(end -0.889 -1.9304)
			(stroke
				(width 0.1524)
				(type default)
			)
			(layer "F.SilkS")
		)
		(fp_rect
			(start -1.016 2.3114)
			(end 1.016 -2.0066)
			(stroke
				(width 0)
				(type default)
			)
			(fill no)
			(layer "F.CrtYd")
		)
		(fp_poly
			(pts
				(xy -1.016 -2.0066) (xy 1.016 -2.0066) (xy 1.016 2.3114) (xy -1.016 2.3114)
			)
			(stroke
				(width 0)
				(type default)
			)
			(fill no)
			(layer "F.Fab")
		)
		(pad "A" smd rect
			(at 0 -1.143 90)
			(size 0.5588 1.016)
			(layers "F.Cu" "F.Mask" "F.Paste")
			(net "SW_HDD_R11")
		)
		(pad "K" smd rect
			(at 0 1.143 90)
			(size 0.5588 1.016)
			(layers "F.Cu" "F.Mask" "F.Paste")
			(net "SW_HDD_N11")
		)
	)
	(footprint ""
		(layer "F.Cu")
		(at 239.300004 -111.149892 90)
		(property "Reference" "MONO1"
			(at 0 0 90)
			(layer "F.SilkS")
			(hide yes)
			(effects
				(font
					(size 1.27 1.27)
				)
			)
		)
		(property "Value" "AMP-CONN164-4R-1-GP"
			(at -25.705054 -1.203706 90)
			(unlocked yes)
			(layer "F.Fab")
			(hide yes)
			(effects
				(font
					(size 1.016 1.016)
					(thickness 0.1524)
				)
			)
		)
		(property "Device Type" "PREFIT-164P-890091-1H441"
			(at -25.705054 -2.727706 90)
			(unlocked yes)
			(layer "F.Fab")
			(hide yes)
			(effects
				(font
					(size 1.016 1.016)
					(thickness 0.1524)
				)
			)
		)
		(duplicate_pad_numbers_are_jumpers no)
		(fp_line
			(start 74.5998 -4.1656)
			(end 74.5998 5.4102)
			(stroke
				(width 0.1524)
				(type default)
			)
			(layer "F.SilkS")
		)
		(fp_line
			(start -14.9098 -4.1656)
			(end 74.5998 -4.1656)
			(stroke
				(width 0.1524)
				(type default)
			)
			(layer "F.SilkS")
		)
		(fp_line
			(start 74.5998 5.4102)
			(end -14.9098 5.4102)
			(stroke
				(width 0.1524)
				(type default)
			)
			(layer "F.SilkS")
		)
		(fp_line
			(start -14.9098 5.4102)
			(end -14.9098 -4.1656)
			(stroke
				(width 0.1524)
				(type default)
			)
			(layer "F.SilkS")
		)
		(fp_poly
			(pts
				(xy -14.9098 5.4102) (xy -14.9098 -4.1656) (xy 74.5998 -4.1656) (xy 74.5998 -3.98653) (xy -13.5636 -3.98653)
				(xy -13.5636 3.98653) (xy 23.4442 3.98653) (xy 23.4442 5.3086) (xy 33.8074 5.3086) (xy 33.8074 3.98653)
				(xy 74.5998 3.98653) (xy 74.5998 5.4102)
			)
			(stroke
				(width 0)
				(type default)
			)
			(fill yes)
			(layer "F.SilkS")
		)
		(fp_poly
			(pts
				(arc
					(start -13.1826 -2.99593)
					(mid -13.4366 -3.24993)
					(end -13.1826 -3.50393)
				)
				(arc
					(start -12.6746 -3.50393)
					(mid -12.4206 -3.24993)
					(end -12.6746 -2.99593)
				)
			)
			(stroke
				(width 0)
				(type default)
			)
			(fill yes)
			(layer "F.SilkS")
		)
		(fp_poly
			(pts
				(arc
					(start -13.1826 -0.995934)
					(mid -13.4366 -1.249934)
					(end -13.1826 -1.503934)
				)
				(arc
					(start -12.6746 -1.503934)
					(mid -12.4206 -1.249934)
					(end -12.6746 -0.995934)
				)
			)
			(stroke
				(width 0)
				(type default)
			)
			(fill yes)
			(layer "F.SilkS")
		)
		(fp_poly
			(pts
				(arc
					(start -13.1826 1.503934)
					(mid -13.4366 1.249934)
					(end -13.1826 0.995934)
				)
				(arc
					(start -12.6746 0.995934)
					(mid -12.4206 1.249934)
					(end -12.6746 1.503934)
				)
			)
			(stroke
				(width 0)
				(type default)
			)
			(fill yes)
			(layer "F.SilkS")
		)
		(fp_poly
			(pts
				(arc
					(start -13.1826 3.50393)
					(mid -13.4366 3.24993)
					(end -13.1826 2.99593)
				)
				(arc
					(start -12.6746 2.99593)
					(mid -12.4206 3.24993)
					(end -12.6746 3.50393)
				)
			)
			(stroke
				(width 0)
				(type default)
			)
			(fill yes)
			(layer "F.SilkS")
		)
		(fp_rect
			(start -17.1958 8.7884)
			(end 76.8858 -8.7884)
			(stroke
				(width 0)
				(type default)
			)
			(fill no)
			(layer "B.CrtYd")
		)
		(fp_rect
			(start -14.6558 5.1562)
			(end 74.3458 -3.9116)
			(stroke
				(width 0)
				(type default)
			)
			(fill no)
			(layer "F.CrtYd")
		)
		(fp_poly
			(pts
				(xy -15.1638 5.6642) (xy -15.1638 -4.4196) (xy 74.8538 -4.4196) (xy 74.8538 -0.00635) (xy 74.3458 -0.00635)
				(xy 74.3458 -3.9116) (xy -14.6558 -3.9116) (xy -14.6558 5.1562) (xy 74.3458 5.1562) (xy 74.3458 0.00635)
				(xy 74.8538 0.00635) (xy 74.8538 5.6642)
			)
			(stroke
				(width 0)
				(type default)
			)
			(fill no)
			(layer "F.CrtYd")
		)
		(fp_poly
			(pts
				(xy -19.6596 10.16) (xy -19.6596 0.00635) (xy -15.1638 0.00635) (xy -15.1638 5.6642) (xy 74.8538 5.6642)
				(xy 74.8538 -4.4196) (xy -15.1638 -4.4196) (xy -15.1638 -0.00635) (xy -19.6596 -0.00635) (xy -19.6596 -8.9154)
				(xy 79.3496 -8.9154) (xy 79.3496 10.16)
			)
			(stroke
				(width 0)
				(type default)
			)
			(fill no)
			(layer "F.CrtYd")
		)
		(fp_rect
			(start -17.1958 8.7884)
			(end 76.8858 -8.7884)
			(stroke
				(width 0)
				(type default)
			)
			(fill no)
			(layer "B.Fab")
		)
		(fp_rect
			(start -22.1996 13.7922)
			(end 81.8896 -13.7922)
			(stroke
				(width 0)
				(type default)
			)
			(fill no)
			(layer "B.Fab")
		)
		(fp_rect
			(start -15.1638 5.6642)
			(end 74.8538 -4.4196)
			(stroke
				(width 0)
				(type default)
			)
			(fill no)
			(layer "F.Fab")
		)
		(fp_rect
			(start -19.6596 10.16)
			(end 79.3496 -8.9154)
			(stroke
				(width 0)
				(type default)
			)
			(fill no)
			(layer "F.Fab")
		)
		(fp_rect
			(start -24.6634 15.1638)
			(end 84.3534 -13.9192)
			(stroke
				(width 0)
				(type default)
			)
			(fill no)
			(layer "F.Fab")
		)
		(fp_text user "Press Fit"
			(at 23.495 4.6482 90)
			(unlocked yes)
			(layer "F.SilkS")
			(effects
				(font
					(size 1.016 1.016)
					(thickness 0.1524)
				)
				(justify left)
			)
		)
		(fp_text user "Can not place BGA,CSP,Wave Solder Component"
			(at 2.032 12.2428 90)
			(unlocked yes)
			(layer "B.Fab")
			(effects
				(font
					(size 1.016 1.016)
					(thickness 0.1524)
				)
				(justify left)
			)
		)
		(fp_text user "High Limit 2mm"
			(at 18.8214 9.025636 90)
			(unlocked yes)
			(layer "F.Fab")
			(effects
				(font
					(size 1.016 1.016)
					(thickness 0.1524)
				)
				(justify left)
			)
		)
		(fp_text user "Can not place BGA,CSP,Wave Solder Component"
			(at 2.032 13.7668 90)
			(unlocked yes)
			(layer "F.Fab")
			(effects
				(font
					(size 1.016 1.016)
					(thickness 0.1524)
				)
				(justify left)
			)
		)
		(pad "" np_thru_hole circle
			(at 0 0 90)
			(size 0.254 0.254)
			(drill 2.3622)
			(layers "*.Cu" "*.Mask")
			(clearance 1.4097)
			(thermal_gap 1.4097)
		)
		(pad "" np_thru_hole circle
			(at 73.149968 0 90)
			(size 0.254 0.254)
			(drill 2.3622)
			(layers "*.Cu" "*.Mask")
			(clearance 1.4097)
			(thermal_gap 1.4097)
		)
		(pad "A1" thru_hole circle
			(at -11.649964 -1.249934 90)
			(size 1.0668 1.0668)
			(drill 0.719836)
			(layers "*.Cu" "*.Mask")
			(remove_unused_layers no)
			(net "COMP_A_PRI_INS_N")
			(clearance 0.1905)
			(thermal_gap 0.1905)
		)
		(pad "A2" thru_hole circle
			(at -10.649966 -3.24993 90)
			(size 1.0668 1.0668)
			(drill 0.719836)
			(layers "*.Cu" "*.Mask")
			(remove_unused_layers no)
			(net "P12V_A_COMP")
			(clearance 0.1905)
			(thermal_gap 0.1905)
		)
		(pad "A3" thru_hole circle
			(at -9.649968 -1.249934 90)
			(size 1.0668 1.0668)
			(drill 0.719836)
			(layers "*.Cu" "*.Mask")
			(remove_unused_layers no)
			(net "P12V_A_COMP")
			(clearance 0.1905)
			(thermal_gap 0.1905)
		)
		(pad "A4" thru_hole circle
			(at -8.64997 -3.24993 90)
			(size 1.0668 1.0668)
			(drill 0.719836)
			(layers "*.Cu" "*.Mask")
			(remove_unused_layers no)
			(net "GND")
			(clearance 0.1905)
			(thermal_gap 0.1905)
		)
		(pad "A5" thru_hole circle
			(at -7.649972 -1.249934 90)
			(size 1.0668 1.0668)
			(drill 0.719836)
			(layers "*.Cu" "*.Mask")
			(remove_unused_layers no)
			(net "SLOT3_SVR_ID0_GPIO0")
			(clearance 0.1905)
			(thermal_gap 0.1905)
		)
		(pad "A6" thru_hole circle
			(at -6.649974 -3.24993 90)
			(size 1.0668 1.0668)
			(drill 0.719836)
			(layers "*.Cu" "*.Mask")
			(remove_unused_layers no)
			(net "SLOT3_SVR_ID0_GPIO1")
			(clearance 0.1905)
			(thermal_gap 0.1905)
		)
		(pad "A7" thru_hole circle
			(at -5.649976 -1.249934 90)
			(size 1.0668 1.0668)
			(drill 0.719836)
			(layers "*.Cu" "*.Mask")
			(remove_unused_layers no)
			(net "UART_COMP_A_TX")
			(clearance 0.1905)
			(thermal_gap 0.1905)
		)
		(pad "A8" thru_hole circle
			(at -4.649978 -3.24993 90)
			(size 1.0668 1.0668)
			(drill 0.719836)
			(layers "*.Cu" "*.Mask")
			(remove_unused_layers no)
			(net "UART_COMP_A_RX")
			(clearance 0.1905)
			(thermal_gap 0.1905)
		)
		(pad "A9" thru_hole circle
			(at -3.64998 -1.249934 90)
			(size 1.0668 1.0668)
			(drill 0.719836)
			(layers "*.Cu" "*.Mask")
			(remove_unused_layers no)
			(net "SLOT3_SVR_ID0_GPIO2")
			(clearance 0.1905)
			(thermal_gap 0.1905)
		)
		(pad "A10" thru_hole circle
			(at -2.649982 -3.24993 90)
			(size 1.0668 1.0668)
			(drill 0.719836)
			(layers "*.Cu" "*.Mask")
			(remove_unused_layers no)
			(net "SLOT3_SVR_ID0_GPIO3")
			(clearance 0.1905)
			(thermal_gap 0.1905)
		)
		(pad "A11" thru_hole circle
			(at -1.649984 -1.249934 90)
			(size 1.0668 1.0668)
			(drill 0.719836)
			(layers "*.Cu" "*.Mask")
			(remove_unused_layers no)
			(net "PCIE_COMP_A_TO_SCC_A_RST_0")
			(clearance 0.1905)
			(thermal_gap 0.1905)
		)
		(pad "A12" thru_hole circle
			(at 1.35001 -3.24993 90)
			(size 1.0668 1.0668)
			(drill 0.719836)
			(layers "*.Cu" "*.Mask")
			(remove_unused_layers no)
			(net "GND")
			(clearance 0.1905)
			(thermal_gap 0.1905)
		)
		(pad "A13" thru_hole circle
			(at 2.350008 -1.249934 90)
			(size 1.0668 1.0668)
			(drill 0.719836)
			(layers "*.Cu" "*.Mask")
			(remove_unused_layers no)
			(net "PCIE_COMP_A_TO_SCC_A_CLK_0_DP")
			(clearance 0.1905)
			(thermal_gap 0.1905)
		)
		(pad "A14" thru_hole circle
			(at 3.350006 -3.24993 90)
			(size 1.0668 1.0668)
			(drill 0.719836)
			(layers "*.Cu" "*.Mask")
			(remove_unused_layers no)
			(net "PCIE_COMP_A_TO_SCC_A_CLK_0_DN")
			(clearance 0.1905)
			(thermal_gap 0.1905)
		)
		(pad "A15" thru_hole circle
			(at 4.350004 -1.249934 90)
			(size 1.0668 1.0668)
			(drill 0.719836)
			(layers "*.Cu" "*.Mask")
			(remove_unused_layers no)
			(net "GND")
			(clearance 0.1905)
			(thermal_gap 0.1905)
		)
		(pad "A16" thru_hole circle
			(at 5.350002 -3.24993 90)
			(size 1.0668 1.0668)
			(drill 0.719836)
			(layers "*.Cu" "*.Mask")
			(remove_unused_layers no)
			(net "GND")
			(clearance 0.1905)
			(thermal_gap 0.1905)
		)
		(pad "A17" thru_hole circle
			(at 6.35 -1.249934 90)
			(size 1.0668 1.0668)
			(drill 0.719836)
			(layers "*.Cu" "*.Mask")
			(remove_unused_layers no)
			(net "PCIE_SCC_A_TO_COMP_A_0_DP")
			(clearance 0.1905)
			(thermal_gap 0.1905)
		)
		(pad "A18" thru_hole circle
			(at 7.349998 -3.24993 90)
			(size 1.0668 1.0668)
			(drill 0.719836)
			(layers "*.Cu" "*.Mask")
			(remove_unused_layers no)
			(net "PCIE_SCC_A_TO_COMP_A_0_DN")
			(clearance 0.1905)
			(thermal_gap 0.1905)
		)
		(pad "A19" thru_hole circle
			(at 8.349996 -1.249934 90)
			(size 1.0668 1.0668)
			(drill 0.719836)
			(layers "*.Cu" "*.Mask")
			(remove_unused_layers no)
			(net "GND")
			(clearance 0.1905)
			(thermal_gap 0.1905)
		)
		(pad "A20" thru_hole circle
			(at 9.349994 -3.24993 90)
			(size 1.0668 1.0668)
			(drill 0.719836)
			(layers "*.Cu" "*.Mask")
			(remove_unused_layers no)
			(net "GND")
			(clearance 0.1905)
			(thermal_gap 0.1905)
		)
		(pad "A21" thru_hole circle
			(at 10.349992 -1.249934 90)
			(size 1.0668 1.0668)
			(drill 0.719836)
			(layers "*.Cu" "*.Mask")
			(remove_unused_layers no)
			(net "PCIE_SCC_A_TO_COMP_A_1_DP")
			(clearance 0.1905)
			(thermal_gap 0.1905)
		)
		(pad "A22" thru_hole circle
			(at 11.34999 -3.24993 90)
			(size 1.0668 1.0668)
			(drill 0.719836)
			(layers "*.Cu" "*.Mask")
			(remove_unused_layers no)
			(net "PCIE_SCC_A_TO_COMP_A_1_DN")
			(clearance 0.1905)
			(thermal_gap 0.1905)
		)
		(pad "A23" thru_hole circle
			(at 12.349988 -1.249934 90)
			(size 1.0668 1.0668)
			(drill 0.719836)
			(layers "*.Cu" "*.Mask")
			(remove_unused_layers no)
			(net "GND")
			(clearance 0.1905)
			(thermal_gap 0.1905)
		)
		(pad "A24" thru_hole circle
			(at 13.349986 -3.24993 90)
			(size 1.0668 1.0668)
			(drill 0.719836)
			(layers "*.Cu" "*.Mask")
			(remove_unused_layers no)
			(net "GND")
			(clearance 0.1905)
			(thermal_gap 0.1905)
		)
		(pad "A25" thru_hole circle
			(at 14.349984 -1.249934 90)
			(size 1.0668 1.0668)
			(drill 0.719836)
			(layers "*.Cu" "*.Mask")
			(remove_unused_layers no)
			(net "PCIE_SCC_A_TO_COMP_A_2_DP")
			(clearance 0.1905)
			(thermal_gap 0.1905)
		)
		(pad "A26" thru_hole circle
			(at 15.349982 -3.24993 90)
			(size 1.0668 1.0668)
			(drill 0.719836)
			(layers "*.Cu" "*.Mask")
			(remove_unused_layers no)
			(net "PCIE_SCC_A_TO_COMP_A_2_DN")
			(clearance 0.1905)
			(thermal_gap 0.1905)
		)
		(pad "A27" thru_hole circle
			(at 16.34998 -1.249934 90)
			(size 1.0668 1.0668)
			(drill 0.719836)
			(layers "*.Cu" "*.Mask")
			(remove_unused_layers no)
			(net "GND")
			(clearance 0.1905)
			(thermal_gap 0.1905)
		)
		(pad "A28" thru_hole circle
			(at 17.349978 -3.24993 90)
			(size 1.0668 1.0668)
			(drill 0.719836)
			(layers "*.Cu" "*.Mask")
			(remove_unused_layers no)
			(net "GND")
			(clearance 0.1905)
			(thermal_gap 0.1905)
		)
		(pad "A29" thru_hole circle
			(at 18.349976 -1.249934 90)
			(size 1.0668 1.0668)
			(drill 0.719836)
			(layers "*.Cu" "*.Mask")
			(remove_unused_layers no)
			(net "PCIE_SCC_A_TO_COMP_A_3_DP")
			(clearance 0.1905)
			(thermal_gap 0.1905)
		)
		(pad "A30" thru_hole circle
			(at 19.349974 -3.24993 90)
			(size 1.0668 1.0668)
			(drill 0.719836)
			(layers "*.Cu" "*.Mask")
			(remove_unused_layers no)
			(net "PCIE_SCC_A_TO_COMP_A_3_DN")
			(clearance 0.1905)
			(thermal_gap 0.1905)
		)
		(pad "A31" thru_hole circle
			(at 20.349972 -1.249934 90)
			(size 1.0668 1.0668)
			(drill 0.719836)
			(layers "*.Cu" "*.Mask")
			(remove_unused_layers no)
			(net "GND")
			(clearance 0.1905)
			(thermal_gap 0.1905)
		)
		(pad "A32" thru_hole circle
			(at 21.34997 -3.24993 90)
			(size 1.0668 1.0668)
			(drill 0.719836)
			(layers "*.Cu" "*.Mask")
			(remove_unused_layers no)
			(net "GND")
			(clearance 0.1905)
			(thermal_gap 0.1905)
		)
		(pad "A33" thru_hole circle
			(at 22.349968 -1.249934 90)
			(size 1.0668 1.0668)
			(drill 0.719836)
			(layers "*.Cu" "*.Mask")
			(remove_unused_layers no)
			(net "TP_COMP_A_SATA_P0_RX_DP")
			(clearance 0.1905)
			(thermal_gap 0.1905)
		)
		(pad "A34" thru_hole circle
			(at 23.349966 -3.24993 90)
			(size 1.0668 1.0668)
			(drill 0.719836)
			(layers "*.Cu" "*.Mask")
			(remove_unused_layers no)
			(net "TP_COMP_A_SATA_P0_RX_DN")
			(clearance 0.1905)
			(thermal_gap 0.1905)
		)
		(pad "A35" thru_hole circle
			(at 24.349964 -1.249934 90)
			(size 1.0668 1.0668)
			(drill 0.719836)
			(layers "*.Cu" "*.Mask")
			(remove_unused_layers no)
			(net "GND")
			(clearance 0.1905)
			(thermal_gap 0.1905)
		)
		(pad "A36" thru_hole circle
			(at 25.349962 -3.24993 90)
			(size 1.0668 1.0668)
			(drill 0.719836)
			(layers "*.Cu" "*.Mask")
			(remove_unused_layers no)
			(net "GND")
			(clearance 0.1905)
			(thermal_gap 0.1905)
		)
		(pad "A37" thru_hole circle
			(at 26.34996 -1.249934 90)
			(size 1.0668 1.0668)
			(drill 0.719836)
			(layers "*.Cu" "*.Mask")
			(remove_unused_layers no)
			(net "PCIE_COMP_A_TO_IOM_A_CLK_2_DP")
			(clearance 0.1905)
			(thermal_gap 0.1905)
		)
		(pad "A38" thru_hole circle
			(at 27.349958 -3.24993 90)
			(size 1.0668 1.0668)
			(drill 0.719836)
			(layers "*.Cu" "*.Mask")
			(remove_unused_layers no)
			(net "PCIE_COMP_A_TO_IOM_A_CLK_2_DN")
			(clearance 0.1905)
			(thermal_gap 0.1905)
		)
		(pad "A39" thru_hole circle
			(at 28.349956 -1.249934 90)
			(size 1.0668 1.0668)
			(drill 0.719836)
			(layers "*.Cu" "*.Mask")
			(remove_unused_layers no)
			(net "GND")
			(clearance 0.1905)
			(thermal_gap 0.1905)
		)
		(pad "A40" thru_hole circle
			(at 29.349954 -3.24993 90)
			(size 1.0668 1.0668)
			(drill 0.719836)
			(layers "*.Cu" "*.Mask")
			(remove_unused_layers no)
			(net "GND")
			(clearance 0.1905)
			(thermal_gap 0.1905)
		)
		(pad "A41" thru_hole circle
			(at 30.349952 -1.249934 90)
			(size 1.0668 1.0668)
			(drill 0.719836)
			(layers "*.Cu" "*.Mask")
			(remove_unused_layers no)
			(net "COMP_A_FAST_THROTTLE_N")
			(clearance 0.1905)
			(thermal_gap 0.1905)
		)
		(pad "A42" thru_hole circle
			(at 31.34995 -3.24993 90)
			(size 1.0668 1.0668)
			(drill 0.719836)
			(layers "*.Cu" "*.Mask")
			(remove_unused_layers no)
			(net "TP_SMB_COMP_A_NIC_ALERT_N")
			(clearance 0.1905)
			(thermal_gap 0.1905)
		)
		(pad "A43" thru_hole circle
			(at 32.349948 -1.249934 90)
			(size 1.0668 1.0668)
			(drill 0.719836)
			(layers "*.Cu" "*.Mask")
			(remove_unused_layers no)
			(net "GND")
			(clearance 0.1905)
			(thermal_gap 0.1905)
		)
		(pad "A44" thru_hole circle
			(at 33.349946 -3.24993 90)
			(size 1.0668 1.0668)
			(drill 0.719836)
			(layers "*.Cu" "*.Mask")
			(remove_unused_layers no)
			(net "GND")
			(clearance 0.1905)
			(thermal_gap 0.1905)
		)
		(pad "A45" thru_hole circle
			(at 34.349944 -1.249934 90)
			(size 1.0668 1.0668)
			(drill 0.719836)
			(layers "*.Cu" "*.Mask")
			(remove_unused_layers no)
			(net "TP_COMP_A_KR_P0_RX_DP")
			(clearance 0.1905)
			(thermal_gap 0.1905)
		)
		(pad "A46" thru_hole circle
			(at 35.349942 -3.24993 90)
			(size 1.0668 1.0668)
			(drill 0.719836)
			(layers "*.Cu" "*.Mask")
			(remove_unused_layers no)
			(net "TP_COMP_A_KR_P0_RX_DN")
			(clearance 0.1905)
			(thermal_gap 0.1905)
		)
		(pad "A47" thru_hole circle
			(at 36.34994 -1.249934 90)
			(size 1.0668 1.0668)
			(drill 0.719836)
			(layers "*.Cu" "*.Mask")
			(remove_unused_layers no)
			(net "GND")
			(clearance 0.1905)
			(thermal_gap 0.1905)
		)
		(pad "A48" thru_hole circle
			(at 37.349938 -3.24993 90)
			(size 1.0668 1.0668)
			(drill 0.719836)
			(layers "*.Cu" "*.Mask")
			(remove_unused_layers no)
			(net "GND")
			(clearance 0.1905)
			(thermal_gap 0.1905)
		)
		(pad "A49" thru_hole circle
			(at 38.349936 -1.249934 90)
			(size 1.0668 1.0668)
			(drill 0.719836)
			(layers "*.Cu" "*.Mask")
			(remove_unused_layers no)
			(net "PCIE_SCC_A_TO_COMP_A_4_DP")
			(clearance 0.1905)
			(thermal_gap 0.1905)
		)
		(pad "A50" thru_hole circle
			(at 39.349934 -3.24993 90)
			(size 1.0668 1.0668)
			(drill 0.719836)
			(layers "*.Cu" "*.Mask")
			(remove_unused_layers no)
			(net "PCIE_SCC_A_TO_COMP_A_4_DN")
			(clearance 0.1905)
			(thermal_gap 0.1905)
		)
		(pad "A51" thru_hole circle
			(at 40.349932 -1.249934 90)
			(size 1.0668 1.0668)
			(drill 0.719836)
			(layers "*.Cu" "*.Mask")
			(remove_unused_layers no)
			(net "GND")
			(clearance 0.1905)
			(thermal_gap 0.1905)
		)
		(pad "A52" thru_hole circle
			(at 41.34993 -3.24993 90)
			(size 1.0668 1.0668)
			(drill 0.719836)
			(layers "*.Cu" "*.Mask")
			(remove_unused_layers no)
			(net "GND")
			(clearance 0.1905)
			(thermal_gap 0.1905)
		)
		(pad "A53" thru_hole circle
			(at 42.349928 -1.249934 90)
			(size 1.0668 1.0668)
			(drill 0.719836)
			(layers "*.Cu" "*.Mask")
			(remove_unused_layers no)
			(net "PCIE_SCC_A_TO_COMP_A_5_DP")
			(clearance 0.1905)
			(thermal_gap 0.1905)
		)
		(pad "A54" thru_hole circle
			(at 43.349926 -3.24993 90)
			(size 1.0668 1.0668)
			(drill 0.719836)
			(layers "*.Cu" "*.Mask")
			(remove_unused_layers no)
			(net "PCIE_SCC_A_TO_COMP_A_5_DN")
			(clearance 0.1905)
			(thermal_gap 0.1905)
		)
		(pad "A55" thru_hole circle
			(at 44.349924 -1.249934 90)
			(size 1.0668 1.0668)
			(drill 0.719836)
			(layers "*.Cu" "*.Mask")
			(remove_unused_layers no)
			(net "GND")
			(clearance 0.1905)
			(thermal_gap 0.1905)
		)
		(pad "A56" thru_hole circle
			(at 45.349922 -3.24993 90)
			(size 1.0668 1.0668)
			(drill 0.719836)
			(layers "*.Cu" "*.Mask")
			(remove_unused_layers no)
			(net "GND")
			(clearance 0.1905)
			(thermal_gap 0.1905)
		)
		(pad "A57" thru_hole circle
			(at 46.34992 -1.249934 90)
			(size 1.0668 1.0668)
			(drill 0.719836)
			(layers "*.Cu" "*.Mask")
			(remove_unused_layers no)
			(net "PCIE_SCC_A_TO_COMP_A_6_DP")
			(clearance 0.1905)
			(thermal_gap 0.1905)
		)
		(pad "A58" thru_hole circle
			(at 47.349918 -3.24993 90)
			(size 1.0668 1.0668)
			(drill 0.719836)
			(layers "*.Cu" "*.Mask")
			(remove_unused_layers no)
			(net "PCIE_SCC_A_TO_COMP_A_6_DN")
			(clearance 0.1905)
			(thermal_gap 0.1905)
		)
		(pad "A59" thru_hole circle
			(at 48.349916 -1.249934 90)
			(size 1.0668 1.0668)
			(drill 0.719836)
			(layers "*.Cu" "*.Mask")
			(remove_unused_layers no)
			(net "GND")
			(clearance 0.1905)
			(thermal_gap 0.1905)
		)
		(pad "A60" thru_hole circle
			(at 49.349914 -3.24993 90)
			(size 1.0668 1.0668)
			(drill 0.719836)
			(layers "*.Cu" "*.Mask")
			(remove_unused_layers no)
			(net "GND")
			(clearance 0.1905)
			(thermal_gap 0.1905)
		)
		(pad "A61" thru_hole circle
			(at 50.349912 -1.249934 90)
			(size 1.0668 1.0668)
			(drill 0.719836)
			(layers "*.Cu" "*.Mask")
			(remove_unused_layers no)
			(net "PCIE_SCC_A_TO_COMP_A_7_DP")
			(clearance 0.1905)
			(thermal_gap 0.1905)
		)
		(pad "A62" thru_hole circle
			(at 51.34991 -3.24993 90)
			(size 1.0668 1.0668)
			(drill 0.719836)
			(layers "*.Cu" "*.Mask")
			(remove_unused_layers no)
			(net "PCIE_SCC_A_TO_COMP_A_7_DN")
			(clearance 0.1905)
			(thermal_gap 0.1905)
		)
		(pad "A63" thru_hole circle
			(at 52.349908 -1.249934 90)
			(size 1.0668 1.0668)
			(drill 0.719836)
			(layers "*.Cu" "*.Mask")
			(remove_unused_layers no)
			(net "GND")
			(clearance 0.1905)
			(thermal_gap 0.1905)
		)
		(pad "A64" thru_hole circle
			(at 53.349906 -3.24993 90)
			(size 1.0668 1.0668)
			(drill 0.719836)
			(layers "*.Cu" "*.Mask")
			(remove_unused_layers no)
			(net "GND")
			(clearance 0.1905)
			(thermal_gap 0.1905)
		)
		(pad "A65" thru_hole circle
			(at 54.349904 -1.249934 90)
			(size 1.0668 1.0668)
			(drill 0.719836)
			(layers "*.Cu" "*.Mask")
			(remove_unused_layers no)
			(net "PCIE_IOM_A_TO_COMP_A_8_DP")
			(clearance 0.1905)
			(thermal_gap 0.1905)
		)
		(pad "A66" thru_hole circle
			(at 55.349902 -3.24993 90)
			(size 1.0668 1.0668)
			(drill 0.719836)
			(layers "*.Cu" "*.Mask")
			(remove_unused_layers no)
			(net "PCIE_IOM_A_TO_COMP_A_8_DN")
			(clearance 0.1905)
			(thermal_gap 0.1905)
		)
		(pad "A67" thru_hole circle
			(at 56.3499 -1.249934 90)
			(size 1.0668 1.0668)
			(drill 0.719836)
			(layers "*.Cu" "*.Mask")
			(remove_unused_layers no)
			(net "GND")
			(clearance 0.1905)
			(thermal_gap 0.1905)
		)
		(pad "A68" thru_hole circle
			(at 57.349898 -3.24993 90)
			(size 1.0668 1.0668)
			(drill 0.719836)
			(layers "*.Cu" "*.Mask")
			(remove_unused_layers no)
			(net "GND")
			(clearance 0.1905)
			(thermal_gap 0.1905)
		)
		(pad "A69" thru_hole circle
			(at 58.349896 -1.249934 90)
			(size 1.0668 1.0668)
			(drill 0.719836)
			(layers "*.Cu" "*.Mask")
			(remove_unused_layers no)
			(net "PCIE_IOM_A_TO_COMP_A_9_DP")
			(clearance 0.1905)
			(thermal_gap 0.1905)
		)
		(pad "A70" thru_hole circle
			(at 59.349894 -3.24993 90)
			(size 1.0668 1.0668)
			(drill 0.719836)
			(layers "*.Cu" "*.Mask")
			(remove_unused_layers no)
			(net "PCIE_IOM_A_TO_COMP_A_9_DN")
			(clearance 0.1905)
			(thermal_gap 0.1905)
		)
		(pad "A71" thru_hole circle
			(at 60.349892 -1.249934 90)
			(size 1.0668 1.0668)
			(drill 0.719836)
			(layers "*.Cu" "*.Mask")
			(remove_unused_layers no)
			(net "GND")
			(clearance 0.1905)
			(thermal_gap 0.1905)
		)
		(pad "A72" thru_hole circle
			(at 61.34989 -3.24993 90)
			(size 1.0668 1.0668)
			(drill 0.719836)
			(layers "*.Cu" "*.Mask")
			(remove_unused_layers no)
			(net "GND")
			(clearance 0.1905)
			(thermal_gap 0.1905)
		)
		(pad "A73" thru_hole circle
			(at 62.349888 -1.249934 90)
			(size 1.0668 1.0668)
			(drill 0.719836)
			(layers "*.Cu" "*.Mask")
			(remove_unused_layers no)
			(net "PCIE_IOM_A_TO_COMP_A_10_DP")
			(clearance 0.1905)
			(thermal_gap 0.1905)
		)
		(pad "A74" thru_hole circle
			(at 63.349886 -3.24993 90)
			(size 1.0668 1.0668)
			(drill 0.719836)
			(layers "*.Cu" "*.Mask")
			(remove_unused_layers no)
			(net "PCIE_IOM_A_TO_COMP_A_10_DN")
			(clearance 0.1905)
			(thermal_gap 0.1905)
		)
		(pad "A75" thru_hole circle
			(at 64.349884 -1.249934 90)
			(size 1.0668 1.0668)
			(drill 0.719836)
			(layers "*.Cu" "*.Mask")
			(remove_unused_layers no)
			(net "GND")
			(clearance 0.1905)
			(thermal_gap 0.1905)
		)
		(pad "A76" thru_hole circle
			(at 65.349882 -3.24993 90)
			(size 1.0668 1.0668)
			(drill 0.719836)
			(layers "*.Cu" "*.Mask")
			(remove_unused_layers no)
			(net "GND")
			(clearance 0.1905)
			(thermal_gap 0.1905)
		)
		(pad "A77" thru_hole circle
			(at 66.34988 -1.249934 90)
			(size 1.0668 1.0668)
			(drill 0.719836)
			(layers "*.Cu" "*.Mask")
			(remove_unused_layers no)
			(net "PCIE_IOM_A_TO_COMP_A_11_DP")
			(clearance 0.1905)
			(thermal_gap 0.1905)
		)
		(pad "A78" thru_hole circle
			(at 67.349878 -3.24993 90)
			(size 1.0668 1.0668)
			(drill 0.719836)
			(layers "*.Cu" "*.Mask")
			(remove_unused_layers no)
			(net "PCIE_IOM_A_TO_COMP_A_11_DN")
			(clearance 0.1905)
			(thermal_gap 0.1905)
		)
		(pad "A79" thru_hole circle
			(at 68.349876 -1.249934 90)
			(size 1.0668 1.0668)
			(drill 0.719836)
			(layers "*.Cu" "*.Mask")
			(remove_unused_layers no)
			(net "GND")
			(clearance 0.1905)
			(thermal_gap 0.1905)
		)
		(pad "A80" thru_hole circle
			(at 69.349874 -3.24993 90)
			(size 1.0668 1.0668)
			(drill 0.719836)
			(layers "*.Cu" "*.Mask")
			(remove_unused_layers no)
			(net "GND")
			(clearance 0.1905)
			(thermal_gap 0.1905)
		)
		(pad "A81" thru_hole circle
			(at 70.350126 -1.249934 90)
			(size 1.0668 1.0668)
			(drill 0.719836)
			(layers "*.Cu" "*.Mask")
			(remove_unused_layers no)
			(net "P12V_A_COMP")
			(clearance 0.1905)
			(thermal_gap 0.1905)
		)
		(pad "A82" thru_hole circle
			(at 71.350124 -3.24993 90)
			(size 1.0668 1.0668)
			(drill 0.719836)
			(layers "*.Cu" "*.Mask")
			(remove_unused_layers no)
			(net "P12V_A_COMP")
			(clearance 0.1905)
			(thermal_gap 0.1905)
		)
		(pad "B1" thru_hole circle
			(at -11.649964 1.249934 90)
			(size 1.0668 1.0668)
			(drill 0.719836)
			(layers "*.Cu" "*.Mask")
			(remove_unused_layers no)
			(net "P12V_A_COMP")
			(clearance 0.1905)
			(thermal_gap 0.1905)
		)
		(pad "B2" thru_hole circle
			(at -10.649966 3.24993 90)
			(size 1.0668 1.0668)
			(drill 0.719836)
			(layers "*.Cu" "*.Mask")
			(remove_unused_layers no)
			(net "P12V_A_COMP")
			(clearance 0.1905)
			(thermal_gap 0.1905)
		)
		(pad "B3" thru_hole circle
			(at -9.649968 1.249934 90)
			(size 1.0668 1.0668)
			(drill 0.719836)
			(layers "*.Cu" "*.Mask")
			(remove_unused_layers no)
			(net "P12V_A_COMP")
			(clearance 0.1905)
			(thermal_gap 0.1905)
		)
		(pad "B4" thru_hole circle
			(at -8.64997 3.24993 90)
			(size 1.0668 1.0668)
			(drill 0.719836)
			(layers "*.Cu" "*.Mask")
			(remove_unused_layers no)
			(net "GND")
			(clearance 0.1905)
			(thermal_gap 0.1905)
		)
		(pad "B5" thru_hole circle
			(at -7.649972 1.249934 90)
			(size 1.0668 1.0668)
			(drill 0.719836)
			(layers "*.Cu" "*.Mask")
			(remove_unused_layers no)
			(net "I2C_BMC_A_COMP_A_SCL")
			(clearance 0.1905)
			(thermal_gap 0.1905)
		)
		(pad "B6" thru_hole circle
			(at -6.649974 3.24993 90)
			(size 1.0668 1.0668)
			(drill 0.719836)
			(layers "*.Cu" "*.Mask")
			(remove_unused_layers no)
			(net "I2C_BMC_A_COMP_A_SDA")
			(clearance 0.1905)
			(thermal_gap 0.1905)
		)
		(pad "B7" thru_hole circle
			(at -5.649976 1.249934 90)
			(size 1.0668 1.0668)
			(drill 0.719836)
			(layers "*.Cu" "*.Mask")
			(remove_unused_layers no)
			(net "GND")
			(clearance 0.1905)
			(thermal_gap 0.1905)
		)
		(pad "B8" thru_hole circle
			(at -4.649978 3.24993 90)
			(size 1.0668 1.0668)
			(drill 0.719836)
			(layers "*.Cu" "*.Mask")
			(remove_unused_layers no)
			(net "COMP_A_PWR_BTN_N")
			(clearance 0.1905)
			(thermal_gap 0.1905)
		)
		(pad "B9" thru_hole circle
			(at -3.64998 1.249934 90)
			(size 1.0668 1.0668)
			(drill 0.719836)
			(layers "*.Cu" "*.Mask")
			(remove_unused_layers no)
			(net "USB_COMP_A_DP")
			(clearance 0.1905)
			(thermal_gap 0.1905)
		)
		(pad "B10" thru_hole circle
			(at -2.649982 3.24993 90)
			(size 1.0668 1.0668)
			(drill 0.719836)
			(layers "*.Cu" "*.Mask")
			(remove_unused_layers no)
			(net "USB_COMP_A_DN")
			(clearance 0.1905)
			(thermal_gap 0.1905)
		)
		(pad "B11" thru_hole circle
			(at -1.649984 1.249934 90)
			(size 1.0668 1.0668)
			(drill 0.719836)
			(layers "*.Cu" "*.Mask")
			(remove_unused_layers no)
			(net "SYS_A_RESET_BUFFER_N")
			(clearance 0.1905)
			(thermal_gap 0.1905)
		)
		(pad "B12" thru_hole circle
			(at 1.35001 3.24993 90)
			(size 1.0668 1.0668)
			(drill 0.719836)
			(layers "*.Cu" "*.Mask")
			(remove_unused_layers no)
			(net "COMP_A_BMC_A_ALERT_N")
			(clearance 0.1905)
			(thermal_gap 0.1905)
		)
		(pad "B13" thru_hole circle
			(at 2.350008 1.249934 90)
			(size 1.0668 1.0668)
			(drill 0.719836)
			(layers "*.Cu" "*.Mask")
			(remove_unused_layers no)
			(net "GND")
			(clearance 0.1905)
			(thermal_gap 0.1905)
		)
		(pad "B14" thru_hole circle
			(at 3.350006 3.24993 90)
			(size 1.0668 1.0668)
			(drill 0.719836)
			(layers "*.Cu" "*.Mask")
			(remove_unused_layers no)
			(net "GND")
			(clearance 0.1905)
			(thermal_gap 0.1905)
		)
		(pad "B15" thru_hole circle
			(at 4.350004 1.249934 90)
			(size 1.0668 1.0668)
			(drill 0.719836)
			(layers "*.Cu" "*.Mask")
			(remove_unused_layers no)
			(net "PCIE_COMP_A_TO_SCC_A_0_DP")
			(clearance 0.1905)
			(thermal_gap 0.1905)
		)
		(pad "B16" thru_hole circle
			(at 5.350002 3.24993 90)
			(size 1.0668 1.0668)
			(drill 0.719836)
			(layers "*.Cu" "*.Mask")
			(remove_unused_layers no)
			(net "PCIE_COMP_A_TO_SCC_A_0_DN")
			(clearance 0.1905)
			(thermal_gap 0.1905)
		)
		(pad "B17" thru_hole circle
			(at 6.35 1.249934 90)
			(size 1.0668 1.0668)
			(drill 0.719836)
			(layers "*.Cu" "*.Mask")
			(remove_unused_layers no)
			(net "GND")
			(clearance 0.1905)
			(thermal_gap 0.1905)
		)
		(pad "B18" thru_hole circle
			(at 7.349998 3.24993 90)
			(size 1.0668 1.0668)
			(drill 0.719836)
			(layers "*.Cu" "*.Mask")
			(remove_unused_layers no)
			(net "GND")
			(clearance 0.1905)
			(thermal_gap 0.1905)
		)
		(pad "B19" thru_hole circle
			(at 8.349996 1.249934 90)
			(size 1.0668 1.0668)
			(drill 0.719836)
			(layers "*.Cu" "*.Mask")
			(remove_unused_layers no)
			(net "PCIE_COMP_A_TO_SCC_A_1_DP")
			(clearance 0.1905)
			(thermal_gap 0.1905)
		)
		(pad "B20" thru_hole circle
			(at 9.349994 3.24993 90)
			(size 1.0668 1.0668)
			(drill 0.719836)
			(layers "*.Cu" "*.Mask")
			(remove_unused_layers no)
			(net "PCIE_COMP_A_TO_SCC_A_1_DN")
			(clearance 0.1905)
			(thermal_gap 0.1905)
		)
		(pad "B21" thru_hole circle
			(at 10.349992 1.249934 90)
			(size 1.0668 1.0668)
			(drill 0.719836)
			(layers "*.Cu" "*.Mask")
			(remove_unused_layers no)
			(net "GND")
			(clearance 0.1905)
			(thermal_gap 0.1905)
		)
		(pad "B22" thru_hole circle
			(at 11.34999 3.24993 90)
			(size 1.0668 1.0668)
			(drill 0.719836)
			(layers "*.Cu" "*.Mask")
			(remove_unused_layers no)
			(net "GND")
			(clearance 0.1905)
			(thermal_gap 0.1905)
		)
		(pad "B23" thru_hole circle
			(at 12.349988 1.249934 90)
			(size 1.0668 1.0668)
			(drill 0.719836)
			(layers "*.Cu" "*.Mask")
			(remove_unused_layers no)
			(net "PCIE_COMP_A_TO_SCC_A_2_DP")
			(clearance 0.1905)
			(thermal_gap 0.1905)
		)
		(pad "B24" thru_hole circle
			(at 13.349986 3.24993 90)
			(size 1.0668 1.0668)
			(drill 0.719836)
			(layers "*.Cu" "*.Mask")
			(remove_unused_layers no)
			(net "PCIE_COMP_A_TO_SCC_A_2_DN")
			(clearance 0.1905)
			(thermal_gap 0.1905)
		)
		(pad "B25" thru_hole circle
			(at 14.349984 1.249934 90)
			(size 1.0668 1.0668)
			(drill 0.719836)
			(layers "*.Cu" "*.Mask")
			(remove_unused_layers no)
			(net "GND")
			(clearance 0.1905)
			(thermal_gap 0.1905)
		)
		(pad "B26" thru_hole circle
			(at 15.349982 3.24993 90)
			(size 1.0668 1.0668)
			(drill 0.719836)
			(layers "*.Cu" "*.Mask")
			(remove_unused_layers no)
			(net "GND")
			(clearance 0.1905)
			(thermal_gap 0.1905)
		)
		(pad "B27" thru_hole circle
			(at 16.34998 1.249934 90)
			(size 1.0668 1.0668)
			(drill 0.719836)
			(layers "*.Cu" "*.Mask")
			(remove_unused_layers no)
			(net "PCIE_COMP_A_TO_SCC_A_3_DP")
			(clearance 0.1905)
			(thermal_gap 0.1905)
		)
		(pad "B28" thru_hole circle
			(at 17.349978 3.24993 90)
			(size 1.0668 1.0668)
			(drill 0.719836)
			(layers "*.Cu" "*.Mask")
			(remove_unused_layers no)
			(net "PCIE_COMP_A_TO_SCC_A_3_DN")
			(clearance 0.1905)
			(thermal_gap 0.1905)
		)
		(pad "B29" thru_hole circle
			(at 18.349976 1.249934 90)
			(size 1.0668 1.0668)
			(drill 0.719836)
			(layers "*.Cu" "*.Mask")
			(remove_unused_layers no)
			(net "GND")
			(clearance 0.1905)
			(thermal_gap 0.1905)
		)
		(pad "B30" thru_hole circle
			(at 19.349974 3.24993 90)
			(size 1.0668 1.0668)
			(drill 0.719836)
			(layers "*.Cu" "*.Mask")
			(remove_unused_layers no)
			(net "GND")
			(clearance 0.1905)
			(thermal_gap 0.1905)
		)
		(pad "B31" thru_hole circle
			(at 20.349972 1.249934 90)
			(size 1.0668 1.0668)
			(drill 0.719836)
			(layers "*.Cu" "*.Mask")
			(remove_unused_layers no)
			(net "TP_COMP_A_SATA_P0_TX_DP")
			(clearance 0.1905)
			(thermal_gap 0.1905)
		)
		(pad "B32" thru_hole circle
			(at 21.34997 3.24993 90)
			(size 1.0668 1.0668)
			(drill 0.719836)
			(layers "*.Cu" "*.Mask")
			(remove_unused_layers no)
			(net "TP_COMP_A_SATA_P0_TX_DN")
			(clearance 0.1905)
			(thermal_gap 0.1905)
		)
		(pad "B33" thru_hole circle
			(at 22.349968 1.249934 90)
			(size 1.0668 1.0668)
			(drill 0.719836)
			(layers "*.Cu" "*.Mask")
			(remove_unused_layers no)
			(net "GND")
			(clearance 0.1905)
			(thermal_gap 0.1905)
		)
		(pad "B34" thru_hole circle
			(at 23.349966 3.24993 90)
			(size 1.0668 1.0668)
			(drill 0.719836)
			(layers "*.Cu" "*.Mask")
			(remove_unused_layers no)
			(net "GND")
			(clearance 0.1905)
			(thermal_gap 0.1905)
		)
		(pad "B35" thru_hole circle
			(at 24.349964 1.249934 90)
			(size 1.0668 1.0668)
			(drill 0.719836)
			(layers "*.Cu" "*.Mask")
			(remove_unused_layers no)
			(net "TP_PCIE_COMP_A_CLK_1_DP")
			(clearance 0.1905)
			(thermal_gap 0.1905)
		)
		(pad "B36" thru_hole circle
			(at 25.349962 3.24993 90)
			(size 1.0668 1.0668)
			(drill 0.719836)
			(layers "*.Cu" "*.Mask")
			(remove_unused_layers no)
			(net "TP_PCIE_COMP_A_CLK_1_DN")
			(clearance 0.1905)
			(thermal_gap 0.1905)
		)
		(pad "B37" thru_hole circle
			(at 26.34996 1.249934 90)
			(size 1.0668 1.0668)
			(drill 0.719836)
			(layers "*.Cu" "*.Mask")
			(remove_unused_layers no)
			(net "GND")
			(clearance 0.1905)
			(thermal_gap 0.1905)
		)
		(pad "B38" thru_hole circle
			(at 27.349958 3.24993 90)
			(size 1.0668 1.0668)
			(drill 0.719836)
			(layers "*.Cu" "*.Mask")
			(remove_unused_layers no)
			(net "GND")
			(clearance 0.1905)
			(thermal_gap 0.1905)
		)
		(pad "B39" thru_hole circle
			(at 28.349956 1.249934 90)
			(size 1.0668 1.0668)
			(drill 0.719836)
			(layers "*.Cu" "*.Mask")
			(remove_unused_layers no)
			(net "PCIE_COMP_A_PCIE_RST_1")
			(clearance 0.1905)
			(thermal_gap 0.1905)
		)
		(pad "B40" thru_hole circle
			(at 29.349954 3.24993 90)
			(size 1.0668 1.0668)
			(drill 0.719836)
			(layers "*.Cu" "*.Mask")
			(remove_unused_layers no)
			(net "PCIE_COMP_A_TO_IOM_A_RST_2")
			(clearance 0.1905)
			(thermal_gap 0.1905)
		)
		(pad "B41" thru_hole circle
			(at 30.349952 1.249934 90)
			(size 1.0668 1.0668)
			(drill 0.719836)
			(layers "*.Cu" "*.Mask")
			(remove_unused_layers no)
			(net "GND")
			(clearance 0.1905)
			(thermal_gap 0.1905)
		)
		(pad "B42" thru_hole circle
			(at 31.34995 3.24993 90)
			(size 1.0668 1.0668)
			(drill 0.719836)
			(layers "*.Cu" "*.Mask")
			(remove_unused_layers no)
			(net "GND")
			(clearance 0.1905)
			(thermal_gap 0.1905)
		)
		(pad "B43" thru_hole circle
			(at 32.349948 1.249934 90)
			(size 1.0668 1.0668)
			(drill 0.719836)
			(layers "*.Cu" "*.Mask")
			(remove_unused_layers no)
			(net "TP_SMB_COMP_A_NIC_SCL")
			(clearance 0.1905)
			(thermal_gap 0.1905)
		)
		(pad "B44" thru_hole circle
			(at 33.349946 3.24993 90)
			(size 1.0668 1.0668)
			(drill 0.719836)
			(layers "*.Cu" "*.Mask")
			(remove_unused_layers no)
			(net "TP_SMB_COMP_A_NIC_SDA")
			(clearance 0.1905)
			(thermal_gap 0.1905)
		)
		(pad "B45" thru_hole circle
			(at 34.349944 1.249934 90)
			(size 1.0668 1.0668)
			(drill 0.719836)
			(layers "*.Cu" "*.Mask")
			(remove_unused_layers no)
			(net "GND")
			(clearance 0.1905)
			(thermal_gap 0.1905)
		)
		(pad "B46" thru_hole circle
			(at 35.349942 3.24993 90)
			(size 1.0668 1.0668)
			(drill 0.719836)
			(layers "*.Cu" "*.Mask")
			(remove_unused_layers no)
			(net "GND")
			(clearance 0.1905)
			(thermal_gap 0.1905)
		)
		(pad "B47" thru_hole circle
			(at 36.34994 1.249934 90)
			(size 1.0668 1.0668)
			(drill 0.719836)
			(layers "*.Cu" "*.Mask")
			(remove_unused_layers no)
			(net "TP_COMP_A_KR_P0_TX_DP")
			(clearance 0.1905)
			(thermal_gap 0.1905)
		)
		(pad "B48" thru_hole circle
			(at 37.349938 3.24993 90)
			(size 1.0668 1.0668)
			(drill 0.719836)
			(layers "*.Cu" "*.Mask")
			(remove_unused_layers no)
			(net "TP_COMP_A_KR_P0_TX_DN")
			(clearance 0.1905)
			(thermal_gap 0.1905)
		)
		(pad "B49" thru_hole circle
			(at 38.349936 1.249934 90)
			(size 1.0668 1.0668)
			(drill 0.719836)
			(layers "*.Cu" "*.Mask")
			(remove_unused_layers no)
			(net "GND")
			(clearance 0.1905)
			(thermal_gap 0.1905)
		)
		(pad "B50" thru_hole circle
			(at 39.349934 3.24993 90)
			(size 1.0668 1.0668)
			(drill 0.719836)
			(layers "*.Cu" "*.Mask")
			(remove_unused_layers no)
			(net "GND")
			(clearance 0.1905)
			(thermal_gap 0.1905)
		)
		(pad "B51" thru_hole circle
			(at 40.349932 1.249934 90)
			(size 1.0668 1.0668)
			(drill 0.719836)
			(layers "*.Cu" "*.Mask")
			(remove_unused_layers no)
			(net "PCIE_COMP_A_TO_SCC_A_4_DP")
			(clearance 0.1905)
			(thermal_gap 0.1905)
		)
		(pad "B52" thru_hole circle
			(at 41.34993 3.24993 90)
			(size 1.0668 1.0668)
			(drill 0.719836)
			(layers "*.Cu" "*.Mask")
			(remove_unused_layers no)
			(net "PCIE_COMP_A_TO_SCC_A_4_DN")
			(clearance 0.1905)
			(thermal_gap 0.1905)
		)
		(pad "B53" thru_hole circle
			(at 42.349928 1.249934 90)
			(size 1.0668 1.0668)
			(drill 0.719836)
			(layers "*.Cu" "*.Mask")
			(remove_unused_layers no)
			(net "GND")
			(clearance 0.1905)
			(thermal_gap 0.1905)
		)
		(pad "B54" thru_hole circle
			(at 43.349926 3.24993 90)
			(size 1.0668 1.0668)
			(drill 0.719836)
			(layers "*.Cu" "*.Mask")
			(remove_unused_layers no)
			(net "GND")
			(clearance 0.1905)
			(thermal_gap 0.1905)
		)
		(pad "B55" thru_hole circle
			(at 44.349924 1.249934 90)
			(size 1.0668 1.0668)
			(drill 0.719836)
			(layers "*.Cu" "*.Mask")
			(remove_unused_layers no)
			(net "PCIE_COMP_A_TO_SCC_A_5_DP")
			(clearance 0.1905)
			(thermal_gap 0.1905)
		)
		(pad "B56" thru_hole circle
			(at 45.349922 3.24993 90)
			(size 1.0668 1.0668)
			(drill 0.719836)
			(layers "*.Cu" "*.Mask")
			(remove_unused_layers no)
			(net "PCIE_COMP_A_TO_SCC_A_5_DN")
			(clearance 0.1905)
			(thermal_gap 0.1905)
		)
		(pad "B57" thru_hole circle
			(at 46.34992 1.249934 90)
			(size 1.0668 1.0668)
			(drill 0.719836)
			(layers "*.Cu" "*.Mask")
			(remove_unused_layers no)
			(net "GND")
			(clearance 0.1905)
			(thermal_gap 0.1905)
		)
		(pad "B58" thru_hole circle
			(at 47.349918 3.24993 90)
			(size 1.0668 1.0668)
			(drill 0.719836)
			(layers "*.Cu" "*.Mask")
			(remove_unused_layers no)
			(net "GND")
			(clearance 0.1905)
			(thermal_gap 0.1905)
		)
		(pad "B59" thru_hole circle
			(at 48.349916 1.249934 90)
			(size 1.0668 1.0668)
			(drill 0.719836)
			(layers "*.Cu" "*.Mask")
			(remove_unused_layers no)
			(net "PCIE_COMP_A_TO_SCC_A_6_DP")
			(clearance 0.1905)
			(thermal_gap 0.1905)
		)
		(pad "B60" thru_hole circle
			(at 49.349914 3.24993 90)
			(size 1.0668 1.0668)
			(drill 0.719836)
			(layers "*.Cu" "*.Mask")
			(remove_unused_layers no)
			(net "PCIE_COMP_A_TO_SCC_A_6_DN")
			(clearance 0.1905)
			(thermal_gap 0.1905)
		)
		(pad "B61" thru_hole circle
			(at 50.349912 1.249934 90)
			(size 1.0668 1.0668)
			(drill 0.719836)
			(layers "*.Cu" "*.Mask")
			(remove_unused_layers no)
			(net "GND")
			(clearance 0.1905)
			(thermal_gap 0.1905)
		)
		(pad "B62" thru_hole circle
			(at 51.34991 3.24993 90)
			(size 1.0668 1.0668)
			(drill 0.719836)
			(layers "*.Cu" "*.Mask")
			(remove_unused_layers no)
			(net "GND")
			(clearance 0.1905)
			(thermal_gap 0.1905)
		)
		(pad "B63" thru_hole circle
			(at 52.349908 1.249934 90)
			(size 1.0668 1.0668)
			(drill 0.719836)
			(layers "*.Cu" "*.Mask")
			(remove_unused_layers no)
			(net "PCIE_COMP_A_TO_SCC_A_7_DP")
			(clearance 0.1905)
			(thermal_gap 0.1905)
		)
		(pad "B64" thru_hole circle
			(at 53.349906 3.24993 90)
			(size 1.0668 1.0668)
			(drill 0.719836)
			(layers "*.Cu" "*.Mask")
			(remove_unused_layers no)
			(net "PCIE_COMP_A_TO_SCC_A_7_DN")
			(clearance 0.1905)
			(thermal_gap 0.1905)
		)
		(pad "B65" thru_hole circle
			(at 54.349904 1.249934 90)
			(size 1.0668 1.0668)
			(drill 0.719836)
			(layers "*.Cu" "*.Mask")
			(remove_unused_layers no)
			(net "GND")
			(clearance 0.1905)
			(thermal_gap 0.1905)
		)
		(pad "B66" thru_hole circle
			(at 55.349902 3.24993 90)
			(size 1.0668 1.0668)
			(drill 0.719836)
			(layers "*.Cu" "*.Mask")
			(remove_unused_layers no)
			(net "GND")
			(clearance 0.1905)
			(thermal_gap 0.1905)
		)
		(pad "B67" thru_hole circle
			(at 56.3499 1.249934 90)
			(size 1.0668 1.0668)
			(drill 0.719836)
			(layers "*.Cu" "*.Mask")
			(remove_unused_layers no)
			(net "PCIE_COMP_A_TO_IOM_A_8_DP")
			(clearance 0.1905)
			(thermal_gap 0.1905)
		)
		(pad "B68" thru_hole circle
			(at 57.349898 3.24993 90)
			(size 1.0668 1.0668)
			(drill 0.719836)
			(layers "*.Cu" "*.Mask")
			(remove_unused_layers no)
			(net "PCIE_COMP_A_TO_IOM_A_8_DN")
			(clearance 0.1905)
			(thermal_gap 0.1905)
		)
		(pad "B69" thru_hole circle
			(at 58.349896 1.249934 90)
			(size 1.0668 1.0668)
			(drill 0.719836)
			(layers "*.Cu" "*.Mask")
			(remove_unused_layers no)
			(net "GND")
			(clearance 0.1905)
			(thermal_gap 0.1905)
		)
		(pad "B70" thru_hole circle
			(at 59.349894 3.24993 90)
			(size 1.0668 1.0668)
			(drill 0.719836)
			(layers "*.Cu" "*.Mask")
			(remove_unused_layers no)
			(net "GND")
			(clearance 0.1905)
			(thermal_gap 0.1905)
		)
		(pad "B71" thru_hole circle
			(at 60.349892 1.249934 90)
			(size 1.0668 1.0668)
			(drill 0.719836)
			(layers "*.Cu" "*.Mask")
			(remove_unused_layers no)
			(net "PCIE_COMP_A_TO_IOM_A_9_DP")
			(clearance 0.1905)
			(thermal_gap 0.1905)
		)
		(pad "B72" thru_hole circle
			(at 61.34989 3.24993 90)
			(size 1.0668 1.0668)
			(drill 0.719836)
			(layers "*.Cu" "*.Mask")
			(remove_unused_layers no)
			(net "PCIE_COMP_A_TO_IOM_A_9_DN")
			(clearance 0.1905)
			(thermal_gap 0.1905)
		)
		(pad "B73" thru_hole circle
			(at 62.349888 1.249934 90)
			(size 1.0668 1.0668)
			(drill 0.719836)
			(layers "*.Cu" "*.Mask")
			(remove_unused_layers no)
			(net "GND")
			(clearance 0.1905)
			(thermal_gap 0.1905)
		)
		(pad "B74" thru_hole circle
			(at 63.349886 3.24993 90)
			(size 1.0668 1.0668)
			(drill 0.719836)
			(layers "*.Cu" "*.Mask")
			(remove_unused_layers no)
			(net "GND")
			(clearance 0.1905)
			(thermal_gap 0.1905)
		)
		(pad "B75" thru_hole circle
			(at 64.349884 1.249934 90)
			(size 1.0668 1.0668)
			(drill 0.719836)
			(layers "*.Cu" "*.Mask")
			(remove_unused_layers no)
			(net "PCIE_COMP_A_TO_IOM_A_10_DP")
			(clearance 0.1905)
			(thermal_gap 0.1905)
		)
		(pad "B76" thru_hole circle
			(at 65.349882 3.24993 90)
			(size 1.0668 1.0668)
			(drill 0.719836)
			(layers "*.Cu" "*.Mask")
			(remove_unused_layers no)
			(net "PCIE_COMP_A_TO_IOM_A_10_DN")
			(clearance 0.1905)
			(thermal_gap 0.1905)
		)
		(pad "B77" thru_hole circle
			(at 66.34988 1.249934 90)
			(size 1.0668 1.0668)
			(drill 0.719836)
			(layers "*.Cu" "*.Mask")
			(remove_unused_layers no)
			(net "GND")
			(clearance 0.1905)
			(thermal_gap 0.1905)
		)
		(pad "B78" thru_hole circle
			(at 67.349878 3.24993 90)
			(size 1.0668 1.0668)
			(drill 0.719836)
			(layers "*.Cu" "*.Mask")
			(remove_unused_layers no)
			(net "GND")
			(clearance 0.1905)
			(thermal_gap 0.1905)
		)
		(pad "B79" thru_hole circle
			(at 68.349876 1.249934 90)
			(size 1.0668 1.0668)
			(drill 0.719836)
			(layers "*.Cu" "*.Mask")
			(remove_unused_layers no)
			(net "PCIE_COMP_A_TO_IOM_A_11_DP")
			(clearance 0.1905)
			(thermal_gap 0.1905)
		)
		(pad "B80" thru_hole circle
			(at 69.349874 3.24993 90)
			(size 1.0668 1.0668)
			(drill 0.719836)
			(layers "*.Cu" "*.Mask")
			(remove_unused_layers no)
			(net "PCIE_COMP_A_TO_IOM_A_11_DN")
			(clearance 0.1905)
			(thermal_gap 0.1905)
		)
		(pad "B81" thru_hole circle
			(at 70.350126 1.249934 90)
			(size 1.0668 1.0668)
			(drill 0.719836)
			(layers "*.Cu" "*.Mask")
			(remove_unused_layers no)
			(net "GND")
			(clearance 0.1905)
			(thermal_gap 0.1905)
		)
		(pad "B82" thru_hole circle
			(at 71.350124 3.24993 90)
			(size 1.0668 1.0668)
			(drill 0.719836)
			(layers "*.Cu" "*.Mask")
			(remove_unused_layers no)
			(net "GND")
			(clearance 0.1905)
			(thermal_gap 0.1905)
		)
		(zone
			(layers "F.Cu" "B.Cu" "In1.Cu" "In2.Cu" "In3.Cu" "In4.Cu" "In5.Cu" "In6.Cu"
				"In7.Cu" "In8.Cu" "In9.Cu" "In10.Cu"
			)
			(hatch none 0.5)
			(connect_pads
				(clearance 0)
			)
			(min_thickness 0.25)
			(keepout
				(tracks not_allowed)
				(vias allowed)
				(pads allowed)
				(copperpour not_allowed)
				(footprints allowed)
			)
			(placement
				(enabled no)
				(sheetname "")
			)
			(fill
				(thermal_gap 0.5)
				(thermal_bridge_width 0.5)
				(island_removal_mode 0)
			)
			(polygon
				(pts
					(arc
						(start 240.785904 -184.29986)
						(mid 237.814104 -184.29986)
						(end 240.785904 -184.29986)
					)
				)
			)
		)
		(zone
			(layers "F.Cu" "B.Cu" "In1.Cu" "In2.Cu" "In3.Cu" "In4.Cu" "In5.Cu" "In6.Cu"
				"In7.Cu" "In8.Cu" "In9.Cu" "In10.Cu"
			)
			(hatch none 0.5)
			(connect_pads
				(clearance 0)
			)
			(min_thickness 0.25)
			(keepout
				(tracks not_allowed)
				(vias allowed)
				(pads allowed)
				(copperpour not_allowed)
				(footprints allowed)
			)
			(placement
				(enabled no)
				(sheetname "")
			)
			(fill
				(thermal_gap 0.5)
				(thermal_bridge_width 0.5)
				(island_removal_mode 0)
			)
			(polygon
				(pts
					(arc
						(start 240.785904 -111.149892)
						(mid 237.814104 -111.149892)
						(end 240.785904 -111.149892)
					)
				)
			)
		)
	)
	(footprint ""
		(layer "F.Cu")
		(at 235.331 -394.1318 180)
		(property "Reference" "R1143"
			(at 0 0 180)
			(layer "F.SilkS")
			(hide yes)
			(effects
				(font
					(size 1.27 1.27)
				)
			)
		)
		(property "Value" "0R2J-2-GP"
			(at 0.064008 -3.993896 180)
			(unlocked yes)
			(layer "F.Fab")
			(hide yes)
			(effects
				(font
					(size 1.016 1.016)
					(thickness 0.1524)
				)
			)
		)
		(property "Device Type" "R402H16"
			(at 0.064008 -5.517896 180)
			(unlocked yes)
			(layer "F.Fab")
			(hide yes)
			(effects
				(font
					(size 1.016 1.016)
					(thickness 0.1524)
				)
			)
		)
		(duplicate_pad_numbers_are_jumpers no)
		(fp_line
			(start 0.508 -0.9398)
			(end -0.508 -0.9398)
			(stroke
				(width 0.1524)
				(type default)
			)
			(layer "F.SilkS")
		)
		(fp_line
			(start -0.508 -0.9398)
			(end -0.508 0.9398)
			(stroke
				(width 0.1524)
				(type default)
			)
			(layer "F.SilkS")
		)
		(fp_rect
			(start -0.508 0.9398)
			(end 0.508 -0.9398)
			(stroke
				(width 0)
				(type default)
			)
			(fill no)
			(layer "F.CrtYd")
		)
		(fp_rect
			(start -0.508 0.9398)
			(end 0.508 -0.9398)
			(stroke
				(width 0)
				(type default)
			)
			(fill no)
			(layer "F.Fab")
		)
		(pad "1" smd custom
			(at 0 -0.4445 180)
			(size 0.1397 0.1397)
			(layers "F.Cu" "F.Mask" "F.Paste")
			(net "MB3_CM_ADR1_R")
			(options
				(clearance outline)
				(anchor circle)
			)
			(primitives
				(gr_poly
					(pts
						(arc
							(start -0.1778 -0.2794)
							(mid -0.249642 -0.249642)
							(end -0.2794 -0.1778)
						)
						(arc
							(start -0.2794 0.1778)
							(mid -0.249642 0.249642)
							(end -0.1778 0.2794)
						)
						(arc
							(start 0.1778 0.2794)
							(mid 0.249642 0.249642)
							(end 0.2794 0.1778)
						)
						(arc
							(start 0.2794 -0.1778)
							(mid 0.249642 -0.249642)
							(end 0.1778 -0.2794)
						)
					)
					(width 0)
					(fill yes)
				)
			)
		)
		(pad "2" smd custom
			(at 0 0.4445 180)
			(size 0.1397 0.1397)
			(layers "F.Cu" "F.Mask" "F.Paste")
			(net "AGND_CURRENT_DPB")
			(options
				(clearance outline)
				(anchor circle)
			)
			(primitives
				(gr_poly
					(pts
						(arc
							(start -0.1778 -0.2794)
							(mid -0.249642 -0.249642)
							(end -0.2794 -0.1778)
						)
						(arc
							(start -0.2794 0.1778)
							(mid -0.249642 0.249642)
							(end -0.1778 0.2794)
						)
						(arc
							(start 0.1778 0.2794)
							(mid 0.249642 0.249642)
							(end 0.2794 0.1778)
						)
						(arc
							(start 0.2794 -0.1778)
							(mid 0.249642 -0.249642)
							(end 0.1778 -0.2794)
						)
					)
					(width 0)
					(fill yes)
				)
			)
		)
	)
	(footprint ""
		(layer "F.Cu")
		(at 150.136098 -186.287918)
		(property "Reference" "C254"
			(at 0 0 0)
			(layer "F.SilkS")
			(hide yes)
			(effects
				(font
					(size 1.27 1.27)
				)
			)
		)
		(property "Value" "SC4D7U25V5KX-1-GP"
			(at -0.0762 -6.1214 0)
			(unlocked yes)
			(layer "F.Fab")
			(hide yes)
			(effects
				(font
					(size 1.016 1.016)
					(thickness 0.1524)
				)
			)
		)
		(property "Device Type" "C805H58"
			(at -0.0762 -8.1534 0)
			(unlocked yes)
			(layer "F.Fab")
			(hide yes)
			(effects
				(font
					(size 1.016 1.016)
					(thickness 0.1524)
				)
			)
		)
		(duplicate_pad_numbers_are_jumpers no)
		(fp_line
			(start 0.635 0)
			(end -0.635 0)
			(stroke
				(width 0.508)
				(type default)
			)
			(layer "F.SilkS")
		)
		(fp_rect
			(start -0.9652 1.778)
			(end 0.9652 -1.778)
			(stroke
				(width 0)
				(type default)
			)
			(fill no)
			(layer "F.CrtYd")
		)
		(fp_poly
			(pts
				(xy -0.9652 -1.778) (xy 0.9652 -1.778) (xy 0.9652 1.778) (xy -0.9652 1.778)
			)
			(stroke
				(width 0)
				(type default)
			)
			(fill no)
			(layer "F.Fab")
		)
		(pad "1" smd rect
			(at 0 -0.9652)
			(size 1.397 1.143)
			(layers "F.Cu" "F.Mask" "F.Paste")
			(net "P12V_HDD16")
		)
		(pad "2" smd rect
			(at 0 0.9652)
			(size 1.397 1.143)
			(layers "F.Cu" "F.Mask" "F.Paste")
			(net "GND")
		)
	)
	(footprint ""
		(layer "F.Cu")
		(at 149.196298 -278.554942 90)
		(property "Reference" "R235"
			(at 0 0 90)
			(layer "F.SilkS")
			(hide yes)
			(effects
				(font
					(size 1.27 1.27)
				)
			)
		)
		(property "Value" "4K7R2J-2-GP"
			(at 0.064008 -3.993896 90)
			(unlocked yes)
			(layer "F.Fab")
			(hide yes)
			(effects
				(font
					(size 1.016 1.016)
					(thickness 0.1524)
				)
			)
		)
		(property "Device Type" "R402H16"
			(at 0.064008 -5.517896 90)
			(unlocked yes)
			(layer "F.Fab")
			(hide yes)
			(effects
				(font
					(size 1.016 1.016)
					(thickness 0.1524)
				)
			)
		)
		(duplicate_pad_numbers_are_jumpers no)
		(fp_line
			(start 0.508 -0.9398)
			(end -0.508 -0.9398)
			(stroke
				(width 0.1524)
				(type default)
			)
			(layer "F.SilkS")
		)
		(fp_line
			(start -0.508 -0.9398)
			(end -0.508 0.9398)
			(stroke
				(width 0.1524)
				(type default)
			)
			(layer "F.SilkS")
		)
		(fp_rect
			(start -0.508 0.9398)
			(end 0.508 -0.9398)
			(stroke
				(width 0)
				(type default)
			)
			(fill no)
			(layer "F.CrtYd")
		)
		(fp_rect
			(start -0.508 0.9398)
			(end 0.508 -0.9398)
			(stroke
				(width 0)
				(type default)
			)
			(fill no)
			(layer "F.Fab")
		)
		(pad "1" smd custom
			(at 0 -0.4445 90)
			(size 0.1397 0.1397)
			(layers "F.Cu" "F.Mask" "F.Paste")
			(net "SW_PWR_R_HDD4")
			(options
				(clearance outline)
				(anchor circle)
			)
			(primitives
				(gr_poly
					(pts
						(arc
							(start -0.1778 -0.2794)
							(mid -0.249642 -0.249642)
							(end -0.2794 -0.1778)
						)
						(arc
							(start -0.2794 0.1778)
							(mid -0.249642 0.249642)
							(end -0.1778 0.2794)
						)
						(arc
							(start 0.1778 0.2794)
							(mid 0.249642 0.249642)
							(end 0.2794 0.1778)
						)
						(arc
							(start 0.2794 -0.1778)
							(mid 0.249642 -0.249642)
							(end 0.1778 -0.2794)
						)
					)
					(width 0)
					(fill yes)
				)
			)
		)
		(pad "2" smd custom
			(at 0 0.4445 90)
			(size 0.1397 0.1397)
			(layers "F.Cu" "F.Mask" "F.Paste")
			(net "GND")
			(options
				(clearance outline)
				(anchor circle)
			)
			(primitives
				(gr_poly
					(pts
						(arc
							(start -0.1778 -0.2794)
							(mid -0.249642 -0.249642)
							(end -0.2794 -0.1778)
						)
						(arc
							(start -0.2794 0.1778)
							(mid -0.249642 0.249642)
							(end -0.1778 0.2794)
						)
						(arc
							(start 0.1778 0.2794)
							(mid 0.249642 0.249642)
							(end 0.2794 0.1778)
						)
						(arc
							(start 0.2794 -0.1778)
							(mid 0.249642 -0.249642)
							(end 0.1778 -0.2794)
						)
					)
					(width 0)
					(fill yes)
				)
			)
		)
	)
	(footprint ""
		(layer "F.Cu")
		(at 239.50295 -349.162878)
		(property "Reference" "C7"
			(at 0 0 0)
			(layer "F.SilkS")
			(hide yes)
			(effects
				(font
					(size 1.27 1.27)
				)
			)
		)
		(property "Value" "SCD1U16V2KX-3GP"
			(at 1.1811 -2.7051 0)
			(unlocked yes)
			(layer "F.Fab")
			(hide yes)
			(effects
				(font
					(size 1.016 1.016)
					(thickness 0.1524)
				)
			)
		)
		(property "Device Type" "C402H22"
			(at 1.1811 -4.2291 0)
			(unlocked yes)
			(layer "F.Fab")
			(hide yes)
			(effects
				(font
					(size 1.016 1.016)
					(thickness 0.1524)
				)
			)
		)
		(duplicate_pad_numbers_are_jumpers no)
		(fp_rect
			(start -0.4318 0.9525)
			(end 0.4318 -0.9525)
			(stroke
				(width 0)
				(type default)
			)
			(fill no)
			(layer "F.CrtYd")
		)
		(fp_rect
			(start -0.4318 0.9525)
			(end 0.4318 -0.9525)
			(stroke
				(width 0)
				(type default)
			)
			(fill no)
			(layer "F.Fab")
		)
		(pad "1" smd custom
			(at 0 -0.4445)
			(size 0.1524 0.1524)
			(layers "F.Cu" "F.Mask" "F.Paste")
			(net "P5V_A_1_SENSE")
			(options
				(clearance outline)
				(anchor circle)
			)
			(primitives
				(gr_poly
					(pts
						(arc
							(start 0.3048 -0.2032)
							(mid 0.275042 -0.275042)
							(end 0.2032 -0.3048)
						)
						(arc
							(start -0.2032 -0.3048)
							(mid -0.275042 -0.275042)
							(end -0.3048 -0.2032)
						)
						(arc
							(start -0.3048 0.2032)
							(mid -0.275042 0.275042)
							(end -0.2032 0.3048)
						)
						(arc
							(start 0.2032 0.3048)
							(mid 0.275042 0.275042)
							(end 0.3048 0.2032)
						)
					)
					(width 0)
					(fill yes)
				)
			)
		)
		(pad "2" smd custom
			(at 0 0.4445)
			(size 0.1524 0.1524)
			(layers "F.Cu" "F.Mask" "F.Paste")
			(net "GND")
			(options
				(clearance outline)
				(anchor circle)
			)
			(primitives
				(gr_poly
					(pts
						(arc
							(start 0.3048 -0.2032)
							(mid 0.275042 -0.275042)
							(end 0.2032 -0.3048)
						)
						(arc
							(start -0.2032 -0.3048)
							(mid -0.275042 -0.275042)
							(end -0.3048 -0.2032)
						)
						(arc
							(start -0.3048 0.2032)
							(mid -0.275042 0.275042)
							(end -0.2032 0.3048)
						)
						(arc
							(start 0.2032 0.3048)
							(mid 0.275042 0.275042)
							(end 0.3048 0.2032)
						)
					)
					(width 0)
					(fill yes)
				)
			)
		)
	)
	(footprint ""
		(layer "F.Cu")
		(at 240.56975 -349.162878)
		(property "Reference" "R19"
			(at 0 0 0)
			(layer "F.SilkS")
			(hide yes)
			(effects
				(font
					(size 1.27 1.27)
				)
			)
		)
		(property "Value" "10KR2F-2-GP"
			(at 0.064008 -3.993896 0)
			(unlocked yes)
			(layer "F.Fab")
			(hide yes)
			(effects
				(font
					(size 1.016 1.016)
					(thickness 0.1524)
				)
			)
		)
		(property "Device Type" "R402H16"
			(at 0.064008 -5.517896 0)
			(unlocked yes)
			(layer "F.Fab")
			(hide yes)
			(effects
				(font
					(size 1.016 1.016)
					(thickness 0.1524)
				)
			)
		)
		(duplicate_pad_numbers_are_jumpers no)
		(fp_line
			(start -0.508 -0.9398)
			(end -0.508 0.9398)
			(stroke
				(width 0.1524)
				(type default)
			)
			(layer "F.SilkS")
		)
		(fp_line
			(start 0.508 -0.9398)
			(end -0.508 -0.9398)
			(stroke
				(width 0.1524)
				(type default)
			)
			(layer "F.SilkS")
		)
		(fp_rect
			(start -0.508 0.9398)
			(end 0.508 -0.9398)
			(stroke
				(width 0)
				(type default)
			)
			(fill no)
			(layer "F.CrtYd")
		)
		(fp_rect
			(start -0.508 0.9398)
			(end 0.508 -0.9398)
			(stroke
				(width 0)
				(type default)
			)
			(fill no)
			(layer "F.Fab")
		)
		(pad "1" smd custom
			(at 0 -0.4445)
			(size 0.1397 0.1397)
			(layers "F.Cu" "F.Mask" "F.Paste")
			(net "P5V_A_1_SENSE")
			(options
				(clearance outline)
				(anchor circle)
			)
			(primitives
				(gr_poly
					(pts
						(arc
							(start -0.1778 -0.2794)
							(mid -0.249642 -0.249642)
							(end -0.2794 -0.1778)
						)
						(arc
							(start -0.2794 0.1778)
							(mid -0.249642 0.249642)
							(end -0.1778 0.2794)
						)
						(arc
							(start 0.1778 0.2794)
							(mid 0.249642 0.249642)
							(end 0.2794 0.1778)
						)
						(arc
							(start 0.2794 -0.1778)
							(mid 0.249642 -0.249642)
							(end 0.1778 -0.2794)
						)
					)
					(width 0)
					(fill yes)
				)
			)
		)
		(pad "2" smd custom
			(at 0 0.4445)
			(size 0.1397 0.1397)
			(layers "F.Cu" "F.Mask" "F.Paste")
			(net "GND")
			(options
				(clearance outline)
				(anchor circle)
			)
			(primitives
				(gr_poly
					(pts
						(arc
							(start -0.1778 -0.2794)
							(mid -0.249642 -0.249642)
							(end -0.2794 -0.1778)
						)
						(arc
							(start -0.2794 0.1778)
							(mid -0.249642 0.249642)
							(end -0.1778 0.2794)
						)
						(arc
							(start 0.1778 0.2794)
							(mid 0.249642 0.249642)
							(end 0.2794 0.1778)
						)
						(arc
							(start 0.2794 -0.1778)
							(mid 0.249642 -0.249642)
							(end 0.1778 -0.2794)
						)
					)
					(width 0)
					(fill yes)
				)
			)
		)
	)
	(footprint ""
		(layer "F.Cu")
		(at 109.873796 -162.157918 180)
		(property "Reference" "R491"
			(at 0 0 180)
			(layer "F.SilkS")
			(hide yes)
			(effects
				(font
					(size 1.27 1.27)
				)
			)
		)
		(property "Value" "200KR2F-L-GP"
			(at 0.064008 -3.993896 180)
			(unlocked yes)
			(layer "F.Fab")
			(hide yes)
			(effects
				(font
					(size 1.016 1.016)
					(thickness 0.1524)
				)
			)
		)
		(property "Device Type" "R402H16"
			(at 0.064008 -5.517896 180)
			(unlocked yes)
			(layer "F.Fab")
			(hide yes)
			(effects
				(font
					(size 1.016 1.016)
					(thickness 0.1524)
				)
			)
		)
		(duplicate_pad_numbers_are_jumpers no)
		(fp_line
			(start 0.508 -0.9398)
			(end -0.508 -0.9398)
			(stroke
				(width 0.1524)
				(type default)
			)
			(layer "F.SilkS")
		)
		(fp_line
			(start -0.508 -0.9398)
			(end -0.508 0.9398)
			(stroke
				(width 0.1524)
				(type default)
			)
			(layer "F.SilkS")
		)
		(fp_rect
			(start -0.508 0.9398)
			(end 0.508 -0.9398)
			(stroke
				(width 0)
				(type default)
			)
			(fill no)
			(layer "F.CrtYd")
		)
		(fp_rect
			(start -0.508 0.9398)
			(end 0.508 -0.9398)
			(stroke
				(width 0)
				(type default)
			)
			(fill no)
			(layer "F.Fab")
		)
		(pad "1" smd custom
			(at 0 -0.4445 180)
			(size 0.1397 0.1397)
			(layers "F.Cu" "F.Mask" "F.Paste")
			(net "SW_HDD_R15")
			(options
				(clearance outline)
				(anchor circle)
			)
			(primitives
				(gr_poly
					(pts
						(arc
							(start -0.1778 -0.2794)
							(mid -0.249642 -0.249642)
							(end -0.2794 -0.1778)
						)
						(arc
							(start -0.2794 0.1778)
							(mid -0.249642 0.249642)
							(end -0.1778 0.2794)
						)
						(arc
							(start 0.1778 0.2794)
							(mid 0.249642 0.249642)
							(end 0.2794 0.1778)
						)
						(arc
							(start 0.2794 -0.1778)
							(mid 0.249642 -0.249642)
							(end 0.1778 -0.2794)
						)
					)
					(width 0)
					(fill yes)
				)
			)
		)
		(pad "2" smd custom
			(at 0 0.4445 180)
			(size 0.1397 0.1397)
			(layers "F.Cu" "F.Mask" "F.Paste")
			(net "SW_HDD_N15")
			(options
				(clearance outline)
				(anchor circle)
			)
			(primitives
				(gr_poly
					(pts
						(arc
							(start -0.1778 -0.2794)
							(mid -0.249642 -0.249642)
							(end -0.2794 -0.1778)
						)
						(arc
							(start -0.2794 0.1778)
							(mid -0.249642 0.249642)
							(end -0.1778 0.2794)
						)
						(arc
							(start 0.1778 0.2794)
							(mid 0.249642 0.249642)
							(end 0.2794 0.1778)
						)
						(arc
							(start 0.2794 -0.1778)
							(mid 0.249642 -0.249642)
							(end 0.1778 -0.2794)
						)
					)
					(width 0)
					(fill yes)
				)
			)
		)
	)
	(footprint ""
		(layer "F.Cu")
		(at 35.797998 -177.169318 -90)
		(property "Reference" "R406"
			(at 0 0 270)
			(layer "F.SilkS")
			(hide yes)
			(effects
				(font
					(size 1.27 1.27)
				)
			)
		)
		(property "Value" "10KR2F-2-GP"
			(at 0.064008 -3.993896 270)
			(unlocked yes)
			(layer "F.Fab")
			(hide yes)
			(effects
				(font
					(size 1.016 1.016)
					(thickness 0.1524)
				)
			)
		)
		(property "Device Type" "R402H16"
			(at 0.064008 -5.517896 270)
			(unlocked yes)
			(layer "F.Fab")
			(hide yes)
			(effects
				(font
					(size 1.016 1.016)
					(thickness 0.1524)
				)
			)
		)
		(duplicate_pad_numbers_are_jumpers no)
		(fp_line
			(start -0.508 -0.9398)
			(end -0.508 0.9398)
			(stroke
				(width 0.1524)
				(type default)
			)
			(layer "F.SilkS")
		)
		(fp_line
			(start 0.508 -0.9398)
			(end -0.508 -0.9398)
			(stroke
				(width 0.1524)
				(type default)
			)
			(layer "F.SilkS")
		)
		(fp_rect
			(start -0.508 0.9398)
			(end 0.508 -0.9398)
			(stroke
				(width 0)
				(type default)
			)
			(fill no)
			(layer "F.CrtYd")
		)
		(fp_rect
			(start -0.508 0.9398)
			(end 0.508 -0.9398)
			(stroke
				(width 0)
				(type default)
			)
			(fill no)
			(layer "F.Fab")
		)
		(pad "1" smd custom
			(at 0 -0.4445 270)
			(size 0.1397 0.1397)
			(layers "F.Cu" "F.Mask" "F.Paste")
			(net "P3V3_STBY_A")
			(options
				(clearance outline)
				(anchor circle)
			)
			(primitives
				(gr_poly
					(pts
						(arc
							(start -0.1778 -0.2794)
							(mid -0.249642 -0.249642)
							(end -0.2794 -0.1778)
						)
						(arc
							(start -0.2794 0.1778)
							(mid -0.249642 0.249642)
							(end -0.1778 0.2794)
						)
						(arc
							(start 0.1778 0.2794)
							(mid 0.249642 0.249642)
							(end 0.2794 0.1778)
						)
						(arc
							(start 0.2794 -0.1778)
							(mid 0.249642 -0.249642)
							(end 0.1778 -0.2794)
						)
					)
					(width 0)
					(fill yes)
				)
			)
		)
		(pad "2" smd custom
			(at 0 0.4445 270)
			(size 0.1397 0.1397)
			(layers "F.Cu" "F.Mask" "F.Paste")
			(net "HDD_PRSNT_12")
			(options
				(clearance outline)
				(anchor circle)
			)
			(primitives
				(gr_poly
					(pts
						(arc
							(start -0.1778 -0.2794)
							(mid -0.249642 -0.249642)
							(end -0.2794 -0.1778)
						)
						(arc
							(start -0.2794 0.1778)
							(mid -0.249642 0.249642)
							(end -0.1778 0.2794)
						)
						(arc
							(start 0.1778 0.2794)
							(mid 0.249642 0.249642)
							(end 0.2794 0.1778)
						)
						(arc
							(start 0.2794 -0.1778)
							(mid 0.249642 -0.249642)
							(end 0.1778 -0.2794)
						)
					)
					(width 0)
					(fill yes)
				)
			)
		)
	)
	(footprint ""
		(layer "F.Cu")
		(at 419.389052 -277.750016 -90)
		(property "Reference" "VIA22"
			(at 0 0 270)
			(layer "F.SilkS")
			(hide yes)
			(effects
				(font
					(size 1.27 1.27)
				)
			)
		)
		(property "Value" "100OHM-8L-1D6MM-L18L16-GP"
			(at -3.7211 -4.5085 270)
			(unlocked yes)
			(layer "F.Fab")
			(hide yes)
			(effects
				(font
					(size 1.016 1.016)
					(thickness 0.1524)
				)
			)
		)
		(property "Device Type" "VIA-PCIE-4P-394076"
			(at -3.7211 -6.0325 270)
			(unlocked yes)
			(layer "F.Fab")
			(hide yes)
			(effects
				(font
					(size 1.016 1.016)
					(thickness 0.1524)
				)
			)
		)
		(duplicate_pad_numbers_are_jumpers no)
		(fp_rect
			(start -1.9685 0.381)
			(end 1.9685 -0.381)
			(stroke
				(width 0)
				(type default)
			)
			(fill no)
			(layer "F.CrtYd")
		)
		(fp_rect
			(start -1.9685 0.381)
			(end 1.9685 -0.381)
			(stroke
				(width 0)
				(type default)
			)
			(fill no)
			(layer "F.Fab")
		)
		(pad "1" thru_hole circle
			(at -1.5875 0 270)
			(size 0.508 0.508)
			(drill 0.254)
			(layers "*.Cu" "*.Mask")
			(remove_unused_layers no)
			(net "GND")
			(clearance 0.127)
			(thermal_gap 0.127)
		)
		(pad "2" thru_hole circle
			(at -0.5715 0 270)
			(size 0.508 0.508)
			(drill 0.254)
			(layers "*.Cu" "*.Mask")
			(remove_unused_layers no)
			(net "PHY_DRV_A_TO_SCC_A_9_DP")
			(clearance 0.127)
			(thermal_gap 0.127)
		)
		(pad "3" thru_hole circle
			(at 0.5715 0 270)
			(size 0.508 0.508)
			(drill 0.254)
			(layers "*.Cu" "*.Mask")
			(remove_unused_layers no)
			(net "PHY_DRV_A_TO_SCC_A_9_DN")
			(clearance 0.127)
			(thermal_gap 0.127)
		)
		(pad "4" thru_hole circle
			(at 1.5875 0 270)
			(size 0.508 0.508)
			(drill 0.254)
			(layers "*.Cu" "*.Mask")
			(remove_unused_layers no)
			(net "GND")
			(clearance 0.127)
			(thermal_gap 0.127)
		)
	)
	(footprint ""
		(layer "F.Cu")
		(at 238.252 -382.1938)
		(property "Reference" "C586"
			(at 0 0 0)
			(layer "F.SilkS")
			(hide yes)
			(effects
				(font
					(size 1.27 1.27)
				)
			)
		)
		(property "Value" "SCD1U16V2KX-3GP"
			(at 1.1811 -2.7051 0)
			(unlocked yes)
			(layer "F.Fab")
			(hide yes)
			(effects
				(font
					(size 1.016 1.016)
					(thickness 0.1524)
				)
			)
		)
		(property "Device Type" "C402H22"
			(at 1.1811 -4.2291 0)
			(unlocked yes)
			(layer "F.Fab")
			(hide yes)
			(effects
				(font
					(size 1.016 1.016)
					(thickness 0.1524)
				)
			)
		)
		(duplicate_pad_numbers_are_jumpers no)
		(fp_rect
			(start -0.4318 0.9525)
			(end 0.4318 -0.9525)
			(stroke
				(width 0)
				(type default)
			)
			(fill no)
			(layer "F.CrtYd")
		)
		(fp_rect
			(start -0.4318 0.9525)
			(end 0.4318 -0.9525)
			(stroke
				(width 0)
				(type default)
			)
			(fill no)
			(layer "F.Fab")
		)
		(pad "1" smd custom
			(at 0 -0.4445)
			(size 0.1524 0.1524)
			(layers "F.Cu" "F.Mask" "F.Paste")
			(net "MB3_CM_VOUT_R")
			(options
				(clearance outline)
				(anchor circle)
			)
			(primitives
				(gr_poly
					(pts
						(arc
							(start 0.3048 -0.2032)
							(mid 0.275042 -0.275042)
							(end 0.2032 -0.3048)
						)
						(arc
							(start -0.2032 -0.3048)
							(mid -0.275042 -0.275042)
							(end -0.3048 -0.2032)
						)
						(arc
							(start -0.3048 0.2032)
							(mid -0.275042 0.275042)
							(end -0.2032 0.3048)
						)
						(arc
							(start 0.2032 0.3048)
							(mid 0.275042 0.275042)
							(end 0.3048 0.2032)
						)
					)
					(width 0)
					(fill yes)
				)
			)
		)
		(pad "2" smd custom
			(at 0 0.4445)
			(size 0.1524 0.1524)
			(layers "F.Cu" "F.Mask" "F.Paste")
			(net "AGND_CURRENT_DPB")
			(options
				(clearance outline)
				(anchor circle)
			)
			(primitives
				(gr_poly
					(pts
						(arc
							(start 0.3048 -0.2032)
							(mid 0.275042 -0.275042)
							(end 0.2032 -0.3048)
						)
						(arc
							(start -0.2032 -0.3048)
							(mid -0.275042 -0.275042)
							(end -0.3048 -0.2032)
						)
						(arc
							(start -0.3048 0.2032)
							(mid -0.275042 0.275042)
							(end -0.2032 0.3048)
						)
						(arc
							(start 0.2032 0.3048)
							(mid 0.275042 0.275042)
							(end 0.3048 0.2032)
						)
					)
					(width 0)
					(fill yes)
				)
			)
		)
	)
	(footprint ""
		(layer "F.Cu")
		(at 54.546246 -48.554894 90)
		(property "Reference" "R717"
			(at 0 0 90)
			(layer "F.SilkS")
			(hide yes)
			(effects
				(font
					(size 1.27 1.27)
				)
			)
		)
		(property "Value" "4K7R2J-2-GP"
			(at 0.064008 -3.993896 90)
			(unlocked yes)
			(layer "F.Fab")
			(hide yes)
			(effects
				(font
					(size 1.016 1.016)
					(thickness 0.1524)
				)
			)
		)
		(property "Device Type" "R402H16"
			(at 0.064008 -5.517896 90)
			(unlocked yes)
			(layer "F.Fab")
			(hide yes)
			(effects
				(font
					(size 1.016 1.016)
					(thickness 0.1524)
				)
			)
		)
		(duplicate_pad_numbers_are_jumpers no)
		(fp_line
			(start 0.508 -0.9398)
			(end -0.508 -0.9398)
			(stroke
				(width 0.1524)
				(type default)
			)
			(layer "F.SilkS")
		)
		(fp_line
			(start -0.508 -0.9398)
			(end -0.508 0.9398)
			(stroke
				(width 0.1524)
				(type default)
			)
			(layer "F.SilkS")
		)
		(fp_rect
			(start -0.508 0.9398)
			(end 0.508 -0.9398)
			(stroke
				(width 0)
				(type default)
			)
			(fill no)
			(layer "F.CrtYd")
		)
		(fp_rect
			(start -0.508 0.9398)
			(end 0.508 -0.9398)
			(stroke
				(width 0)
				(type default)
			)
			(fill no)
			(layer "F.Fab")
		)
		(pad "1" smd custom
			(at 0 -0.4445 90)
			(size 0.1397 0.1397)
			(layers "F.Cu" "F.Mask" "F.Paste")
			(net "SW_PWR_R_HDD25")
			(options
				(clearance outline)
				(anchor circle)
			)
			(primitives
				(gr_poly
					(pts
						(arc
							(start -0.1778 -0.2794)
							(mid -0.249642 -0.249642)
							(end -0.2794 -0.1778)
						)
						(arc
							(start -0.2794 0.1778)
							(mid -0.249642 0.249642)
							(end -0.1778 0.2794)
						)
						(arc
							(start 0.1778 0.2794)
							(mid 0.249642 0.249642)
							(end 0.2794 0.1778)
						)
						(arc
							(start 0.2794 -0.1778)
							(mid 0.249642 -0.249642)
							(end 0.1778 -0.2794)
						)
					)
					(width 0)
					(fill yes)
				)
			)
		)
		(pad "2" smd custom
			(at 0 0.4445 90)
			(size 0.1397 0.1397)
			(layers "F.Cu" "F.Mask" "F.Paste")
			(net "GND")
			(options
				(clearance outline)
				(anchor circle)
			)
			(primitives
				(gr_poly
					(pts
						(arc
							(start -0.1778 -0.2794)
							(mid -0.249642 -0.249642)
							(end -0.2794 -0.1778)
						)
						(arc
							(start -0.2794 0.1778)
							(mid -0.249642 0.249642)
							(end -0.1778 0.2794)
						)
						(arc
							(start 0.1778 0.2794)
							(mid 0.249642 0.249642)
							(end 0.2794 0.1778)
						)
						(arc
							(start 0.2794 -0.1778)
							(mid 0.249642 -0.249642)
							(end 0.1778 -0.2794)
						)
					)
					(width 0)
					(fill yes)
				)
			)
		)
	)
	(footprint ""
		(layer "F.Cu")
		(at 80.63357 -17.368266 90)
		(property "Reference" "R39"
			(at 0 0 90)
			(layer "F.SilkS")
			(hide yes)
			(effects
				(font
					(size 1.27 1.27)
				)
			)
		)
		(property "Value" "4K7R2F-GP"
			(at 0.064008 -3.993896 90)
			(unlocked yes)
			(layer "F.Fab")
			(hide yes)
			(effects
				(font
					(size 1.016 1.016)
					(thickness 0.1524)
				)
			)
		)
		(property "Device Type" "R402H16"
			(at 0.064008 -5.517896 90)
			(unlocked yes)
			(layer "F.Fab")
			(hide yes)
			(effects
				(font
					(size 1.016 1.016)
					(thickness 0.1524)
				)
			)
		)
		(duplicate_pad_numbers_are_jumpers no)
		(fp_line
			(start 0.508 -0.9398)
			(end -0.508 -0.9398)
			(stroke
				(width 0.1524)
				(type default)
			)
			(layer "F.SilkS")
		)
		(fp_line
			(start -0.508 -0.9398)
			(end -0.508 0.9398)
			(stroke
				(width 0.1524)
				(type default)
			)
			(layer "F.SilkS")
		)
		(fp_rect
			(start -0.508 0.9398)
			(end 0.508 -0.9398)
			(stroke
				(width 0)
				(type default)
			)
			(fill no)
			(layer "F.CrtYd")
		)
		(fp_rect
			(start -0.508 0.9398)
			(end 0.508 -0.9398)
			(stroke
				(width 0)
				(type default)
			)
			(fill no)
			(layer "F.Fab")
		)
		(pad "1" smd custom
			(at 0 -0.4445 90)
			(size 0.1397 0.1397)
			(layers "F.Cu" "F.Mask" "F.Paste")
			(net "P3V3_STBY_A")
			(options
				(clearance outline)
				(anchor circle)
			)
			(primitives
				(gr_poly
					(pts
						(arc
							(start -0.1778 -0.2794)
							(mid -0.249642 -0.249642)
							(end -0.2794 -0.1778)
						)
						(arc
							(start -0.2794 0.1778)
							(mid -0.249642 0.249642)
							(end -0.1778 0.2794)
						)
						(arc
							(start 0.1778 0.2794)
							(mid 0.249642 0.249642)
							(end 0.2794 0.1778)
						)
						(arc
							(start 0.2794 -0.1778)
							(mid 0.249642 -0.249642)
							(end 0.1778 -0.2794)
						)
					)
					(width 0)
					(fill yes)
				)
			)
		)
		(pad "2" smd custom
			(at 0 0.4445 90)
			(size 0.1397 0.1397)
			(layers "F.Cu" "F.Mask" "F.Paste")
			(net "IO_EXP10_A1")
			(options
				(clearance outline)
				(anchor circle)
			)
			(primitives
				(gr_poly
					(pts
						(arc
							(start -0.1778 -0.2794)
							(mid -0.249642 -0.249642)
							(end -0.2794 -0.1778)
						)
						(arc
							(start -0.2794 0.1778)
							(mid -0.249642 0.249642)
							(end -0.1778 0.2794)
						)
						(arc
							(start 0.1778 0.2794)
							(mid 0.249642 0.249642)
							(end 0.2794 0.1778)
						)
						(arc
							(start 0.2794 -0.1778)
							(mid 0.249642 -0.249642)
							(end 0.1778 -0.2794)
						)
					)
					(width 0)
					(fill yes)
				)
			)
		)
	)
	(footprint ""
		(layer "F.Cu")
		(at 106.281728 -130.260598 -90)
		(property "Reference" "R516"
			(at 0 0 270)
			(layer "F.SilkS")
			(hide yes)
			(effects
				(font
					(size 1.27 1.27)
				)
			)
		)
		(property "Value" "4K7R2J-2-GP"
			(at 0.064008 -3.993896 270)
			(unlocked yes)
			(layer "F.Fab")
			(hide yes)
			(effects
				(font
					(size 1.016 1.016)
					(thickness 0.1524)
				)
			)
		)
		(property "Device Type" "R402H16"
			(at 0.064008 -5.517896 270)
			(unlocked yes)
			(layer "F.Fab")
			(hide yes)
			(effects
				(font
					(size 1.016 1.016)
					(thickness 0.1524)
				)
			)
		)
		(duplicate_pad_numbers_are_jumpers no)
		(fp_line
			(start -0.508 -0.9398)
			(end -0.508 0.9398)
			(stroke
				(width 0.1524)
				(type default)
			)
			(layer "F.SilkS")
		)
		(fp_line
			(start 0.508 -0.9398)
			(end -0.508 -0.9398)
			(stroke
				(width 0.1524)
				(type default)
			)
			(layer "F.SilkS")
		)
		(fp_rect
			(start -0.508 0.9398)
			(end 0.508 -0.9398)
			(stroke
				(width 0)
				(type default)
			)
			(fill no)
			(layer "F.CrtYd")
		)
		(fp_rect
			(start -0.508 0.9398)
			(end 0.508 -0.9398)
			(stroke
				(width 0)
				(type default)
			)
			(fill no)
			(layer "F.Fab")
		)
		(pad "1" smd custom
			(at 0 -0.4445 270)
			(size 0.1397 0.1397)
			(layers "F.Cu" "F.Mask" "F.Paste")
			(net "DRIVE_A_15_ACT")
			(options
				(clearance outline)
				(anchor circle)
			)
			(primitives
				(gr_poly
					(pts
						(arc
							(start -0.1778 -0.2794)
							(mid -0.249642 -0.249642)
							(end -0.2794 -0.1778)
						)
						(arc
							(start -0.2794 0.1778)
							(mid -0.249642 0.249642)
							(end -0.1778 0.2794)
						)
						(arc
							(start 0.1778 0.2794)
							(mid 0.249642 0.249642)
							(end 0.2794 0.1778)
						)
						(arc
							(start 0.2794 -0.1778)
							(mid 0.249642 -0.249642)
							(end 0.1778 -0.2794)
						)
					)
					(width 0)
					(fill yes)
				)
			)
		)
		(pad "2" smd custom
			(at 0 0.4445 270)
			(size 0.1397 0.1397)
			(layers "F.Cu" "F.Mask" "F.Paste")
			(net "GND")
			(options
				(clearance outline)
				(anchor circle)
			)
			(primitives
				(gr_poly
					(pts
						(arc
							(start -0.1778 -0.2794)
							(mid -0.249642 -0.249642)
							(end -0.2794 -0.1778)
						)
						(arc
							(start -0.2794 0.1778)
							(mid -0.249642 0.249642)
							(end -0.1778 0.2794)
						)
						(arc
							(start 0.1778 0.2794)
							(mid 0.249642 0.249642)
							(end 0.2794 0.1778)
						)
						(arc
							(start 0.2794 -0.1778)
							(mid 0.249642 -0.249642)
							(end 0.1778 -0.2794)
						)
					)
					(width 0)
					(fill yes)
				)
			)
		)
	)
	(footprint ""
		(layer "F.Cu")
		(at 240.000028 17.799812)
		(property "Reference" ""
			(at 0 0 0)
			(layer "F.SilkS")
			(hide yes)
			(effects
				(font
					(size 1.27 1.27)
				)
			)
		)
		(property "Value" "*"
			(at 8.305292 -3.58013 0)
			(unlocked yes)
			(layer "F.Fab")
			(hide yes)
			(effects
				(font
					(size 1.016 1.016)
					(thickness 0.1524)
				)
			)
		)
		(duplicate_pad_numbers_are_jumpers no)
		(fp_poly
			(pts
				(arc
					(start 6.80466 0)
					(mid 0 6.80466)
					(end -6.804914 0)
				)
				(arc
					(start -6.804914 -5.999988)
					(mid -2.856487 -12.176179)
					(end 4.406646 -11.18489)
				)
				(arc
					(start 4.406646 -11.18489)
					(mid 4.994737 -9.371935)
					(end 6.45668 -8.149082)
				)
				(arc
					(start 6.45668 -8.149082)
					(mid 6.717129 -7.088791)
					(end 6.80466 -6.000496)
				)
			)
			(stroke
				(width 0)
				(type default)
			)
			(fill no)
			(layer "B.CrtYd")
		)
		(fp_poly
			(pts
				(arc
					(start 6.80466 0)
					(mid 0 6.80466)
					(end -6.804914 0)
				)
				(arc
					(start -6.804914 -5.999988)
					(mid -2.856487 -12.176179)
					(end 4.406646 -11.18489)
				)
				(arc
					(start 4.406646 -11.18489)
					(mid 4.994737 -9.371935)
					(end 6.45668 -8.149082)
				)
				(arc
					(start 6.45668 -8.149082)
					(mid 6.7171 -7.088787)
					(end 6.80466 -6.000496)
				)
			)
			(stroke
				(width 0)
				(type default)
			)
			(fill no)
			(layer "F.CrtYd")
		)
		(fp_poly
			(pts
				(arc
					(start 6.80466 0)
					(mid 0 6.80466)
					(end -6.804914 0)
				)
				(arc
					(start -6.804914 -5.999988)
					(mid -2.856487 -12.176179)
					(end 4.406646 -11.18489)
				)
				(arc
					(start 4.406646 -11.18489)
					(mid 4.994737 -9.371935)
					(end 6.45668 -8.149082)
				)
				(arc
					(start 6.45668 -8.149082)
					(mid 6.7171 -7.088787)
					(end 6.80466 -6.000496)
				)
			)
			(stroke
				(width 0)
				(type default)
			)
			(fill no)
			(layer "B.Fab")
		)
		(fp_poly
			(pts
				(arc
					(start 6.80466 0)
					(mid 0 6.80466)
					(end -6.804914 0)
				)
				(arc
					(start -6.804914 -5.999988)
					(mid -2.856487 -12.176179)
					(end 4.406646 -11.18489)
				)
				(arc
					(start 4.406646 -11.18489)
					(mid 4.994737 -9.371935)
					(end 6.45668 -8.149082)
				)
				(arc
					(start 6.45668 -8.149082)
					(mid 6.7171 -7.088787)
					(end 6.80466 -6.000496)
				)
			)
			(stroke
				(width 0)
				(type default)
			)
			(fill no)
			(layer "F.Fab")
		)
		(pad "1" thru_hole custom
			(at 0 0)
			(size 3.249993 3.249993)
			(drill 0.0254)
			(layers "*.Cu" "*.Mask")
			(remove_unused_layers no)
			(net "Net_20")
			(clearance -0.491998)
			(thermal_gap 0.152146)
			(options
				(clearance outline)
				(anchor circle)
			)
			(primitives
				(gr_poly
					(pts
						(arc
							(start 6.207506 -4.92887)
							(mid 6.426581 -3.975471)
							(end 6.500114 -2.999994)
						)
						(arc
							(start 6.500114 2.999994)
							(mid 0.000254 9.499854)
							(end -6.49986 2.999994)
						)
						(arc
							(start -6.49986 -2.999994)
							(mid -2.787263 -8.871905)
							(end 4.109466 -8.036052)
						)
						(arc
							(start 4.109466 -8.036052)
							(mid 4.742316 -6.201459)
							(end 6.207506 -4.92887)
						)
					)
					(width 0)
					(fill yes)
				)
			)
			(padstack
				(mode front_inner_back)
				(layer "Inner"
					(shape custom)
					(size 2.928042 2.928042)
					(options
						(anchor circle)
					)
					(primitives
						(gr_poly
							(pts
								(arc
									(start 4.827016 -1.740154)
									(mid 0.000326 7.43067)
									(end -4.826762 -1.740154)
								)
								(arc
									(start -4.826762 -1.740154)
									(mid -3.703196 -3.586115)
									(end -2.789174 -5.544312)
								)
								(arc
									(start -2.789174 -5.544312)
									(mid 0.000254 -7.430741)
									(end 2.789682 -5.544312)
								)
								(arc
									(start 2.789682 -5.544312)
									(mid 3.703559 -3.586111)
									(end 4.827016 -1.740154)
								)
							)
							(width 0)
							(fill yes)
						)
					)
					(clearance 0.152146)
				)
				(layer "B.Cu"
					(shape custom)
					(size 3.249993 3.249993)
					(options
						(anchor circle)
					)
					(primitives
						(gr_poly
							(pts
								(arc
									(start 6.207506 -4.92887)
									(mid 6.426581 -3.975471)
									(end 6.500114 -2.999994)
								)
								(arc
									(start 6.500114 2.999994)
									(mid 0.000254 9.499854)
									(end -6.49986 2.999994)
								)
								(arc
									(start -6.49986 -2.999994)
									(mid -2.787263 -8.871905)
									(end 4.109466 -8.036052)
								)
								(arc
									(start 4.109466 -8.036052)
									(mid 4.742316 -6.201459)
									(end 6.207506 -4.92887)
								)
							)
							(width 0)
							(fill yes)
						)
					)
					(clearance -0.491998)
				)
			)
		)
		(zone
			(layers "F.Cu" "B.Cu" "In1.Cu" "In2.Cu" "In3.Cu" "In4.Cu" "In5.Cu" "In6.Cu"
				"In7.Cu" "In8.Cu" "In9.Cu" "In10.Cu"
			)
			(hatch none 0.5)
			(connect_pads
				(clearance 0)
			)
			(min_thickness 0.25)
			(keepout
				(tracks not_allowed)
				(vias allowed)
				(pads allowed)
				(copperpour not_allowed)
				(footprints allowed)
			)
			(placement
				(enabled no)
				(sheetname "")
			)
			(fill
				(thermal_gap 0.5)
				(thermal_bridge_width 0.5)
				(island_removal_mode 0)
			)
			(polygon
				(pts
					(arc
						(start 246.499888 17.799812)
						(mid 240.000028 24.299672)
						(end 233.499914 17.799812)
					)
					(arc
						(start 233.499914 11.799824)
						(mid 237.212511 5.927913)
						(end 244.10924 6.763766)
					)
					(arc
						(start 244.10924 6.763766)
						(mid 244.74209 8.598359)
						(end 246.20728 9.870948)
					)
					(arc
						(start 246.20728 9.870948)
						(mid 246.426317 10.824095)
						(end 246.499888 11.799316)
					)
				)
			)
		)
	)
	(footprint ""
		(layer "F.Cu")
		(at 300.20006 -138.205718)
		(property "Reference" ""
			(at 0 0 0)
			(layer "F.SilkS")
			(hide yes)
			(effects
				(font
					(size 1.27 1.27)
				)
			)
		)
		(property "Value" "*"
			(at -8.398764 -8.057642 0)
			(unlocked yes)
			(layer "F.Fab")
			(hide yes)
			(effects
				(font
					(size 1.016 1.016)
					(thickness 0.1524)
				)
			)
		)
		(duplicate_pad_numbers_are_jumpers no)
		(fp_poly
			(pts
				(arc
					(start 7.3152 0)
					(mid 0 7.3152)
					(end -7.3152 0)
				)
				(arc
					(start -7.3152 -5.9944)
					(mid 0 -13.3096)
					(end 7.3152 -5.9944)
				)
			)
			(stroke
				(width 0)
				(type default)
			)
			(fill no)
			(layer "B.CrtYd")
		)
		(fp_poly
			(pts
				(arc
					(start 7.3152 0)
					(mid 0 7.3152)
					(end -7.3152 0)
				)
				(arc
					(start -7.3152 -5.9944)
					(mid 0 -13.3096)
					(end 7.3152 -5.9944)
				)
			)
			(stroke
				(width 0)
				(type default)
			)
			(fill no)
			(layer "F.CrtYd")
		)
		(fp_poly
			(pts
				(arc
					(start 7.3152 0)
					(mid 0 7.3152)
					(end -7.3152 0)
				)
				(arc
					(start -7.3152 -5.9944)
					(mid 0 -13.3096)
					(end 7.3152 -5.9944)
				)
			)
			(stroke
				(width 0)
				(type default)
			)
			(fill no)
			(layer "B.Fab")
		)
		(fp_poly
			(pts
				(arc
					(start 7.3152 0)
					(mid 0 7.3152)
					(end -7.3152 0)
				)
				(arc
					(start -7.3152 -5.9944)
					(mid 0 -13.3096)
					(end 7.3152 -5.9944)
				)
			)
			(stroke
				(width 0)
				(type default)
			)
			(fill no)
			(layer "F.Fab")
		)
		(pad "1" thru_hole oval
			(at 0 0)
			(size 14.0208 20.0152)
			(drill 0.0254
				(offset 0 -2.9972)
			)
			(layers "*.Cu" "*.Mask")
			(remove_unused_layers no)
			(net "Net_68")
			(clearance -1.002284)
			(thermal_gap 0.1524)
			(padstack
				(mode front_inner_back)
				(layer "Inner"
					(shape custom)
					(size 2.928012 2.928012)
					(options
						(anchor circle)
					)
					(primitives
						(gr_poly
							(pts
								(arc
									(start 4.571746 -2.084324)
									(mid 0.000333 7.430372)
									(end -4.571492 -2.084324)
								)
								(arc
									(start -4.571492 -2.084324)
									(mid -3.570296 -3.611977)
									(end -2.875026 -5.30098)
								)
								(arc
									(start -2.875026 -5.30098)
									(mid 0.000217 -7.43089)
									(end 2.87528 -5.30098)
								)
								(arc
									(start 2.87528 -5.30098)
									(mid 3.570511 -3.611956)
									(end 4.571746 -2.084324)
								)
							)
							(width 0)
							(fill yes)
						)
					)
					(clearance 0.1524)
				)
				(layer "B.Cu"
					(shape oval)
					(size 14.0208 20.0152)
					(offset 0 -2.9972)
					(clearance -1.002284)
				)
			)
		)
		(zone
			(layers "F.Cu" "B.Cu" "In1.Cu" "In2.Cu" "In3.Cu" "In4.Cu" "In5.Cu" "In6.Cu"
				"In7.Cu" "In8.Cu" "In9.Cu" "In10.Cu"
			)
			(hatch none 0.5)
			(connect_pads
				(clearance 0)
			)
			(min_thickness 0.25)
			(keepout
				(tracks not_allowed)
				(vias allowed)
				(pads allowed)
				(copperpour not_allowed)
				(footprints allowed)
			)
			(placement
				(enabled no)
				(sheetname "")
			)
			(fill
				(thermal_gap 0.5)
				(thermal_bridge_width 0.5)
				(island_removal_mode 0)
			)
			(polygon
				(pts
					(arc
						(start 293.18966 -144.200118)
						(mid 300.20006 -151.210518)
						(end 307.21046 -144.200118)
					)
					(arc
						(start 307.21046 -138.205718)
						(mid 300.20006 -131.195318)
						(end 293.18966 -138.205718)
					)
				)
			)
		)
	)
	(footprint ""
		(layer "F.Cu")
		(at 318.482218 -127.8001 180)
		(property "Reference" "Q245"
			(at 0 0 180)
			(layer "F.SilkS")
			(hide yes)
			(effects
				(font
					(size 1.27 1.27)
				)
			)
		)
		(property "Value" "2N7002K-2-GP"
			(at 0.127 -8.9662 180)
			(unlocked yes)
			(layer "F.Fab")
			(hide yes)
			(effects
				(font
					(size 1.016 1.016)
					(thickness 0.1524)
				)
			)
		)
		(property "Device Type" "SOT23DGS2D4H44"
			(at 0.127 -10.4902 180)
			(unlocked yes)
			(layer "F.Fab")
			(hide yes)
			(effects
				(font
					(size 1.016 1.016)
					(thickness 0.1524)
				)
			)
		)
		(duplicate_pad_numbers_are_jumpers no)
		(fp_line
			(start 1.651 1.778)
			(end 1.651 -1.778)
			(stroke
				(width 0.1524)
				(type default)
			)
			(layer "F.SilkS")
		)
		(fp_line
			(start 1.651 -1.778)
			(end -1.651 -1.778)
			(stroke
				(width 0.1524)
				(type default)
			)
			(layer "F.SilkS")
		)
		(fp_line
			(start -1.651 1.778)
			(end 1.651 1.778)
			(stroke
				(width 0.1524)
				(type default)
			)
			(layer "F.SilkS")
		)
		(fp_line
			(start -1.651 -1.778)
			(end -1.651 1.778)
			(stroke
				(width 0.1524)
				(type default)
			)
			(layer "F.SilkS")
		)
		(fp_poly
			(pts
				(xy -1.778 1.8796) (xy -1.778 -1.8796) (xy 1.778 -1.8796) (xy 1.778 1.8796)
			)
			(stroke
				(width 0)
				(type default)
			)
			(fill no)
			(layer "F.CrtYd")
		)
		(fp_poly
			(pts
				(xy -1.778 1.8796) (xy -1.778 -1.8796) (xy 1.778 -1.8796) (xy 1.778 1.8796)
			)
			(stroke
				(width 0)
				(type default)
			)
			(fill no)
			(layer "F.Fab")
		)
		(pad "D" smd custom
			(at 0 -0.9525 180)
			(size 0.1905 0.1905)
			(layers "F.Cu" "F.Mask" "F.Paste")
			(net "FLT_HDD018_N")
			(options
				(clearance outline)
				(anchor circle)
			)
			(primitives
				(gr_poly
					(pts
						(arc
							(start -0.1778 0.5715)
							(mid -0.321484 0.511984)
							(end -0.381 0.3683)
						)
						(arc
							(start -0.381 -0.3683)
							(mid -0.321484 -0.511984)
							(end -0.1778 -0.5715)
						)
						(arc
							(start 0.1778 -0.5715)
							(mid 0.321484 -0.511984)
							(end 0.381 -0.3683)
						)
						(arc
							(start 0.381 0.3683)
							(mid 0.321484 0.511984)
							(end 0.1778 0.5715)
						)
					)
					(width 0)
					(fill yes)
				)
			)
		)
		(pad "G" smd custom
			(at -0.98425 0.9525 180)
			(size 0.1905 0.1905)
			(layers "F.Cu" "F.Mask" "F.Paste")
			(net "DRIVE_A_18_FLT_LED")
			(options
				(clearance outline)
				(anchor circle)
			)
			(primitives
				(gr_poly
					(pts
						(arc
							(start -0.1778 0.5715)
							(mid -0.321484 0.511984)
							(end -0.381 0.3683)
						)
						(arc
							(start -0.381 -0.3683)
							(mid -0.321484 -0.511984)
							(end -0.1778 -0.5715)
						)
						(arc
							(start 0.1778 -0.5715)
							(mid 0.321484 -0.511984)
							(end 0.381 -0.3683)
						)
						(arc
							(start 0.381 0.3683)
							(mid 0.321484 0.511984)
							(end 0.1778 0.5715)
						)
					)
					(width 0)
					(fill yes)
				)
			)
		)
		(pad "S" smd custom
			(at 0.98425 0.9525 180)
			(size 0.1905 0.1905)
			(layers "F.Cu" "F.Mask" "F.Paste")
			(net "GND")
			(options
				(clearance outline)
				(anchor circle)
			)
			(primitives
				(gr_poly
					(pts
						(arc
							(start -0.1778 0.5715)
							(mid -0.321484 0.511984)
							(end -0.381 0.3683)
						)
						(arc
							(start -0.381 -0.3683)
							(mid -0.321484 -0.511984)
							(end -0.1778 -0.5715)
						)
						(arc
							(start 0.1778 -0.5715)
							(mid 0.321484 -0.511984)
							(end 0.381 -0.3683)
						)
						(arc
							(start 0.381 0.3683)
							(mid 0.321484 0.511984)
							(end 0.1778 0.5715)
						)
					)
					(width 0)
					(fill yes)
				)
			)
		)
	)
	(footprint ""
		(layer "F.Cu")
		(at 74.206862 -127.798068 180)
		(property "Reference" "Q277"
			(at 0 0 180)
			(layer "F.SilkS")
			(hide yes)
			(effects
				(font
					(size 1.27 1.27)
				)
			)
		)
		(property "Value" "SSM3K324R-GP"
			(at 0.127 -8.9662 180)
			(unlocked yes)
			(layer "F.Fab")
			(hide yes)
			(effects
				(font
					(size 1.016 1.016)
					(thickness 0.1524)
				)
			)
		)
		(property "Device Type" "SOT23DGS2D4H35"
			(at 0.127 -10.4902 180)
			(unlocked yes)
			(layer "F.Fab")
			(hide yes)
			(effects
				(font
					(size 1.016 1.016)
					(thickness 0.1524)
				)
			)
		)
		(duplicate_pad_numbers_are_jumpers no)
		(fp_line
			(start 1.651 1.778)
			(end 1.651 -1.778)
			(stroke
				(width 0.1524)
				(type default)
			)
			(layer "F.SilkS")
		)
		(fp_line
			(start 1.651 -1.778)
			(end -1.651 -1.778)
			(stroke
				(width 0.1524)
				(type default)
			)
			(layer "F.SilkS")
		)
		(fp_line
			(start -1.651 1.778)
			(end 1.651 1.778)
			(stroke
				(width 0.1524)
				(type default)
			)
			(layer "F.SilkS")
		)
		(fp_line
			(start -1.651 -1.778)
			(end -1.651 1.778)
			(stroke
				(width 0.1524)
				(type default)
			)
			(layer "F.SilkS")
		)
		(fp_poly
			(pts
				(xy -1.778 1.8796) (xy -1.778 -1.8796) (xy 1.778 -1.8796) (xy 1.778 1.8796)
			)
			(stroke
				(width 0)
				(type default)
			)
			(fill no)
			(layer "F.CrtYd")
		)
		(fp_poly
			(pts
				(xy -1.778 1.8796) (xy -1.778 -1.8796) (xy 1.778 -1.8796) (xy 1.778 1.8796)
			)
			(stroke
				(width 0)
				(type default)
			)
			(fill no)
			(layer "F.Fab")
		)
		(pad "D" smd custom
			(at 0 -0.9525 180)
			(size 0.1905 0.1905)
			(layers "F.Cu" "F.Mask" "F.Paste")
			(net "DRV_ACT_14_N")
			(options
				(clearance outline)
				(anchor circle)
			)
			(primitives
				(gr_poly
					(pts
						(arc
							(start -0.1778 0.5715)
							(mid -0.321484 0.511984)
							(end -0.381 0.3683)
						)
						(arc
							(start -0.381 -0.3683)
							(mid -0.321484 -0.511984)
							(end -0.1778 -0.5715)
						)
						(arc
							(start 0.1778 -0.5715)
							(mid 0.321484 -0.511984)
							(end 0.381 -0.3683)
						)
						(arc
							(start 0.381 0.3683)
							(mid 0.321484 0.511984)
							(end 0.1778 0.5715)
						)
					)
					(width 0)
					(fill yes)
				)
			)
		)
		(pad "G" smd custom
			(at -0.98425 0.9525 180)
			(size 0.1905 0.1905)
			(layers "F.Cu" "F.Mask" "F.Paste")
			(net "DRIVE_A_14_ACT")
			(options
				(clearance outline)
				(anchor circle)
			)
			(primitives
				(gr_poly
					(pts
						(arc
							(start -0.1778 0.5715)
							(mid -0.321484 0.511984)
							(end -0.381 0.3683)
						)
						(arc
							(start -0.381 -0.3683)
							(mid -0.321484 -0.511984)
							(end -0.1778 -0.5715)
						)
						(arc
							(start 0.1778 -0.5715)
							(mid 0.321484 -0.511984)
							(end 0.381 -0.3683)
						)
						(arc
							(start 0.381 0.3683)
							(mid 0.321484 0.511984)
							(end 0.1778 0.5715)
						)
					)
					(width 0)
					(fill yes)
				)
			)
		)
		(pad "S" smd custom
			(at 0.98425 0.9525 180)
			(size 0.1905 0.1905)
			(layers "F.Cu" "F.Mask" "F.Paste")
			(net "GND")
			(options
				(clearance outline)
				(anchor circle)
			)
			(primitives
				(gr_poly
					(pts
						(arc
							(start -0.1778 0.5715)
							(mid -0.321484 0.511984)
							(end -0.381 0.3683)
						)
						(arc
							(start -0.381 -0.3683)
							(mid -0.321484 -0.511984)
							(end -0.1778 -0.5715)
						)
						(arc
							(start 0.1778 -0.5715)
							(mid 0.321484 -0.511984)
							(end 0.381 -0.3683)
						)
						(arc
							(start 0.381 0.3683)
							(mid 0.321484 0.511984)
							(end 0.1778 0.5715)
						)
					)
					(width 0)
					(fill yes)
				)
			)
		)
	)
	(footprint ""
		(layer "F.Cu")
		(at 381.13716 -134.866126 180)
		(property "Reference" "Q10"
			(at 0 0 180)
			(layer "F.SilkS")
			(hide yes)
			(effects
				(font
					(size 1.27 1.27)
				)
			)
		)
		(property "Value" "MMBT3904TT1G-GP"
			(at 0 -9.7282 180)
			(unlocked yes)
			(layer "F.Fab")
			(hide yes)
			(effects
				(font
					(size 1.016 1.016)
					(thickness 0.1524)
				)
			)
		)
		(property "Device Type" "SC75CBE1D6H36"
			(at 0 -11.6332 180)
			(unlocked yes)
			(layer "F.Fab")
			(hide yes)
			(effects
				(font
					(size 1.016 1.016)
					(thickness 0.1524)
				)
			)
		)
		(duplicate_pad_numbers_are_jumpers no)
		(fp_line
			(start 0.9652 1.3716)
			(end 0.9652 -1.3716)
			(stroke
				(width 0.1524)
				(type default)
			)
			(layer "F.SilkS")
		)
		(fp_line
			(start 0.9652 -1.3716)
			(end -0.9652 -1.3716)
			(stroke
				(width 0.1524)
				(type default)
			)
			(layer "F.SilkS")
		)
		(fp_line
			(start -0.9652 1.3716)
			(end 0.9652 1.3716)
			(stroke
				(width 0.1524)
				(type default)
			)
			(layer "F.SilkS")
		)
		(fp_line
			(start -0.9652 -1.3716)
			(end -0.9652 1.3716)
			(stroke
				(width 0.1524)
				(type default)
			)
			(layer "F.SilkS")
		)
		(fp_rect
			(start -1.0414 1.4478)
			(end 1.0414 -1.4478)
			(stroke
				(width 0)
				(type default)
			)
			(fill no)
			(layer "F.CrtYd")
		)
		(fp_poly
			(pts
				(xy -1.0414 -1.4478) (xy 1.0414 -1.4478) (xy 1.0414 1.4478) (xy -1.0414 1.4478)
			)
			(stroke
				(width 0)
				(type default)
			)
			(fill no)
			(layer "F.Fab")
		)
		(pad "B" smd custom
			(at -0.508 0.7112 180)
			(size 0.127 0.127)
			(layers "F.Cu" "F.Mask" "F.Paste")
			(net "VCCP_B")
			(options
				(clearance outline)
				(anchor circle)
			)
			(primitives
				(gr_poly
					(pts
						(arc
							(start -0.044958 0.4572)
							(mid -0.192463 0.399794)
							(end -0.254 0.254)
						)
						(xy -0.254 -0.254)
						(arc
							(start -0.253746 -0.254)
							(mid -0.192968 -0.398936)
							(end -0.04699 -0.4572)
						)
						(arc
							(start 0.04699 -0.4572)
							(mid 0.192989 -0.398958)
							(end 0.253746 -0.254)
						)
						(xy 0.254 -0.254)
						(arc
							(start 0.254 0.254)
							(mid 0.192404 0.399734)
							(end 0.044958 0.4572)
						)
					)
					(width 0)
					(fill yes)
				)
			)
		)
		(pad "C" smd custom
			(at 0 -0.7112 180)
			(size 0.127 0.127)
			(layers "F.Cu" "F.Mask" "F.Paste")
			(net "P12V_B")
			(options
				(clearance outline)
				(anchor circle)
			)
			(primitives
				(gr_poly
					(pts
						(arc
							(start -0.044958 0.4572)
							(mid -0.192463 0.399794)
							(end -0.254 0.254)
						)
						(xy -0.254 -0.254)
						(arc
							(start -0.253746 -0.254)
							(mid -0.192968 -0.398936)
							(end -0.04699 -0.4572)
						)
						(arc
							(start 0.04699 -0.4572)
							(mid 0.192989 -0.398958)
							(end 0.253746 -0.254)
						)
						(xy 0.254 -0.254)
						(arc
							(start 0.254 0.254)
							(mid 0.192404 0.399734)
							(end 0.044958 0.4572)
						)
					)
					(width 0)
					(fill yes)
				)
			)
		)
		(pad "E" smd custom
			(at 0.508 0.7112 180)
			(size 0.127 0.127)
			(layers "F.Cu" "F.Mask" "F.Paste")
			(net "P3V3_B_BIAS")
			(options
				(clearance outline)
				(anchor circle)
			)
			(primitives
				(gr_poly
					(pts
						(arc
							(start -0.044958 0.4572)
							(mid -0.192463 0.399794)
							(end -0.254 0.254)
						)
						(xy -0.254 -0.254)
						(arc
							(start -0.253746 -0.254)
							(mid -0.192968 -0.398936)
							(end -0.04699 -0.4572)
						)
						(arc
							(start 0.04699 -0.4572)
							(mid 0.192989 -0.398958)
							(end 0.253746 -0.254)
						)
						(xy 0.254 -0.254)
						(arc
							(start 0.254 0.254)
							(mid 0.192404 0.399734)
							(end 0.044958 0.4572)
						)
					)
					(width 0)
					(fill yes)
				)
			)
		)
	)
	(footprint ""
		(layer "F.Cu")
		(at 398.88795 -272.585942 180)
		(property "Reference" "R325"
			(at 0 0 180)
			(layer "F.SilkS")
			(hide yes)
			(effects
				(font
					(size 1.27 1.27)
				)
			)
		)
		(property "Value" "0R2J-2-GP"
			(at 0.064008 -3.993896 180)
			(unlocked yes)
			(layer "F.Fab")
			(hide yes)
			(effects
				(font
					(size 1.016 1.016)
					(thickness 0.1524)
				)
			)
		)
		(property "Device Type" "R402H16"
			(at 0.064008 -5.517896 180)
			(unlocked yes)
			(layer "F.Fab")
			(hide yes)
			(effects
				(font
					(size 1.016 1.016)
					(thickness 0.1524)
				)
			)
		)
		(duplicate_pad_numbers_are_jumpers no)
		(fp_line
			(start 0.508 -0.9398)
			(end -0.508 -0.9398)
			(stroke
				(width 0.1524)
				(type default)
			)
			(layer "F.SilkS")
		)
		(fp_line
			(start -0.508 -0.9398)
			(end -0.508 0.9398)
			(stroke
				(width 0.1524)
				(type default)
			)
			(layer "F.SilkS")
		)
		(fp_rect
			(start -0.508 0.9398)
			(end 0.508 -0.9398)
			(stroke
				(width 0)
				(type default)
			)
			(fill no)
			(layer "F.CrtYd")
		)
		(fp_rect
			(start -0.508 0.9398)
			(end 0.508 -0.9398)
			(stroke
				(width 0)
				(type default)
			)
			(fill no)
			(layer "F.Fab")
		)
		(pad "1" smd custom
			(at 0 -0.4445 180)
			(size 0.1397 0.1397)
			(layers "F.Cu" "F.Mask" "F.Paste")
			(net "DRIVE_A_8_PWR")
			(options
				(clearance outline)
				(anchor circle)
			)
			(primitives
				(gr_poly
					(pts
						(arc
							(start -0.1778 -0.2794)
							(mid -0.249642 -0.249642)
							(end -0.2794 -0.1778)
						)
						(arc
							(start -0.2794 0.1778)
							(mid -0.249642 0.249642)
							(end -0.1778 0.2794)
						)
						(arc
							(start 0.1778 0.2794)
							(mid 0.249642 0.249642)
							(end 0.2794 0.1778)
						)
						(arc
							(start 0.2794 -0.1778)
							(mid 0.249642 -0.249642)
							(end 0.1778 -0.2794)
						)
					)
					(width 0)
					(fill yes)
				)
			)
		)
		(pad "2" smd custom
			(at 0 0.4445 180)
			(size 0.1397 0.1397)
			(layers "F.Cu" "F.Mask" "F.Paste")
			(net "SW_PWR_R_HDD8")
			(options
				(clearance outline)
				(anchor circle)
			)
			(primitives
				(gr_poly
					(pts
						(arc
							(start -0.1778 -0.2794)
							(mid -0.249642 -0.249642)
							(end -0.2794 -0.1778)
						)
						(arc
							(start -0.2794 0.1778)
							(mid -0.249642 0.249642)
							(end -0.1778 0.2794)
						)
						(arc
							(start 0.1778 0.2794)
							(mid 0.249642 0.249642)
							(end 0.2794 0.1778)
						)
						(arc
							(start 0.2794 -0.1778)
							(mid 0.249642 -0.249642)
							(end 0.1778 -0.2794)
						)
					)
					(width 0)
					(fill yes)
				)
			)
		)
	)
	(footprint ""
		(layer "F.Cu")
		(at 23.732998 -292.270942)
		(property "Reference" "R957"
			(at 0 0 0)
			(layer "F.SilkS")
			(hide yes)
			(effects
				(font
					(size 1.27 1.27)
				)
			)
		)
		(property "Value" "2R6F-GP"
			(at -0.0508 -4.8514 0)
			(unlocked yes)
			(layer "F.Fab")
			(hide yes)
			(effects
				(font
					(size 1.016 1.016)
					(thickness 0.1524)
				)
			)
		)
		(property "Device Type" "R1206H26"
			(at 0 -6.3754 0)
			(unlocked yes)
			(layer "F.Fab")
			(hide yes)
			(effects
				(font
					(size 1.016 1.016)
					(thickness 0.1524)
				)
			)
		)
		(duplicate_pad_numbers_are_jumpers no)
		(fp_line
			(start -1.016 -2.2352)
			(end 1.016 -2.2352)
			(stroke
				(width 0.1524)
				(type default)
			)
			(layer "F.SilkS")
		)
		(fp_line
			(start -1.016 2.2352)
			(end -1.016 -2.2352)
			(stroke
				(width 0.1524)
				(type default)
			)
			(layer "F.SilkS")
		)
		(fp_line
			(start 1.016 -2.2352)
			(end 1.016 2.2352)
			(stroke
				(width 0.1524)
				(type default)
			)
			(layer "F.SilkS")
		)
		(fp_line
			(start 1.016 2.2352)
			(end -1.016 2.2352)
			(stroke
				(width 0.1524)
				(type default)
			)
			(layer "F.SilkS")
		)
		(fp_rect
			(start -1.0922 2.3114)
			(end 1.0922 -2.3114)
			(stroke
				(width 0)
				(type default)
			)
			(fill no)
			(layer "F.CrtYd")
		)
		(fp_poly
			(pts
				(xy -1.0922 -2.3114) (xy 1.0922 -2.3114) (xy 1.0922 2.3114) (xy -1.0922 2.3114)
			)
			(stroke
				(width 0)
				(type default)
			)
			(fill no)
			(layer "F.Fab")
		)
		(pad "1" smd rect
			(at 0 -1.397)
			(size 1.651 1.27)
			(layers "F.Cu" "F.Mask" "F.Paste")
			(net "P5V_HDD0")
		)
		(pad "2" smd rect
			(at 0 1.397)
			(size 1.651 1.27)
			(layers "F.Cu" "F.Mask" "F.Paste")
			(net "5V_PRE_0")
		)
	)
	(footprint ""
		(layer "F.Cu")
		(at 409.144978 -242.25377)
		(property "Reference" "R263"
			(at 0 0 0)
			(layer "F.SilkS")
			(hide yes)
			(effects
				(font
					(size 1.27 1.27)
				)
			)
		)
		(property "Value" "130R3F-GP"
			(at -0.0254 -2.5146 0)
			(unlocked yes)
			(layer "F.Fab")
			(hide yes)
			(effects
				(font
					(size 1.016 1.016)
					(thickness 0.1524)
				)
			)
		)
		(property "Device Type" "R603H22"
			(at -0.0254 -4.0386 0)
			(unlocked yes)
			(layer "F.Fab")
			(hide yes)
			(effects
				(font
					(size 1.016 1.016)
					(thickness 0.1524)
				)
			)
		)
		(duplicate_pad_numbers_are_jumpers no)
		(fp_line
			(start -0.4826 0)
			(end -0.2032 0)
			(stroke
				(width 0.2032)
				(type default)
			)
			(layer "F.SilkS")
		)
		(fp_line
			(start 0.2032 0)
			(end 0.4826 0)
			(stroke
				(width 0.2032)
				(type default)
			)
			(layer "F.SilkS")
		)
		(fp_rect
			(start -0.5842 1.3335)
			(end 0.5842 -1.3335)
			(stroke
				(width 0)
				(type default)
			)
			(fill no)
			(layer "F.CrtYd")
		)
		(fp_rect
			(start -0.5842 1.3335)
			(end 0.5842 -1.3335)
			(stroke
				(width 0)
				(type default)
			)
			(fill no)
			(layer "F.Fab")
		)
		(pad "1" smd custom
			(at 0 -0.762)
			(size 0.2159 0.2159)
			(layers "F.Cu" "F.Mask" "F.Paste")
			(net "P5V_A_3")
			(options
				(clearance outline)
				(anchor circle)
			)
			(primitives
				(gr_poly
					(pts
						(arc
							(start -0.3302 -0.4318)
							(mid -0.402042 -0.402042)
							(end -0.4318 -0.3302)
						)
						(arc
							(start -0.4318 0.3302)
							(mid -0.402042 0.402042)
							(end -0.3302 0.4318)
						)
						(arc
							(start 0.3302 0.4318)
							(mid 0.402042 0.402042)
							(end 0.4318 0.3302)
						)
						(arc
							(start 0.4318 -0.3302)
							(mid 0.402042 -0.402042)
							(end 0.3302 -0.4318)
						)
					)
					(width 0)
					(fill yes)
				)
			)
		)
		(pad "2" smd custom
			(at 0 0.762)
			(size 0.2159 0.2159)
			(layers "F.Cu" "F.Mask" "F.Paste")
			(net "FLT_HDD9")
			(options
				(clearance outline)
				(anchor circle)
			)
			(primitives
				(gr_poly
					(pts
						(arc
							(start -0.3302 -0.4318)
							(mid -0.402042 -0.402042)
							(end -0.4318 -0.3302)
						)
						(arc
							(start -0.4318 0.3302)
							(mid -0.402042 0.402042)
							(end -0.3302 0.4318)
						)
						(arc
							(start 0.3302 0.4318)
							(mid 0.402042 0.402042)
							(end 0.4318 0.3302)
						)
						(arc
							(start 0.4318 -0.3302)
							(mid 0.402042 -0.402042)
							(end 0.3302 -0.4318)
						)
					)
					(width 0)
					(fill yes)
				)
			)
		)
	)
	(footprint ""
		(layer "F.Cu")
		(at 64.0588 -162.749992 -90)
		(property "Reference" "VIA48"
			(at 0 0 270)
			(layer "F.SilkS")
			(hide yes)
			(effects
				(font
					(size 1.27 1.27)
				)
			)
		)
		(property "Value" "100OHM-8L-1D6MM-L18L16-GP"
			(at -3.7211 -4.5085 270)
			(unlocked yes)
			(layer "F.Fab")
			(hide yes)
			(effects
				(font
					(size 1.016 1.016)
					(thickness 0.1524)
				)
			)
		)
		(property "Device Type" "VIA-PCIE-4P-394076"
			(at -3.7211 -6.0325 270)
			(unlocked yes)
			(layer "F.Fab")
			(hide yes)
			(effects
				(font
					(size 1.016 1.016)
					(thickness 0.1524)
				)
			)
		)
		(duplicate_pad_numbers_are_jumpers no)
		(fp_rect
			(start -1.9685 0.381)
			(end 1.9685 -0.381)
			(stroke
				(width 0)
				(type default)
			)
			(fill no)
			(layer "F.CrtYd")
		)
		(fp_rect
			(start -1.9685 0.381)
			(end 1.9685 -0.381)
			(stroke
				(width 0)
				(type default)
			)
			(fill no)
			(layer "F.Fab")
		)
		(pad "1" thru_hole circle
			(at -1.5875 0 270)
			(size 0.508 0.508)
			(drill 0.254)
			(layers "*.Cu" "*.Mask")
			(remove_unused_layers no)
			(net "GND")
			(clearance 0.127)
			(thermal_gap 0.127)
		)
		(pad "2" thru_hole circle
			(at -0.5715 0 270)
			(size 0.508 0.508)
			(drill 0.254)
			(layers "*.Cu" "*.Mask")
			(remove_unused_layers no)
			(net "PHY_DRV_A_TO_SCC_A_13_DP")
			(clearance 0.127)
			(thermal_gap 0.127)
		)
		(pad "3" thru_hole circle
			(at 0.5715 0 270)
			(size 0.508 0.508)
			(drill 0.254)
			(layers "*.Cu" "*.Mask")
			(remove_unused_layers no)
			(net "PHY_DRV_A_TO_SCC_A_13_DN")
			(clearance 0.127)
			(thermal_gap 0.127)
		)
		(pad "4" thru_hole circle
			(at 1.5875 0 270)
			(size 0.508 0.508)
			(drill 0.254)
			(layers "*.Cu" "*.Mask")
			(remove_unused_layers no)
			(net "GND")
			(clearance 0.127)
			(thermal_gap 0.127)
		)
	)
	(footprint ""
		(layer "F.Cu")
		(at 461.0989 -167.872918 -90)
		(property "Reference" "Q132"
			(at 0 0 270)
			(layer "F.SilkS")
			(hide yes)
			(effects
				(font
					(size 1.27 1.27)
				)
			)
		)
		(property "Value" "AO4406AL-GP"
			(at -3.707384 -1.5367 270)
			(unlocked yes)
			(layer "F.Fab")
			(hide yes)
			(effects
				(font
					(size 1.016 1.016)
					(thickness 0.1524)
				)
			)
		)
		(property "Device Type" "SOIC8H69"
			(at -3.707384 -3.0607 270)
			(unlocked yes)
			(layer "F.Fab")
			(hide yes)
			(effects
				(font
					(size 1.016 1.016)
					(thickness 0.1524)
				)
			)
		)
		(duplicate_pad_numbers_are_jumpers no)
		(fp_line
			(start -2.6289 3.4417)
			(end -2.6289 1.4732)
			(stroke
				(width 0.381)
				(type default)
			)
			(layer "F.SilkS")
		)
		(fp_line
			(start -2.7432 1.4224)
			(end -2.6416 1.4224)
			(stroke
				(width 0.1524)
				(type default)
			)
			(layer "F.SilkS")
		)
		(fp_line
			(start -2.7432 1.4224)
			(end 2.1336 1.4224)
			(stroke
				(width 0.1524)
				(type default)
			)
			(layer "F.SilkS")
		)
		(fp_line
			(start 2.1336 1.4224)
			(end 2.1336 -1.4224)
			(stroke
				(width 0.1524)
				(type default)
			)
			(layer "F.SilkS")
		)
		(fp_line
			(start -2.1844 -0.0508)
			(end -2.7178 0.508)
			(stroke
				(width 0.1524)
				(type default)
			)
			(layer "F.SilkS")
		)
		(fp_line
			(start -2.7178 -0.508)
			(end -2.1844 -0.0508)
			(stroke
				(width 0.1524)
				(type default)
			)
			(layer "F.SilkS")
		)
		(fp_line
			(start -2.7432 -1.4224)
			(end -2.7432 1.4224)
			(stroke
				(width 0.1524)
				(type default)
			)
			(layer "F.SilkS")
		)
		(fp_line
			(start 2.1336 -1.4224)
			(end -2.7432 -1.4224)
			(stroke
				(width 0.1524)
				(type default)
			)
			(layer "F.SilkS")
		)
		(fp_poly
			(pts
				(xy -2.2098 -1.4224) (xy -2.2098 1.4224) (xy 2.2098 1.4224) (xy 2.2098 -1.4224)
			)
			(stroke
				(width 0)
				(type default)
			)
			(fill yes)
			(layer "F.SilkS")
		)
		(fp_rect
			(start -2.450084 2.999994)
			(end 2.450084 -2.999994)
			(stroke
				(width 0)
				(type default)
			)
			(fill no)
			(layer "F.CrtYd")
		)
		(fp_poly
			(pts
				(xy -2.8194 3.6322) (xy -2.8194 -3.6322) (xy 2.8194 -3.6322) (xy 2.8194 1.18364) (xy 2.450084 1.18364)
				(xy 2.450084 -2.999994) (xy -2.450084 -2.999994) (xy -2.450084 2.999994) (xy 2.450084 2.999994)
				(xy 2.450084 1.18618) (xy 2.8194 1.18618) (xy 2.8194 3.6322)
			)
			(stroke
				(width 0)
				(type default)
			)
			(fill no)
			(layer "F.CrtYd")
		)
		(fp_rect
			(start -2.8194 3.6322)
			(end 2.8194 -3.6322)
			(stroke
				(width 0)
				(type default)
			)
			(fill no)
			(layer "F.Fab")
		)
		(pad "1" smd rect
			(at -1.905 2.54 270)
			(size 0.635 1.651)
			(layers "F.Cu" "F.Mask" "F.Paste")
			(net "P5V_HDD22")
		)
		(pad "2" smd rect
			(at -0.635 2.54 270)
			(size 0.635 1.651)
			(layers "F.Cu" "F.Mask" "F.Paste")
			(net "P5V_HDD22")
		)
		(pad "3" smd rect
			(at 0.635 2.54 270)
			(size 0.635 1.651)
			(layers "F.Cu" "F.Mask" "F.Paste")
			(net "P5V_HDD22")
		)
		(pad "4" smd rect
			(at 1.905 2.54 270)
			(size 0.635 1.651)
			(layers "F.Cu" "F.Mask" "F.Paste")
			(net "SW_HDD_P22")
		)
		(pad "5" smd rect
			(at 1.905 -2.54 270)
			(size 0.635 1.651)
			(layers "F.Cu" "F.Mask" "F.Paste")
			(net "P5V_A_4")
		)
		(pad "6" smd rect
			(at 0.635 -2.54 270)
			(size 0.635 1.651)
			(layers "F.Cu" "F.Mask" "F.Paste")
			(net "P5V_A_4")
		)
		(pad "7" smd rect
			(at -0.635 -2.54 270)
			(size 0.635 1.651)
			(layers "F.Cu" "F.Mask" "F.Paste")
			(net "P5V_A_4")
		)
		(pad "8" smd rect
			(at -1.905 -2.54 270)
			(size 0.635 1.651)
			(layers "F.Cu" "F.Mask" "F.Paste")
			(net "P5V_A_4")
		)
	)
	(footprint ""
		(layer "F.Cu")
		(at 154.399996 -172.909992 -90)
		(property "Reference" "HDDSAS16"
			(at 0 0 270)
			(layer "F.SilkS")
			(hide yes)
			(effects
				(font
					(size 1.27 1.27)
				)
			)
		)
		(property "Value" "SKT-SAS15P-14P-45-GP"
			(at -20.7645 -8.9789 270)
			(unlocked yes)
			(layer "F.Fab")
			(hide yes)
			(effects
				(font
					(size 1.016 1.016)
					(thickness 0.1524)
				)
			)
		)
		(property "Device Type" "10120818-001C-TRLF"
			(at -20.7645 -10.5029 270)
			(unlocked yes)
			(layer "F.Fab")
			(hide yes)
			(effects
				(font
					(size 1.016 1.016)
					(thickness 0.1524)
				)
			)
		)
		(duplicate_pad_numbers_are_jumpers no)
		(fp_line
			(start 1.651 4.2926)
			(end 1.651 3.0099)
			(stroke
				(width 0.1524)
				(type default)
			)
			(layer "F.SilkS")
		)
		(fp_line
			(start 8.509 4.2926)
			(end 1.651 4.2926)
			(stroke
				(width 0.1524)
				(type default)
			)
			(layer "F.SilkS")
		)
		(fp_line
			(start -23.4188 3.0099)
			(end -23.4188 -3.2512)
			(stroke
				(width 0.1524)
				(type default)
			)
			(layer "F.SilkS")
		)
		(fp_line
			(start 1.651 3.0099)
			(end -23.4188 3.0099)
			(stroke
				(width 0.1524)
				(type default)
			)
			(layer "F.SilkS")
		)
		(fp_line
			(start 8.509 3.0099)
			(end 8.509 4.2926)
			(stroke
				(width 0.1524)
				(type default)
			)
			(layer "F.SilkS")
		)
		(fp_line
			(start 23.4188 3.0099)
			(end 8.509 3.0099)
			(stroke
				(width 0.1524)
				(type default)
			)
			(layer "F.SilkS")
		)
		(fp_line
			(start -23.4188 -3.2512)
			(end 23.4188 -3.2512)
			(stroke
				(width 0.1524)
				(type default)
			)
			(layer "F.SilkS")
		)
		(fp_line
			(start 23.4188 -3.2512)
			(end 23.4188 3.0099)
			(stroke
				(width 0.1524)
				(type default)
			)
			(layer "F.SilkS")
		)
		(fp_line
			(start 15.5067 -3.3401)
			(end 16.2687 -3.3401)
			(stroke
				(width 0.3302)
				(type default)
			)
			(layer "F.SilkS")
		)
		(fp_poly
			(pts
				(xy 15.868904 -3.230372) (xy 16.503904 -3.865372) (xy 15.233904 -3.865372)
			)
			(stroke
				(width 0)
				(type default)
			)
			(fill yes)
			(layer "F.SilkS")
		)
		(fp_poly
			(pts
				(xy -22.8727 -2.7559) (xy 22.8727 -2.7559) (xy 22.8727 2.7559) (xy 8.255 2.7559) (xy 8.255 3.5179)
				(xy 1.905 3.5179) (xy 1.905 2.7559) (xy -22.8727 2.7559)
			)
			(stroke
				(width 0)
				(type default)
			)
			(fill no)
			(layer "F.CrtYd")
		)
		(fp_poly
			(pts
				(xy 1.397 4.5466) (xy 1.397 3.2639) (xy -23.6728 3.2639) (xy -23.6728 -3.5052) (xy 23.6728 -3.5052)
				(xy 23.6728 -0.00635) (xy 22.8727 -0.00635) (xy 22.8727 -2.7559) (xy -22.8727 -2.7559) (xy -22.8727 2.7559)
				(xy 1.905 2.7559) (xy 1.905 3.5179) (xy 8.255 3.5179) (xy 8.255 2.7559) (xy 22.8727 2.7559) (xy 22.8727 0.00635)
				(xy 23.6728 0.00635) (xy 23.6728 3.2639) (xy 8.763 3.2639) (xy 8.763 4.5466)
			)
			(stroke
				(width 0)
				(type default)
			)
			(fill no)
			(layer "F.CrtYd")
		)
		(fp_poly
			(pts
				(xy 1.397 4.5466) (xy 1.397 3.2639) (xy -23.6728 3.2639) (xy -23.6728 -3.5052) (xy 23.6728 -3.5052)
				(xy 23.6728 3.2639) (xy 8.763 3.2639) (xy 8.763 4.5466)
			)
			(stroke
				(width 0)
				(type default)
			)
			(fill no)
			(layer "F.Fab")
		)
		(pad "" np_thru_hole circle
			(at -18.874994 0 270)
			(size 0.254 0.254)
			(drill 1.3462)
			(layers "*.Cu" "*.Mask")
			(clearance 0.9017)
			(thermal_gap 0.9017)
		)
		(pad "" np_thru_hole circle
			(at 18.874994 0 270)
			(size 0.254 0.254)
			(drill 0.9398)
			(layers "*.Cu" "*.Mask")
			(clearance 0.6985)
			(thermal_gap 0.6985)
		)
		(pad "G1" smd rect
			(at 21.874988 0 270)
			(size 2.5908 2.5908)
			(layers "F.Cu" "F.Mask" "F.Paste")
			(net "GND")
		)
		(pad "G2" smd rect
			(at -21.874988 0 270)
			(size 2.5908 2.5908)
			(layers "F.Cu" "F.Mask" "F.Paste")
			(net "GND")
		)
		(pad "P1" smd rect
			(at 1.905 -1.82499 270)
			(size 0.6096 2.3622)
			(layers "F.Cu" "F.Mask" "F.Paste")
			(net "Net_2136")
		)
		(pad "P2" smd rect
			(at 0.635 -1.82499 270)
			(size 0.6096 2.3622)
			(layers "F.Cu" "F.Mask" "F.Paste")
			(net "Net_2137")
		)
		(pad "P3" smd rect
			(at -0.635 -1.82499 270)
			(size 0.6096 2.3622)
			(layers "F.Cu" "F.Mask" "F.Paste")
			(net "Net_2138")
		)
		(pad "P4" smd rect
			(at -1.905 -1.82499 270)
			(size 0.6096 2.3622)
			(layers "F.Cu" "F.Mask" "F.Paste")
			(net "GND")
		)
		(pad "P5" smd rect
			(at -3.175 -1.82499 270)
			(size 0.6096 2.3622)
			(layers "F.Cu" "F.Mask" "F.Paste")
			(net "HDD_PRSNT_16")
		)
		(pad "P6" smd rect
			(at -4.445 -1.82499 270)
			(size 0.6096 2.3622)
			(layers "F.Cu" "F.Mask" "F.Paste")
			(net "GND")
		)
		(pad "P7" smd rect
			(at -5.715 -1.82499 270)
			(size 0.6096 2.3622)
			(layers "F.Cu" "F.Mask" "F.Paste")
			(net "5V_PRE_16")
		)
		(pad "P8" smd rect
			(at -6.985 -1.82499 270)
			(size 0.6096 2.3622)
			(layers "F.Cu" "F.Mask" "F.Paste")
			(net "P5V_HDD16")
		)
		(pad "P9" smd rect
			(at -8.255 -1.82499 270)
			(size 0.6096 2.3622)
			(layers "F.Cu" "F.Mask" "F.Paste")
			(net "P5V_HDD16")
		)
		(pad "P10" smd rect
			(at -9.525 -1.82499 270)
			(size 0.6096 2.3622)
			(layers "F.Cu" "F.Mask" "F.Paste")
			(net "GND")
		)
		(pad "P11" smd rect
			(at -10.795 -1.82499 270)
			(size 0.6096 2.3622)
			(layers "F.Cu" "F.Mask" "F.Paste")
			(net "ACT_HDD_16")
		)
		(pad "P12" smd rect
			(at -12.065 -1.82499 270)
			(size 0.6096 2.3622)
			(layers "F.Cu" "F.Mask" "F.Paste")
			(net "GND")
		)
		(pad "P13" smd rect
			(at -13.335 -1.82499 270)
			(size 0.6096 2.3622)
			(layers "F.Cu" "F.Mask" "F.Paste")
			(net "12V_PRE_16")
		)
		(pad "P14" smd rect
			(at -14.605 -1.82499 270)
			(size 0.6096 2.3622)
			(layers "F.Cu" "F.Mask" "F.Paste")
			(net "P12V_HDD16")
		)
		(pad "P15" smd rect
			(at -15.875 -1.82499 270)
			(size 0.6096 2.3622)
			(layers "F.Cu" "F.Mask" "F.Paste")
			(net "P12V_HDD16")
		)
		(pad "S1" smd rect
			(at 15.875 -1.82499 270)
			(size 0.6096 2.3622)
			(layers "F.Cu" "F.Mask" "F.Paste")
			(net "GND")
		)
		(pad "S2" smd rect
			(at 14.605 -1.82499 270)
			(size 0.6096 2.3622)
			(layers "F.Cu" "F.Mask" "F.Paste")
			(net "SAS_HDD_RX_P16")
		)
		(pad "S3" smd rect
			(at 13.335 -1.82499 270)
			(size 0.6096 2.3622)
			(layers "F.Cu" "F.Mask" "F.Paste")
			(net "SAS_HDD_RX_N16")
		)
		(pad "S4" smd rect
			(at 12.065 -1.82499 270)
			(size 0.6096 2.3622)
			(layers "F.Cu" "F.Mask" "F.Paste")
			(net "GND")
		)
		(pad "S5" smd rect
			(at 10.795 -1.82499 270)
			(size 0.6096 2.3622)
			(layers "F.Cu" "F.Mask" "F.Paste")
			(net "PHY_DRV_A_TO_SCC_A_16_DN")
		)
		(pad "S6" smd rect
			(at 9.525 -1.82499 270)
			(size 0.6096 2.3622)
			(layers "F.Cu" "F.Mask" "F.Paste")
			(net "PHY_DRV_A_TO_SCC_A_16_DP")
		)
		(pad "S7" smd rect
			(at 8.255 -1.82499 270)
			(size 0.6096 2.3622)
			(layers "F.Cu" "F.Mask" "F.Paste")
			(net "GND")
		)
		(pad "S8" smd rect
			(at 7.480046 2.845054 270)
			(size 0.508 2.3622)
			(layers "F.Cu" "F.Mask" "F.Paste")
			(net "GND")
		)
		(pad "S9" smd rect
			(at 6.679946 2.845054 270)
			(size 0.508 2.3622)
			(layers "F.Cu" "F.Mask" "F.Paste")
			(net "Net_453")
		)
		(pad "S10" smd rect
			(at 5.8801 2.845054 270)
			(size 0.508 2.3622)
			(layers "F.Cu" "F.Mask" "F.Paste")
			(net "Net_345")
		)
		(pad "S11" smd rect
			(at 5.08 2.845054 270)
			(size 0.508 2.3622)
			(layers "F.Cu" "F.Mask" "F.Paste")
			(net "GND")
		)
		(pad "S12" smd rect
			(at 4.2799 2.845054 270)
			(size 0.508 2.3622)
			(layers "F.Cu" "F.Mask" "F.Paste")
			(net "Net_381")
		)
		(pad "S13" smd rect
			(at 3.480054 2.845054 270)
			(size 0.508 2.3622)
			(layers "F.Cu" "F.Mask" "F.Paste")
			(net "Net_417")
		)
		(pad "S14" smd rect
			(at 2.679954 2.845054 270)
			(size 0.508 2.3622)
			(layers "F.Cu" "F.Mask" "F.Paste")
			(net "GND")
		)
		(zone
			(layer "F.Cu")
			(hatch none 0.5)
			(connect_pads
				(clearance 0)
			)
			(min_thickness 0.25)
			(keepout
				(tracks allowed)
				(vias not_allowed)
				(pads allowed)
				(copperpour not_allowed)
				(footprints allowed)
			)
			(placement
				(enabled no)
				(sheetname "")
			)
			(fill
				(thermal_gap 0.5)
				(thermal_bridge_width 0.5)
				(island_removal_mode 0)
			)
			(polygon
				(pts
					(xy 158.057596 -189.648592) (xy 150.983696 -189.648592) (xy 150.983696 -196.582792) (xy 152.088596 -196.582792)
					(xy 152.088596 -192.467992) (xy 156.711396 -192.467992) (xy 156.711396 -196.582792) (xy 158.057596 -196.582792)
				)
			)
		)
		(zone
			(layer "F.Cu")
			(hatch none 0.5)
			(connect_pads
				(clearance 0)
			)
			(min_thickness 0.25)
			(keepout
				(tracks not_allowed)
				(vias allowed)
				(pads allowed)
				(copperpour not_allowed)
				(footprints allowed)
			)
			(placement
				(enabled no)
				(sheetname "")
			)
			(fill
				(thermal_gap 0.5)
				(thermal_bridge_width 0.5)
				(island_removal_mode 0)
			)
			(polygon
				(pts
					(xy 158.057596 -189.648592) (xy 150.983696 -189.648592) (xy 150.983696 -196.582792) (xy 152.088596 -196.582792)
					(xy 152.088596 -192.467992) (xy 156.711396 -192.467992) (xy 156.711396 -196.582792) (xy 158.057596 -196.582792)
				)
			)
		)
		(zone
			(layer "F.Cu")
			(hatch none 0.5)
			(connect_pads
				(clearance 0)
			)
			(min_thickness 0.25)
			(keepout
				(tracks allowed)
				(vias not_allowed)
				(pads allowed)
				(copperpour not_allowed)
				(footprints allowed)
			)
			(placement
				(enabled no)
				(sheetname "")
			)
			(fill
				(thermal_gap 0.5)
				(thermal_bridge_width 0.5)
				(island_removal_mode 0)
			)
			(polygon
				(pts
					(xy 158.057596 -156.171392) (xy 150.983696 -156.171392) (xy 150.983696 -149.237192) (xy 152.088596 -149.237192)
					(xy 152.088596 -153.351992) (xy 156.711396 -153.351992) (xy 156.711396 -149.237192) (xy 158.057596 -149.237192)
				)
			)
		)
		(zone
			(layer "F.Cu")
			(hatch none 0.5)
			(connect_pads
				(clearance 0)
			)
			(min_thickness 0.25)
			(keepout
				(tracks not_allowed)
				(vias allowed)
				(pads allowed)
				(copperpour not_allowed)
				(footprints allowed)
			)
			(placement
				(enabled no)
				(sheetname "")
			)
			(fill
				(thermal_gap 0.5)
				(thermal_bridge_width 0.5)
				(island_removal_mode 0)
			)
			(polygon
				(pts
					(xy 158.057596 -156.171392) (xy 150.983696 -156.171392) (xy 150.983696 -149.237192) (xy 152.088596 -149.237192)
					(xy 152.088596 -153.351992) (xy 156.711396 -153.351992) (xy 156.711396 -149.237192) (xy 158.057596 -149.237192)
				)
			)
		)
		(zone
			(layers "F.Cu" "B.Cu" "In1.Cu" "In2.Cu" "In3.Cu" "In4.Cu" "In5.Cu" "In6.Cu"
				"In7.Cu" "In8.Cu" "In9.Cu" "In10.Cu"
			)
			(hatch none 0.5)
			(connect_pads
				(clearance 0)
			)
			(min_thickness 0.25)
			(keepout
				(tracks not_allowed)
				(vias allowed)
				(pads allowed)
				(copperpour not_allowed)
				(footprints allowed)
			)
			(placement
				(enabled no)
				(sheetname "")
			)
			(fill
				(thermal_gap 0.5)
				(thermal_bridge_width 0.5)
				(island_removal_mode 0)
			)
			(polygon
				(pts
					(arc
						(start 155.174696 -154.034998)
						(mid 153.625296 -154.034998)
						(end 155.174696 -154.034998)
					)
				)
			)
		)
		(zone
			(layers "F.Cu" "B.Cu" "In1.Cu" "In2.Cu" "In3.Cu" "In4.Cu" "In5.Cu" "In6.Cu"
				"In7.Cu" "In8.Cu" "In9.Cu" "In10.Cu"
			)
			(hatch none 0.5)
			(connect_pads
				(clearance 0)
			)
			(min_thickness 0.25)
			(keepout
				(tracks not_allowed)
				(vias allowed)
				(pads allowed)
				(copperpour not_allowed)
				(footprints allowed)
			)
			(placement
				(enabled no)
				(sheetname "")
			)
			(fill
				(thermal_gap 0.5)
				(thermal_bridge_width 0.5)
				(island_removal_mode 0)
			)
			(polygon
				(pts
					(arc
						(start 155.377896 -191.784986)
						(mid 153.422096 -191.784986)
						(end 155.377896 -191.784986)
					)
				)
			)
		)
	)
	(footprint ""
		(layer "F.Cu")
		(at 266.2936 -230.3018 180)
		(property "Reference" "R90"
			(at 0 0 180)
			(layer "F.SilkS")
			(hide yes)
			(effects
				(font
					(size 1.27 1.27)
				)
			)
		)
		(property "Value" "4K7R2F-GP"
			(at 0.064008 -3.993896 180)
			(unlocked yes)
			(layer "F.Fab")
			(hide yes)
			(effects
				(font
					(size 1.016 1.016)
					(thickness 0.1524)
				)
			)
		)
		(property "Device Type" "R402H16"
			(at 0.064008 -5.517896 180)
			(unlocked yes)
			(layer "F.Fab")
			(hide yes)
			(effects
				(font
					(size 1.016 1.016)
					(thickness 0.1524)
				)
			)
		)
		(duplicate_pad_numbers_are_jumpers no)
		(fp_line
			(start 0.508 -0.9398)
			(end -0.508 -0.9398)
			(stroke
				(width 0.1524)
				(type default)
			)
			(layer "F.SilkS")
		)
		(fp_line
			(start -0.508 -0.9398)
			(end -0.508 0.9398)
			(stroke
				(width 0.1524)
				(type default)
			)
			(layer "F.SilkS")
		)
		(fp_rect
			(start -0.508 0.9398)
			(end 0.508 -0.9398)
			(stroke
				(width 0)
				(type default)
			)
			(fill no)
			(layer "F.CrtYd")
		)
		(fp_rect
			(start -0.508 0.9398)
			(end 0.508 -0.9398)
			(stroke
				(width 0)
				(type default)
			)
			(fill no)
			(layer "F.Fab")
		)
		(pad "1" smd custom
			(at 0 -0.4445 180)
			(size 0.1397 0.1397)
			(layers "F.Cu" "F.Mask" "F.Paste")
			(net "P3V3_STBY_A")
			(options
				(clearance outline)
				(anchor circle)
			)
			(primitives
				(gr_poly
					(pts
						(arc
							(start -0.1778 -0.2794)
							(mid -0.249642 -0.249642)
							(end -0.2794 -0.1778)
						)
						(arc
							(start -0.2794 0.1778)
							(mid -0.249642 0.249642)
							(end -0.1778 0.2794)
						)
						(arc
							(start 0.1778 0.2794)
							(mid 0.249642 0.249642)
							(end 0.2794 0.1778)
						)
						(arc
							(start 0.2794 -0.1778)
							(mid 0.249642 -0.249642)
							(end 0.1778 -0.2794)
						)
					)
					(width 0)
					(fill yes)
				)
			)
		)
		(pad "2" smd custom
			(at 0 0.4445 180)
			(size 0.1397 0.1397)
			(layers "F.Cu" "F.Mask" "F.Paste")
			(net "IO_EXP3_A1")
			(options
				(clearance outline)
				(anchor circle)
			)
			(primitives
				(gr_poly
					(pts
						(arc
							(start -0.1778 -0.2794)
							(mid -0.249642 -0.249642)
							(end -0.2794 -0.1778)
						)
						(arc
							(start -0.2794 0.1778)
							(mid -0.249642 0.249642)
							(end -0.1778 0.2794)
						)
						(arc
							(start 0.1778 0.2794)
							(mid 0.249642 0.249642)
							(end 0.2794 0.1778)
						)
						(arc
							(start 0.2794 -0.1778)
							(mid 0.249642 -0.249642)
							(end 0.1778 -0.2794)
						)
					)
					(width 0)
					(fill yes)
				)
			)
		)
	)
	(footprint ""
		(layer "F.Cu")
		(at 474.853 -162.687)
		(property "Reference" "R663"
			(at 0 0 0)
			(layer "F.SilkS")
			(hide yes)
			(effects
				(font
					(size 1.27 1.27)
				)
			)
		)
		(property "Value" "220R3F-1-GP"
			(at -0.0254 -2.5146 0)
			(unlocked yes)
			(layer "F.Fab")
			(hide yes)
			(effects
				(font
					(size 1.016 1.016)
					(thickness 0.1524)
				)
			)
		)
		(property "Device Type" "R603H22"
			(at -0.0254 -4.0386 0)
			(unlocked yes)
			(layer "F.Fab")
			(hide yes)
			(effects
				(font
					(size 1.016 1.016)
					(thickness 0.1524)
				)
			)
		)
		(duplicate_pad_numbers_are_jumpers no)
		(fp_line
			(start -0.4826 0)
			(end -0.2032 0)
			(stroke
				(width 0.2032)
				(type default)
			)
			(layer "F.SilkS")
		)
		(fp_line
			(start 0.2032 0)
			(end 0.4826 0)
			(stroke
				(width 0.2032)
				(type default)
			)
			(layer "F.SilkS")
		)
		(fp_rect
			(start -0.5842 1.3335)
			(end 0.5842 -1.3335)
			(stroke
				(width 0)
				(type default)
			)
			(fill no)
			(layer "F.CrtYd")
		)
		(fp_rect
			(start -0.5842 1.3335)
			(end 0.5842 -1.3335)
			(stroke
				(width 0)
				(type default)
			)
			(fill no)
			(layer "F.Fab")
		)
		(pad "1" smd custom
			(at 0 -0.762)
			(size 0.2159 0.2159)
			(layers "F.Cu" "F.Mask" "F.Paste")
			(net "HDD_PRSNT_23")
			(options
				(clearance outline)
				(anchor circle)
			)
			(primitives
				(gr_poly
					(pts
						(arc
							(start -0.3302 -0.4318)
							(mid -0.402042 -0.402042)
							(end -0.4318 -0.3302)
						)
						(arc
							(start -0.4318 0.3302)
							(mid -0.402042 0.402042)
							(end -0.3302 0.4318)
						)
						(arc
							(start 0.3302 0.4318)
							(mid 0.402042 0.402042)
							(end 0.4318 0.3302)
						)
						(arc
							(start 0.4318 -0.3302)
							(mid 0.402042 -0.402042)
							(end 0.3302 -0.4318)
						)
					)
					(width 0)
					(fill yes)
				)
			)
		)
		(pad "2" smd custom
			(at 0 0.762)
			(size 0.2159 0.2159)
			(layers "F.Cu" "F.Mask" "F.Paste")
			(net "DRIVE_A_23_INS")
			(options
				(clearance outline)
				(anchor circle)
			)
			(primitives
				(gr_poly
					(pts
						(arc
							(start -0.3302 -0.4318)
							(mid -0.402042 -0.402042)
							(end -0.4318 -0.3302)
						)
						(arc
							(start -0.4318 0.3302)
							(mid -0.402042 0.402042)
							(end -0.3302 0.4318)
						)
						(arc
							(start 0.3302 0.4318)
							(mid 0.402042 0.402042)
							(end 0.4318 0.3302)
						)
						(arc
							(start 0.4318 -0.3302)
							(mid 0.402042 -0.402042)
							(end 0.3302 -0.4318)
						)
					)
					(width 0)
					(fill yes)
				)
			)
		)
	)
	(footprint ""
		(layer "F.Cu")
		(at 342.420702 -130.386836 -90)
		(property "Reference" "R532"
			(at 0 0 270)
			(layer "F.SilkS")
			(hide yes)
			(effects
				(font
					(size 1.27 1.27)
				)
			)
		)
		(property "Value" "4K7R2J-2-GP"
			(at 0.064008 -3.993896 270)
			(unlocked yes)
			(layer "F.Fab")
			(hide yes)
			(effects
				(font
					(size 1.016 1.016)
					(thickness 0.1524)
				)
			)
		)
		(property "Device Type" "R402H16"
			(at 0.064008 -5.517896 270)
			(unlocked yes)
			(layer "F.Fab")
			(hide yes)
			(effects
				(font
					(size 1.016 1.016)
					(thickness 0.1524)
				)
			)
		)
		(duplicate_pad_numbers_are_jumpers no)
		(fp_line
			(start -0.508 -0.9398)
			(end -0.508 0.9398)
			(stroke
				(width 0.1524)
				(type default)
			)
			(layer "F.SilkS")
		)
		(fp_line
			(start 0.508 -0.9398)
			(end -0.508 -0.9398)
			(stroke
				(width 0.1524)
				(type default)
			)
			(layer "F.SilkS")
		)
		(fp_rect
			(start -0.508 0.9398)
			(end 0.508 -0.9398)
			(stroke
				(width 0)
				(type default)
			)
			(fill no)
			(layer "F.CrtYd")
		)
		(fp_rect
			(start -0.508 0.9398)
			(end 0.508 -0.9398)
			(stroke
				(width 0)
				(type default)
			)
			(fill no)
			(layer "F.Fab")
		)
		(pad "1" smd custom
			(at 0 -0.4445 270)
			(size 0.1397 0.1397)
			(layers "F.Cu" "F.Mask" "F.Paste")
			(net "DRIVE_A_19_FLT_LED")
			(options
				(clearance outline)
				(anchor circle)
			)
			(primitives
				(gr_poly
					(pts
						(arc
							(start -0.1778 -0.2794)
							(mid -0.249642 -0.249642)
							(end -0.2794 -0.1778)
						)
						(arc
							(start -0.2794 0.1778)
							(mid -0.249642 0.249642)
							(end -0.1778 0.2794)
						)
						(arc
							(start 0.1778 0.2794)
							(mid 0.249642 0.249642)
							(end 0.2794 0.1778)
						)
						(arc
							(start 0.2794 -0.1778)
							(mid 0.249642 -0.249642)
							(end 0.1778 -0.2794)
						)
					)
					(width 0)
					(fill yes)
				)
			)
		)
		(pad "2" smd custom
			(at 0 0.4445 270)
			(size 0.1397 0.1397)
			(layers "F.Cu" "F.Mask" "F.Paste")
			(net "GND")
			(options
				(clearance outline)
				(anchor circle)
			)
			(primitives
				(gr_poly
					(pts
						(arc
							(start -0.1778 -0.2794)
							(mid -0.249642 -0.249642)
							(end -0.2794 -0.1778)
						)
						(arc
							(start -0.2794 0.1778)
							(mid -0.249642 0.249642)
							(end -0.1778 0.2794)
						)
						(arc
							(start 0.1778 0.2794)
							(mid 0.249642 0.249642)
							(end 0.2794 0.1778)
						)
						(arc
							(start 0.2794 -0.1778)
							(mid 0.249642 -0.249642)
							(end 0.1778 -0.2794)
						)
					)
					(width 0)
					(fill yes)
				)
			)
		)
	)
	(footprint ""
		(layer "F.Cu")
		(at 115.334796 -170.285918 180)
		(property "Reference" "Q89"
			(at 0 0 180)
			(layer "F.SilkS")
			(hide yes)
			(effects
				(font
					(size 1.27 1.27)
				)
			)
		)
		(property "Value" "AO4406AL-GP"
			(at -3.707384 -1.5367 180)
			(unlocked yes)
			(layer "F.Fab")
			(hide yes)
			(effects
				(font
					(size 1.016 1.016)
					(thickness 0.1524)
				)
			)
		)
		(property "Device Type" "SOIC8H69"
			(at -3.707384 -3.0607 180)
			(unlocked yes)
			(layer "F.Fab")
			(hide yes)
			(effects
				(font
					(size 1.016 1.016)
					(thickness 0.1524)
				)
			)
		)
		(duplicate_pad_numbers_are_jumpers no)
		(fp_line
			(start 2.1336 1.4224)
			(end 2.1336 -1.4224)
			(stroke
				(width 0.1524)
				(type default)
			)
			(layer "F.SilkS")
		)
		(fp_line
			(start 2.1336 -1.4224)
			(end -2.7432 -1.4224)
			(stroke
				(width 0.1524)
				(type default)
			)
			(layer "F.SilkS")
		)
		(fp_line
			(start -2.1844 -0.0508)
			(end -2.7178 0.508)
			(stroke
				(width 0.1524)
				(type default)
			)
			(layer "F.SilkS")
		)
		(fp_line
			(start -2.6289 3.4417)
			(end -2.6289 1.4732)
			(stroke
				(width 0.381)
				(type default)
			)
			(layer "F.SilkS")
		)
		(fp_line
			(start -2.7178 -0.508)
			(end -2.1844 -0.0508)
			(stroke
				(width 0.1524)
				(type default)
			)
			(layer "F.SilkS")
		)
		(fp_line
			(start -2.7432 1.4224)
			(end 2.1336 1.4224)
			(stroke
				(width 0.1524)
				(type default)
			)
			(layer "F.SilkS")
		)
		(fp_line
			(start -2.7432 1.4224)
			(end -2.6416 1.4224)
			(stroke
				(width 0.1524)
				(type default)
			)
			(layer "F.SilkS")
		)
		(fp_line
			(start -2.7432 -1.4224)
			(end -2.7432 1.4224)
			(stroke
				(width 0.1524)
				(type default)
			)
			(layer "F.SilkS")
		)
		(fp_poly
			(pts
				(xy -2.2098 -1.4224) (xy -2.2098 1.4224) (xy 2.2098 1.4224) (xy 2.2098 -1.4224)
			)
			(stroke
				(width 0)
				(type default)
			)
			(fill yes)
			(layer "F.SilkS")
		)
		(fp_rect
			(start -2.450084 2.999994)
			(end 2.450084 -2.999994)
			(stroke
				(width 0)
				(type default)
			)
			(fill no)
			(layer "F.CrtYd")
		)
		(fp_poly
			(pts
				(xy -2.8194 3.6322) (xy -2.8194 -3.6322) (xy 2.8194 -3.6322) (xy 2.8194 1.18364) (xy 2.450084 1.18364)
				(xy 2.450084 -2.999994) (xy -2.450084 -2.999994) (xy -2.450084 2.999994) (xy 2.450084 2.999994)
				(xy 2.450084 1.18618) (xy 2.8194 1.18618) (xy 2.8194 3.6322)
			)
			(stroke
				(width 0)
				(type default)
			)
			(fill no)
			(layer "F.CrtYd")
		)
		(fp_rect
			(start -2.8194 3.6322)
			(end 2.8194 -3.6322)
			(stroke
				(width 0)
				(type default)
			)
			(fill no)
			(layer "F.Fab")
		)
		(pad "1" smd rect
			(at -1.905 2.54 180)
			(size 0.635 1.651)
			(layers "F.Cu" "F.Mask" "F.Paste")
			(net "P5V_HDD15")
		)
		(pad "2" smd rect
			(at -0.635 2.54 180)
			(size 0.635 1.651)
			(layers "F.Cu" "F.Mask" "F.Paste")
			(net "P5V_HDD15")
		)
		(pad "3" smd rect
			(at 0.635 2.54 180)
			(size 0.635 1.651)
			(layers "F.Cu" "F.Mask" "F.Paste")
			(net "P5V_HDD15")
		)
		(pad "4" smd rect
			(at 1.905 2.54 180)
			(size 0.635 1.651)
			(layers "F.Cu" "F.Mask" "F.Paste")
			(net "SW_HDD_P15")
		)
		(pad "5" smd rect
			(at 1.905 -2.54 180)
			(size 0.635 1.651)
			(layers "F.Cu" "F.Mask" "F.Paste")
			(net "P5V_A_2")
		)
		(pad "6" smd rect
			(at 0.635 -2.54 180)
			(size 0.635 1.651)
			(layers "F.Cu" "F.Mask" "F.Paste")
			(net "P5V_A_2")
		)
		(pad "7" smd rect
			(at -0.635 -2.54 180)
			(size 0.635 1.651)
			(layers "F.Cu" "F.Mask" "F.Paste")
			(net "P5V_A_2")
		)
		(pad "8" smd rect
			(at -1.905 -2.54 180)
			(size 0.635 1.651)
			(layers "F.Cu" "F.Mask" "F.Paste")
			(net "P5V_A_2")
		)
	)
	(footprint ""
		(layer "F.Cu")
		(at 399.90395 -62.016894)
		(property "Reference" "Q194"
			(at 0 0 0)
			(layer "F.SilkS")
			(hide yes)
			(effects
				(font
					(size 1.27 1.27)
				)
			)
		)
		(property "Value" "AO4407AL-GP"
			(at -3.707384 -1.5367 0)
			(unlocked yes)
			(layer "F.Fab")
			(hide yes)
			(effects
				(font
					(size 1.016 1.016)
					(thickness 0.1524)
				)
			)
		)
		(property "Device Type" "SOIC8H69"
			(at -3.707384 -3.0607 0)
			(unlocked yes)
			(layer "F.Fab")
			(hide yes)
			(effects
				(font
					(size 1.016 1.016)
					(thickness 0.1524)
				)
			)
		)
		(duplicate_pad_numbers_are_jumpers no)
		(fp_line
			(start -2.7432 -1.4224)
			(end -2.7432 1.4224)
			(stroke
				(width 0.1524)
				(type default)
			)
			(layer "F.SilkS")
		)
		(fp_line
			(start -2.7432 1.4224)
			(end -2.6416 1.4224)
			(stroke
				(width 0.1524)
				(type default)
			)
			(layer "F.SilkS")
		)
		(fp_line
			(start -2.7432 1.4224)
			(end 2.1336 1.4224)
			(stroke
				(width 0.1524)
				(type default)
			)
			(layer "F.SilkS")
		)
		(fp_line
			(start -2.7178 -0.508)
			(end -2.1844 -0.0508)
			(stroke
				(width 0.1524)
				(type default)
			)
			(layer "F.SilkS")
		)
		(fp_line
			(start -2.6289 3.4417)
			(end -2.6289 1.4732)
			(stroke
				(width 0.381)
				(type default)
			)
			(layer "F.SilkS")
		)
		(fp_line
			(start -2.1844 -0.0508)
			(end -2.7178 0.508)
			(stroke
				(width 0.1524)
				(type default)
			)
			(layer "F.SilkS")
		)
		(fp_line
			(start 2.1336 -1.4224)
			(end -2.7432 -1.4224)
			(stroke
				(width 0.1524)
				(type default)
			)
			(layer "F.SilkS")
		)
		(fp_line
			(start 2.1336 1.4224)
			(end 2.1336 -1.4224)
			(stroke
				(width 0.1524)
				(type default)
			)
			(layer "F.SilkS")
		)
		(fp_poly
			(pts
				(xy -2.2098 -1.4224) (xy -2.2098 1.4224) (xy 2.2098 1.4224) (xy 2.2098 -1.4224)
			)
			(stroke
				(width 0)
				(type default)
			)
			(fill yes)
			(layer "F.SilkS")
		)
		(fp_rect
			(start -2.450084 2.999994)
			(end 2.450084 -2.999994)
			(stroke
				(width 0)
				(type default)
			)
			(fill no)
			(layer "F.CrtYd")
		)
		(fp_poly
			(pts
				(xy -2.8194 3.6322) (xy -2.8194 -3.6322) (xy 2.8194 -3.6322) (xy 2.8194 1.18364) (xy 2.450084 1.18364)
				(xy 2.450084 -2.999994) (xy -2.450084 -2.999994) (xy -2.450084 2.999994) (xy 2.450084 2.999994)
				(xy 2.450084 1.18618) (xy 2.8194 1.18618) (xy 2.8194 3.6322)
			)
			(stroke
				(width 0)
				(type default)
			)
			(fill no)
			(layer "F.CrtYd")
		)
		(fp_rect
			(start -2.8194 3.6322)
			(end 2.8194 -3.6322)
			(stroke
				(width 0)
				(type default)
			)
			(fill no)
			(layer "F.Fab")
		)
		(pad "1" smd rect
			(at -1.905 2.54)
			(size 0.635 1.651)
			(layers "F.Cu" "F.Mask" "F.Paste")
			(net "P12V_A")
		)
		(pad "2" smd rect
			(at -0.635 2.54)
			(size 0.635 1.651)
			(layers "F.Cu" "F.Mask" "F.Paste")
			(net "P12V_A")
		)
		(pad "3" smd rect
			(at 0.635 2.54)
			(size 0.635 1.651)
			(layers "F.Cu" "F.Mask" "F.Paste")
			(net "P12V_A")
		)
		(pad "4" smd rect
			(at 1.905 2.54)
			(size 0.635 1.651)
			(layers "F.Cu" "F.Mask" "F.Paste")
			(net "SW_HDD_N32")
		)
		(pad "5" smd rect
			(at 1.905 -2.54)
			(size 0.635 1.651)
			(layers "F.Cu" "F.Mask" "F.Paste")
			(net "P12V_HDD32")
		)
		(pad "6" smd rect
			(at 0.635 -2.54)
			(size 0.635 1.651)
			(layers "F.Cu" "F.Mask" "F.Paste")
			(net "P12V_HDD32")
		)
		(pad "7" smd rect
			(at -0.635 -2.54)
			(size 0.635 1.651)
			(layers "F.Cu" "F.Mask" "F.Paste")
			(net "P12V_HDD32")
		)
		(pad "8" smd rect
			(at -1.905 -2.54)
			(size 0.635 1.651)
			(layers "F.Cu" "F.Mask" "F.Paste")
			(net "P12V_HDD32")
		)
	)
	(footprint ""
		(layer "F.Cu")
		(at 338.074 -279.443942 90)
		(property "Reference" "R284"
			(at 0 0 90)
			(layer "F.SilkS")
			(hide yes)
			(effects
				(font
					(size 1.27 1.27)
				)
			)
		)
		(property "Value" "200KR2F-L-GP"
			(at 0.064008 -3.993896 90)
			(unlocked yes)
			(layer "F.Fab")
			(hide yes)
			(effects
				(font
					(size 1.016 1.016)
					(thickness 0.1524)
				)
			)
		)
		(property "Device Type" "R402H16"
			(at 0.064008 -5.517896 90)
			(unlocked yes)
			(layer "F.Fab")
			(hide yes)
			(effects
				(font
					(size 1.016 1.016)
					(thickness 0.1524)
				)
			)
		)
		(duplicate_pad_numbers_are_jumpers no)
		(fp_line
			(start 0.508 -0.9398)
			(end -0.508 -0.9398)
			(stroke
				(width 0.1524)
				(type default)
			)
			(layer "F.SilkS")
		)
		(fp_line
			(start -0.508 -0.9398)
			(end -0.508 0.9398)
			(stroke
				(width 0.1524)
				(type default)
			)
			(layer "F.SilkS")
		)
		(fp_rect
			(start -0.508 0.9398)
			(end 0.508 -0.9398)
			(stroke
				(width 0)
				(type default)
			)
			(fill no)
			(layer "F.CrtYd")
		)
		(fp_rect
			(start -0.508 0.9398)
			(end 0.508 -0.9398)
			(stroke
				(width 0)
				(type default)
			)
			(fill no)
			(layer "F.Fab")
		)
		(pad "1" smd custom
			(at 0 -0.4445 90)
			(size 0.1397 0.1397)
			(layers "F.Cu" "F.Mask" "F.Paste")
			(net "SW_HDD_R6")
			(options
				(clearance outline)
				(anchor circle)
			)
			(primitives
				(gr_poly
					(pts
						(arc
							(start -0.1778 -0.2794)
							(mid -0.249642 -0.249642)
							(end -0.2794 -0.1778)
						)
						(arc
							(start -0.2794 0.1778)
							(mid -0.249642 0.249642)
							(end -0.1778 0.2794)
						)
						(arc
							(start 0.1778 0.2794)
							(mid 0.249642 0.249642)
							(end 0.2794 0.1778)
						)
						(arc
							(start 0.2794 -0.1778)
							(mid 0.249642 -0.249642)
							(end 0.1778 -0.2794)
						)
					)
					(width 0)
					(fill yes)
				)
			)
		)
		(pad "2" smd custom
			(at 0 0.4445 90)
			(size 0.1397 0.1397)
			(layers "F.Cu" "F.Mask" "F.Paste")
			(net "SW_HDD_N6")
			(options
				(clearance outline)
				(anchor circle)
			)
			(primitives
				(gr_poly
					(pts
						(arc
							(start -0.1778 -0.2794)
							(mid -0.249642 -0.249642)
							(end -0.2794 -0.1778)
						)
						(arc
							(start -0.2794 0.1778)
							(mid -0.249642 0.249642)
							(end -0.1778 0.2794)
						)
						(arc
							(start 0.1778 0.2794)
							(mid 0.249642 0.249642)
							(end 0.2794 0.1778)
						)
						(arc
							(start 0.2794 -0.1778)
							(mid 0.249642 -0.249642)
							(end 0.1778 -0.2794)
						)
					)
					(width 0)
					(fill yes)
				)
			)
		)
	)
	(footprint ""
		(layer "F.Cu")
		(at 22.996398 -278.554942 90)
		(property "Reference" "R970"
			(at 0 0 90)
			(layer "F.SilkS")
			(hide yes)
			(effects
				(font
					(size 1.27 1.27)
				)
			)
		)
		(property "Value" "4K7R2J-2-GP"
			(at 0.064008 -3.993896 90)
			(unlocked yes)
			(layer "F.Fab")
			(hide yes)
			(effects
				(font
					(size 1.016 1.016)
					(thickness 0.1524)
				)
			)
		)
		(property "Device Type" "R402H16"
			(at 0.064008 -5.517896 90)
			(unlocked yes)
			(layer "F.Fab")
			(hide yes)
			(effects
				(font
					(size 1.016 1.016)
					(thickness 0.1524)
				)
			)
		)
		(duplicate_pad_numbers_are_jumpers no)
		(fp_line
			(start 0.508 -0.9398)
			(end -0.508 -0.9398)
			(stroke
				(width 0.1524)
				(type default)
			)
			(layer "F.SilkS")
		)
		(fp_line
			(start -0.508 -0.9398)
			(end -0.508 0.9398)
			(stroke
				(width 0.1524)
				(type default)
			)
			(layer "F.SilkS")
		)
		(fp_rect
			(start -0.508 0.9398)
			(end 0.508 -0.9398)
			(stroke
				(width 0)
				(type default)
			)
			(fill no)
			(layer "F.CrtYd")
		)
		(fp_rect
			(start -0.508 0.9398)
			(end 0.508 -0.9398)
			(stroke
				(width 0)
				(type default)
			)
			(fill no)
			(layer "F.Fab")
		)
		(pad "1" smd custom
			(at 0 -0.4445 90)
			(size 0.1397 0.1397)
			(layers "F.Cu" "F.Mask" "F.Paste")
			(net "SW_PWR_R_HDD0")
			(options
				(clearance outline)
				(anchor circle)
			)
			(primitives
				(gr_poly
					(pts
						(arc
							(start -0.1778 -0.2794)
							(mid -0.249642 -0.249642)
							(end -0.2794 -0.1778)
						)
						(arc
							(start -0.2794 0.1778)
							(mid -0.249642 0.249642)
							(end -0.1778 0.2794)
						)
						(arc
							(start 0.1778 0.2794)
							(mid 0.249642 0.249642)
							(end 0.2794 0.1778)
						)
						(arc
							(start 0.2794 -0.1778)
							(mid 0.249642 -0.249642)
							(end 0.1778 -0.2794)
						)
					)
					(width 0)
					(fill yes)
				)
			)
		)
		(pad "2" smd custom
			(at 0 0.4445 90)
			(size 0.1397 0.1397)
			(layers "F.Cu" "F.Mask" "F.Paste")
			(net "GND")
			(options
				(clearance outline)
				(anchor circle)
			)
			(primitives
				(gr_poly
					(pts
						(arc
							(start -0.1778 -0.2794)
							(mid -0.249642 -0.249642)
							(end -0.2794 -0.1778)
						)
						(arc
							(start -0.2794 0.1778)
							(mid -0.249642 0.249642)
							(end -0.1778 0.2794)
						)
						(arc
							(start 0.1778 0.2794)
							(mid 0.249642 0.249642)
							(end 0.2794 0.1778)
						)
						(arc
							(start 0.2794 -0.1778)
							(mid 0.249642 -0.249642)
							(end 0.1778 -0.2794)
						)
					)
					(width 0)
					(fill yes)
				)
			)
		)
	)
	(footprint ""
		(layer "F.Cu")
		(at 180.7464 -276.014942 -90)
		(property "Reference" "R253"
			(at 0 0 270)
			(layer "F.SilkS")
			(hide yes)
			(effects
				(font
					(size 1.27 1.27)
				)
			)
		)
		(property "Value" "1KR2F-3-GP"
			(at 0.064008 -3.993896 270)
			(unlocked yes)
			(layer "F.Fab")
			(hide yes)
			(effects
				(font
					(size 1.016 1.016)
					(thickness 0.1524)
				)
			)
		)
		(property "Device Type" "R402H16"
			(at 0.064008 -5.517896 270)
			(unlocked yes)
			(layer "F.Fab")
			(hide yes)
			(effects
				(font
					(size 1.016 1.016)
					(thickness 0.1524)
				)
			)
		)
		(duplicate_pad_numbers_are_jumpers no)
		(fp_line
			(start -0.508 -0.9398)
			(end -0.508 0.9398)
			(stroke
				(width 0.1524)
				(type default)
			)
			(layer "F.SilkS")
		)
		(fp_line
			(start 0.508 -0.9398)
			(end -0.508 -0.9398)
			(stroke
				(width 0.1524)
				(type default)
			)
			(layer "F.SilkS")
		)
		(fp_rect
			(start -0.508 0.9398)
			(end 0.508 -0.9398)
			(stroke
				(width 0)
				(type default)
			)
			(fill no)
			(layer "F.CrtYd")
		)
		(fp_rect
			(start -0.508 0.9398)
			(end 0.508 -0.9398)
			(stroke
				(width 0)
				(type default)
			)
			(fill no)
			(layer "F.Fab")
		)
		(pad "1" smd custom
			(at 0 -0.4445 270)
			(size 0.1397 0.1397)
			(layers "F.Cu" "F.Mask" "F.Paste")
			(net "P3V3_STBY_A")
			(options
				(clearance outline)
				(anchor circle)
			)
			(primitives
				(gr_poly
					(pts
						(arc
							(start -0.1778 -0.2794)
							(mid -0.249642 -0.249642)
							(end -0.2794 -0.1778)
						)
						(arc
							(start -0.2794 0.1778)
							(mid -0.249642 0.249642)
							(end -0.1778 0.2794)
						)
						(arc
							(start 0.1778 0.2794)
							(mid 0.249642 0.249642)
							(end 0.2794 0.1778)
						)
						(arc
							(start 0.2794 -0.1778)
							(mid 0.249642 -0.249642)
							(end 0.1778 -0.2794)
						)
					)
					(width 0)
					(fill yes)
				)
			)
		)
		(pad "2" smd custom
			(at 0 0.4445 270)
			(size 0.1397 0.1397)
			(layers "F.Cu" "F.Mask" "F.Paste")
			(net "SW_PWR_R_HDD5")
			(options
				(clearance outline)
				(anchor circle)
			)
			(primitives
				(gr_poly
					(pts
						(arc
							(start -0.1778 -0.2794)
							(mid -0.249642 -0.249642)
							(end -0.2794 -0.1778)
						)
						(arc
							(start -0.2794 0.1778)
							(mid -0.249642 0.249642)
							(end -0.1778 0.2794)
						)
						(arc
							(start 0.1778 0.2794)
							(mid 0.249642 0.249642)
							(end 0.2794 0.1778)
						)
						(arc
							(start 0.2794 -0.1778)
							(mid 0.249642 -0.249642)
							(end 0.1778 -0.2794)
						)
					)
					(width 0)
					(fill yes)
				)
			)
		)
	)
	(footprint ""
		(layer "F.Cu")
		(at 51.943 -163.576 90)
		(property "Reference" "C217"
			(at 0 0 90)
			(layer "F.SilkS")
			(hide yes)
			(effects
				(font
					(size 1.27 1.27)
				)
			)
		)
		(property "Value" "SCD033U25V2KX-GP"
			(at 1.1811 -2.7051 90)
			(unlocked yes)
			(layer "F.Fab")
			(hide yes)
			(effects
				(font
					(size 1.016 1.016)
					(thickness 0.1524)
				)
			)
		)
		(property "Device Type" "C402H22"
			(at 1.1811 -4.2291 90)
			(unlocked yes)
			(layer "F.Fab")
			(hide yes)
			(effects
				(font
					(size 1.016 1.016)
					(thickness 0.1524)
				)
			)
		)
		(duplicate_pad_numbers_are_jumpers no)
		(fp_rect
			(start -0.4318 0.9525)
			(end 0.4318 -0.9525)
			(stroke
				(width 0)
				(type default)
			)
			(fill no)
			(layer "F.CrtYd")
		)
		(fp_rect
			(start -0.4318 0.9525)
			(end 0.4318 -0.9525)
			(stroke
				(width 0)
				(type default)
			)
			(fill no)
			(layer "F.Fab")
		)
		(pad "1" smd custom
			(at 0 -0.4445 90)
			(size 0.1524 0.1524)
			(layers "F.Cu" "F.Mask" "F.Paste")
			(net "SW_HDD_P13")
			(options
				(clearance outline)
				(anchor circle)
			)
			(primitives
				(gr_poly
					(pts
						(arc
							(start 0.3048 -0.2032)
							(mid 0.275042 -0.275042)
							(end 0.2032 -0.3048)
						)
						(arc
							(start -0.2032 -0.3048)
							(mid -0.275042 -0.275042)
							(end -0.3048 -0.2032)
						)
						(arc
							(start -0.3048 0.2032)
							(mid -0.275042 0.275042)
							(end -0.2032 0.3048)
						)
						(arc
							(start 0.2032 0.3048)
							(mid 0.275042 0.275042)
							(end 0.3048 0.2032)
						)
					)
					(width 0)
					(fill yes)
				)
			)
		)
		(pad "2" smd custom
			(at 0 0.4445 90)
			(size 0.1524 0.1524)
			(layers "F.Cu" "F.Mask" "F.Paste")
			(net "GND")
			(options
				(clearance outline)
				(anchor circle)
			)
			(primitives
				(gr_poly
					(pts
						(arc
							(start 0.3048 -0.2032)
							(mid 0.275042 -0.275042)
							(end 0.2032 -0.3048)
						)
						(arc
							(start -0.2032 -0.3048)
							(mid -0.275042 -0.275042)
							(end -0.3048 -0.2032)
						)
						(arc
							(start -0.3048 0.2032)
							(mid -0.275042 0.275042)
							(end -0.2032 0.3048)
						)
						(arc
							(start 0.2032 0.3048)
							(mid 0.275042 0.275042)
							(end 0.3048 0.2032)
						)
					)
					(width 0)
					(fill yes)
				)
			)
		)
	)
	(footprint ""
		(layer "F.Cu")
		(at 368.481102 -160.735518 180)
		(property "Reference" "R581"
			(at 0 0 180)
			(layer "F.SilkS")
			(hide yes)
			(effects
				(font
					(size 1.27 1.27)
				)
			)
		)
		(property "Value" "4K7R2J-2-GP"
			(at 0.064008 -3.993896 180)
			(unlocked yes)
			(layer "F.Fab")
			(hide yes)
			(effects
				(font
					(size 1.016 1.016)
					(thickness 0.1524)
				)
			)
		)
		(property "Device Type" "R402H16"
			(at 0.064008 -5.517896 180)
			(unlocked yes)
			(layer "F.Fab")
			(hide yes)
			(effects
				(font
					(size 1.016 1.016)
					(thickness 0.1524)
				)
			)
		)
		(duplicate_pad_numbers_are_jumpers no)
		(fp_line
			(start 0.508 -0.9398)
			(end -0.508 -0.9398)
			(stroke
				(width 0.1524)
				(type default)
			)
			(layer "F.SilkS")
		)
		(fp_line
			(start -0.508 -0.9398)
			(end -0.508 0.9398)
			(stroke
				(width 0.1524)
				(type default)
			)
			(layer "F.SilkS")
		)
		(fp_rect
			(start -0.508 0.9398)
			(end 0.508 -0.9398)
			(stroke
				(width 0)
				(type default)
			)
			(fill no)
			(layer "F.CrtYd")
		)
		(fp_rect
			(start -0.508 0.9398)
			(end 0.508 -0.9398)
			(stroke
				(width 0)
				(type default)
			)
			(fill no)
			(layer "F.Fab")
		)
		(pad "1" smd custom
			(at 0 -0.4445 180)
			(size 0.1397 0.1397)
			(layers "F.Cu" "F.Mask" "F.Paste")
			(net "P12V_A")
			(options
				(clearance outline)
				(anchor circle)
			)
			(primitives
				(gr_poly
					(pts
						(arc
							(start -0.1778 -0.2794)
							(mid -0.249642 -0.249642)
							(end -0.2794 -0.1778)
						)
						(arc
							(start -0.2794 0.1778)
							(mid -0.249642 0.249642)
							(end -0.1778 0.2794)
						)
						(arc
							(start 0.1778 0.2794)
							(mid 0.249642 0.249642)
							(end 0.2794 0.1778)
						)
						(arc
							(start 0.2794 -0.1778)
							(mid 0.249642 -0.249642)
							(end 0.1778 -0.2794)
						)
					)
					(width 0)
					(fill yes)
				)
			)
		)
		(pad "2" smd custom
			(at 0 0.4445 180)
			(size 0.1397 0.1397)
			(layers "F.Cu" "F.Mask" "F.Paste")
			(net "SW_HDD_R19")
			(options
				(clearance outline)
				(anchor circle)
			)
			(primitives
				(gr_poly
					(pts
						(arc
							(start -0.1778 -0.2794)
							(mid -0.249642 -0.249642)
							(end -0.2794 -0.1778)
						)
						(arc
							(start -0.2794 0.1778)
							(mid -0.249642 0.249642)
							(end -0.1778 0.2794)
						)
						(arc
							(start 0.1778 0.2794)
							(mid 0.249642 0.249642)
							(end 0.2794 0.1778)
						)
						(arc
							(start 0.2794 -0.1778)
							(mid 0.249642 -0.249642)
							(end 0.1778 -0.2794)
						)
					)
					(width 0)
					(fill yes)
				)
			)
		)
	)
	(footprint ""
		(layer "F.Cu")
		(at 181.483 -177.270918)
		(property "Reference" "R520"
			(at 0 0 0)
			(layer "F.SilkS")
			(hide yes)
			(effects
				(font
					(size 1.27 1.27)
				)
			)
		)
		(property "Value" "2R6F-GP"
			(at -0.0508 -4.8514 0)
			(unlocked yes)
			(layer "F.Fab")
			(hide yes)
			(effects
				(font
					(size 1.016 1.016)
					(thickness 0.1524)
				)
			)
		)
		(property "Device Type" "R1206H26"
			(at 0 -6.3754 0)
			(unlocked yes)
			(layer "F.Fab")
			(hide yes)
			(effects
				(font
					(size 1.016 1.016)
					(thickness 0.1524)
				)
			)
		)
		(duplicate_pad_numbers_are_jumpers no)
		(fp_line
			(start -1.016 -2.2352)
			(end 1.016 -2.2352)
			(stroke
				(width 0.1524)
				(type default)
			)
			(layer "F.SilkS")
		)
		(fp_line
			(start -1.016 2.2352)
			(end -1.016 -2.2352)
			(stroke
				(width 0.1524)
				(type default)
			)
			(layer "F.SilkS")
		)
		(fp_line
			(start 1.016 -2.2352)
			(end 1.016 2.2352)
			(stroke
				(width 0.1524)
				(type default)
			)
			(layer "F.SilkS")
		)
		(fp_line
			(start 1.016 2.2352)
			(end -1.016 2.2352)
			(stroke
				(width 0.1524)
				(type default)
			)
			(layer "F.SilkS")
		)
		(fp_rect
			(start -1.0922 2.3114)
			(end 1.0922 -2.3114)
			(stroke
				(width 0)
				(type default)
			)
			(fill no)
			(layer "F.CrtYd")
		)
		(fp_poly
			(pts
				(xy -1.0922 -2.3114) (xy 1.0922 -2.3114) (xy 1.0922 2.3114) (xy -1.0922 2.3114)
			)
			(stroke
				(width 0)
				(type default)
			)
			(fill no)
			(layer "F.Fab")
		)
		(pad "1" smd rect
			(at 0 -1.397)
			(size 1.651 1.27)
			(layers "F.Cu" "F.Mask" "F.Paste")
			(net "P5V_HDD17")
		)
		(pad "2" smd rect
			(at 0 1.397)
			(size 1.651 1.27)
			(layers "F.Cu" "F.Mask" "F.Paste")
			(net "5V_PRE_17")
		)
	)
	(footprint ""
		(layer "F.Cu")
		(at 238.76 -388.4168)
		(property "Reference" "U26"
			(at 0 0 0)
			(layer "F.SilkS")
			(hide yes)
			(effects
				(font
					(size 1.27 1.27)
				)
			)
		)
		(property "Value" "ADM1278-2ACPZ-RL-1-GP"
			(at -4.7625 -7.4422 0)
			(unlocked yes)
			(layer "F.Fab")
			(hide yes)
			(effects
				(font
					(size 1.016 1.016)
					(thickness 0.1524)
				)
			)
		)
		(property "Device Type" "QFN32-G3D45-UH32"
			(at -4.7625 -8.9662 0)
			(unlocked yes)
			(layer "F.Fab")
			(hide yes)
			(effects
				(font
					(size 1.016 1.016)
					(thickness 0.1524)
				)
			)
		)
		(duplicate_pad_numbers_are_jumpers no)
		(fp_line
			(start -4.0513 -1.24968)
			(end -3.2893 -1.24968)
			(stroke
				(width 0.1524)
				(type default)
			)
			(layer "F.SilkS")
		)
		(fp_line
			(start -3.7973 1.24968)
			(end -3.2893 1.24968)
			(stroke
				(width 0.1524)
				(type default)
			)
			(layer "F.SilkS")
		)
		(fp_line
			(start -3.5179 -3.5179)
			(end -2.2479 -3.5179)
			(stroke
				(width 0.1524)
				(type default)
			)
			(layer "F.SilkS")
		)
		(fp_line
			(start -3.5179 -2.2479)
			(end -3.5179 -3.5179)
			(stroke
				(width 0.1524)
				(type default)
			)
			(layer "F.SilkS")
		)
		(fp_line
			(start -3.5179 2.2479)
			(end -3.5179 3.5179)
			(stroke
				(width 0.1524)
				(type default)
			)
			(layer "F.SilkS")
		)
		(fp_line
			(start -3.5179 3.5179)
			(end -2.2479 3.5179)
			(stroke
				(width 0.1524)
				(type default)
			)
			(layer "F.SilkS")
		)
		(fp_line
			(start -0.250698 -3.7973)
			(end -0.250698 -3.2893)
			(stroke
				(width 0.1524)
				(type default)
			)
			(layer "F.SilkS")
		)
		(fp_line
			(start -0.250698 4.0513)
			(end -0.250698 3.2893)
			(stroke
				(width 0.1524)
				(type default)
			)
			(layer "F.SilkS")
		)
		(fp_line
			(start 3.5179 2.2479)
			(end 3.5179 3.5179)
			(stroke
				(width 0.1524)
				(type default)
			)
			(layer "F.SilkS")
		)
		(fp_line
			(start 3.5179 3.5179)
			(end 2.2479 3.5179)
			(stroke
				(width 0.1524)
				(type default)
			)
			(layer "F.SilkS")
		)
		(fp_line
			(start 3.7973 1.749552)
			(end 3.2893 1.749552)
			(stroke
				(width 0.1524)
				(type default)
			)
			(layer "F.SilkS")
		)
		(fp_line
			(start 4.0513 -0.749808)
			(end 3.2893 -0.749808)
			(stroke
				(width 0.1524)
				(type default)
			)
			(layer "F.SilkS")
		)
		(fp_poly
			(pts
				(xy 2.2479 -3.5179) (xy 3.5179 -2.2479) (xy 3.5179 -3.5179)
			)
			(stroke
				(width 0)
				(type default)
			)
			(fill yes)
			(layer "F.SilkS")
		)
		(fp_rect
			(start -2.5019 2.5019)
			(end 2.5019 -2.5019)
			(stroke
				(width 0)
				(type default)
			)
			(fill no)
			(layer "F.CrtYd")
		)
		(fp_poly
			(pts
				(xy -3.5179 3.5179) (xy -3.5179 -3.5179) (xy 3.5179 -3.5179) (xy 3.5179 3.5179) (xy -2.49682 3.5179)
				(xy -2.49682 2.5019) (xy 2.5019 2.5019) (xy 2.5019 -2.5019) (xy -2.5019 -2.5019) (xy -2.5019 3.5179)
			)
			(stroke
				(width 0)
				(type default)
			)
			(fill no)
			(layer "F.CrtYd")
		)
		(fp_rect
			(start -3.5179 3.5179)
			(end 3.5179 -3.5179)
			(stroke
				(width 0)
				(type default)
			)
			(fill no)
			(layer "F.Fab")
		)
		(pad "1" smd rect
			(at 1.75006 -2.5527)
			(size 0.3048 0.9144)
			(layers "F.Cu" "F.Mask" "F.Paste")
			(net "MB3_PSET_R")
		)
		(pad "2" smd rect
			(at 1.249934 -2.4765)
			(size 0.3048 1.0668)
			(layers "F.Cu" "F.Mask" "F.Paste")
			(net "MB3_VCAP_R")
		)
		(pad "3" smd rect
			(at 0.750062 -2.4765)
			(size 0.3048 1.0668)
			(layers "F.Cu" "F.Mask" "F.Paste")
			(net "MB3_ISET_R")
		)
		(pad "4" smd rect
			(at 0.249936 -2.4765)
			(size 0.3048 1.0668)
			(layers "F.Cu" "F.Mask" "F.Paste")
			(net "MB3_ISTART_R")
		)
		(pad "5" smd rect
			(at -0.249936 -2.4765)
			(size 0.3048 1.0668)
			(layers "F.Cu" "F.Mask" "F.Paste")
			(net "MB3_TIME_R")
		)
		(pad "6" smd rect
			(at -0.750062 -2.4765)
			(size 0.3048 1.0668)
			(layers "F.Cu" "F.Mask" "F.Paste")
			(net "Net_1348")
		)
		(pad "7" smd rect
			(at -1.249934 -2.4765)
			(size 0.3048 1.0668)
			(layers "F.Cu" "F.Mask" "F.Paste")
			(net "MB3_CM_ADR1_R")
		)
		(pad "8" smd rect
			(at -1.75006 -2.5527)
			(size 0.3048 0.9144)
			(layers "F.Cu" "F.Mask" "F.Paste")
			(net "MB3_CM_ADR2_R")
		)
		(pad "9" smd rect
			(at -2.5527 -1.75006)
			(size 0.9144 0.3048)
			(layers "F.Cu" "F.Mask" "F.Paste")
			(net "MB3_SPISS_PD")
		)
		(pad "10" smd rect
			(at -2.4765 -1.249934)
			(size 1.0668 0.3048)
			(layers "F.Cu" "F.Mask" "F.Paste")
			(net "Net_1352")
		)
		(pad "11" smd rect
			(at -2.4765 -0.750062)
			(size 1.0668 0.3048)
			(layers "F.Cu" "F.Mask" "F.Paste")
			(net "Net_1351")
		)
		(pad "12" smd rect
			(at -2.4765 -0.249936)
			(size 1.0668 0.3048)
			(layers "F.Cu" "F.Mask" "F.Paste")
			(net "MB3_HS_ENABLE")
		)
		(pad "13" smd rect
			(at -2.4765 0.249936)
			(size 1.0668 0.3048)
			(layers "F.Cu" "F.Mask" "F.Paste")
			(net "Net_1350")
		)
		(pad "14" smd rect
			(at -2.4765 0.750062)
			(size 1.0668 0.3048)
			(layers "F.Cu" "F.Mask" "F.Paste")
			(net "Net_1349")
		)
		(pad "15" smd rect
			(at -2.4765 1.249934)
			(size 1.0668 0.3048)
			(layers "F.Cu" "F.Mask" "F.Paste")
			(net "MB3_SDA_R")
		)
		(pad "16" smd rect
			(at -2.5527 1.75006)
			(size 0.9144 0.3048)
			(layers "F.Cu" "F.Mask" "F.Paste")
			(net "MB3_SCL_R")
		)
		(pad "17" smd rect
			(at -1.75006 2.5527)
			(size 0.3048 0.9144)
			(layers "F.Cu" "F.Mask" "F.Paste")
			(net "MB3_RETRY_R")
		)
		(pad "18" smd rect
			(at -1.249934 2.4765)
			(size 0.3048 1.0668)
			(layers "F.Cu" "F.Mask" "F.Paste")
			(net "P12V_A_PGOOD")
		)
		(pad "19" smd rect
			(at -0.750062 2.4765)
			(size 0.3048 1.0668)
			(layers "F.Cu" "F.Mask" "F.Paste")
			(net "Net_1353")
		)
		(pad "20" smd rect
			(at -0.249936 2.4765)
			(size 0.3048 1.0668)
			(layers "F.Cu" "F.Mask" "F.Paste")
			(net "MB3_CM_VOUT_R")
		)
		(pad "21" smd rect
			(at 0.249936 2.4765)
			(size 0.3048 1.0668)
			(layers "F.Cu" "F.Mask" "F.Paste")
			(net "MB3_P12V_PWGIN_R")
		)
		(pad "22" smd rect
			(at 0.750062 2.4765)
			(size 0.3048 1.0668)
			(layers "F.Cu" "F.Mask" "F.Paste")
			(net "AGND_CURRENT_DPB")
		)
		(pad "23" smd rect
			(at 1.249934 2.4765)
			(size 0.3048 1.0668)
			(layers "F.Cu" "F.Mask" "F.Paste")
			(net "GND")
		)
		(pad "24" smd rect
			(at 1.75006 2.5527)
			(size 0.3048 0.9144)
			(layers "F.Cu" "F.Mask" "F.Paste")
			(net "MB3_CM_GATE")
		)
		(pad "25" smd rect
			(at 2.5527 1.75006)
			(size 0.9144 0.3048)
			(layers "F.Cu" "F.Mask" "F.Paste")
			(net "MB3_TEMP")
		)
		(pad "26" smd rect
			(at 2.4765 1.249934)
			(size 1.0668 0.3048)
			(layers "F.Cu" "F.Mask" "F.Paste")
			(net "MB3_CM_SENSE_N")
		)
		(pad "27" smd rect
			(at 2.4765 0.750062)
			(size 1.0668 0.3048)
			(layers "F.Cu" "F.Mask" "F.Paste")
			(net "MB3_HS_SENSE_N")
		)
		(pad "28" smd rect
			(at 2.4765 0.249936)
			(size 1.0668 0.3048)
			(layers "F.Cu" "F.Mask" "F.Paste")
			(net "MB3_HS_SENSE_P")
		)
		(pad "29" smd rect
			(at 2.4765 -0.249936)
			(size 1.0668 0.3048)
			(layers "F.Cu" "F.Mask" "F.Paste")
			(net "MB3_CM_SENSE_P")
		)
		(pad "30" smd rect
			(at 2.4765 -0.750062)
			(size 1.0668 0.3048)
			(layers "F.Cu" "F.Mask" "F.Paste")
			(net "MB3_P12V_HS")
		)
		(pad "31" smd rect
			(at 2.4765 -1.249934)
			(size 1.0668 0.3048)
			(layers "F.Cu" "F.Mask" "F.Paste")
			(net "MB3_CM_UV_R")
		)
		(pad "32" smd rect
			(at 2.5527 -1.75006)
			(size 0.9144 0.3048)
			(layers "F.Cu" "F.Mask" "F.Paste")
			(net "MB3_CM_OV_R")
		)
		(pad "33" smd rect
			(at 0 0)
			(size 3.4544 3.4544)
			(layers "F.Cu" "F.Mask" "F.Paste")
			(net "AGND_CURRENT_DPB")
		)
	)
	(footprint ""
		(layer "F.Cu")
		(at 77.942948 -53.482494 -90)
		(property "Reference" "R743"
			(at 0 0 270)
			(layer "F.SilkS")
			(hide yes)
			(effects
				(font
					(size 1.27 1.27)
				)
			)
		)
		(property "Value" "300KR2F-GP"
			(at 0.064008 -3.993896 270)
			(unlocked yes)
			(layer "F.Fab")
			(hide yes)
			(effects
				(font
					(size 1.016 1.016)
					(thickness 0.1524)
				)
			)
		)
		(property "Device Type" "R402H16"
			(at 0.064008 -5.517896 270)
			(unlocked yes)
			(layer "F.Fab")
			(hide yes)
			(effects
				(font
					(size 1.016 1.016)
					(thickness 0.1524)
				)
			)
		)
		(duplicate_pad_numbers_are_jumpers no)
		(fp_line
			(start -0.508 -0.9398)
			(end -0.508 0.9398)
			(stroke
				(width 0.1524)
				(type default)
			)
			(layer "F.SilkS")
		)
		(fp_line
			(start 0.508 -0.9398)
			(end -0.508 -0.9398)
			(stroke
				(width 0.1524)
				(type default)
			)
			(layer "F.SilkS")
		)
		(fp_rect
			(start -0.508 0.9398)
			(end 0.508 -0.9398)
			(stroke
				(width 0)
				(type default)
			)
			(fill no)
			(layer "F.CrtYd")
		)
		(fp_rect
			(start -0.508 0.9398)
			(end 0.508 -0.9398)
			(stroke
				(width 0)
				(type default)
			)
			(fill no)
			(layer "F.Fab")
		)
		(pad "1" smd custom
			(at 0 -0.4445 270)
			(size 0.1397 0.1397)
			(layers "F.Cu" "F.Mask" "F.Paste")
			(net "SW_HDD_N26")
			(options
				(clearance outline)
				(anchor circle)
			)
			(primitives
				(gr_poly
					(pts
						(arc
							(start -0.1778 -0.2794)
							(mid -0.249642 -0.249642)
							(end -0.2794 -0.1778)
						)
						(arc
							(start -0.2794 0.1778)
							(mid -0.249642 0.249642)
							(end -0.1778 0.2794)
						)
						(arc
							(start 0.1778 0.2794)
							(mid 0.249642 0.249642)
							(end 0.2794 0.1778)
						)
						(arc
							(start 0.2794 -0.1778)
							(mid 0.249642 -0.249642)
							(end 0.1778 -0.2794)
						)
					)
					(width 0)
					(fill yes)
				)
			)
		)
		(pad "2" smd custom
			(at 0 0.4445 270)
			(size 0.1397 0.1397)
			(layers "F.Cu" "F.Mask" "F.Paste")
			(net "P12V_A")
			(options
				(clearance outline)
				(anchor circle)
			)
			(primitives
				(gr_poly
					(pts
						(arc
							(start -0.1778 -0.2794)
							(mid -0.249642 -0.249642)
							(end -0.2794 -0.1778)
						)
						(arc
							(start -0.2794 0.1778)
							(mid -0.249642 0.249642)
							(end -0.1778 0.2794)
						)
						(arc
							(start 0.1778 0.2794)
							(mid 0.249642 0.249642)
							(end 0.2794 0.1778)
						)
						(arc
							(start 0.2794 -0.1778)
							(mid 0.249642 -0.249642)
							(end 0.1778 -0.2794)
						)
					)
					(width 0)
					(fill yes)
				)
			)
		)
	)
	(footprint ""
		(layer "F.Cu")
		(at 364.0328 -143.4084)
		(property "Reference" "C555"
			(at 0 0 0)
			(layer "F.SilkS")
			(hide yes)
			(effects
				(font
					(size 1.27 1.27)
				)
			)
		)
		(property "Value" "SC1KP50V2KX-1GP"
			(at 1.1811 -2.7051 0)
			(unlocked yes)
			(layer "F.Fab")
			(hide yes)
			(effects
				(font
					(size 1.016 1.016)
					(thickness 0.1524)
				)
			)
		)
		(property "Device Type" "C402H22"
			(at 1.1811 -4.2291 0)
			(unlocked yes)
			(layer "F.Fab")
			(hide yes)
			(effects
				(font
					(size 1.016 1.016)
					(thickness 0.1524)
				)
			)
		)
		(duplicate_pad_numbers_are_jumpers no)
		(fp_rect
			(start -0.4318 0.9525)
			(end 0.4318 -0.9525)
			(stroke
				(width 0)
				(type default)
			)
			(fill no)
			(layer "F.CrtYd")
		)
		(fp_rect
			(start -0.4318 0.9525)
			(end 0.4318 -0.9525)
			(stroke
				(width 0)
				(type default)
			)
			(fill no)
			(layer "F.Fab")
		)
		(pad "1" smd custom
			(at 0 -0.4445)
			(size 0.1524 0.1524)
			(layers "F.Cu" "F.Mask" "F.Paste")
			(net "MB1_TEMP_B")
			(options
				(clearance outline)
				(anchor circle)
			)
			(primitives
				(gr_poly
					(pts
						(arc
							(start 0.3048 -0.2032)
							(mid 0.275042 -0.275042)
							(end 0.2032 -0.3048)
						)
						(arc
							(start -0.2032 -0.3048)
							(mid -0.275042 -0.275042)
							(end -0.3048 -0.2032)
						)
						(arc
							(start -0.3048 0.2032)
							(mid -0.275042 0.275042)
							(end -0.2032 0.3048)
						)
						(arc
							(start 0.2032 0.3048)
							(mid 0.275042 0.275042)
							(end 0.3048 0.2032)
						)
					)
					(width 0)
					(fill yes)
				)
			)
		)
		(pad "2" smd custom
			(at 0 0.4445)
			(size 0.1524 0.1524)
			(layers "F.Cu" "F.Mask" "F.Paste")
			(net "MB1_TEMP_E")
			(options
				(clearance outline)
				(anchor circle)
			)
			(primitives
				(gr_poly
					(pts
						(arc
							(start 0.3048 -0.2032)
							(mid 0.275042 -0.275042)
							(end 0.2032 -0.3048)
						)
						(arc
							(start -0.2032 -0.3048)
							(mid -0.275042 -0.275042)
							(end -0.3048 -0.2032)
						)
						(arc
							(start -0.3048 0.2032)
							(mid -0.275042 0.275042)
							(end -0.2032 0.3048)
						)
						(arc
							(start 0.2032 0.3048)
							(mid 0.275042 0.275042)
							(end 0.3048 0.2032)
						)
					)
					(width 0)
					(fill yes)
				)
			)
		)
	)
	(footprint ""
		(layer "F.Cu")
		(at 374.892062 -294.392858 180)
		(property "Reference" "R297"
			(at 0 0 180)
			(layer "F.SilkS")
			(hide yes)
			(effects
				(font
					(size 1.27 1.27)
				)
			)
		)
		(property "Value" "130R3F-GP"
			(at -0.0254 -2.5146 180)
			(unlocked yes)
			(layer "F.Fab")
			(hide yes)
			(effects
				(font
					(size 1.016 1.016)
					(thickness 0.1524)
				)
			)
		)
		(property "Device Type" "R603H22"
			(at -0.0254 -4.0386 180)
			(unlocked yes)
			(layer "F.Fab")
			(hide yes)
			(effects
				(font
					(size 1.016 1.016)
					(thickness 0.1524)
				)
			)
		)
		(duplicate_pad_numbers_are_jumpers no)
		(fp_line
			(start 0.2032 0)
			(end 0.4826 0)
			(stroke
				(width 0.2032)
				(type default)
			)
			(layer "F.SilkS")
		)
		(fp_line
			(start -0.4826 0)
			(end -0.2032 0)
			(stroke
				(width 0.2032)
				(type default)
			)
			(layer "F.SilkS")
		)
		(fp_rect
			(start -0.5842 1.3335)
			(end 0.5842 -1.3335)
			(stroke
				(width 0)
				(type default)
			)
			(fill no)
			(layer "F.CrtYd")
		)
		(fp_rect
			(start -0.5842 1.3335)
			(end 0.5842 -1.3335)
			(stroke
				(width 0)
				(type default)
			)
			(fill no)
			(layer "F.Fab")
		)
		(pad "1" smd custom
			(at 0 -0.762 180)
			(size 0.2159 0.2159)
			(layers "F.Cu" "F.Mask" "F.Paste")
			(net "P5V_B")
			(options
				(clearance outline)
				(anchor circle)
			)
			(primitives
				(gr_poly
					(pts
						(arc
							(start -0.3302 -0.4318)
							(mid -0.402042 -0.402042)
							(end -0.4318 -0.3302)
						)
						(arc
							(start -0.4318 0.3302)
							(mid -0.402042 0.402042)
							(end -0.3302 0.4318)
						)
						(arc
							(start 0.3302 0.4318)
							(mid 0.402042 0.402042)
							(end 0.4318 0.3302)
						)
						(arc
							(start 0.4318 -0.3302)
							(mid 0.402042 -0.402042)
							(end 0.3302 -0.4318)
						)
					)
					(width 0)
					(fill yes)
				)
			)
		)
		(pad "2" smd custom
			(at 0 0.762 180)
			(size 0.2159 0.2159)
			(layers "F.Cu" "F.Mask" "F.Paste")
			(net "FLT_HDD32")
			(options
				(clearance outline)
				(anchor circle)
			)
			(primitives
				(gr_poly
					(pts
						(arc
							(start -0.3302 -0.4318)
							(mid -0.402042 -0.402042)
							(end -0.4318 -0.3302)
						)
						(arc
							(start -0.4318 0.3302)
							(mid -0.402042 0.402042)
							(end -0.3302 0.4318)
						)
						(arc
							(start 0.3302 0.4318)
							(mid 0.402042 0.402042)
							(end 0.4318 0.3302)
						)
						(arc
							(start 0.4318 -0.3302)
							(mid 0.402042 -0.402042)
							(end 0.3302 -0.4318)
						)
					)
					(width 0)
					(fill yes)
				)
			)
		)
	)
	(footprint ""
		(layer "F.Cu")
		(at 109.492796 -169.523918 90)
		(property "Reference" "C244"
			(at 0 0 90)
			(layer "F.SilkS")
			(hide yes)
			(effects
				(font
					(size 1.27 1.27)
				)
			)
		)
		(property "Value" "SCD033U25V2KX-GP"
			(at 1.1811 -2.7051 90)
			(unlocked yes)
			(layer "F.Fab")
			(hide yes)
			(effects
				(font
					(size 1.016 1.016)
					(thickness 0.1524)
				)
			)
		)
		(property "Device Type" "C402H22"
			(at 1.1811 -4.2291 90)
			(unlocked yes)
			(layer "F.Fab")
			(hide yes)
			(effects
				(font
					(size 1.016 1.016)
					(thickness 0.1524)
				)
			)
		)
		(duplicate_pad_numbers_are_jumpers no)
		(fp_rect
			(start -0.4318 0.9525)
			(end 0.4318 -0.9525)
			(stroke
				(width 0)
				(type default)
			)
			(fill no)
			(layer "F.CrtYd")
		)
		(fp_rect
			(start -0.4318 0.9525)
			(end 0.4318 -0.9525)
			(stroke
				(width 0)
				(type default)
			)
			(fill no)
			(layer "F.Fab")
		)
		(pad "1" smd custom
			(at 0 -0.4445 90)
			(size 0.1524 0.1524)
			(layers "F.Cu" "F.Mask" "F.Paste")
			(net "P12V_A")
			(options
				(clearance outline)
				(anchor circle)
			)
			(primitives
				(gr_poly
					(pts
						(arc
							(start 0.3048 -0.2032)
							(mid 0.275042 -0.275042)
							(end 0.2032 -0.3048)
						)
						(arc
							(start -0.2032 -0.3048)
							(mid -0.275042 -0.275042)
							(end -0.3048 -0.2032)
						)
						(arc
							(start -0.3048 0.2032)
							(mid -0.275042 0.275042)
							(end -0.2032 0.3048)
						)
						(arc
							(start 0.2032 0.3048)
							(mid 0.275042 0.275042)
							(end 0.3048 0.2032)
						)
					)
					(width 0)
					(fill yes)
				)
			)
		)
		(pad "2" smd custom
			(at 0 0.4445 90)
			(size 0.1524 0.1524)
			(layers "F.Cu" "F.Mask" "F.Paste")
			(net "SW_HDD_N15")
			(options
				(clearance outline)
				(anchor circle)
			)
			(primitives
				(gr_poly
					(pts
						(arc
							(start 0.3048 -0.2032)
							(mid 0.275042 -0.275042)
							(end 0.2032 -0.3048)
						)
						(arc
							(start -0.2032 -0.3048)
							(mid -0.275042 -0.275042)
							(end -0.3048 -0.2032)
						)
						(arc
							(start -0.3048 0.2032)
							(mid -0.275042 0.275042)
							(end -0.2032 0.3048)
						)
						(arc
							(start 0.2032 0.3048)
							(mid 0.275042 0.275042)
							(end 0.3048 0.2032)
						)
					)
					(width 0)
					(fill yes)
				)
			)
		)
	)
	(footprint ""
		(layer "F.Cu")
		(at 302.8442 -67.784472 180)
		(property "Reference" "R356"
			(at 0 0 180)
			(layer "F.SilkS")
			(hide yes)
			(effects
				(font
					(size 1.27 1.27)
				)
			)
		)
		(property "Value" "0R2J-2-GP"
			(at 0.064008 -3.993896 180)
			(unlocked yes)
			(layer "F.Fab")
			(hide yes)
			(effects
				(font
					(size 1.016 1.016)
					(thickness 0.1524)
				)
			)
		)
		(property "Device Type" "R402H16"
			(at 0.064008 -5.517896 180)
			(unlocked yes)
			(layer "F.Fab")
			(hide yes)
			(effects
				(font
					(size 1.016 1.016)
					(thickness 0.1524)
				)
			)
		)
		(duplicate_pad_numbers_are_jumpers no)
		(fp_line
			(start 0.508 -0.9398)
			(end -0.508 -0.9398)
			(stroke
				(width 0.1524)
				(type default)
			)
			(layer "F.SilkS")
		)
		(fp_line
			(start -0.508 -0.9398)
			(end -0.508 0.9398)
			(stroke
				(width 0.1524)
				(type default)
			)
			(layer "F.SilkS")
		)
		(fp_rect
			(start -0.508 0.9398)
			(end 0.508 -0.9398)
			(stroke
				(width 0)
				(type default)
			)
			(fill no)
			(layer "F.CrtYd")
		)
		(fp_rect
			(start -0.508 0.9398)
			(end 0.508 -0.9398)
			(stroke
				(width 0)
				(type default)
			)
			(fill no)
			(layer "F.Fab")
		)
		(pad "1" smd custom
			(at 0 -0.4445 180)
			(size 0.1397 0.1397)
			(layers "F.Cu" "F.Mask" "F.Paste")
			(net "I2C_BMC_B_COMP_B_SCL")
			(options
				(clearance outline)
				(anchor circle)
			)
			(primitives
				(gr_poly
					(pts
						(arc
							(start -0.1778 -0.2794)
							(mid -0.249642 -0.249642)
							(end -0.2794 -0.1778)
						)
						(arc
							(start -0.2794 0.1778)
							(mid -0.249642 0.249642)
							(end -0.1778 0.2794)
						)
						(arc
							(start 0.1778 0.2794)
							(mid 0.249642 0.249642)
							(end 0.2794 0.1778)
						)
						(arc
							(start 0.2794 -0.1778)
							(mid 0.249642 -0.249642)
							(end 0.1778 -0.2794)
						)
					)
					(width 0)
					(fill yes)
				)
			)
		)
		(pad "2" smd custom
			(at 0 0.4445 180)
			(size 0.1397 0.1397)
			(layers "F.Cu" "F.Mask" "F.Paste")
			(net "I2C_BMC_B_COMP_B_SCL_R")
			(options
				(clearance outline)
				(anchor circle)
			)
			(primitives
				(gr_poly
					(pts
						(arc
							(start -0.1778 -0.2794)
							(mid -0.249642 -0.249642)
							(end -0.2794 -0.1778)
						)
						(arc
							(start -0.2794 0.1778)
							(mid -0.249642 0.249642)
							(end -0.1778 0.2794)
						)
						(arc
							(start 0.1778 0.2794)
							(mid 0.249642 0.249642)
							(end 0.2794 0.1778)
						)
						(arc
							(start 0.2794 -0.1778)
							(mid 0.249642 -0.249642)
							(end 0.1778 -0.2794)
						)
					)
					(width 0)
					(fill yes)
				)
			)
		)
	)
	(footprint ""
		(layer "F.Cu")
		(at 156.92374 -142.893796 -90)
		(property "Reference" "R1063"
			(at 0 0 270)
			(layer "F.SilkS")
			(hide yes)
			(effects
				(font
					(size 1.27 1.27)
				)
			)
		)
		(property "Value" "49K9R2F-L-GP"
			(at 0.064008 -3.993896 270)
			(unlocked yes)
			(layer "F.Fab")
			(hide yes)
			(effects
				(font
					(size 1.016 1.016)
					(thickness 0.1524)
				)
			)
		)
		(property "Device Type" "R402H16"
			(at 0.064008 -5.517896 270)
			(unlocked yes)
			(layer "F.Fab")
			(hide yes)
			(effects
				(font
					(size 1.016 1.016)
					(thickness 0.1524)
				)
			)
		)
		(duplicate_pad_numbers_are_jumpers no)
		(fp_line
			(start -0.508 -0.9398)
			(end -0.508 0.9398)
			(stroke
				(width 0.1524)
				(type default)
			)
			(layer "F.SilkS")
		)
		(fp_line
			(start 0.508 -0.9398)
			(end -0.508 -0.9398)
			(stroke
				(width 0.1524)
				(type default)
			)
			(layer "F.SilkS")
		)
		(fp_rect
			(start -0.508 0.9398)
			(end 0.508 -0.9398)
			(stroke
				(width 0)
				(type default)
			)
			(fill no)
			(layer "F.CrtYd")
		)
		(fp_rect
			(start -0.508 0.9398)
			(end 0.508 -0.9398)
			(stroke
				(width 0)
				(type default)
			)
			(fill no)
			(layer "F.Fab")
		)
		(pad "1" smd custom
			(at 0 -0.4445 270)
			(size 0.1397 0.1397)
			(layers "F.Cu" "F.Mask" "F.Paste")
			(net "P12V_A")
			(options
				(clearance outline)
				(anchor circle)
			)
			(primitives
				(gr_poly
					(pts
						(arc
							(start -0.1778 -0.2794)
							(mid -0.249642 -0.249642)
							(end -0.2794 -0.1778)
						)
						(arc
							(start -0.2794 0.1778)
							(mid -0.249642 0.249642)
							(end -0.1778 0.2794)
						)
						(arc
							(start 0.1778 0.2794)
							(mid 0.249642 0.249642)
							(end 0.2794 0.1778)
						)
						(arc
							(start 0.2794 -0.1778)
							(mid 0.249642 -0.249642)
							(end 0.1778 -0.2794)
						)
					)
					(width 0)
					(fill yes)
				)
			)
		)
		(pad "2" smd custom
			(at 0 0.4445 270)
			(size 0.1397 0.1397)
			(layers "F.Cu" "F.Mask" "F.Paste")
			(net "MB0_CM_OV_R")
			(options
				(clearance outline)
				(anchor circle)
			)
			(primitives
				(gr_poly
					(pts
						(arc
							(start -0.1778 -0.2794)
							(mid -0.249642 -0.249642)
							(end -0.2794 -0.1778)
						)
						(arc
							(start -0.2794 0.1778)
							(mid -0.249642 0.249642)
							(end -0.1778 0.2794)
						)
						(arc
							(start 0.1778 0.2794)
							(mid 0.249642 0.249642)
							(end 0.2794 0.1778)
						)
						(arc
							(start 0.2794 -0.1778)
							(mid 0.249642 -0.249642)
							(end 0.1778 -0.2794)
						)
					)
					(width 0)
					(fill yes)
				)
			)
		)
	)
	(footprint ""
		(layer "F.Cu")
		(at 361.369102 -189.335918 180)
		(property "Reference" "C294"
			(at 0 0 180)
			(layer "F.SilkS")
			(hide yes)
			(effects
				(font
					(size 1.27 1.27)
				)
			)
		)
		(property "Value" "SC1U25V3KX-GP"
			(at 0 -2.8194 180)
			(unlocked yes)
			(layer "F.Fab")
			(hide yes)
			(effects
				(font
					(size 1.016 1.016)
					(thickness 0.1524)
				)
			)
		)
		(property "Device Type" "C603H36"
			(at 0 -4.3434 180)
			(unlocked yes)
			(layer "F.Fab")
			(hide yes)
			(effects
				(font
					(size 1.016 1.016)
					(thickness 0.1524)
				)
			)
		)
		(duplicate_pad_numbers_are_jumpers no)
		(fp_line
			(start 0.508 0)
			(end -0.508 0)
			(stroke
				(width 0.2032)
				(type default)
			)
			(layer "F.SilkS")
		)
		(fp_rect
			(start -0.5842 1.3335)
			(end 0.5842 -1.3335)
			(stroke
				(width 0)
				(type default)
			)
			(fill no)
			(layer "F.CrtYd")
		)
		(fp_rect
			(start -0.5842 1.3335)
			(end 0.5842 -1.3335)
			(stroke
				(width 0)
				(type default)
			)
			(fill no)
			(layer "F.Fab")
		)
		(pad "1" smd custom
			(at 0 -0.762 180)
			(size 0.2159 0.2159)
			(layers "F.Cu" "F.Mask" "F.Paste")
			(net "P12V_HDD19")
			(options
				(clearance outline)
				(anchor circle)
			)
			(primitives
				(gr_poly
					(pts
						(arc
							(start -0.3302 -0.4318)
							(mid -0.402042 -0.402042)
							(end -0.4318 -0.3302)
						)
						(arc
							(start -0.4318 0.3302)
							(mid -0.402042 0.402042)
							(end -0.3302 0.4318)
						)
						(arc
							(start 0.3302 0.4318)
							(mid 0.402042 0.402042)
							(end 0.4318 0.3302)
						)
						(arc
							(start 0.4318 -0.3302)
							(mid 0.402042 -0.402042)
							(end 0.3302 -0.4318)
						)
					)
					(width 0)
					(fill yes)
				)
			)
		)
		(pad "2" smd custom
			(at 0 0.762 180)
			(size 0.2159 0.2159)
			(layers "F.Cu" "F.Mask" "F.Paste")
			(net "GND")
			(options
				(clearance outline)
				(anchor circle)
			)
			(primitives
				(gr_poly
					(pts
						(arc
							(start -0.3302 -0.4318)
							(mid -0.402042 -0.402042)
							(end -0.4318 -0.3302)
						)
						(arc
							(start -0.4318 0.3302)
							(mid -0.402042 0.402042)
							(end -0.3302 0.4318)
						)
						(arc
							(start 0.3302 0.4318)
							(mid 0.402042 0.402042)
							(end 0.4318 0.3302)
						)
						(arc
							(start 0.4318 -0.3302)
							(mid 0.402042 -0.402042)
							(end 0.3302 -0.4318)
						)
					)
					(width 0)
					(fill yes)
				)
			)
		)
	)
	(footprint ""
		(layer "F.Cu")
		(at 317.881 -180.064918 -90)
		(property "Reference" "R548"
			(at 0 0 270)
			(layer "F.SilkS")
			(hide yes)
			(effects
				(font
					(size 1.27 1.27)
				)
			)
		)
		(property "Value" "220R3F-1-GP"
			(at -0.0254 -2.5146 270)
			(unlocked yes)
			(layer "F.Fab")
			(hide yes)
			(effects
				(font
					(size 1.016 1.016)
					(thickness 0.1524)
				)
			)
		)
		(property "Device Type" "R603H22"
			(at -0.0254 -4.0386 270)
			(unlocked yes)
			(layer "F.Fab")
			(hide yes)
			(effects
				(font
					(size 1.016 1.016)
					(thickness 0.1524)
				)
			)
		)
		(duplicate_pad_numbers_are_jumpers no)
		(fp_line
			(start -0.4826 0)
			(end -0.2032 0)
			(stroke
				(width 0.2032)
				(type default)
			)
			(layer "F.SilkS")
		)
		(fp_line
			(start 0.2032 0)
			(end 0.4826 0)
			(stroke
				(width 0.2032)
				(type default)
			)
			(layer "F.SilkS")
		)
		(fp_rect
			(start -0.5842 1.3335)
			(end 0.5842 -1.3335)
			(stroke
				(width 0)
				(type default)
			)
			(fill no)
			(layer "F.CrtYd")
		)
		(fp_rect
			(start -0.5842 1.3335)
			(end 0.5842 -1.3335)
			(stroke
				(width 0)
				(type default)
			)
			(fill no)
			(layer "F.Fab")
		)
		(pad "1" smd custom
			(at 0 -0.762 270)
			(size 0.2159 0.2159)
			(layers "F.Cu" "F.Mask" "F.Paste")
			(net "HDD_PRSNT_18")
			(options
				(clearance outline)
				(anchor circle)
			)
			(primitives
				(gr_poly
					(pts
						(arc
							(start -0.3302 -0.4318)
							(mid -0.402042 -0.402042)
							(end -0.4318 -0.3302)
						)
						(arc
							(start -0.4318 0.3302)
							(mid -0.402042 0.402042)
							(end -0.3302 0.4318)
						)
						(arc
							(start 0.3302 0.4318)
							(mid 0.402042 0.402042)
							(end 0.4318 0.3302)
						)
						(arc
							(start 0.4318 -0.3302)
							(mid 0.402042 -0.402042)
							(end 0.3302 -0.4318)
						)
					)
					(width 0)
					(fill yes)
				)
			)
		)
		(pad "2" smd custom
			(at 0 0.762 270)
			(size 0.2159 0.2159)
			(layers "F.Cu" "F.Mask" "F.Paste")
			(net "DRIVE_A_18_INS")
			(options
				(clearance outline)
				(anchor circle)
			)
			(primitives
				(gr_poly
					(pts
						(arc
							(start -0.3302 -0.4318)
							(mid -0.402042 -0.402042)
							(end -0.4318 -0.3302)
						)
						(arc
							(start -0.4318 0.3302)
							(mid -0.402042 0.402042)
							(end -0.3302 0.4318)
						)
						(arc
							(start 0.3302 0.4318)
							(mid 0.402042 0.402042)
							(end 0.4318 0.3302)
						)
						(arc
							(start 0.4318 -0.3302)
							(mid 0.402042 -0.402042)
							(end 0.3302 -0.4318)
						)
					)
					(width 0)
					(fill yes)
				)
			)
		)
	)
	(footprint ""
		(layer "F.Cu")
		(at 467.618318 -41.52265 180)
		(property "Reference" "R945"
			(at 0 0 180)
			(layer "F.SilkS")
			(hide yes)
			(effects
				(font
					(size 1.27 1.27)
				)
			)
		)
		(property "Value" "0R2J-2-GP"
			(at 0.064008 -3.993896 180)
			(unlocked yes)
			(layer "F.Fab")
			(hide yes)
			(effects
				(font
					(size 1.016 1.016)
					(thickness 0.1524)
				)
			)
		)
		(property "Device Type" "R402H16"
			(at 0.064008 -5.517896 180)
			(unlocked yes)
			(layer "F.Fab")
			(hide yes)
			(effects
				(font
					(size 1.016 1.016)
					(thickness 0.1524)
				)
			)
		)
		(duplicate_pad_numbers_are_jumpers no)
		(fp_line
			(start 0.508 -0.9398)
			(end -0.508 -0.9398)
			(stroke
				(width 0.1524)
				(type default)
			)
			(layer "F.SilkS")
		)
		(fp_line
			(start -0.508 -0.9398)
			(end -0.508 0.9398)
			(stroke
				(width 0.1524)
				(type default)
			)
			(layer "F.SilkS")
		)
		(fp_rect
			(start -0.508 0.9398)
			(end 0.508 -0.9398)
			(stroke
				(width 0)
				(type default)
			)
			(fill no)
			(layer "F.CrtYd")
		)
		(fp_rect
			(start -0.508 0.9398)
			(end 0.508 -0.9398)
			(stroke
				(width 0)
				(type default)
			)
			(fill no)
			(layer "F.Fab")
		)
		(pad "1" smd custom
			(at 0 -0.4445 180)
			(size 0.1397 0.1397)
			(layers "F.Cu" "F.Mask" "F.Paste")
			(net "DRIVE_A_35_PWR")
			(options
				(clearance outline)
				(anchor circle)
			)
			(primitives
				(gr_poly
					(pts
						(arc
							(start -0.1778 -0.2794)
							(mid -0.249642 -0.249642)
							(end -0.2794 -0.1778)
						)
						(arc
							(start -0.2794 0.1778)
							(mid -0.249642 0.249642)
							(end -0.1778 0.2794)
						)
						(arc
							(start 0.1778 0.2794)
							(mid 0.249642 0.249642)
							(end 0.2794 0.1778)
						)
						(arc
							(start 0.2794 -0.1778)
							(mid 0.249642 -0.249642)
							(end 0.1778 -0.2794)
						)
					)
					(width 0)
					(fill yes)
				)
			)
		)
		(pad "2" smd custom
			(at 0 0.4445 180)
			(size 0.1397 0.1397)
			(layers "F.Cu" "F.Mask" "F.Paste")
			(net "SW_PWR_R_HDD35")
			(options
				(clearance outline)
				(anchor circle)
			)
			(primitives
				(gr_poly
					(pts
						(arc
							(start -0.1778 -0.2794)
							(mid -0.249642 -0.249642)
							(end -0.2794 -0.1778)
						)
						(arc
							(start -0.2794 0.1778)
							(mid -0.249642 0.249642)
							(end -0.1778 0.2794)
						)
						(arc
							(start 0.1778 0.2794)
							(mid 0.249642 0.249642)
							(end 0.2794 0.1778)
						)
						(arc
							(start 0.2794 -0.1778)
							(mid 0.249642 -0.249642)
							(end 0.1778 -0.2794)
						)
					)
					(width 0)
					(fill yes)
				)
			)
		)
	)
	(footprint ""
		(layer "F.Cu")
		(at 244.8306 -242.6716)
		(property "Reference" "R77"
			(at 0 0 0)
			(layer "F.SilkS")
			(hide yes)
			(effects
				(font
					(size 1.27 1.27)
				)
			)
		)
		(property "Value" "4K7R2F-GP"
			(at 0.064008 -3.993896 0)
			(unlocked yes)
			(layer "F.Fab")
			(hide yes)
			(effects
				(font
					(size 1.016 1.016)
					(thickness 0.1524)
				)
			)
		)
		(property "Device Type" "R402H16"
			(at 0.064008 -5.517896 0)
			(unlocked yes)
			(layer "F.Fab")
			(hide yes)
			(effects
				(font
					(size 1.016 1.016)
					(thickness 0.1524)
				)
			)
		)
		(duplicate_pad_numbers_are_jumpers no)
		(fp_line
			(start -0.508 -0.9398)
			(end -0.508 0.9398)
			(stroke
				(width 0.1524)
				(type default)
			)
			(layer "F.SilkS")
		)
		(fp_line
			(start 0.508 -0.9398)
			(end -0.508 -0.9398)
			(stroke
				(width 0.1524)
				(type default)
			)
			(layer "F.SilkS")
		)
		(fp_rect
			(start -0.508 0.9398)
			(end 0.508 -0.9398)
			(stroke
				(width 0)
				(type default)
			)
			(fill no)
			(layer "F.CrtYd")
		)
		(fp_rect
			(start -0.508 0.9398)
			(end 0.508 -0.9398)
			(stroke
				(width 0)
				(type default)
			)
			(fill no)
			(layer "F.Fab")
		)
		(pad "1" smd custom
			(at 0 -0.4445)
			(size 0.1397 0.1397)
			(layers "F.Cu" "F.Mask" "F.Paste")
			(net "P3V3_STBY_A")
			(options
				(clearance outline)
				(anchor circle)
			)
			(primitives
				(gr_poly
					(pts
						(arc
							(start -0.1778 -0.2794)
							(mid -0.249642 -0.249642)
							(end -0.2794 -0.1778)
						)
						(arc
							(start -0.2794 0.1778)
							(mid -0.249642 0.249642)
							(end -0.1778 0.2794)
						)
						(arc
							(start 0.1778 0.2794)
							(mid 0.249642 0.249642)
							(end 0.2794 0.1778)
						)
						(arc
							(start 0.2794 -0.1778)
							(mid 0.249642 -0.249642)
							(end 0.1778 -0.2794)
						)
					)
					(width 0)
					(fill yes)
				)
			)
		)
		(pad "2" smd custom
			(at 0 0.4445)
			(size 0.1397 0.1397)
			(layers "F.Cu" "F.Mask" "F.Paste")
			(net "IO_EXP2_A0")
			(options
				(clearance outline)
				(anchor circle)
			)
			(primitives
				(gr_poly
					(pts
						(arc
							(start -0.1778 -0.2794)
							(mid -0.249642 -0.249642)
							(end -0.2794 -0.1778)
						)
						(arc
							(start -0.2794 0.1778)
							(mid -0.249642 0.249642)
							(end -0.1778 0.2794)
						)
						(arc
							(start 0.1778 0.2794)
							(mid 0.249642 0.249642)
							(end 0.2794 0.1778)
						)
						(arc
							(start 0.2794 -0.1778)
							(mid 0.249642 -0.249642)
							(end 0.1778 -0.2794)
						)
					)
					(width 0)
					(fill yes)
				)
			)
		)
	)
	(footprint ""
		(layer "F.Cu")
		(at 444.4619 -292.169342 90)
		(property "Reference" "R360"
			(at 0 0 90)
			(layer "F.SilkS")
			(hide yes)
			(effects
				(font
					(size 1.27 1.27)
				)
			)
		)
		(property "Value" "10KR2F-2-GP"
			(at 0.064008 -3.993896 90)
			(unlocked yes)
			(layer "F.Fab")
			(hide yes)
			(effects
				(font
					(size 1.016 1.016)
					(thickness 0.1524)
				)
			)
		)
		(property "Device Type" "R402H16"
			(at 0.064008 -5.517896 90)
			(unlocked yes)
			(layer "F.Fab")
			(hide yes)
			(effects
				(font
					(size 1.016 1.016)
					(thickness 0.1524)
				)
			)
		)
		(duplicate_pad_numbers_are_jumpers no)
		(fp_line
			(start 0.508 -0.9398)
			(end -0.508 -0.9398)
			(stroke
				(width 0.1524)
				(type default)
			)
			(layer "F.SilkS")
		)
		(fp_line
			(start -0.508 -0.9398)
			(end -0.508 0.9398)
			(stroke
				(width 0.1524)
				(type default)
			)
			(layer "F.SilkS")
		)
		(fp_rect
			(start -0.508 0.9398)
			(end 0.508 -0.9398)
			(stroke
				(width 0)
				(type default)
			)
			(fill no)
			(layer "F.CrtYd")
		)
		(fp_rect
			(start -0.508 0.9398)
			(end 0.508 -0.9398)
			(stroke
				(width 0)
				(type default)
			)
			(fill no)
			(layer "F.Fab")
		)
		(pad "1" smd custom
			(at 0 -0.4445 90)
			(size 0.1397 0.1397)
			(layers "F.Cu" "F.Mask" "F.Paste")
			(net "P3V3_STBY_A")
			(options
				(clearance outline)
				(anchor circle)
			)
			(primitives
				(gr_poly
					(pts
						(arc
							(start -0.1778 -0.2794)
							(mid -0.249642 -0.249642)
							(end -0.2794 -0.1778)
						)
						(arc
							(start -0.2794 0.1778)
							(mid -0.249642 0.249642)
							(end -0.1778 0.2794)
						)
						(arc
							(start 0.1778 0.2794)
							(mid 0.249642 0.249642)
							(end 0.2794 0.1778)
						)
						(arc
							(start 0.2794 -0.1778)
							(mid 0.249642 -0.249642)
							(end 0.1778 -0.2794)
						)
					)
					(width 0)
					(fill yes)
				)
			)
		)
		(pad "2" smd custom
			(at 0 0.4445 90)
			(size 0.1397 0.1397)
			(layers "F.Cu" "F.Mask" "F.Paste")
			(net "HDD_PRSNT_10")
			(options
				(clearance outline)
				(anchor circle)
			)
			(primitives
				(gr_poly
					(pts
						(arc
							(start -0.1778 -0.2794)
							(mid -0.249642 -0.249642)
							(end -0.2794 -0.1778)
						)
						(arc
							(start -0.2794 0.1778)
							(mid -0.249642 0.249642)
							(end -0.1778 0.2794)
						)
						(arc
							(start 0.1778 0.2794)
							(mid 0.249642 0.249642)
							(end 0.2794 0.1778)
						)
						(arc
							(start 0.2794 -0.1778)
							(mid 0.249642 -0.249642)
							(end 0.1778 -0.2794)
						)
					)
					(width 0)
					(fill yes)
				)
			)
		)
	)
	(footprint ""
		(layer "F.Cu")
		(at 441.964826 -242.25377)
		(property "Reference" "R266"
			(at 0 0 0)
			(layer "F.SilkS")
			(hide yes)
			(effects
				(font
					(size 1.27 1.27)
				)
			)
		)
		(property "Value" "91R3F-1-GP"
			(at -0.0254 -2.5146 0)
			(unlocked yes)
			(layer "F.Fab")
			(hide yes)
			(effects
				(font
					(size 1.016 1.016)
					(thickness 0.1524)
				)
			)
		)
		(property "Device Type" "R603H22"
			(at -0.0254 -4.0386 0)
			(unlocked yes)
			(layer "F.Fab")
			(hide yes)
			(effects
				(font
					(size 1.016 1.016)
					(thickness 0.1524)
				)
			)
		)
		(duplicate_pad_numbers_are_jumpers no)
		(fp_line
			(start -0.4826 0)
			(end -0.2032 0)
			(stroke
				(width 0.2032)
				(type default)
			)
			(layer "F.SilkS")
		)
		(fp_line
			(start 0.2032 0)
			(end 0.4826 0)
			(stroke
				(width 0.2032)
				(type default)
			)
			(layer "F.SilkS")
		)
		(fp_rect
			(start -0.5842 1.3335)
			(end 0.5842 -1.3335)
			(stroke
				(width 0)
				(type default)
			)
			(fill no)
			(layer "F.CrtYd")
		)
		(fp_rect
			(start -0.5842 1.3335)
			(end 0.5842 -1.3335)
			(stroke
				(width 0)
				(type default)
			)
			(fill no)
			(layer "F.Fab")
		)
		(pad "1" smd custom
			(at 0 -0.762)
			(size 0.2159 0.2159)
			(layers "F.Cu" "F.Mask" "F.Paste")
			(net "P5V_A_3")
			(options
				(clearance outline)
				(anchor circle)
			)
			(primitives
				(gr_poly
					(pts
						(arc
							(start -0.3302 -0.4318)
							(mid -0.402042 -0.402042)
							(end -0.4318 -0.3302)
						)
						(arc
							(start -0.4318 0.3302)
							(mid -0.402042 0.402042)
							(end -0.3302 0.4318)
						)
						(arc
							(start 0.3302 0.4318)
							(mid 0.402042 0.402042)
							(end 0.4318 0.3302)
						)
						(arc
							(start 0.4318 -0.3302)
							(mid 0.402042 -0.402042)
							(end 0.3302 -0.4318)
						)
					)
					(width 0)
					(fill yes)
				)
			)
		)
		(pad "2" smd custom
			(at 0 0.762)
			(size 0.2159 0.2159)
			(layers "F.Cu" "F.Mask" "F.Paste")
			(net "DRV_ACT_10")
			(options
				(clearance outline)
				(anchor circle)
			)
			(primitives
				(gr_poly
					(pts
						(arc
							(start -0.3302 -0.4318)
							(mid -0.402042 -0.402042)
							(end -0.4318 -0.3302)
						)
						(arc
							(start -0.4318 0.3302)
							(mid -0.402042 0.402042)
							(end -0.3302 0.4318)
						)
						(arc
							(start 0.3302 0.4318)
							(mid 0.402042 0.402042)
							(end 0.4318 0.3302)
						)
						(arc
							(start 0.4318 -0.3302)
							(mid 0.402042 -0.402042)
							(end 0.3302 -0.4318)
						)
					)
					(width 0)
					(fill yes)
				)
			)
		)
	)
	(footprint ""
		(layer "F.Cu")
		(at 130.828796 -65.064894 90)
		(property "Reference" "R755"
			(at 0 0 90)
			(layer "F.SilkS")
			(hide yes)
			(effects
				(font
					(size 1.27 1.27)
				)
			)
		)
		(property "Value" "220R3F-1-GP"
			(at -0.0254 -2.5146 90)
			(unlocked yes)
			(layer "F.Fab")
			(hide yes)
			(effects
				(font
					(size 1.016 1.016)
					(thickness 0.1524)
				)
			)
		)
		(property "Device Type" "R603H22"
			(at -0.0254 -4.0386 90)
			(unlocked yes)
			(layer "F.Fab")
			(hide yes)
			(effects
				(font
					(size 1.016 1.016)
					(thickness 0.1524)
				)
			)
		)
		(duplicate_pad_numbers_are_jumpers no)
		(fp_line
			(start 0.2032 0)
			(end 0.4826 0)
			(stroke
				(width 0.2032)
				(type default)
			)
			(layer "F.SilkS")
		)
		(fp_line
			(start -0.4826 0)
			(end -0.2032 0)
			(stroke
				(width 0.2032)
				(type default)
			)
			(layer "F.SilkS")
		)
		(fp_rect
			(start -0.5842 1.3335)
			(end 0.5842 -1.3335)
			(stroke
				(width 0)
				(type default)
			)
			(fill no)
			(layer "F.CrtYd")
		)
		(fp_rect
			(start -0.5842 1.3335)
			(end 0.5842 -1.3335)
			(stroke
				(width 0)
				(type default)
			)
			(fill no)
			(layer "F.Fab")
		)
		(pad "1" smd custom
			(at 0 -0.762 90)
			(size 0.2159 0.2159)
			(layers "F.Cu" "F.Mask" "F.Paste")
			(net "HDD_PRSNT_27")
			(options
				(clearance outline)
				(anchor circle)
			)
			(primitives
				(gr_poly
					(pts
						(arc
							(start -0.3302 -0.4318)
							(mid -0.402042 -0.402042)
							(end -0.4318 -0.3302)
						)
						(arc
							(start -0.4318 0.3302)
							(mid -0.402042 0.402042)
							(end -0.3302 0.4318)
						)
						(arc
							(start 0.3302 0.4318)
							(mid 0.402042 0.402042)
							(end 0.4318 0.3302)
						)
						(arc
							(start 0.4318 -0.3302)
							(mid 0.402042 -0.402042)
							(end 0.3302 -0.4318)
						)
					)
					(width 0)
					(fill yes)
				)
			)
		)
		(pad "2" smd custom
			(at 0 0.762 90)
			(size 0.2159 0.2159)
			(layers "F.Cu" "F.Mask" "F.Paste")
			(net "DRIVE_A_27_INS")
			(options
				(clearance outline)
				(anchor circle)
			)
			(primitives
				(gr_poly
					(pts
						(arc
							(start -0.3302 -0.4318)
							(mid -0.402042 -0.402042)
							(end -0.4318 -0.3302)
						)
						(arc
							(start -0.4318 0.3302)
							(mid -0.402042 0.402042)
							(end -0.3302 0.4318)
						)
						(arc
							(start 0.3302 0.4318)
							(mid 0.402042 0.402042)
							(end 0.4318 0.3302)
						)
						(arc
							(start 0.4318 -0.3302)
							(mid 0.402042 -0.402042)
							(end 0.3302 -0.4318)
						)
					)
					(width 0)
					(fill yes)
				)
			)
		)
	)
	(footprint ""
		(layer "F.Cu")
		(at 23.936198 -301.287942)
		(property "Reference" "C514"
			(at 0 0 0)
			(layer "F.SilkS")
			(hide yes)
			(effects
				(font
					(size 1.27 1.27)
				)
			)
		)
		(property "Value" "SC4D7U25V5KX-1-GP"
			(at -0.0762 -6.1214 0)
			(unlocked yes)
			(layer "F.Fab")
			(hide yes)
			(effects
				(font
					(size 1.016 1.016)
					(thickness 0.1524)
				)
			)
		)
		(property "Device Type" "C805H58"
			(at -0.0762 -8.1534 0)
			(unlocked yes)
			(layer "F.Fab")
			(hide yes)
			(effects
				(font
					(size 1.016 1.016)
					(thickness 0.1524)
				)
			)
		)
		(duplicate_pad_numbers_are_jumpers no)
		(fp_line
			(start 0.635 0)
			(end -0.635 0)
			(stroke
				(width 0.508)
				(type default)
			)
			(layer "F.SilkS")
		)
		(fp_rect
			(start -0.9652 1.778)
			(end 0.9652 -1.778)
			(stroke
				(width 0)
				(type default)
			)
			(fill no)
			(layer "F.CrtYd")
		)
		(fp_poly
			(pts
				(xy -0.9652 -1.778) (xy 0.9652 -1.778) (xy 0.9652 1.778) (xy -0.9652 1.778)
			)
			(stroke
				(width 0)
				(type default)
			)
			(fill no)
			(layer "F.Fab")
		)
		(pad "1" smd rect
			(at 0 -0.9652)
			(size 1.397 1.143)
			(layers "F.Cu" "F.Mask" "F.Paste")
			(net "P12V_HDD0")
		)
		(pad "2" smd rect
			(at 0 0.9652)
			(size 1.397 1.143)
			(layers "F.Cu" "F.Mask" "F.Paste")
			(net "GND")
		)
	)
	(footprint ""
		(layer "F.Cu")
		(at 471.603324 -283.818076 90)
		(property "Reference" "C192"
			(at 0 0 90)
			(layer "F.SilkS")
			(hide yes)
			(effects
				(font
					(size 1.27 1.27)
				)
			)
		)
		(property "Value" "SCD033U25V2KX-GP"
			(at 1.1811 -2.7051 90)
			(unlocked yes)
			(layer "F.Fab")
			(hide yes)
			(effects
				(font
					(size 1.016 1.016)
					(thickness 0.1524)
				)
			)
		)
		(property "Device Type" "C402H22"
			(at 1.1811 -4.2291 90)
			(unlocked yes)
			(layer "F.Fab")
			(hide yes)
			(effects
				(font
					(size 1.016 1.016)
					(thickness 0.1524)
				)
			)
		)
		(duplicate_pad_numbers_are_jumpers no)
		(fp_rect
			(start -0.4318 0.9525)
			(end 0.4318 -0.9525)
			(stroke
				(width 0)
				(type default)
			)
			(fill no)
			(layer "F.CrtYd")
		)
		(fp_rect
			(start -0.4318 0.9525)
			(end 0.4318 -0.9525)
			(stroke
				(width 0)
				(type default)
			)
			(fill no)
			(layer "F.Fab")
		)
		(pad "1" smd custom
			(at 0 -0.4445 90)
			(size 0.1524 0.1524)
			(layers "F.Cu" "F.Mask" "F.Paste")
			(net "P12V_A")
			(options
				(clearance outline)
				(anchor circle)
			)
			(primitives
				(gr_poly
					(pts
						(arc
							(start 0.3048 -0.2032)
							(mid 0.275042 -0.275042)
							(end 0.2032 -0.3048)
						)
						(arc
							(start -0.2032 -0.3048)
							(mid -0.275042 -0.275042)
							(end -0.3048 -0.2032)
						)
						(arc
							(start -0.3048 0.2032)
							(mid -0.275042 0.275042)
							(end -0.2032 0.3048)
						)
						(arc
							(start 0.2032 0.3048)
							(mid 0.275042 0.275042)
							(end 0.3048 0.2032)
						)
					)
					(width 0)
					(fill yes)
				)
			)
		)
		(pad "2" smd custom
			(at 0 0.4445 90)
			(size 0.1524 0.1524)
			(layers "F.Cu" "F.Mask" "F.Paste")
			(net "SW_HDD_N11")
			(options
				(clearance outline)
				(anchor circle)
			)
			(primitives
				(gr_poly
					(pts
						(arc
							(start 0.3048 -0.2032)
							(mid 0.275042 -0.275042)
							(end 0.2032 -0.3048)
						)
						(arc
							(start -0.2032 -0.3048)
							(mid -0.275042 -0.275042)
							(end -0.3048 -0.2032)
						)
						(arc
							(start -0.3048 0.2032)
							(mid -0.275042 0.275042)
							(end -0.2032 0.3048)
						)
						(arc
							(start 0.2032 0.3048)
							(mid 0.275042 0.275042)
							(end 0.3048 0.2032)
						)
					)
					(width 0)
					(fill yes)
				)
			)
		)
	)
	(footprint ""
		(layer "F.Cu")
		(at 319.786 -42.627042 180)
		(property "Reference" "VIA69"
			(at 0 0 180)
			(layer "F.SilkS")
			(hide yes)
			(effects
				(font
					(size 1.27 1.27)
				)
			)
		)
		(property "Value" "100OHM-8L-1D6MM-L18L16-GP"
			(at -3.7211 -4.5085 180)
			(unlocked yes)
			(layer "F.Fab")
			(hide yes)
			(effects
				(font
					(size 1.016 1.016)
					(thickness 0.1524)
				)
			)
		)
		(property "Device Type" "VIA-PCIE-4P-394076"
			(at -3.7211 -6.0325 180)
			(unlocked yes)
			(layer "F.Fab")
			(hide yes)
			(effects
				(font
					(size 1.016 1.016)
					(thickness 0.1524)
				)
			)
		)
		(duplicate_pad_numbers_are_jumpers no)
		(fp_rect
			(start -1.9685 0.381)
			(end 1.9685 -0.381)
			(stroke
				(width 0)
				(type default)
			)
			(fill no)
			(layer "F.CrtYd")
		)
		(fp_rect
			(start -1.9685 0.381)
			(end 1.9685 -0.381)
			(stroke
				(width 0)
				(type default)
			)
			(fill no)
			(layer "F.Fab")
		)
		(pad "1" thru_hole circle
			(at -1.5875 0 180)
			(size 0.508 0.508)
			(drill 0.254)
			(layers "*.Cu" "*.Mask")
			(remove_unused_layers no)
			(net "GND")
			(clearance 0.127)
			(thermal_gap 0.127)
		)
		(pad "2" thru_hole circle
			(at -0.5715 0 180)
			(size 0.508 0.508)
			(drill 0.254)
			(layers "*.Cu" "*.Mask")
			(remove_unused_layers no)
			(net "PHY_SCC_A_TO_DRV_A_30_DP")
			(clearance 0.127)
			(thermal_gap 0.127)
		)
		(pad "3" thru_hole circle
			(at 0.5715 0 180)
			(size 0.508 0.508)
			(drill 0.254)
			(layers "*.Cu" "*.Mask")
			(remove_unused_layers no)
			(net "PHY_SCC_A_TO_DRV_A_30_DN")
			(clearance 0.127)
			(thermal_gap 0.127)
		)
		(pad "4" thru_hole circle
			(at 1.5875 0 180)
			(size 0.508 0.508)
			(drill 0.254)
			(layers "*.Cu" "*.Mask")
			(remove_unused_layers no)
			(net "GND")
			(clearance 0.127)
			(thermal_gap 0.127)
		)
	)
	(footprint ""
		(layer "F.Cu")
		(at 34.397188 -304.428398 180)
		(property "Reference" "R210"
			(at 0 0 180)
			(layer "F.SilkS")
			(hide yes)
			(effects
				(font
					(size 1.27 1.27)
				)
			)
		)
		(property "Value" "91R3F-1-GP"
			(at -0.0254 -2.5146 180)
			(unlocked yes)
			(layer "F.Fab")
			(hide yes)
			(effects
				(font
					(size 1.016 1.016)
					(thickness 0.1524)
				)
			)
		)
		(property "Device Type" "R603H22"
			(at -0.0254 -4.0386 180)
			(unlocked yes)
			(layer "F.Fab")
			(hide yes)
			(effects
				(font
					(size 1.016 1.016)
					(thickness 0.1524)
				)
			)
		)
		(duplicate_pad_numbers_are_jumpers no)
		(fp_line
			(start 0.2032 0)
			(end 0.4826 0)
			(stroke
				(width 0.2032)
				(type default)
			)
			(layer "F.SilkS")
		)
		(fp_line
			(start -0.4826 0)
			(end -0.2032 0)
			(stroke
				(width 0.2032)
				(type default)
			)
			(layer "F.SilkS")
		)
		(fp_rect
			(start -0.5842 1.3335)
			(end 0.5842 -1.3335)
			(stroke
				(width 0)
				(type default)
			)
			(fill no)
			(layer "F.CrtYd")
		)
		(fp_rect
			(start -0.5842 1.3335)
			(end 0.5842 -1.3335)
			(stroke
				(width 0)
				(type default)
			)
			(fill no)
			(layer "F.Fab")
		)
		(pad "1" smd custom
			(at 0 -0.762 180)
			(size 0.2159 0.2159)
			(layers "F.Cu" "F.Mask" "F.Paste")
			(net "P5V_B")
			(options
				(clearance outline)
				(anchor circle)
			)
			(primitives
				(gr_poly
					(pts
						(arc
							(start -0.3302 -0.4318)
							(mid -0.402042 -0.402042)
							(end -0.4318 -0.3302)
						)
						(arc
							(start -0.4318 0.3302)
							(mid -0.402042 0.402042)
							(end -0.3302 0.4318)
						)
						(arc
							(start 0.3302 0.4318)
							(mid 0.402042 0.402042)
							(end 0.4318 0.3302)
						)
						(arc
							(start 0.4318 -0.3302)
							(mid 0.402042 -0.402042)
							(end 0.3302 -0.4318)
						)
					)
					(width 0)
					(fill yes)
				)
			)
		)
		(pad "2" smd custom
			(at 0 0.762 180)
			(size 0.2159 0.2159)
			(layers "F.Cu" "F.Mask" "F.Paste")
			(net "DRV_ACT_25")
			(options
				(clearance outline)
				(anchor circle)
			)
			(primitives
				(gr_poly
					(pts
						(arc
							(start -0.3302 -0.4318)
							(mid -0.402042 -0.402042)
							(end -0.4318 -0.3302)
						)
						(arc
							(start -0.4318 0.3302)
							(mid -0.402042 0.402042)
							(end -0.3302 0.4318)
						)
						(arc
							(start 0.3302 0.4318)
							(mid 0.402042 0.402042)
							(end 0.4318 0.3302)
						)
						(arc
							(start 0.4318 -0.3302)
							(mid 0.402042 -0.402042)
							(end 0.3302 -0.4318)
						)
					)
					(width 0)
					(fill yes)
				)
			)
		)
	)
	(footprint ""
		(layer "F.Cu")
		(at 172.593 -289.857942)
		(property "Reference" "Q32"
			(at 0 0 0)
			(layer "F.SilkS")
			(hide yes)
			(effects
				(font
					(size 1.27 1.27)
				)
			)
		)
		(property "Value" "AO4407AL-GP"
			(at -3.707384 -1.5367 0)
			(unlocked yes)
			(layer "F.Fab")
			(hide yes)
			(effects
				(font
					(size 1.016 1.016)
					(thickness 0.1524)
				)
			)
		)
		(property "Device Type" "SOIC8H69"
			(at -3.707384 -3.0607 0)
			(unlocked yes)
			(layer "F.Fab")
			(hide yes)
			(effects
				(font
					(size 1.016 1.016)
					(thickness 0.1524)
				)
			)
		)
		(duplicate_pad_numbers_are_jumpers no)
		(fp_line
			(start -2.7432 -1.4224)
			(end -2.7432 1.4224)
			(stroke
				(width 0.1524)
				(type default)
			)
			(layer "F.SilkS")
		)
		(fp_line
			(start -2.7432 1.4224)
			(end -2.6416 1.4224)
			(stroke
				(width 0.1524)
				(type default)
			)
			(layer "F.SilkS")
		)
		(fp_line
			(start -2.7432 1.4224)
			(end 2.1336 1.4224)
			(stroke
				(width 0.1524)
				(type default)
			)
			(layer "F.SilkS")
		)
		(fp_line
			(start -2.7178 -0.508)
			(end -2.1844 -0.0508)
			(stroke
				(width 0.1524)
				(type default)
			)
			(layer "F.SilkS")
		)
		(fp_line
			(start -2.6289 3.4417)
			(end -2.6289 1.4732)
			(stroke
				(width 0.381)
				(type default)
			)
			(layer "F.SilkS")
		)
		(fp_line
			(start -2.1844 -0.0508)
			(end -2.7178 0.508)
			(stroke
				(width 0.1524)
				(type default)
			)
			(layer "F.SilkS")
		)
		(fp_line
			(start 2.1336 -1.4224)
			(end -2.7432 -1.4224)
			(stroke
				(width 0.1524)
				(type default)
			)
			(layer "F.SilkS")
		)
		(fp_line
			(start 2.1336 1.4224)
			(end 2.1336 -1.4224)
			(stroke
				(width 0.1524)
				(type default)
			)
			(layer "F.SilkS")
		)
		(fp_poly
			(pts
				(xy -2.2098 -1.4224) (xy -2.2098 1.4224) (xy 2.2098 1.4224) (xy 2.2098 -1.4224)
			)
			(stroke
				(width 0)
				(type default)
			)
			(fill yes)
			(layer "F.SilkS")
		)
		(fp_rect
			(start -2.450084 2.999994)
			(end 2.450084 -2.999994)
			(stroke
				(width 0)
				(type default)
			)
			(fill no)
			(layer "F.CrtYd")
		)
		(fp_poly
			(pts
				(xy -2.8194 3.6322) (xy -2.8194 -3.6322) (xy 2.8194 -3.6322) (xy 2.8194 1.18364) (xy 2.450084 1.18364)
				(xy 2.450084 -2.999994) (xy -2.450084 -2.999994) (xy -2.450084 2.999994) (xy 2.450084 2.999994)
				(xy 2.450084 1.18618) (xy 2.8194 1.18618) (xy 2.8194 3.6322)
			)
			(stroke
				(width 0)
				(type default)
			)
			(fill no)
			(layer "F.CrtYd")
		)
		(fp_rect
			(start -2.8194 3.6322)
			(end 2.8194 -3.6322)
			(stroke
				(width 0)
				(type default)
			)
			(fill no)
			(layer "F.Fab")
		)
		(pad "1" smd rect
			(at -1.905 2.54)
			(size 0.635 1.651)
			(layers "F.Cu" "F.Mask" "F.Paste")
			(net "P12V_A")
		)
		(pad "2" smd rect
			(at -0.635 2.54)
			(size 0.635 1.651)
			(layers "F.Cu" "F.Mask" "F.Paste")
			(net "P12V_A")
		)
		(pad "3" smd rect
			(at 0.635 2.54)
			(size 0.635 1.651)
			(layers "F.Cu" "F.Mask" "F.Paste")
			(net "P12V_A")
		)
		(pad "4" smd rect
			(at 1.905 2.54)
			(size 0.635 1.651)
			(layers "F.Cu" "F.Mask" "F.Paste")
			(net "SW_HDD_N5")
		)
		(pad "5" smd rect
			(at 1.905 -2.54)
			(size 0.635 1.651)
			(layers "F.Cu" "F.Mask" "F.Paste")
			(net "P12V_HDD5")
		)
		(pad "6" smd rect
			(at 0.635 -2.54)
			(size 0.635 1.651)
			(layers "F.Cu" "F.Mask" "F.Paste")
			(net "P12V_HDD5")
		)
		(pad "7" smd rect
			(at -0.635 -2.54)
			(size 0.635 1.651)
			(layers "F.Cu" "F.Mask" "F.Paste")
			(net "P12V_HDD5")
		)
		(pad "8" smd rect
			(at -1.905 -2.54)
			(size 0.635 1.651)
			(layers "F.Cu" "F.Mask" "F.Paste")
			(net "P12V_HDD5")
		)
	)
	(footprint ""
		(layer "F.Cu")
		(at 247.15597 -300.038262 180)
		(property "Reference" "C159"
			(at 0 0 180)
			(layer "F.SilkS")
			(hide yes)
			(effects
				(font
					(size 1.27 1.27)
				)
			)
		)
		(property "Value" "SCD1U16V2KX-3GP"
			(at 1.1811 -2.7051 180)
			(unlocked yes)
			(layer "F.Fab")
			(hide yes)
			(effects
				(font
					(size 1.016 1.016)
					(thickness 0.1524)
				)
			)
		)
		(property "Device Type" "C402H22"
			(at 1.1811 -4.2291 180)
			(unlocked yes)
			(layer "F.Fab")
			(hide yes)
			(effects
				(font
					(size 1.016 1.016)
					(thickness 0.1524)
				)
			)
		)
		(duplicate_pad_numbers_are_jumpers no)
		(fp_rect
			(start -0.4318 0.9525)
			(end 0.4318 -0.9525)
			(stroke
				(width 0)
				(type default)
			)
			(fill no)
			(layer "F.CrtYd")
		)
		(fp_rect
			(start -0.4318 0.9525)
			(end 0.4318 -0.9525)
			(stroke
				(width 0)
				(type default)
			)
			(fill no)
			(layer "F.Fab")
		)
		(pad "1" smd custom
			(at 0 -0.4445 180)
			(size 0.1524 0.1524)
			(layers "F.Cu" "F.Mask" "F.Paste")
			(net "P3V3_STBY_A")
			(options
				(clearance outline)
				(anchor circle)
			)
			(primitives
				(gr_poly
					(pts
						(arc
							(start 0.3048 -0.2032)
							(mid 0.275042 -0.275042)
							(end 0.2032 -0.3048)
						)
						(arc
							(start -0.2032 -0.3048)
							(mid -0.275042 -0.275042)
							(end -0.3048 -0.2032)
						)
						(arc
							(start -0.3048 0.2032)
							(mid -0.275042 0.275042)
							(end -0.2032 0.3048)
						)
						(arc
							(start 0.2032 0.3048)
							(mid 0.275042 0.275042)
							(end 0.3048 0.2032)
						)
					)
					(width 0)
					(fill yes)
				)
			)
		)
		(pad "2" smd custom
			(at 0 0.4445 180)
			(size 0.1524 0.1524)
			(layers "F.Cu" "F.Mask" "F.Paste")
			(net "GND")
			(options
				(clearance outline)
				(anchor circle)
			)
			(primitives
				(gr_poly
					(pts
						(arc
							(start 0.3048 -0.2032)
							(mid 0.275042 -0.275042)
							(end 0.2032 -0.3048)
						)
						(arc
							(start -0.2032 -0.3048)
							(mid -0.275042 -0.275042)
							(end -0.3048 -0.2032)
						)
						(arc
							(start -0.3048 0.2032)
							(mid -0.275042 0.275042)
							(end -0.2032 0.3048)
						)
						(arc
							(start 0.2032 0.3048)
							(mid 0.275042 0.275042)
							(end 0.3048 0.2032)
						)
					)
					(width 0)
					(fill yes)
				)
			)
		)
	)
	(footprint ""
		(layer "F.Cu")
		(at 18.500598 -160.633918)
		(property "Reference" "R423"
			(at 0 0 0)
			(layer "F.SilkS")
			(hide yes)
			(effects
				(font
					(size 1.27 1.27)
				)
			)
		)
		(property "Value" "0R2J-2-GP"
			(at 0.064008 -3.993896 0)
			(unlocked yes)
			(layer "F.Fab")
			(hide yes)
			(effects
				(font
					(size 1.016 1.016)
					(thickness 0.1524)
				)
			)
		)
		(property "Device Type" "R402H16"
			(at 0.064008 -5.517896 0)
			(unlocked yes)
			(layer "F.Fab")
			(hide yes)
			(effects
				(font
					(size 1.016 1.016)
					(thickness 0.1524)
				)
			)
		)
		(duplicate_pad_numbers_are_jumpers no)
		(fp_line
			(start -0.508 -0.9398)
			(end -0.508 0.9398)
			(stroke
				(width 0.1524)
				(type default)
			)
			(layer "F.SilkS")
		)
		(fp_line
			(start 0.508 -0.9398)
			(end -0.508 -0.9398)
			(stroke
				(width 0.1524)
				(type default)
			)
			(layer "F.SilkS")
		)
		(fp_rect
			(start -0.508 0.9398)
			(end 0.508 -0.9398)
			(stroke
				(width 0)
				(type default)
			)
			(fill no)
			(layer "F.CrtYd")
		)
		(fp_rect
			(start -0.508 0.9398)
			(end 0.508 -0.9398)
			(stroke
				(width 0)
				(type default)
			)
			(fill no)
			(layer "F.Fab")
		)
		(pad "1" smd custom
			(at 0 -0.4445)
			(size 0.1397 0.1397)
			(layers "F.Cu" "F.Mask" "F.Paste")
			(net "SW_HDD_G12")
			(options
				(clearance outline)
				(anchor circle)
			)
			(primitives
				(gr_poly
					(pts
						(arc
							(start -0.1778 -0.2794)
							(mid -0.249642 -0.249642)
							(end -0.2794 -0.1778)
						)
						(arc
							(start -0.2794 0.1778)
							(mid -0.249642 0.249642)
							(end -0.1778 0.2794)
						)
						(arc
							(start 0.1778 0.2794)
							(mid 0.249642 0.249642)
							(end 0.2794 0.1778)
						)
						(arc
							(start 0.2794 -0.1778)
							(mid 0.249642 -0.249642)
							(end 0.1778 -0.2794)
						)
					)
					(width 0)
					(fill yes)
				)
			)
		)
		(pad "2" smd custom
			(at 0 0.4445)
			(size 0.1397 0.1397)
			(layers "F.Cu" "F.Mask" "F.Paste")
			(net "SW_HDD_R12")
			(options
				(clearance outline)
				(anchor circle)
			)
			(primitives
				(gr_poly
					(pts
						(arc
							(start -0.1778 -0.2794)
							(mid -0.249642 -0.249642)
							(end -0.2794 -0.1778)
						)
						(arc
							(start -0.2794 0.1778)
							(mid -0.249642 0.249642)
							(end -0.1778 0.2794)
						)
						(arc
							(start 0.1778 0.2794)
							(mid 0.249642 0.249642)
							(end 0.2794 0.1778)
						)
						(arc
							(start 0.2794 -0.1778)
							(mid 0.249642 -0.249642)
							(end 0.1778 -0.2794)
						)
					)
					(width 0)
					(fill yes)
				)
			)
		)
	)
	(footprint ""
		(layer "F.Cu")
		(at 469.815926 -64.683894 -90)
		(property "Reference" "C501"
			(at 0 0 270)
			(layer "F.SilkS")
			(hide yes)
			(effects
				(font
					(size 1.27 1.27)
				)
			)
		)
		(property "Value" "SC4D7U25V5KX-1-GP"
			(at -0.0762 -6.1214 270)
			(unlocked yes)
			(layer "F.Fab")
			(hide yes)
			(effects
				(font
					(size 1.016 1.016)
					(thickness 0.1524)
				)
			)
		)
		(property "Device Type" "C805H58"
			(at -0.0762 -8.1534 270)
			(unlocked yes)
			(layer "F.Fab")
			(hide yes)
			(effects
				(font
					(size 1.016 1.016)
					(thickness 0.1524)
				)
			)
		)
		(duplicate_pad_numbers_are_jumpers no)
		(fp_line
			(start 0.635 0)
			(end -0.635 0)
			(stroke
				(width 0.508)
				(type default)
			)
			(layer "F.SilkS")
		)
		(fp_rect
			(start -0.9652 1.778)
			(end 0.9652 -1.778)
			(stroke
				(width 0)
				(type default)
			)
			(fill no)
			(layer "F.CrtYd")
		)
		(fp_poly
			(pts
				(xy -0.9652 -1.778) (xy 0.9652 -1.778) (xy 0.9652 1.778) (xy -0.9652 1.778)
			)
			(stroke
				(width 0)
				(type default)
			)
			(fill no)
			(layer "F.Fab")
		)
		(pad "1" smd rect
			(at 0 -0.9652 270)
			(size 1.397 1.143)
			(layers "F.Cu" "F.Mask" "F.Paste")
			(net "P12V_HDD35")
		)
		(pad "2" smd rect
			(at 0 0.9652 270)
			(size 1.397 1.143)
			(layers "F.Cu" "F.Mask" "F.Paste")
			(net "GND")
		)
	)
	(footprint ""
		(layer "F.Cu")
		(at 368.481102 -45.735494 180)
		(property "Reference" "R856"
			(at 0 0 180)
			(layer "F.SilkS")
			(hide yes)
			(effects
				(font
					(size 1.27 1.27)
				)
			)
		)
		(property "Value" "4K7R2J-2-GP"
			(at 0.064008 -3.993896 180)
			(unlocked yes)
			(layer "F.Fab")
			(hide yes)
			(effects
				(font
					(size 1.016 1.016)
					(thickness 0.1524)
				)
			)
		)
		(property "Device Type" "R402H16"
			(at 0.064008 -5.517896 180)
			(unlocked yes)
			(layer "F.Fab")
			(hide yes)
			(effects
				(font
					(size 1.016 1.016)
					(thickness 0.1524)
				)
			)
		)
		(duplicate_pad_numbers_are_jumpers no)
		(fp_line
			(start 0.508 -0.9398)
			(end -0.508 -0.9398)
			(stroke
				(width 0.1524)
				(type default)
			)
			(layer "F.SilkS")
		)
		(fp_line
			(start -0.508 -0.9398)
			(end -0.508 0.9398)
			(stroke
				(width 0.1524)
				(type default)
			)
			(layer "F.SilkS")
		)
		(fp_rect
			(start -0.508 0.9398)
			(end 0.508 -0.9398)
			(stroke
				(width 0)
				(type default)
			)
			(fill no)
			(layer "F.CrtYd")
		)
		(fp_rect
			(start -0.508 0.9398)
			(end 0.508 -0.9398)
			(stroke
				(width 0)
				(type default)
			)
			(fill no)
			(layer "F.Fab")
		)
		(pad "1" smd custom
			(at 0 -0.4445 180)
			(size 0.1397 0.1397)
			(layers "F.Cu" "F.Mask" "F.Paste")
			(net "P12V_A")
			(options
				(clearance outline)
				(anchor circle)
			)
			(primitives
				(gr_poly
					(pts
						(arc
							(start -0.1778 -0.2794)
							(mid -0.249642 -0.249642)
							(end -0.2794 -0.1778)
						)
						(arc
							(start -0.2794 0.1778)
							(mid -0.249642 0.249642)
							(end -0.1778 0.2794)
						)
						(arc
							(start 0.1778 0.2794)
							(mid 0.249642 0.249642)
							(end 0.2794 0.1778)
						)
						(arc
							(start 0.2794 -0.1778)
							(mid 0.249642 -0.249642)
							(end 0.1778 -0.2794)
						)
					)
					(width 0)
					(fill yes)
				)
			)
		)
		(pad "2" smd custom
			(at 0 0.4445 180)
			(size 0.1397 0.1397)
			(layers "F.Cu" "F.Mask" "F.Paste")
			(net "SW_HDD_R31")
			(options
				(clearance outline)
				(anchor circle)
			)
			(primitives
				(gr_poly
					(pts
						(arc
							(start -0.1778 -0.2794)
							(mid -0.249642 -0.249642)
							(end -0.2794 -0.1778)
						)
						(arc
							(start -0.2794 0.1778)
							(mid -0.249642 0.249642)
							(end -0.1778 0.2794)
						)
						(arc
							(start 0.1778 0.2794)
							(mid 0.249642 0.249642)
							(end 0.2794 0.1778)
						)
						(arc
							(start 0.2794 -0.1778)
							(mid 0.249642 -0.249642)
							(end 0.1778 -0.2794)
						)
					)
					(width 0)
					(fill yes)
				)
			)
		)
	)
	(footprint ""
		(layer "F.Cu")
		(at 130.193796 -183.747918)
		(property "Reference" "TP77"
			(at 0 0 0)
			(layer "F.SilkS")
			(hide yes)
			(effects
				(font
					(size 1.27 1.27)
				)
			)
		)
		(property "Value" "TPAD32-GP"
			(at -0.0508 -1.6764 0)
			(unlocked yes)
			(layer "F.Fab")
			(hide yes)
			(effects
				(font
					(size 1.016 1.016)
					(thickness 0.1524)
				)
			)
		)
		(property "Device Type" "TPAD32"
			(at -0.0508 -3.2004 0)
			(unlocked yes)
			(layer "F.Fab")
			(hide yes)
			(effects
				(font
					(size 1.016 1.016)
					(thickness 0.1524)
				)
			)
		)
		(duplicate_pad_numbers_are_jumpers no)
		(fp_poly
			(pts
				(arc
					(start 0.4064 0)
					(mid -0.4064 0)
					(end 0.4064 0)
				)
			)
			(stroke
				(width 0)
				(type default)
			)
			(fill no)
			(layer "F.CrtYd")
		)
		(fp_poly
			(pts
				(arc
					(start 0.7112 0)
					(mid -0.7112 0)
					(end 0.7112 0)
				)
			)
			(stroke
				(width 0)
				(type default)
			)
			(fill no)
			(layer "F.Fab")
		)
		(pad "1" smd circle
			(at 0 0)
			(size 0.8128 0.8128)
			(layers "F.Cu" "F.Mask" "F.Paste")
			(net "ACT_HDD_15")
		)
	)
	(footprint ""
		(layer "F.Cu")
		(at 38.055804 -185.125614)
		(property "Reference" "Q264"
			(at 0 0 0)
			(layer "F.SilkS")
			(hide yes)
			(effects
				(font
					(size 1.27 1.27)
				)
			)
		)
		(property "Value" "SSM3K324R-GP"
			(at 0.127 -8.9662 0)
			(unlocked yes)
			(layer "F.Fab")
			(hide yes)
			(effects
				(font
					(size 1.016 1.016)
					(thickness 0.1524)
				)
			)
		)
		(property "Device Type" "SOT23DGS2D4H35"
			(at 0.127 -10.4902 0)
			(unlocked yes)
			(layer "F.Fab")
			(hide yes)
			(effects
				(font
					(size 1.016 1.016)
					(thickness 0.1524)
				)
			)
		)
		(duplicate_pad_numbers_are_jumpers no)
		(fp_line
			(start -1.651 -1.778)
			(end -1.651 1.778)
			(stroke
				(width 0.1524)
				(type default)
			)
			(layer "F.SilkS")
		)
		(fp_line
			(start -1.651 1.778)
			(end 1.651 1.778)
			(stroke
				(width 0.1524)
				(type default)
			)
			(layer "F.SilkS")
		)
		(fp_line
			(start 1.651 -1.778)
			(end -1.651 -1.778)
			(stroke
				(width 0.1524)
				(type default)
			)
			(layer "F.SilkS")
		)
		(fp_line
			(start 1.651 1.778)
			(end 1.651 -1.778)
			(stroke
				(width 0.1524)
				(type default)
			)
			(layer "F.SilkS")
		)
		(fp_poly
			(pts
				(xy -1.778 1.8796) (xy -1.778 -1.8796) (xy 1.778 -1.8796) (xy 1.778 1.8796)
			)
			(stroke
				(width 0)
				(type default)
			)
			(fill no)
			(layer "F.CrtYd")
		)
		(fp_poly
			(pts
				(xy -1.778 1.8796) (xy -1.778 -1.8796) (xy 1.778 -1.8796) (xy 1.778 1.8796)
			)
			(stroke
				(width 0)
				(type default)
			)
			(fill no)
			(layer "F.Fab")
		)
		(pad "D" smd custom
			(at 0 -0.9525)
			(size 0.1905 0.1905)
			(layers "F.Cu" "F.Mask" "F.Paste")
			(net "DRV_ACT_1_N")
			(options
				(clearance outline)
				(anchor circle)
			)
			(primitives
				(gr_poly
					(pts
						(arc
							(start -0.1778 0.5715)
							(mid -0.321484 0.511984)
							(end -0.381 0.3683)
						)
						(arc
							(start -0.381 -0.3683)
							(mid -0.321484 -0.511984)
							(end -0.1778 -0.5715)
						)
						(arc
							(start 0.1778 -0.5715)
							(mid 0.321484 -0.511984)
							(end 0.381 -0.3683)
						)
						(arc
							(start 0.381 0.3683)
							(mid 0.321484 0.511984)
							(end 0.1778 0.5715)
						)
					)
					(width 0)
					(fill yes)
				)
			)
		)
		(pad "G" smd custom
			(at -0.98425 0.9525)
			(size 0.1905 0.1905)
			(layers "F.Cu" "F.Mask" "F.Paste")
			(net "DRIVE_A_1_ACT")
			(options
				(clearance outline)
				(anchor circle)
			)
			(primitives
				(gr_poly
					(pts
						(arc
							(start -0.1778 0.5715)
							(mid -0.321484 0.511984)
							(end -0.381 0.3683)
						)
						(arc
							(start -0.381 -0.3683)
							(mid -0.321484 -0.511984)
							(end -0.1778 -0.5715)
						)
						(arc
							(start 0.1778 -0.5715)
							(mid 0.321484 -0.511984)
							(end 0.381 -0.3683)
						)
						(arc
							(start 0.381 0.3683)
							(mid 0.321484 0.511984)
							(end 0.1778 0.5715)
						)
					)
					(width 0)
					(fill yes)
				)
			)
		)
		(pad "S" smd custom
			(at 0.98425 0.9525)
			(size 0.1905 0.1905)
			(layers "F.Cu" "F.Mask" "F.Paste")
			(net "GND")
			(options
				(clearance outline)
				(anchor circle)
			)
			(primitives
				(gr_poly
					(pts
						(arc
							(start -0.1778 0.5715)
							(mid -0.321484 0.511984)
							(end -0.381 0.3683)
						)
						(arc
							(start -0.381 -0.3683)
							(mid -0.321484 -0.511984)
							(end -0.1778 -0.5715)
						)
						(arc
							(start 0.1778 -0.5715)
							(mid 0.321484 -0.511984)
							(end 0.381 -0.3683)
						)
						(arc
							(start 0.381 0.3683)
							(mid 0.321484 0.511984)
							(end 0.1778 0.5715)
						)
					)
					(width 0)
					(fill yes)
				)
			)
		)
	)
	(footprint ""
		(layer "F.Cu")
		(at 263.137142 -210.617562 180)
		(property "Reference" "R371"
			(at 0 0 180)
			(layer "F.SilkS")
			(hide yes)
			(effects
				(font
					(size 1.27 1.27)
				)
			)
		)
		(property "Value" "10KR2F-2-GP"
			(at 0.064008 -3.993896 180)
			(unlocked yes)
			(layer "F.Fab")
			(hide yes)
			(effects
				(font
					(size 1.016 1.016)
					(thickness 0.1524)
				)
			)
		)
		(property "Device Type" "R402H16"
			(at 0.064008 -5.517896 180)
			(unlocked yes)
			(layer "F.Fab")
			(hide yes)
			(effects
				(font
					(size 1.016 1.016)
					(thickness 0.1524)
				)
			)
		)
		(duplicate_pad_numbers_are_jumpers no)
		(fp_line
			(start 0.508 -0.9398)
			(end -0.508 -0.9398)
			(stroke
				(width 0.1524)
				(type default)
			)
			(layer "F.SilkS")
		)
		(fp_line
			(start -0.508 -0.9398)
			(end -0.508 0.9398)
			(stroke
				(width 0.1524)
				(type default)
			)
			(layer "F.SilkS")
		)
		(fp_rect
			(start -0.508 0.9398)
			(end 0.508 -0.9398)
			(stroke
				(width 0)
				(type default)
			)
			(fill no)
			(layer "F.CrtYd")
		)
		(fp_rect
			(start -0.508 0.9398)
			(end 0.508 -0.9398)
			(stroke
				(width 0)
				(type default)
			)
			(fill no)
			(layer "F.Fab")
		)
		(pad "1" smd custom
			(at 0 -0.4445 180)
			(size 0.1397 0.1397)
			(layers "F.Cu" "F.Mask" "F.Paste")
			(net "P3V3_STBY_A")
			(options
				(clearance outline)
				(anchor circle)
			)
			(primitives
				(gr_poly
					(pts
						(arc
							(start -0.1778 -0.2794)
							(mid -0.249642 -0.249642)
							(end -0.2794 -0.1778)
						)
						(arc
							(start -0.2794 0.1778)
							(mid -0.249642 0.249642)
							(end -0.1778 0.2794)
						)
						(arc
							(start 0.1778 0.2794)
							(mid 0.249642 0.249642)
							(end 0.2794 0.1778)
						)
						(arc
							(start 0.2794 -0.1778)
							(mid 0.249642 -0.249642)
							(end 0.1778 -0.2794)
						)
					)
					(width 0)
					(fill yes)
				)
			)
		)
		(pad "2" smd custom
			(at 0 0.4445 180)
			(size 0.1397 0.1397)
			(layers "F.Cu" "F.Mask" "F.Paste")
			(net "I2C_DPB_BUFF_EN")
			(options
				(clearance outline)
				(anchor circle)
			)
			(primitives
				(gr_poly
					(pts
						(arc
							(start -0.1778 -0.2794)
							(mid -0.249642 -0.249642)
							(end -0.2794 -0.1778)
						)
						(arc
							(start -0.2794 0.1778)
							(mid -0.249642 0.249642)
							(end -0.1778 0.2794)
						)
						(arc
							(start 0.1778 0.2794)
							(mid 0.249642 0.249642)
							(end 0.2794 0.1778)
						)
						(arc
							(start 0.2794 -0.1778)
							(mid 0.249642 -0.249642)
							(end 0.1778 -0.2794)
						)
					)
					(width 0)
					(fill yes)
				)
			)
		)
	)
	(footprint ""
		(layer "F.Cu")
		(at 255.389634 -8.215122 90)
		(property "Reference" "TP216"
			(at 0 0 90)
			(layer "F.SilkS")
			(hide yes)
			(effects
				(font
					(size 1.27 1.27)
				)
			)
		)
		(property "Value" "TPAD32-GP"
			(at -0.0508 -1.6764 90)
			(unlocked yes)
			(layer "F.Fab")
			(hide yes)
			(effects
				(font
					(size 1.016 1.016)
					(thickness 0.1524)
				)
			)
		)
		(property "Device Type" "TPAD32"
			(at -0.0508 -3.2004 90)
			(unlocked yes)
			(layer "F.Fab")
			(hide yes)
			(effects
				(font
					(size 1.016 1.016)
					(thickness 0.1524)
				)
			)
		)
		(duplicate_pad_numbers_are_jumpers no)
		(fp_poly
			(pts
				(arc
					(start 0 0.4064)
					(mid 0 -0.4064)
					(end 0 0.4064)
				)
			)
			(stroke
				(width 0)
				(type default)
			)
			(fill no)
			(layer "F.CrtYd")
		)
		(fp_poly
			(pts
				(arc
					(start 0 0.7112)
					(mid 0 -0.7112)
					(end 0 0.7112)
				)
			)
			(stroke
				(width 0)
				(type default)
			)
			(fill no)
			(layer "F.Fab")
		)
		(pad "1" smd circle
			(at 0 0 90)
			(size 0.8128 0.8128)
			(layers "F.Cu" "F.Mask" "F.Paste")
			(net "TP_COMP_A_NCSI_TXD1")
		)
	)
	(footprint ""
		(layer "F.Cu")
		(at 80.724248 -26.804874)
		(property "Reference" "C12"
			(at 0 0 0)
			(layer "F.SilkS")
			(hide yes)
			(effects
				(font
					(size 1.27 1.27)
				)
			)
		)
		(property "Value" "SCD1U16V2KX-3GP"
			(at 1.1811 -2.7051 0)
			(unlocked yes)
			(layer "F.Fab")
			(hide yes)
			(effects
				(font
					(size 1.016 1.016)
					(thickness 0.1524)
				)
			)
		)
		(property "Device Type" "C402H22"
			(at 1.1811 -4.2291 0)
			(unlocked yes)
			(layer "F.Fab")
			(hide yes)
			(effects
				(font
					(size 1.016 1.016)
					(thickness 0.1524)
				)
			)
		)
		(duplicate_pad_numbers_are_jumpers no)
		(fp_rect
			(start -0.4318 0.9525)
			(end 0.4318 -0.9525)
			(stroke
				(width 0)
				(type default)
			)
			(fill no)
			(layer "F.CrtYd")
		)
		(fp_rect
			(start -0.4318 0.9525)
			(end 0.4318 -0.9525)
			(stroke
				(width 0)
				(type default)
			)
			(fill no)
			(layer "F.Fab")
		)
		(pad "1" smd custom
			(at 0 -0.4445)
			(size 0.1524 0.1524)
			(layers "F.Cu" "F.Mask" "F.Paste")
			(net "P3V3_STBY_A")
			(options
				(clearance outline)
				(anchor circle)
			)
			(primitives
				(gr_poly
					(pts
						(arc
							(start 0.3048 -0.2032)
							(mid 0.275042 -0.275042)
							(end 0.2032 -0.3048)
						)
						(arc
							(start -0.2032 -0.3048)
							(mid -0.275042 -0.275042)
							(end -0.3048 -0.2032)
						)
						(arc
							(start -0.3048 0.2032)
							(mid -0.275042 0.275042)
							(end -0.2032 0.3048)
						)
						(arc
							(start 0.2032 0.3048)
							(mid 0.275042 0.275042)
							(end 0.3048 0.2032)
						)
					)
					(width 0)
					(fill yes)
				)
			)
		)
		(pad "2" smd custom
			(at 0 0.4445)
			(size 0.1524 0.1524)
			(layers "F.Cu" "F.Mask" "F.Paste")
			(net "GND")
			(options
				(clearance outline)
				(anchor circle)
			)
			(primitives
				(gr_poly
					(pts
						(arc
							(start 0.3048 -0.2032)
							(mid 0.275042 -0.275042)
							(end 0.2032 -0.3048)
						)
						(arc
							(start -0.2032 -0.3048)
							(mid -0.275042 -0.275042)
							(end -0.3048 -0.2032)
						)
						(arc
							(start -0.3048 0.2032)
							(mid -0.275042 0.275042)
							(end -0.2032 0.3048)
						)
						(arc
							(start 0.2032 0.3048)
							(mid 0.275042 0.275042)
							(end 0.3048 0.2032)
						)
					)
					(width 0)
					(fill yes)
				)
			)
		)
	)
	(footprint ""
		(layer "F.Cu")
		(at 370.259102 -172.851318 90)
		(property "Reference" "C296"
			(at 0 0 90)
			(layer "F.SilkS")
			(hide yes)
			(effects
				(font
					(size 1.27 1.27)
				)
			)
		)
		(property "Value" "SCD033U25V2KX-GP"
			(at 1.1811 -2.7051 90)
			(unlocked yes)
			(layer "F.Fab")
			(hide yes)
			(effects
				(font
					(size 1.016 1.016)
					(thickness 0.1524)
				)
			)
		)
		(property "Device Type" "C402H22"
			(at 1.1811 -4.2291 90)
			(unlocked yes)
			(layer "F.Fab")
			(hide yes)
			(effects
				(font
					(size 1.016 1.016)
					(thickness 0.1524)
				)
			)
		)
		(duplicate_pad_numbers_are_jumpers no)
		(fp_rect
			(start -0.4318 0.9525)
			(end 0.4318 -0.9525)
			(stroke
				(width 0)
				(type default)
			)
			(fill no)
			(layer "F.CrtYd")
		)
		(fp_rect
			(start -0.4318 0.9525)
			(end 0.4318 -0.9525)
			(stroke
				(width 0)
				(type default)
			)
			(fill no)
			(layer "F.Fab")
		)
		(pad "1" smd custom
			(at 0 -0.4445 90)
			(size 0.1524 0.1524)
			(layers "F.Cu" "F.Mask" "F.Paste")
			(net "P12V_A")
			(options
				(clearance outline)
				(anchor circle)
			)
			(primitives
				(gr_poly
					(pts
						(arc
							(start 0.3048 -0.2032)
							(mid 0.275042 -0.275042)
							(end 0.2032 -0.3048)
						)
						(arc
							(start -0.2032 -0.3048)
							(mid -0.275042 -0.275042)
							(end -0.3048 -0.2032)
						)
						(arc
							(start -0.3048 0.2032)
							(mid -0.275042 0.275042)
							(end -0.2032 0.3048)
						)
						(arc
							(start 0.2032 0.3048)
							(mid 0.275042 0.275042)
							(end 0.3048 0.2032)
						)
					)
					(width 0)
					(fill yes)
				)
			)
		)
		(pad "2" smd custom
			(at 0 0.4445 90)
			(size 0.1524 0.1524)
			(layers "F.Cu" "F.Mask" "F.Paste")
			(net "SW_HDD_N19")
			(options
				(clearance outline)
				(anchor circle)
			)
			(primitives
				(gr_poly
					(pts
						(arc
							(start 0.3048 -0.2032)
							(mid 0.275042 -0.275042)
							(end 0.2032 -0.3048)
						)
						(arc
							(start -0.2032 -0.3048)
							(mid -0.275042 -0.275042)
							(end -0.3048 -0.2032)
						)
						(arc
							(start -0.3048 0.2032)
							(mid -0.275042 0.275042)
							(end -0.2032 0.3048)
						)
						(arc
							(start 0.2032 0.3048)
							(mid 0.275042 0.275042)
							(end 0.3048 0.2032)
						)
					)
					(width 0)
					(fill yes)
				)
			)
		)
	)
	(footprint ""
		(layer "F.Cu")
		(at 262.258556 -221.676214 90)
		(property "Reference" "R403"
			(at 0 0 90)
			(layer "F.SilkS")
			(hide yes)
			(effects
				(font
					(size 1.27 1.27)
				)
			)
		)
		(property "Value" "1KR2F-3-GP"
			(at 0.064008 -3.993896 90)
			(unlocked yes)
			(layer "F.Fab")
			(hide yes)
			(effects
				(font
					(size 1.016 1.016)
					(thickness 0.1524)
				)
			)
		)
		(property "Device Type" "R402H16"
			(at 0.064008 -5.517896 90)
			(unlocked yes)
			(layer "F.Fab")
			(hide yes)
			(effects
				(font
					(size 1.016 1.016)
					(thickness 0.1524)
				)
			)
		)
		(duplicate_pad_numbers_are_jumpers no)
		(fp_line
			(start 0.508 -0.9398)
			(end -0.508 -0.9398)
			(stroke
				(width 0.1524)
				(type default)
			)
			(layer "F.SilkS")
		)
		(fp_line
			(start -0.508 -0.9398)
			(end -0.508 0.9398)
			(stroke
				(width 0.1524)
				(type default)
			)
			(layer "F.SilkS")
		)
		(fp_rect
			(start -0.508 0.9398)
			(end 0.508 -0.9398)
			(stroke
				(width 0)
				(type default)
			)
			(fill no)
			(layer "F.CrtYd")
		)
		(fp_rect
			(start -0.508 0.9398)
			(end 0.508 -0.9398)
			(stroke
				(width 0)
				(type default)
			)
			(fill no)
			(layer "F.Fab")
		)
		(pad "1" smd custom
			(at 0 -0.4445 90)
			(size 0.1397 0.1397)
			(layers "F.Cu" "F.Mask" "F.Paste")
			(net "P3V3_STBY_A")
			(options
				(clearance outline)
				(anchor circle)
			)
			(primitives
				(gr_poly
					(pts
						(arc
							(start -0.1778 -0.2794)
							(mid -0.249642 -0.249642)
							(end -0.2794 -0.1778)
						)
						(arc
							(start -0.2794 0.1778)
							(mid -0.249642 0.249642)
							(end -0.1778 0.2794)
						)
						(arc
							(start 0.1778 0.2794)
							(mid 0.249642 0.249642)
							(end 0.2794 0.1778)
						)
						(arc
							(start 0.2794 -0.1778)
							(mid 0.249642 -0.249642)
							(end 0.1778 -0.2794)
						)
					)
					(width 0)
					(fill yes)
				)
			)
		)
		(pad "2" smd custom
			(at 0 0.4445 90)
			(size 0.1397 0.1397)
			(layers "F.Cu" "F.Mask" "F.Paste")
			(net "I2C_DPB_A_SDA_BUF")
			(options
				(clearance outline)
				(anchor circle)
			)
			(primitives
				(gr_poly
					(pts
						(arc
							(start -0.1778 -0.2794)
							(mid -0.249642 -0.249642)
							(end -0.2794 -0.1778)
						)
						(arc
							(start -0.2794 0.1778)
							(mid -0.249642 0.249642)
							(end -0.1778 0.2794)
						)
						(arc
							(start 0.1778 0.2794)
							(mid 0.249642 0.249642)
							(end 0.2794 0.1778)
						)
						(arc
							(start 0.2794 -0.1778)
							(mid 0.249642 -0.249642)
							(end 0.1778 -0.2794)
						)
					)
					(width 0)
					(fill yes)
				)
			)
		)
	)
	(footprint ""
		(layer "F.Cu")
		(at 174.5742 -168.152318 -90)
		(property "Reference" "C269"
			(at 0 0 270)
			(layer "F.SilkS")
			(hide yes)
			(effects
				(font
					(size 1.27 1.27)
				)
			)
		)
		(property "Value" "SCD033U25V2KX-GP"
			(at 1.1811 -2.7051 270)
			(unlocked yes)
			(layer "F.Fab")
			(hide yes)
			(effects
				(font
					(size 1.016 1.016)
					(thickness 0.1524)
				)
			)
		)
		(property "Device Type" "C402H22"
			(at 1.1811 -4.2291 270)
			(unlocked yes)
			(layer "F.Fab")
			(hide yes)
			(effects
				(font
					(size 1.016 1.016)
					(thickness 0.1524)
				)
			)
		)
		(duplicate_pad_numbers_are_jumpers no)
		(fp_rect
			(start -0.4318 0.9525)
			(end 0.4318 -0.9525)
			(stroke
				(width 0)
				(type default)
			)
			(fill no)
			(layer "F.CrtYd")
		)
		(fp_rect
			(start -0.4318 0.9525)
			(end 0.4318 -0.9525)
			(stroke
				(width 0)
				(type default)
			)
			(fill no)
			(layer "F.Fab")
		)
		(pad "1" smd custom
			(at 0 -0.4445 270)
			(size 0.1524 0.1524)
			(layers "F.Cu" "F.Mask" "F.Paste")
			(net "SW_HDD_P17")
			(options
				(clearance outline)
				(anchor circle)
			)
			(primitives
				(gr_poly
					(pts
						(arc
							(start 0.3048 -0.2032)
							(mid 0.275042 -0.275042)
							(end 0.2032 -0.3048)
						)
						(arc
							(start -0.2032 -0.3048)
							(mid -0.275042 -0.275042)
							(end -0.3048 -0.2032)
						)
						(arc
							(start -0.3048 0.2032)
							(mid -0.275042 0.275042)
							(end -0.2032 0.3048)
						)
						(arc
							(start 0.2032 0.3048)
							(mid 0.275042 0.275042)
							(end 0.3048 0.2032)
						)
					)
					(width 0)
					(fill yes)
				)
			)
		)
		(pad "2" smd custom
			(at 0 0.4445 270)
			(size 0.1524 0.1524)
			(layers "F.Cu" "F.Mask" "F.Paste")
			(net "GND")
			(options
				(clearance outline)
				(anchor circle)
			)
			(primitives
				(gr_poly
					(pts
						(arc
							(start 0.3048 -0.2032)
							(mid 0.275042 -0.275042)
							(end 0.2032 -0.3048)
						)
						(arc
							(start -0.2032 -0.3048)
							(mid -0.275042 -0.275042)
							(end -0.3048 -0.2032)
						)
						(arc
							(start -0.3048 0.2032)
							(mid -0.275042 0.275042)
							(end -0.2032 0.3048)
						)
						(arc
							(start 0.2032 0.3048)
							(mid 0.275042 0.275042)
							(end 0.3048 0.2032)
						)
					)
					(width 0)
					(fill yes)
				)
			)
		)
	)
	(footprint ""
		(layer "F.Cu")
		(at 456.0189 -296.842942 180)
		(property "Reference" "C170"
			(at 0 0 180)
			(layer "F.SilkS")
			(hide yes)
			(effects
				(font
					(size 1.27 1.27)
				)
			)
		)
		(property "Value" "SC1U16V3KX-5GP"
			(at 0 -2.8194 180)
			(unlocked yes)
			(layer "F.Fab")
			(hide yes)
			(effects
				(font
					(size 1.016 1.016)
					(thickness 0.1524)
				)
			)
		)
		(property "Device Type" "C603H36"
			(at 0 -4.3434 180)
			(unlocked yes)
			(layer "F.Fab")
			(hide yes)
			(effects
				(font
					(size 1.016 1.016)
					(thickness 0.1524)
				)
			)
		)
		(duplicate_pad_numbers_are_jumpers no)
		(fp_line
			(start 0.508 0)
			(end -0.508 0)
			(stroke
				(width 0.2032)
				(type default)
			)
			(layer "F.SilkS")
		)
		(fp_rect
			(start -0.5842 1.3335)
			(end 0.5842 -1.3335)
			(stroke
				(width 0)
				(type default)
			)
			(fill no)
			(layer "F.CrtYd")
		)
		(fp_rect
			(start -0.5842 1.3335)
			(end 0.5842 -1.3335)
			(stroke
				(width 0)
				(type default)
			)
			(fill no)
			(layer "F.Fab")
		)
		(pad "1" smd custom
			(at 0 -0.762 180)
			(size 0.2159 0.2159)
			(layers "F.Cu" "F.Mask" "F.Paste")
			(net "P5V_HDD10")
			(options
				(clearance outline)
				(anchor circle)
			)
			(primitives
				(gr_poly
					(pts
						(arc
							(start -0.3302 -0.4318)
							(mid -0.402042 -0.402042)
							(end -0.4318 -0.3302)
						)
						(arc
							(start -0.4318 0.3302)
							(mid -0.402042 0.402042)
							(end -0.3302 0.4318)
						)
						(arc
							(start 0.3302 0.4318)
							(mid 0.402042 0.402042)
							(end 0.4318 0.3302)
						)
						(arc
							(start 0.4318 -0.3302)
							(mid 0.402042 -0.402042)
							(end 0.3302 -0.4318)
						)
					)
					(width 0)
					(fill yes)
				)
			)
		)
		(pad "2" smd custom
			(at 0 0.762 180)
			(size 0.2159 0.2159)
			(layers "F.Cu" "F.Mask" "F.Paste")
			(net "GND")
			(options
				(clearance outline)
				(anchor circle)
			)
			(primitives
				(gr_poly
					(pts
						(arc
							(start -0.3302 -0.4318)
							(mid -0.402042 -0.402042)
							(end -0.4318 -0.3302)
						)
						(arc
							(start -0.4318 0.3302)
							(mid -0.402042 0.402042)
							(end -0.3302 0.4318)
						)
						(arc
							(start 0.3302 0.4318)
							(mid 0.402042 0.402042)
							(end 0.4318 0.3302)
						)
						(arc
							(start 0.4318 -0.3302)
							(mid 0.402042 -0.402042)
							(end 0.3302 -0.4318)
						)
					)
					(width 0)
					(fill yes)
				)
			)
		)
	)
	(footprint ""
		(layer "F.Cu")
		(at 463.5119 -277.792942 90)
		(property "Reference" "D10"
			(at 0 0 90)
			(layer "F.SilkS")
			(hide yes)
			(effects
				(font
					(size 1.27 1.27)
				)
			)
		)
		(property "Value" "RB551V30-GP"
			(at 0 -6.7818 90)
			(unlocked yes)
			(layer "F.Fab")
			(hide yes)
			(effects
				(font
					(size 1.016 1.016)
					(thickness 0.1524)
				)
			)
		)
		(property "Device Type" "SOD323AKH38"
			(at 0 -8.6868 90)
			(unlocked yes)
			(layer "F.Fab")
			(hide yes)
			(effects
				(font
					(size 1.016 1.016)
					(thickness 0.1524)
				)
			)
		)
		(duplicate_pad_numbers_are_jumpers no)
		(fp_line
			(start 0.889 -1.9304)
			(end 0.889 2.159)
			(stroke
				(width 0.1524)
				(type default)
			)
			(layer "F.SilkS")
		)
		(fp_line
			(start -0.889 -1.9304)
			(end 0.889 -1.9304)
			(stroke
				(width 0.1524)
				(type default)
			)
			(layer "F.SilkS")
		)
		(fp_line
			(start 0.762 2.0574)
			(end -0.762 2.0574)
			(stroke
				(width 0.508)
				(type default)
			)
			(layer "F.SilkS")
		)
		(fp_line
			(start 0.889 2.159)
			(end -0.889 2.159)
			(stroke
				(width 0.1524)
				(type default)
			)
			(layer "F.SilkS")
		)
		(fp_line
			(start -0.889 2.159)
			(end -0.889 -1.9304)
			(stroke
				(width 0.1524)
				(type default)
			)
			(layer "F.SilkS")
		)
		(fp_rect
			(start -1.016 2.3114)
			(end 1.016 -2.0066)
			(stroke
				(width 0)
				(type default)
			)
			(fill no)
			(layer "F.CrtYd")
		)
		(fp_poly
			(pts
				(xy -1.016 -2.0066) (xy 1.016 -2.0066) (xy 1.016 2.3114) (xy -1.016 2.3114)
			)
			(stroke
				(width 0)
				(type default)
			)
			(fill no)
			(layer "F.Fab")
		)
		(pad "A" smd rect
			(at 0 -1.143 90)
			(size 0.5588 1.016)
			(layers "F.Cu" "F.Mask" "F.Paste")
			(net "SW_HDD_R10")
		)
		(pad "K" smd rect
			(at 0 1.143 90)
			(size 0.5588 1.016)
			(layers "F.Cu" "F.Mask" "F.Paste")
			(net "SW_HDD_N10")
		)
	)
	(footprint ""
		(layer "F.Cu")
		(at 145.422366 -128.683258 -90)
		(property "Reference" "C554"
			(at 0 0 270)
			(layer "F.SilkS")
			(hide yes)
			(effects
				(font
					(size 1.27 1.27)
				)
			)
		)
		(property "Value" "SCD033U50V3KX-1GP"
			(at 0 -2.8194 270)
			(unlocked yes)
			(layer "F.Fab")
			(hide yes)
			(effects
				(font
					(size 1.016 1.016)
					(thickness 0.1524)
				)
			)
		)
		(property "Device Type" "C603H36"
			(at 0 -4.3434 270)
			(unlocked yes)
			(layer "F.Fab")
			(hide yes)
			(effects
				(font
					(size 1.016 1.016)
					(thickness 0.1524)
				)
			)
		)
		(duplicate_pad_numbers_are_jumpers no)
		(fp_line
			(start 0.508 0)
			(end -0.508 0)
			(stroke
				(width 0.2032)
				(type default)
			)
			(layer "F.SilkS")
		)
		(fp_rect
			(start -0.5842 1.3335)
			(end 0.5842 -1.3335)
			(stroke
				(width 0)
				(type default)
			)
			(fill no)
			(layer "F.CrtYd")
		)
		(fp_rect
			(start -0.5842 1.3335)
			(end 0.5842 -1.3335)
			(stroke
				(width 0)
				(type default)
			)
			(fill no)
			(layer "F.Fab")
		)
		(pad "1" smd custom
			(at 0 -0.762 270)
			(size 0.2159 0.2159)
			(layers "F.Cu" "F.Mask" "F.Paste")
			(net "MB0_CM_GATE_C")
			(options
				(clearance outline)
				(anchor circle)
			)
			(primitives
				(gr_poly
					(pts
						(arc
							(start -0.3302 -0.4318)
							(mid -0.402042 -0.402042)
							(end -0.4318 -0.3302)
						)
						(arc
							(start -0.4318 0.3302)
							(mid -0.402042 0.402042)
							(end -0.3302 0.4318)
						)
						(arc
							(start 0.3302 0.4318)
							(mid 0.402042 0.402042)
							(end 0.4318 0.3302)
						)
						(arc
							(start 0.4318 -0.3302)
							(mid 0.402042 -0.402042)
							(end 0.3302 -0.4318)
						)
					)
					(width 0)
					(fill yes)
				)
			)
		)
		(pad "2" smd custom
			(at 0 0.762 270)
			(size 0.2159 0.2159)
			(layers "F.Cu" "F.Mask" "F.Paste")
			(net "GND")
			(options
				(clearance outline)
				(anchor circle)
			)
			(primitives
				(gr_poly
					(pts
						(arc
							(start -0.3302 -0.4318)
							(mid -0.402042 -0.402042)
							(end -0.4318 -0.3302)
						)
						(arc
							(start -0.4318 0.3302)
							(mid -0.402042 0.402042)
							(end -0.3302 0.4318)
						)
						(arc
							(start 0.3302 0.4318)
							(mid 0.402042 0.402042)
							(end 0.4318 0.3302)
						)
						(arc
							(start 0.4318 -0.3302)
							(mid 0.402042 -0.402042)
							(end 0.3302 -0.4318)
						)
					)
					(width 0)
					(fill yes)
				)
			)
		)
	)
	(footprint ""
		(layer "F.Cu")
		(at 452.288402 -258.47675 -90)
		(property "Reference" "R1244"
			(at 0 0 270)
			(layer "F.SilkS")
			(hide yes)
			(effects
				(font
					(size 1.27 1.27)
				)
			)
		)
		(property "Value" "0R2J-2-GP"
			(at 0.064008 -3.993896 270)
			(unlocked yes)
			(layer "F.Fab")
			(hide yes)
			(effects
				(font
					(size 1.016 1.016)
					(thickness 0.1524)
				)
			)
		)
		(property "Device Type" "R402H16"
			(at 0.064008 -5.517896 270)
			(unlocked yes)
			(layer "F.Fab")
			(hide yes)
			(effects
				(font
					(size 1.016 1.016)
					(thickness 0.1524)
				)
			)
		)
		(duplicate_pad_numbers_are_jumpers no)
		(fp_line
			(start -0.508 -0.9398)
			(end -0.508 0.9398)
			(stroke
				(width 0.1524)
				(type default)
			)
			(layer "F.SilkS")
		)
		(fp_line
			(start 0.508 -0.9398)
			(end -0.508 -0.9398)
			(stroke
				(width 0.1524)
				(type default)
			)
			(layer "F.SilkS")
		)
		(fp_rect
			(start -0.508 0.9398)
			(end 0.508 -0.9398)
			(stroke
				(width 0)
				(type default)
			)
			(fill no)
			(layer "F.CrtYd")
		)
		(fp_rect
			(start -0.508 0.9398)
			(end 0.508 -0.9398)
			(stroke
				(width 0)
				(type default)
			)
			(fill no)
			(layer "F.Fab")
		)
		(pad "1" smd custom
			(at 0 -0.4445 270)
			(size 0.1397 0.1397)
			(layers "F.Cu" "F.Mask" "F.Paste")
			(net "P12V_A_PGOOD")
			(options
				(clearance outline)
				(anchor circle)
			)
			(primitives
				(gr_poly
					(pts
						(arc
							(start -0.1778 -0.2794)
							(mid -0.249642 -0.249642)
							(end -0.2794 -0.1778)
						)
						(arc
							(start -0.2794 0.1778)
							(mid -0.249642 0.249642)
							(end -0.1778 0.2794)
						)
						(arc
							(start 0.1778 0.2794)
							(mid 0.249642 0.249642)
							(end 0.2794 0.1778)
						)
						(arc
							(start 0.2794 -0.1778)
							(mid 0.249642 -0.249642)
							(end 0.1778 -0.2794)
						)
					)
					(width 0)
					(fill yes)
				)
			)
		)
		(pad "2" smd custom
			(at 0 0.4445 270)
			(size 0.1397 0.1397)
			(layers "F.Cu" "F.Mask" "F.Paste")
			(net "P5V_C_EN_R")
			(options
				(clearance outline)
				(anchor circle)
			)
			(primitives
				(gr_poly
					(pts
						(arc
							(start -0.1778 -0.2794)
							(mid -0.249642 -0.249642)
							(end -0.2794 -0.1778)
						)
						(arc
							(start -0.2794 0.1778)
							(mid -0.249642 0.249642)
							(end -0.1778 0.2794)
						)
						(arc
							(start 0.1778 0.2794)
							(mid 0.249642 0.249642)
							(end 0.2794 0.1778)
						)
						(arc
							(start 0.2794 -0.1778)
							(mid 0.249642 -0.249642)
							(end 0.1778 -0.2794)
						)
					)
					(width 0)
					(fill yes)
				)
			)
		)
	)
	(footprint ""
		(layer "F.Cu")
		(at 457.6699 -176.127918 -90)
		(property "Reference" "R635"
			(at 0 0 270)
			(layer "F.SilkS")
			(hide yes)
			(effects
				(font
					(size 1.27 1.27)
				)
			)
		)
		(property "Value" "2R6F-GP"
			(at -0.0508 -4.8514 270)
			(unlocked yes)
			(layer "F.Fab")
			(hide yes)
			(effects
				(font
					(size 1.016 1.016)
					(thickness 0.1524)
				)
			)
		)
		(property "Device Type" "R1206H26"
			(at 0 -6.3754 270)
			(unlocked yes)
			(layer "F.Fab")
			(hide yes)
			(effects
				(font
					(size 1.016 1.016)
					(thickness 0.1524)
				)
			)
		)
		(duplicate_pad_numbers_are_jumpers no)
		(fp_line
			(start -1.016 2.2352)
			(end -1.016 -2.2352)
			(stroke
				(width 0.1524)
				(type default)
			)
			(layer "F.SilkS")
		)
		(fp_line
			(start 1.016 2.2352)
			(end -1.016 2.2352)
			(stroke
				(width 0.1524)
				(type default)
			)
			(layer "F.SilkS")
		)
		(fp_line
			(start -1.016 -2.2352)
			(end 1.016 -2.2352)
			(stroke
				(width 0.1524)
				(type default)
			)
			(layer "F.SilkS")
		)
		(fp_line
			(start 1.016 -2.2352)
			(end 1.016 2.2352)
			(stroke
				(width 0.1524)
				(type default)
			)
			(layer "F.SilkS")
		)
		(fp_rect
			(start -1.0922 2.3114)
			(end 1.0922 -2.3114)
			(stroke
				(width 0)
				(type default)
			)
			(fill no)
			(layer "F.CrtYd")
		)
		(fp_poly
			(pts
				(xy -1.0922 -2.3114) (xy 1.0922 -2.3114) (xy 1.0922 2.3114) (xy -1.0922 2.3114)
			)
			(stroke
				(width 0)
				(type default)
			)
			(fill no)
			(layer "F.Fab")
		)
		(pad "1" smd rect
			(at 0 -1.397 270)
			(size 1.651 1.27)
			(layers "F.Cu" "F.Mask" "F.Paste")
			(net "P5V_HDD22")
		)
		(pad "2" smd rect
			(at 0 1.397 270)
			(size 1.651 1.27)
			(layers "F.Cu" "F.Mask" "F.Paste")
			(net "5V_PRE_22")
		)
	)
	(footprint ""
		(layer "F.Cu")
		(at 243.9416 -260.5532)
		(property "Reference" "R48"
			(at 0 0 0)
			(layer "F.SilkS")
			(hide yes)
			(effects
				(font
					(size 1.27 1.27)
				)
			)
		)
		(property "Value" "4K7R2F-GP"
			(at 0.064008 -3.993896 0)
			(unlocked yes)
			(layer "F.Fab")
			(hide yes)
			(effects
				(font
					(size 1.016 1.016)
					(thickness 0.1524)
				)
			)
		)
		(property "Device Type" "R402H16"
			(at 0.064008 -5.517896 0)
			(unlocked yes)
			(layer "F.Fab")
			(hide yes)
			(effects
				(font
					(size 1.016 1.016)
					(thickness 0.1524)
				)
			)
		)
		(duplicate_pad_numbers_are_jumpers no)
		(fp_line
			(start -0.508 -0.9398)
			(end -0.508 0.9398)
			(stroke
				(width 0.1524)
				(type default)
			)
			(layer "F.SilkS")
		)
		(fp_line
			(start 0.508 -0.9398)
			(end -0.508 -0.9398)
			(stroke
				(width 0.1524)
				(type default)
			)
			(layer "F.SilkS")
		)
		(fp_rect
			(start -0.508 0.9398)
			(end 0.508 -0.9398)
			(stroke
				(width 0)
				(type default)
			)
			(fill no)
			(layer "F.CrtYd")
		)
		(fp_rect
			(start -0.508 0.9398)
			(end 0.508 -0.9398)
			(stroke
				(width 0)
				(type default)
			)
			(fill no)
			(layer "F.Fab")
		)
		(pad "1" smd custom
			(at 0 -0.4445)
			(size 0.1397 0.1397)
			(layers "F.Cu" "F.Mask" "F.Paste")
			(net "P3V3_STBY_A")
			(options
				(clearance outline)
				(anchor circle)
			)
			(primitives
				(gr_poly
					(pts
						(arc
							(start -0.1778 -0.2794)
							(mid -0.249642 -0.249642)
							(end -0.2794 -0.1778)
						)
						(arc
							(start -0.2794 0.1778)
							(mid -0.249642 0.249642)
							(end -0.1778 0.2794)
						)
						(arc
							(start 0.1778 0.2794)
							(mid 0.249642 0.249642)
							(end 0.2794 0.1778)
						)
						(arc
							(start 0.2794 -0.1778)
							(mid 0.249642 -0.249642)
							(end 0.1778 -0.2794)
						)
					)
					(width 0)
					(fill yes)
				)
			)
		)
		(pad "2" smd custom
			(at 0 0.4445)
			(size 0.1397 0.1397)
			(layers "F.Cu" "F.Mask" "F.Paste")
			(net "IO_EXP5_A0")
			(options
				(clearance outline)
				(anchor circle)
			)
			(primitives
				(gr_poly
					(pts
						(arc
							(start -0.1778 -0.2794)
							(mid -0.249642 -0.249642)
							(end -0.2794 -0.1778)
						)
						(arc
							(start -0.2794 0.1778)
							(mid -0.249642 0.249642)
							(end -0.1778 0.2794)
						)
						(arc
							(start 0.1778 0.2794)
							(mid 0.249642 0.249642)
							(end 0.2794 0.1778)
						)
						(arc
							(start 0.2794 -0.1778)
							(mid 0.249642 -0.249642)
							(end 0.1778 -0.2794)
						)
					)
					(width 0)
					(fill yes)
				)
			)
		)
	)
	(footprint ""
		(layer "F.Cu")
		(at 176.2506 -45.633894)
		(property "Reference" "R814"
			(at 0 0 0)
			(layer "F.SilkS")
			(hide yes)
			(effects
				(font
					(size 1.27 1.27)
				)
			)
		)
		(property "Value" "0R2J-2-GP"
			(at 0.064008 -3.993896 0)
			(unlocked yes)
			(layer "F.Fab")
			(hide yes)
			(effects
				(font
					(size 1.016 1.016)
					(thickness 0.1524)
				)
			)
		)
		(property "Device Type" "R402H16"
			(at 0.064008 -5.517896 0)
			(unlocked yes)
			(layer "F.Fab")
			(hide yes)
			(effects
				(font
					(size 1.016 1.016)
					(thickness 0.1524)
				)
			)
		)
		(duplicate_pad_numbers_are_jumpers no)
		(fp_line
			(start -0.508 -0.9398)
			(end -0.508 0.9398)
			(stroke
				(width 0.1524)
				(type default)
			)
			(layer "F.SilkS")
		)
		(fp_line
			(start 0.508 -0.9398)
			(end -0.508 -0.9398)
			(stroke
				(width 0.1524)
				(type default)
			)
			(layer "F.SilkS")
		)
		(fp_rect
			(start -0.508 0.9398)
			(end 0.508 -0.9398)
			(stroke
				(width 0)
				(type default)
			)
			(fill no)
			(layer "F.CrtYd")
		)
		(fp_rect
			(start -0.508 0.9398)
			(end 0.508 -0.9398)
			(stroke
				(width 0)
				(type default)
			)
			(fill no)
			(layer "F.Fab")
		)
		(pad "1" smd custom
			(at 0 -0.4445)
			(size 0.1397 0.1397)
			(layers "F.Cu" "F.Mask" "F.Paste")
			(net "SW_HDD_G29")
			(options
				(clearance outline)
				(anchor circle)
			)
			(primitives
				(gr_poly
					(pts
						(arc
							(start -0.1778 -0.2794)
							(mid -0.249642 -0.249642)
							(end -0.2794 -0.1778)
						)
						(arc
							(start -0.2794 0.1778)
							(mid -0.249642 0.249642)
							(end -0.1778 0.2794)
						)
						(arc
							(start 0.1778 0.2794)
							(mid 0.249642 0.249642)
							(end 0.2794 0.1778)
						)
						(arc
							(start 0.2794 -0.1778)
							(mid 0.249642 -0.249642)
							(end 0.1778 -0.2794)
						)
					)
					(width 0)
					(fill yes)
				)
			)
		)
		(pad "2" smd custom
			(at 0 0.4445)
			(size 0.1397 0.1397)
			(layers "F.Cu" "F.Mask" "F.Paste")
			(net "SW_HDD_R29")
			(options
				(clearance outline)
				(anchor circle)
			)
			(primitives
				(gr_poly
					(pts
						(arc
							(start -0.1778 -0.2794)
							(mid -0.249642 -0.249642)
							(end -0.2794 -0.1778)
						)
						(arc
							(start -0.2794 0.1778)
							(mid -0.249642 0.249642)
							(end -0.1778 0.2794)
						)
						(arc
							(start 0.1778 0.2794)
							(mid 0.249642 0.249642)
							(end 0.2794 0.1778)
						)
						(arc
							(start 0.2794 -0.1778)
							(mid 0.249642 -0.249642)
							(end 0.1778 -0.2794)
						)
					)
					(width 0)
					(fill yes)
				)
			)
		)
	)
	(footprint ""
		(layer "F.Cu")
		(at 162.657536 -130.185414 -90)
		(property "Reference" "R524"
			(at 0 0 270)
			(layer "F.SilkS")
			(hide yes)
			(effects
				(font
					(size 1.27 1.27)
				)
			)
		)
		(property "Value" "4K7R2J-2-GP"
			(at 0.064008 -3.993896 270)
			(unlocked yes)
			(layer "F.Fab")
			(hide yes)
			(effects
				(font
					(size 1.016 1.016)
					(thickness 0.1524)
				)
			)
		)
		(property "Device Type" "R402H16"
			(at 0.064008 -5.517896 270)
			(unlocked yes)
			(layer "F.Fab")
			(hide yes)
			(effects
				(font
					(size 1.016 1.016)
					(thickness 0.1524)
				)
			)
		)
		(duplicate_pad_numbers_are_jumpers no)
		(fp_line
			(start -0.508 -0.9398)
			(end -0.508 0.9398)
			(stroke
				(width 0.1524)
				(type default)
			)
			(layer "F.SilkS")
		)
		(fp_line
			(start 0.508 -0.9398)
			(end -0.508 -0.9398)
			(stroke
				(width 0.1524)
				(type default)
			)
			(layer "F.SilkS")
		)
		(fp_rect
			(start -0.508 0.9398)
			(end 0.508 -0.9398)
			(stroke
				(width 0)
				(type default)
			)
			(fill no)
			(layer "F.CrtYd")
		)
		(fp_rect
			(start -0.508 0.9398)
			(end 0.508 -0.9398)
			(stroke
				(width 0)
				(type default)
			)
			(fill no)
			(layer "F.Fab")
		)
		(pad "1" smd custom
			(at 0 -0.4445 270)
			(size 0.1397 0.1397)
			(layers "F.Cu" "F.Mask" "F.Paste")
			(net "DRIVE_A_17_FLT_LED")
			(options
				(clearance outline)
				(anchor circle)
			)
			(primitives
				(gr_poly
					(pts
						(arc
							(start -0.1778 -0.2794)
							(mid -0.249642 -0.249642)
							(end -0.2794 -0.1778)
						)
						(arc
							(start -0.2794 0.1778)
							(mid -0.249642 0.249642)
							(end -0.1778 0.2794)
						)
						(arc
							(start 0.1778 0.2794)
							(mid 0.249642 0.249642)
							(end 0.2794 0.1778)
						)
						(arc
							(start 0.2794 -0.1778)
							(mid 0.249642 -0.249642)
							(end 0.1778 -0.2794)
						)
					)
					(width 0)
					(fill yes)
				)
			)
		)
		(pad "2" smd custom
			(at 0 0.4445 270)
			(size 0.1397 0.1397)
			(layers "F.Cu" "F.Mask" "F.Paste")
			(net "GND")
			(options
				(clearance outline)
				(anchor circle)
			)
			(primitives
				(gr_poly
					(pts
						(arc
							(start -0.1778 -0.2794)
							(mid -0.249642 -0.249642)
							(end -0.2794 -0.1778)
						)
						(arc
							(start -0.2794 0.1778)
							(mid -0.249642 0.249642)
							(end -0.1778 0.2794)
						)
						(arc
							(start 0.1778 0.2794)
							(mid 0.249642 0.249642)
							(end 0.2794 0.1778)
						)
						(arc
							(start 0.2794 -0.1778)
							(mid 0.249642 -0.249642)
							(end 0.1778 -0.2794)
						)
					)
					(width 0)
					(fill yes)
				)
			)
		)
	)
	(footprint ""
		(layer "F.Cu")
		(at 172.4406 -277.6474 90)
		(property "Reference" "R259"
			(at 0 0 90)
			(layer "F.SilkS")
			(hide yes)
			(effects
				(font
					(size 1.27 1.27)
				)
			)
		)
		(property "Value" "4K7R2J-2-GP"
			(at 0.064008 -3.993896 90)
			(unlocked yes)
			(layer "F.Fab")
			(hide yes)
			(effects
				(font
					(size 1.016 1.016)
					(thickness 0.1524)
				)
			)
		)
		(property "Device Type" "R402H16"
			(at 0.064008 -5.517896 90)
			(unlocked yes)
			(layer "F.Fab")
			(hide yes)
			(effects
				(font
					(size 1.016 1.016)
					(thickness 0.1524)
				)
			)
		)
		(duplicate_pad_numbers_are_jumpers no)
		(fp_line
			(start 0.508 -0.9398)
			(end -0.508 -0.9398)
			(stroke
				(width 0.1524)
				(type default)
			)
			(layer "F.SilkS")
		)
		(fp_line
			(start -0.508 -0.9398)
			(end -0.508 0.9398)
			(stroke
				(width 0.1524)
				(type default)
			)
			(layer "F.SilkS")
		)
		(fp_rect
			(start -0.508 0.9398)
			(end 0.508 -0.9398)
			(stroke
				(width 0)
				(type default)
			)
			(fill no)
			(layer "F.CrtYd")
		)
		(fp_rect
			(start -0.508 0.9398)
			(end 0.508 -0.9398)
			(stroke
				(width 0)
				(type default)
			)
			(fill no)
			(layer "F.Fab")
		)
		(pad "1" smd custom
			(at 0 -0.4445 90)
			(size 0.1397 0.1397)
			(layers "F.Cu" "F.Mask" "F.Paste")
			(net "P12V_A")
			(options
				(clearance outline)
				(anchor circle)
			)
			(primitives
				(gr_poly
					(pts
						(arc
							(start -0.1778 -0.2794)
							(mid -0.249642 -0.249642)
							(end -0.2794 -0.1778)
						)
						(arc
							(start -0.2794 0.1778)
							(mid -0.249642 0.249642)
							(end -0.1778 0.2794)
						)
						(arc
							(start 0.1778 0.2794)
							(mid 0.249642 0.249642)
							(end 0.2794 0.1778)
						)
						(arc
							(start 0.2794 -0.1778)
							(mid 0.249642 -0.249642)
							(end 0.1778 -0.2794)
						)
					)
					(width 0)
					(fill yes)
				)
			)
		)
		(pad "2" smd custom
			(at 0 0.4445 90)
			(size 0.1397 0.1397)
			(layers "F.Cu" "F.Mask" "F.Paste")
			(net "SW_HDD_R5")
			(options
				(clearance outline)
				(anchor circle)
			)
			(primitives
				(gr_poly
					(pts
						(arc
							(start -0.1778 -0.2794)
							(mid -0.249642 -0.249642)
							(end -0.2794 -0.1778)
						)
						(arc
							(start -0.2794 0.1778)
							(mid -0.249642 0.249642)
							(end -0.1778 0.2794)
						)
						(arc
							(start 0.1778 0.2794)
							(mid 0.249642 0.249642)
							(end 0.2794 0.1778)
						)
						(arc
							(start 0.2794 -0.1778)
							(mid 0.249642 -0.249642)
							(end 0.1778 -0.2794)
						)
					)
					(width 0)
					(fill yes)
				)
			)
		)
	)
	(footprint ""
		(layer "F.Cu")
		(at 16.824198 -167.110918 90)
		(property "Reference" "R413"
			(at 0 0 90)
			(layer "F.SilkS")
			(hide yes)
			(effects
				(font
					(size 1.27 1.27)
				)
			)
		)
		(property "Value" "4K7R2J-2-GP"
			(at 0.064008 -3.993896 90)
			(unlocked yes)
			(layer "F.Fab")
			(hide yes)
			(effects
				(font
					(size 1.016 1.016)
					(thickness 0.1524)
				)
			)
		)
		(property "Device Type" "R402H16"
			(at 0.064008 -5.517896 90)
			(unlocked yes)
			(layer "F.Fab")
			(hide yes)
			(effects
				(font
					(size 1.016 1.016)
					(thickness 0.1524)
				)
			)
		)
		(duplicate_pad_numbers_are_jumpers no)
		(fp_line
			(start 0.508 -0.9398)
			(end -0.508 -0.9398)
			(stroke
				(width 0.1524)
				(type default)
			)
			(layer "F.SilkS")
		)
		(fp_line
			(start -0.508 -0.9398)
			(end -0.508 0.9398)
			(stroke
				(width 0.1524)
				(type default)
			)
			(layer "F.SilkS")
		)
		(fp_rect
			(start -0.508 0.9398)
			(end 0.508 -0.9398)
			(stroke
				(width 0)
				(type default)
			)
			(fill no)
			(layer "F.CrtYd")
		)
		(fp_rect
			(start -0.508 0.9398)
			(end 0.508 -0.9398)
			(stroke
				(width 0)
				(type default)
			)
			(fill no)
			(layer "F.Fab")
		)
		(pad "1" smd custom
			(at 0 -0.4445 90)
			(size 0.1397 0.1397)
			(layers "F.Cu" "F.Mask" "F.Paste")
			(net "P12V_A")
			(options
				(clearance outline)
				(anchor circle)
			)
			(primitives
				(gr_poly
					(pts
						(arc
							(start -0.1778 -0.2794)
							(mid -0.249642 -0.249642)
							(end -0.2794 -0.1778)
						)
						(arc
							(start -0.2794 0.1778)
							(mid -0.249642 0.249642)
							(end -0.1778 0.2794)
						)
						(arc
							(start 0.1778 0.2794)
							(mid 0.249642 0.249642)
							(end 0.2794 0.1778)
						)
						(arc
							(start 0.2794 -0.1778)
							(mid 0.249642 -0.249642)
							(end 0.1778 -0.2794)
						)
					)
					(width 0)
					(fill yes)
				)
			)
		)
		(pad "2" smd custom
			(at 0 0.4445 90)
			(size 0.1397 0.1397)
			(layers "F.Cu" "F.Mask" "F.Paste")
			(net "SW_HDD_P12")
			(options
				(clearance outline)
				(anchor circle)
			)
			(primitives
				(gr_poly
					(pts
						(arc
							(start -0.1778 -0.2794)
							(mid -0.249642 -0.249642)
							(end -0.2794 -0.1778)
						)
						(arc
							(start -0.2794 0.1778)
							(mid -0.249642 0.249642)
							(end -0.1778 0.2794)
						)
						(arc
							(start 0.1778 0.2794)
							(mid 0.249642 0.249642)
							(end 0.2794 0.1778)
						)
						(arc
							(start 0.2794 -0.1778)
							(mid 0.249642 -0.249642)
							(end 0.1778 -0.2794)
						)
					)
					(width 0)
					(fill yes)
				)
			)
		)
	)
	(footprint ""
		(layer "F.Cu")
		(at 20.049998 -61.000894 -90)
		(property "Reference" "C353"
			(at 0 0 270)
			(layer "F.SilkS")
			(hide yes)
			(effects
				(font
					(size 1.27 1.27)
				)
			)
		)
		(property "Value" "SC10U16V6KX-2GP"
			(at -0.0762 -5.1308 270)
			(unlocked yes)
			(layer "F.Fab")
			(hide yes)
			(effects
				(font
					(size 1.016 1.016)
					(thickness 0.1524)
				)
			)
		)
		(property "Device Type" "C1206H71"
			(at -0.127 -6.6548 270)
			(unlocked yes)
			(layer "F.Fab")
			(hide yes)
			(effects
				(font
					(size 1.016 1.016)
					(thickness 0.1524)
				)
			)
		)
		(duplicate_pad_numbers_are_jumpers no)
		(fp_line
			(start -1.016 2.2352)
			(end -1.016 0.8382)
			(stroke
				(width 0.1524)
				(type default)
			)
			(layer "F.SilkS")
		)
		(fp_line
			(start 1.016 2.2352)
			(end -1.016 2.2352)
			(stroke
				(width 0.1524)
				(type default)
			)
			(layer "F.SilkS")
		)
		(fp_line
			(start 1.016 0.8382)
			(end 1.016 2.2352)
			(stroke
				(width 0.1524)
				(type default)
			)
			(layer "F.SilkS")
		)
		(fp_line
			(start -1.016 -0.8382)
			(end -1.016 -2.2352)
			(stroke
				(width 0.1524)
				(type default)
			)
			(layer "F.SilkS")
		)
		(fp_line
			(start -1.016 -2.2352)
			(end 1.016 -2.2352)
			(stroke
				(width 0.1524)
				(type default)
			)
			(layer "F.SilkS")
		)
		(fp_line
			(start 1.016 -2.2352)
			(end 1.016 -0.8382)
			(stroke
				(width 0.1524)
				(type default)
			)
			(layer "F.SilkS")
		)
		(fp_rect
			(start -1.0922 2.3114)
			(end 1.0922 -2.3114)
			(stroke
				(width 0)
				(type default)
			)
			(fill no)
			(layer "F.CrtYd")
		)
		(fp_poly
			(pts
				(xy 1.0922 -2.3114) (xy 1.0922 2.3114) (xy -1.0922 2.3114) (xy -1.0922 -2.3114)
			)
			(stroke
				(width 0)
				(type default)
			)
			(fill no)
			(layer "F.Fab")
		)
		(pad "1" smd rect
			(at 0 -1.397 270)
			(size 1.651 1.27)
			(layers "F.Cu" "F.Mask" "F.Paste")
			(net "P5V_HDD24")
		)
		(pad "2" smd rect
			(at 0 1.397 270)
			(size 1.651 1.27)
			(layers "F.Cu" "F.Mask" "F.Paste")
			(net "GND")
		)
	)
	(footprint ""
		(layer "F.Cu")
		(at 272.542 -312.704988 180)
		(property "Reference" "VIA67"
			(at 0 0 180)
			(layer "F.SilkS")
			(hide yes)
			(effects
				(font
					(size 1.27 1.27)
				)
			)
		)
		(property "Value" "100OHM-8L-1D6MM-L18L16-GP"
			(at -3.7211 -4.5085 180)
			(unlocked yes)
			(layer "F.Fab")
			(hide yes)
			(effects
				(font
					(size 1.016 1.016)
					(thickness 0.1524)
				)
			)
		)
		(property "Device Type" "VIA-PCIE-4P-394076"
			(at -3.7211 -6.0325 180)
			(unlocked yes)
			(layer "F.Fab")
			(hide yes)
			(effects
				(font
					(size 1.016 1.016)
					(thickness 0.1524)
				)
			)
		)
		(duplicate_pad_numbers_are_jumpers no)
		(fp_rect
			(start -1.9685 0.381)
			(end 1.9685 -0.381)
			(stroke
				(width 0)
				(type default)
			)
			(fill no)
			(layer "F.CrtYd")
		)
		(fp_rect
			(start -1.9685 0.381)
			(end 1.9685 -0.381)
			(stroke
				(width 0)
				(type default)
			)
			(fill no)
			(layer "F.Fab")
		)
		(pad "1" thru_hole circle
			(at -1.5875 0 180)
			(size 0.508 0.508)
			(drill 0.254)
			(layers "*.Cu" "*.Mask")
			(remove_unused_layers no)
			(net "GND")
			(clearance 0.127)
			(thermal_gap 0.127)
		)
		(pad "2" thru_hole circle
			(at -0.5715 0 180)
			(size 0.508 0.508)
			(drill 0.254)
			(layers "*.Cu" "*.Mask")
			(remove_unused_layers no)
			(net "PHY_SCC_A_TO_DRV_A_26_DP")
			(clearance 0.127)
			(thermal_gap 0.127)
		)
		(pad "3" thru_hole circle
			(at 0.5715 0 180)
			(size 0.508 0.508)
			(drill 0.254)
			(layers "*.Cu" "*.Mask")
			(remove_unused_layers no)
			(net "PHY_SCC_A_TO_DRV_A_26_DN")
			(clearance 0.127)
			(thermal_gap 0.127)
		)
		(pad "4" thru_hole circle
			(at 1.5875 0 180)
			(size 0.508 0.508)
			(drill 0.254)
			(layers "*.Cu" "*.Mask")
			(remove_unused_layers no)
			(net "GND")
			(clearance 0.127)
			(thermal_gap 0.127)
		)
	)
	(footprint ""
		(layer "F.Cu")
		(at 370.8908 -132.1054)
		(property "Reference" "C564"
			(at 0 0 0)
			(layer "F.SilkS")
			(hide yes)
			(effects
				(font
					(size 1.27 1.27)
				)
			)
		)
		(property "Value" "SCD1U25V2KX-2-GP"
			(at 1.1811 -2.7051 0)
			(unlocked yes)
			(layer "F.Fab")
			(hide yes)
			(effects
				(font
					(size 1.016 1.016)
					(thickness 0.1524)
				)
			)
		)
		(property "Device Type" "C402H22"
			(at 1.1811 -4.2291 0)
			(unlocked yes)
			(layer "F.Fab")
			(hide yes)
			(effects
				(font
					(size 1.016 1.016)
					(thickness 0.1524)
				)
			)
		)
		(duplicate_pad_numbers_are_jumpers no)
		(fp_rect
			(start -0.4318 0.9525)
			(end 0.4318 -0.9525)
			(stroke
				(width 0)
				(type default)
			)
			(fill no)
			(layer "F.CrtYd")
		)
		(fp_rect
			(start -0.4318 0.9525)
			(end 0.4318 -0.9525)
			(stroke
				(width 0)
				(type default)
			)
			(fill no)
			(layer "F.Fab")
		)
		(pad "1" smd custom
			(at 0 -0.4445)
			(size 0.1524 0.1524)
			(layers "F.Cu" "F.Mask" "F.Paste")
			(net "MB1_ISTART_R")
			(options
				(clearance outline)
				(anchor circle)
			)
			(primitives
				(gr_poly
					(pts
						(arc
							(start 0.3048 -0.2032)
							(mid 0.275042 -0.275042)
							(end 0.2032 -0.3048)
						)
						(arc
							(start -0.2032 -0.3048)
							(mid -0.275042 -0.275042)
							(end -0.3048 -0.2032)
						)
						(arc
							(start -0.3048 0.2032)
							(mid -0.275042 0.275042)
							(end -0.2032 0.3048)
						)
						(arc
							(start 0.2032 0.3048)
							(mid 0.275042 0.275042)
							(end 0.3048 0.2032)
						)
					)
					(width 0)
					(fill yes)
				)
			)
		)
		(pad "2" smd custom
			(at 0 0.4445)
			(size 0.1524 0.1524)
			(layers "F.Cu" "F.Mask" "F.Paste")
			(net "AGND_CURRENT_MONOB")
			(options
				(clearance outline)
				(anchor circle)
			)
			(primitives
				(gr_poly
					(pts
						(arc
							(start 0.3048 -0.2032)
							(mid 0.275042 -0.275042)
							(end 0.2032 -0.3048)
						)
						(arc
							(start -0.2032 -0.3048)
							(mid -0.275042 -0.275042)
							(end -0.3048 -0.2032)
						)
						(arc
							(start -0.3048 0.2032)
							(mid -0.275042 0.275042)
							(end -0.2032 0.3048)
						)
						(arc
							(start 0.2032 0.3048)
							(mid 0.275042 0.275042)
							(end 0.3048 0.2032)
						)
					)
					(width 0)
					(fill yes)
				)
			)
		)
	)
	(footprint ""
		(layer "F.Cu")
		(at 190.246 -169.926)
		(property "Reference" "R525"
			(at 0 0 0)
			(layer "F.SilkS")
			(hide yes)
			(effects
				(font
					(size 1.27 1.27)
				)
			)
		)
		(property "Value" "220R3F-1-GP"
			(at -0.0254 -2.5146 0)
			(unlocked yes)
			(layer "F.Fab")
			(hide yes)
			(effects
				(font
					(size 1.016 1.016)
					(thickness 0.1524)
				)
			)
		)
		(property "Device Type" "R603H22"
			(at -0.0254 -4.0386 0)
			(unlocked yes)
			(layer "F.Fab")
			(hide yes)
			(effects
				(font
					(size 1.016 1.016)
					(thickness 0.1524)
				)
			)
		)
		(duplicate_pad_numbers_are_jumpers no)
		(fp_line
			(start -0.4826 0)
			(end -0.2032 0)
			(stroke
				(width 0.2032)
				(type default)
			)
			(layer "F.SilkS")
		)
		(fp_line
			(start 0.2032 0)
			(end 0.4826 0)
			(stroke
				(width 0.2032)
				(type default)
			)
			(layer "F.SilkS")
		)
		(fp_rect
			(start -0.5842 1.3335)
			(end 0.5842 -1.3335)
			(stroke
				(width 0)
				(type default)
			)
			(fill no)
			(layer "F.CrtYd")
		)
		(fp_rect
			(start -0.5842 1.3335)
			(end 0.5842 -1.3335)
			(stroke
				(width 0)
				(type default)
			)
			(fill no)
			(layer "F.Fab")
		)
		(pad "1" smd custom
			(at 0 -0.762)
			(size 0.2159 0.2159)
			(layers "F.Cu" "F.Mask" "F.Paste")
			(net "HDD_PRSNT_17")
			(options
				(clearance outline)
				(anchor circle)
			)
			(primitives
				(gr_poly
					(pts
						(arc
							(start -0.3302 -0.4318)
							(mid -0.402042 -0.402042)
							(end -0.4318 -0.3302)
						)
						(arc
							(start -0.4318 0.3302)
							(mid -0.402042 0.402042)
							(end -0.3302 0.4318)
						)
						(arc
							(start 0.3302 0.4318)
							(mid 0.402042 0.402042)
							(end 0.4318 0.3302)
						)
						(arc
							(start 0.4318 -0.3302)
							(mid 0.402042 -0.402042)
							(end 0.3302 -0.4318)
						)
					)
					(width 0)
					(fill yes)
				)
			)
		)
		(pad "2" smd custom
			(at 0 0.762)
			(size 0.2159 0.2159)
			(layers "F.Cu" "F.Mask" "F.Paste")
			(net "DRIVE_A_17_INS")
			(options
				(clearance outline)
				(anchor circle)
			)
			(primitives
				(gr_poly
					(pts
						(arc
							(start -0.3302 -0.4318)
							(mid -0.402042 -0.402042)
							(end -0.4318 -0.3302)
						)
						(arc
							(start -0.4318 0.3302)
							(mid -0.402042 0.402042)
							(end -0.3302 0.4318)
						)
						(arc
							(start 0.3302 0.4318)
							(mid 0.402042 0.402042)
							(end 0.4318 0.3302)
						)
						(arc
							(start 0.4318 -0.3302)
							(mid 0.402042 -0.402042)
							(end 0.3302 -0.4318)
						)
					)
					(width 0)
					(fill yes)
				)
			)
		)
	)
	(footprint ""
		(layer "F.Cu")
		(at 141.017498 -275.633942 90)
		(property "Reference" "R236"
			(at 0 0 90)
			(layer "F.SilkS")
			(hide yes)
			(effects
				(font
					(size 1.27 1.27)
				)
			)
		)
		(property "Value" "4K7R2J-2-GP"
			(at 0.064008 -3.993896 90)
			(unlocked yes)
			(layer "F.Fab")
			(hide yes)
			(effects
				(font
					(size 1.016 1.016)
					(thickness 0.1524)
				)
			)
		)
		(property "Device Type" "R402H16"
			(at 0.064008 -5.517896 90)
			(unlocked yes)
			(layer "F.Fab")
			(hide yes)
			(effects
				(font
					(size 1.016 1.016)
					(thickness 0.1524)
				)
			)
		)
		(duplicate_pad_numbers_are_jumpers no)
		(fp_line
			(start 0.508 -0.9398)
			(end -0.508 -0.9398)
			(stroke
				(width 0.1524)
				(type default)
			)
			(layer "F.SilkS")
		)
		(fp_line
			(start -0.508 -0.9398)
			(end -0.508 0.9398)
			(stroke
				(width 0.1524)
				(type default)
			)
			(layer "F.SilkS")
		)
		(fp_rect
			(start -0.508 0.9398)
			(end 0.508 -0.9398)
			(stroke
				(width 0)
				(type default)
			)
			(fill no)
			(layer "F.CrtYd")
		)
		(fp_rect
			(start -0.508 0.9398)
			(end 0.508 -0.9398)
			(stroke
				(width 0)
				(type default)
			)
			(fill no)
			(layer "F.Fab")
		)
		(pad "1" smd custom
			(at 0 -0.4445 90)
			(size 0.1397 0.1397)
			(layers "F.Cu" "F.Mask" "F.Paste")
			(net "P12V_A")
			(options
				(clearance outline)
				(anchor circle)
			)
			(primitives
				(gr_poly
					(pts
						(arc
							(start -0.1778 -0.2794)
							(mid -0.249642 -0.249642)
							(end -0.2794 -0.1778)
						)
						(arc
							(start -0.2794 0.1778)
							(mid -0.249642 0.249642)
							(end -0.1778 0.2794)
						)
						(arc
							(start 0.1778 0.2794)
							(mid 0.249642 0.249642)
							(end 0.2794 0.1778)
						)
						(arc
							(start 0.2794 -0.1778)
							(mid 0.249642 -0.249642)
							(end 0.1778 -0.2794)
						)
					)
					(width 0)
					(fill yes)
				)
			)
		)
		(pad "2" smd custom
			(at 0 0.4445 90)
			(size 0.1397 0.1397)
			(layers "F.Cu" "F.Mask" "F.Paste")
			(net "SW_HDD_R4")
			(options
				(clearance outline)
				(anchor circle)
			)
			(primitives
				(gr_poly
					(pts
						(arc
							(start -0.1778 -0.2794)
							(mid -0.249642 -0.249642)
							(end -0.2794 -0.1778)
						)
						(arc
							(start -0.2794 0.1778)
							(mid -0.249642 0.249642)
							(end -0.1778 0.2794)
						)
						(arc
							(start 0.1778 0.2794)
							(mid 0.249642 0.249642)
							(end 0.2794 0.1778)
						)
						(arc
							(start 0.2794 -0.1778)
							(mid 0.249642 -0.249642)
							(end 0.1778 -0.2794)
						)
					)
					(width 0)
					(fill yes)
				)
			)
		)
	)
	(footprint ""
		(layer "F.Cu")
		(at 145.106898 -294.683942 90)
		(property "Reference" "R225"
			(at 0 0 90)
			(layer "F.SilkS")
			(hide yes)
			(effects
				(font
					(size 1.27 1.27)
				)
			)
		)
		(property "Value" "2R6F-GP"
			(at -0.0508 -4.8514 90)
			(unlocked yes)
			(layer "F.Fab")
			(hide yes)
			(effects
				(font
					(size 1.016 1.016)
					(thickness 0.1524)
				)
			)
		)
		(property "Device Type" "R1206H26"
			(at 0 -6.3754 90)
			(unlocked yes)
			(layer "F.Fab")
			(hide yes)
			(effects
				(font
					(size 1.016 1.016)
					(thickness 0.1524)
				)
			)
		)
		(duplicate_pad_numbers_are_jumpers no)
		(fp_line
			(start 1.016 -2.2352)
			(end 1.016 2.2352)
			(stroke
				(width 0.1524)
				(type default)
			)
			(layer "F.SilkS")
		)
		(fp_line
			(start -1.016 -2.2352)
			(end 1.016 -2.2352)
			(stroke
				(width 0.1524)
				(type default)
			)
			(layer "F.SilkS")
		)
		(fp_line
			(start 1.016 2.2352)
			(end -1.016 2.2352)
			(stroke
				(width 0.1524)
				(type default)
			)
			(layer "F.SilkS")
		)
		(fp_line
			(start -1.016 2.2352)
			(end -1.016 -2.2352)
			(stroke
				(width 0.1524)
				(type default)
			)
			(layer "F.SilkS")
		)
		(fp_rect
			(start -1.0922 2.3114)
			(end 1.0922 -2.3114)
			(stroke
				(width 0)
				(type default)
			)
			(fill no)
			(layer "F.CrtYd")
		)
		(fp_poly
			(pts
				(xy -1.0922 -2.3114) (xy 1.0922 -2.3114) (xy 1.0922 2.3114) (xy -1.0922 2.3114)
			)
			(stroke
				(width 0)
				(type default)
			)
			(fill no)
			(layer "F.Fab")
		)
		(pad "1" smd rect
			(at 0 -1.397 90)
			(size 1.651 1.27)
			(layers "F.Cu" "F.Mask" "F.Paste")
			(net "P12V_HDD4")
		)
		(pad "2" smd rect
			(at 0 1.397 90)
			(size 1.651 1.27)
			(layers "F.Cu" "F.Mask" "F.Paste")
			(net "12V_PRE_4")
		)
	)
	(footprint ""
		(layer "F.Cu")
		(at 113.556796 -179.683918 90)
		(property "Reference" "R476"
			(at 0 0 90)
			(layer "F.SilkS")
			(hide yes)
			(effects
				(font
					(size 1.27 1.27)
				)
			)
		)
		(property "Value" "2R6F-GP"
			(at -0.0508 -4.8514 90)
			(unlocked yes)
			(layer "F.Fab")
			(hide yes)
			(effects
				(font
					(size 1.016 1.016)
					(thickness 0.1524)
				)
			)
		)
		(property "Device Type" "R1206H26"
			(at 0 -6.3754 90)
			(unlocked yes)
			(layer "F.Fab")
			(hide yes)
			(effects
				(font
					(size 1.016 1.016)
					(thickness 0.1524)
				)
			)
		)
		(duplicate_pad_numbers_are_jumpers no)
		(fp_line
			(start 1.016 -2.2352)
			(end 1.016 2.2352)
			(stroke
				(width 0.1524)
				(type default)
			)
			(layer "F.SilkS")
		)
		(fp_line
			(start -1.016 -2.2352)
			(end 1.016 -2.2352)
			(stroke
				(width 0.1524)
				(type default)
			)
			(layer "F.SilkS")
		)
		(fp_line
			(start 1.016 2.2352)
			(end -1.016 2.2352)
			(stroke
				(width 0.1524)
				(type default)
			)
			(layer "F.SilkS")
		)
		(fp_line
			(start -1.016 2.2352)
			(end -1.016 -2.2352)
			(stroke
				(width 0.1524)
				(type default)
			)
			(layer "F.SilkS")
		)
		(fp_rect
			(start -1.0922 2.3114)
			(end 1.0922 -2.3114)
			(stroke
				(width 0)
				(type default)
			)
			(fill no)
			(layer "F.CrtYd")
		)
		(fp_poly
			(pts
				(xy -1.0922 -2.3114) (xy 1.0922 -2.3114) (xy 1.0922 2.3114) (xy -1.0922 2.3114)
			)
			(stroke
				(width 0)
				(type default)
			)
			(fill no)
			(layer "F.Fab")
		)
		(pad "1" smd rect
			(at 0 -1.397 90)
			(size 1.651 1.27)
			(layers "F.Cu" "F.Mask" "F.Paste")
			(net "P12V_HDD15")
		)
		(pad "2" smd rect
			(at 0 1.397 90)
			(size 1.651 1.27)
			(layers "F.Cu" "F.Mask" "F.Paste")
			(net "12V_PRE_15")
		)
	)
	(footprint ""
		(layer "F.Cu")
		(at 117.646196 -161.014918 -90)
		(property "Reference" "R483"
			(at 0 0 270)
			(layer "F.SilkS")
			(hide yes)
			(effects
				(font
					(size 1.27 1.27)
				)
			)
		)
		(property "Value" "1KR2F-3-GP"
			(at 0.064008 -3.993896 270)
			(unlocked yes)
			(layer "F.Fab")
			(hide yes)
			(effects
				(font
					(size 1.016 1.016)
					(thickness 0.1524)
				)
			)
		)
		(property "Device Type" "R402H16"
			(at 0.064008 -5.517896 270)
			(unlocked yes)
			(layer "F.Fab")
			(hide yes)
			(effects
				(font
					(size 1.016 1.016)
					(thickness 0.1524)
				)
			)
		)
		(duplicate_pad_numbers_are_jumpers no)
		(fp_line
			(start -0.508 -0.9398)
			(end -0.508 0.9398)
			(stroke
				(width 0.1524)
				(type default)
			)
			(layer "F.SilkS")
		)
		(fp_line
			(start 0.508 -0.9398)
			(end -0.508 -0.9398)
			(stroke
				(width 0.1524)
				(type default)
			)
			(layer "F.SilkS")
		)
		(fp_rect
			(start -0.508 0.9398)
			(end 0.508 -0.9398)
			(stroke
				(width 0)
				(type default)
			)
			(fill no)
			(layer "F.CrtYd")
		)
		(fp_rect
			(start -0.508 0.9398)
			(end 0.508 -0.9398)
			(stroke
				(width 0)
				(type default)
			)
			(fill no)
			(layer "F.Fab")
		)
		(pad "1" smd custom
			(at 0 -0.4445 270)
			(size 0.1397 0.1397)
			(layers "F.Cu" "F.Mask" "F.Paste")
			(net "P3V3_STBY_A")
			(options
				(clearance outline)
				(anchor circle)
			)
			(primitives
				(gr_poly
					(pts
						(arc
							(start -0.1778 -0.2794)
							(mid -0.249642 -0.249642)
							(end -0.2794 -0.1778)
						)
						(arc
							(start -0.2794 0.1778)
							(mid -0.249642 0.249642)
							(end -0.1778 0.2794)
						)
						(arc
							(start 0.1778 0.2794)
							(mid 0.249642 0.249642)
							(end 0.2794 0.1778)
						)
						(arc
							(start 0.2794 -0.1778)
							(mid 0.249642 -0.249642)
							(end 0.1778 -0.2794)
						)
					)
					(width 0)
					(fill yes)
				)
			)
		)
		(pad "2" smd custom
			(at 0 0.4445 270)
			(size 0.1397 0.1397)
			(layers "F.Cu" "F.Mask" "F.Paste")
			(net "SW_PWR_R_HDD15")
			(options
				(clearance outline)
				(anchor circle)
			)
			(primitives
				(gr_poly
					(pts
						(arc
							(start -0.1778 -0.2794)
							(mid -0.249642 -0.249642)
							(end -0.2794 -0.1778)
						)
						(arc
							(start -0.2794 0.1778)
							(mid -0.249642 0.249642)
							(end -0.1778 0.2794)
						)
						(arc
							(start 0.1778 0.2794)
							(mid 0.249642 0.249642)
							(end 0.2794 0.1778)
						)
						(arc
							(start 0.2794 -0.1778)
							(mid 0.249642 -0.249642)
							(end 0.1778 -0.2794)
						)
					)
					(width 0)
					(fill yes)
				)
			)
		)
	)
	(footprint ""
		(layer "F.Cu")
		(at 244.856 -249.174 180)
		(property "Reference" "R46"
			(at 0 0 180)
			(layer "F.SilkS")
			(hide yes)
			(effects
				(font
					(size 1.27 1.27)
				)
			)
		)
		(property "Value" "4K7R2F-GP"
			(at 0.064008 -3.993896 180)
			(unlocked yes)
			(layer "F.Fab")
			(hide yes)
			(effects
				(font
					(size 1.016 1.016)
					(thickness 0.1524)
				)
			)
		)
		(property "Device Type" "R402H16"
			(at 0.064008 -5.517896 180)
			(unlocked yes)
			(layer "F.Fab")
			(hide yes)
			(effects
				(font
					(size 1.016 1.016)
					(thickness 0.1524)
				)
			)
		)
		(duplicate_pad_numbers_are_jumpers no)
		(fp_line
			(start 0.508 -0.9398)
			(end -0.508 -0.9398)
			(stroke
				(width 0.1524)
				(type default)
			)
			(layer "F.SilkS")
		)
		(fp_line
			(start -0.508 -0.9398)
			(end -0.508 0.9398)
			(stroke
				(width 0.1524)
				(type default)
			)
			(layer "F.SilkS")
		)
		(fp_rect
			(start -0.508 0.9398)
			(end 0.508 -0.9398)
			(stroke
				(width 0)
				(type default)
			)
			(fill no)
			(layer "F.CrtYd")
		)
		(fp_rect
			(start -0.508 0.9398)
			(end 0.508 -0.9398)
			(stroke
				(width 0)
				(type default)
			)
			(fill no)
			(layer "F.Fab")
		)
		(pad "1" smd custom
			(at 0 -0.4445 180)
			(size 0.1397 0.1397)
			(layers "F.Cu" "F.Mask" "F.Paste")
			(net "P3V3_STBY_A")
			(options
				(clearance outline)
				(anchor circle)
			)
			(primitives
				(gr_poly
					(pts
						(arc
							(start -0.1778 -0.2794)
							(mid -0.249642 -0.249642)
							(end -0.2794 -0.1778)
						)
						(arc
							(start -0.2794 0.1778)
							(mid -0.249642 0.249642)
							(end -0.1778 0.2794)
						)
						(arc
							(start 0.1778 0.2794)
							(mid 0.249642 0.249642)
							(end 0.2794 0.1778)
						)
						(arc
							(start 0.2794 -0.1778)
							(mid 0.249642 -0.249642)
							(end 0.1778 -0.2794)
						)
					)
					(width 0)
					(fill yes)
				)
			)
		)
		(pad "2" smd custom
			(at 0 0.4445 180)
			(size 0.1397 0.1397)
			(layers "F.Cu" "F.Mask" "F.Paste")
			(net "IO_EXP5_A2")
			(options
				(clearance outline)
				(anchor circle)
			)
			(primitives
				(gr_poly
					(pts
						(arc
							(start -0.1778 -0.2794)
							(mid -0.249642 -0.249642)
							(end -0.2794 -0.1778)
						)
						(arc
							(start -0.2794 0.1778)
							(mid -0.249642 0.249642)
							(end -0.1778 0.2794)
						)
						(arc
							(start 0.1778 0.2794)
							(mid 0.249642 0.249642)
							(end 0.2794 0.1778)
						)
						(arc
							(start 0.2794 -0.1778)
							(mid 0.249642 -0.249642)
							(end 0.1778 -0.2794)
						)
					)
					(width 0)
					(fill yes)
				)
			)
		)
	)
	(footprint ""
		(layer "F.Cu")
		(at 64.013334 -274.219416 90)
		(property "Reference" "C51"
			(at 0 0 90)
			(layer "F.SilkS")
			(hide yes)
			(effects
				(font
					(size 1.27 1.27)
				)
			)
		)
		(property "Value" "SCD01U16V1KX-GP"
			(at -2.8321 -1.7399 90)
			(unlocked yes)
			(layer "F.Fab")
			(hide yes)
			(effects
				(font
					(size 1.016 1.016)
					(thickness 0.1524)
				)
			)
		)
		(property "Device Type" "C0201H13"
			(at -2.8321 -3.2639 90)
			(unlocked yes)
			(layer "F.Fab")
			(hide yes)
			(effects
				(font
					(size 1.016 1.016)
					(thickness 0.1524)
				)
			)
		)
		(duplicate_pad_numbers_are_jumpers no)
		(fp_rect
			(start -0.2794 0.6477)
			(end 0.2794 -0.6477)
			(stroke
				(width 0)
				(type default)
			)
			(fill no)
			(layer "F.CrtYd")
		)
		(fp_rect
			(start -0.2794 0.6477)
			(end 0.2794 -0.6477)
			(stroke
				(width 0)
				(type default)
			)
			(fill no)
			(layer "F.Fab")
		)
		(pad "1" smd custom
			(at 0 -0.2794 90)
			(size 0.0762 0.0762)
			(layers "F.Cu" "F.Mask" "F.Paste")
			(net "SAS_HDD_RX_N1")
			(options
				(clearance outline)
				(anchor circle)
			)
			(primitives
				(gr_poly
					(pts
						(arc
							(start 0.1524 -0.127)
							(mid 0.137521 -0.162921)
							(end 0.1016 -0.1778)
						)
						(arc
							(start -0.1016 -0.1778)
							(mid -0.137521 -0.162921)
							(end -0.1524 -0.127)
						)
						(arc
							(start -0.1524 0.127)
							(mid -0.137521 0.162921)
							(end -0.1016 0.1778)
						)
						(arc
							(start 0.1016 0.1778)
							(mid 0.137521 0.162921)
							(end 0.1524 0.127)
						)
					)
					(width 0)
					(fill yes)
				)
			)
		)
		(pad "2" smd custom
			(at 0 0.2794 90)
			(size 0.0762 0.0762)
			(layers "F.Cu" "F.Mask" "F.Paste")
			(net "PHY_SCC_A_TO_DRV_A_1_DN")
			(options
				(clearance outline)
				(anchor circle)
			)
			(primitives
				(gr_poly
					(pts
						(arc
							(start 0.1524 -0.127)
							(mid 0.137521 -0.162921)
							(end 0.1016 -0.1778)
						)
						(arc
							(start -0.1016 -0.1778)
							(mid -0.137521 -0.162921)
							(end -0.1524 -0.127)
						)
						(arc
							(start -0.1524 0.127)
							(mid -0.137521 0.162921)
							(end -0.1016 0.1778)
						)
						(arc
							(start 0.1016 0.1778)
							(mid 0.137521 0.162921)
							(end 0.1524 0.127)
						)
					)
					(width 0)
					(fill yes)
				)
			)
		)
	)
	(footprint ""
		(layer "F.Cu")
		(at 161.743898 -183.747918)
		(property "Reference" "TP82"
			(at 0 0 0)
			(layer "F.SilkS")
			(hide yes)
			(effects
				(font
					(size 1.27 1.27)
				)
			)
		)
		(property "Value" "TPAD32-GP"
			(at -0.0508 -1.6764 0)
			(unlocked yes)
			(layer "F.Fab")
			(hide yes)
			(effects
				(font
					(size 1.016 1.016)
					(thickness 0.1524)
				)
			)
		)
		(property "Device Type" "TPAD32"
			(at -0.0508 -3.2004 0)
			(unlocked yes)
			(layer "F.Fab")
			(hide yes)
			(effects
				(font
					(size 1.016 1.016)
					(thickness 0.1524)
				)
			)
		)
		(duplicate_pad_numbers_are_jumpers no)
		(fp_poly
			(pts
				(arc
					(start 0.4064 0)
					(mid -0.4064 0)
					(end 0.4064 0)
				)
			)
			(stroke
				(width 0)
				(type default)
			)
			(fill no)
			(layer "F.CrtYd")
		)
		(fp_poly
			(pts
				(arc
					(start 0.7112 0)
					(mid -0.7112 0)
					(end 0.7112 0)
				)
			)
			(stroke
				(width 0)
				(type default)
			)
			(fill no)
			(layer "F.Fab")
		)
		(pad "1" smd circle
			(at 0 0)
			(size 0.8128 0.8128)
			(layers "F.Cu" "F.Mask" "F.Paste")
			(net "ACT_HDD_16")
		)
	)
	(footprint ""
		(layer "F.Cu")
		(at 366.449102 -52.872894 -90)
		(property "Reference" "Q185"
			(at 0 0 270)
			(layer "F.SilkS")
			(hide yes)
			(effects
				(font
					(size 1.27 1.27)
				)
			)
		)
		(property "Value" "AO4406AL-GP"
			(at -3.707384 -1.5367 270)
			(unlocked yes)
			(layer "F.Fab")
			(hide yes)
			(effects
				(font
					(size 1.016 1.016)
					(thickness 0.1524)
				)
			)
		)
		(property "Device Type" "SOIC8H69"
			(at -3.707384 -3.0607 270)
			(unlocked yes)
			(layer "F.Fab")
			(hide yes)
			(effects
				(font
					(size 1.016 1.016)
					(thickness 0.1524)
				)
			)
		)
		(duplicate_pad_numbers_are_jumpers no)
		(fp_line
			(start -2.6289 3.4417)
			(end -2.6289 1.4732)
			(stroke
				(width 0.381)
				(type default)
			)
			(layer "F.SilkS")
		)
		(fp_line
			(start -2.7432 1.4224)
			(end -2.6416 1.4224)
			(stroke
				(width 0.1524)
				(type default)
			)
			(layer "F.SilkS")
		)
		(fp_line
			(start -2.7432 1.4224)
			(end 2.1336 1.4224)
			(stroke
				(width 0.1524)
				(type default)
			)
			(layer "F.SilkS")
		)
		(fp_line
			(start 2.1336 1.4224)
			(end 2.1336 -1.4224)
			(stroke
				(width 0.1524)
				(type default)
			)
			(layer "F.SilkS")
		)
		(fp_line
			(start -2.1844 -0.0508)
			(end -2.7178 0.508)
			(stroke
				(width 0.1524)
				(type default)
			)
			(layer "F.SilkS")
		)
		(fp_line
			(start -2.7178 -0.508)
			(end -2.1844 -0.0508)
			(stroke
				(width 0.1524)
				(type default)
			)
			(layer "F.SilkS")
		)
		(fp_line
			(start -2.7432 -1.4224)
			(end -2.7432 1.4224)
			(stroke
				(width 0.1524)
				(type default)
			)
			(layer "F.SilkS")
		)
		(fp_line
			(start 2.1336 -1.4224)
			(end -2.7432 -1.4224)
			(stroke
				(width 0.1524)
				(type default)
			)
			(layer "F.SilkS")
		)
		(fp_poly
			(pts
				(xy -2.2098 -1.4224) (xy -2.2098 1.4224) (xy 2.2098 1.4224) (xy 2.2098 -1.4224)
			)
			(stroke
				(width 0)
				(type default)
			)
			(fill yes)
			(layer "F.SilkS")
		)
		(fp_rect
			(start -2.450084 2.999994)
			(end 2.450084 -2.999994)
			(stroke
				(width 0)
				(type default)
			)
			(fill no)
			(layer "F.CrtYd")
		)
		(fp_poly
			(pts
				(xy -2.8194 3.6322) (xy -2.8194 -3.6322) (xy 2.8194 -3.6322) (xy 2.8194 1.18364) (xy 2.450084 1.18364)
				(xy 2.450084 -2.999994) (xy -2.450084 -2.999994) (xy -2.450084 2.999994) (xy 2.450084 2.999994)
				(xy 2.450084 1.18618) (xy 2.8194 1.18618) (xy 2.8194 3.6322)
			)
			(stroke
				(width 0)
				(type default)
			)
			(fill no)
			(layer "F.CrtYd")
		)
		(fp_rect
			(start -2.8194 3.6322)
			(end 2.8194 -3.6322)
			(stroke
				(width 0)
				(type default)
			)
			(fill no)
			(layer "F.Fab")
		)
		(pad "1" smd rect
			(at -1.905 2.54 270)
			(size 0.635 1.651)
			(layers "F.Cu" "F.Mask" "F.Paste")
			(net "P5V_HDD31")
		)
		(pad "2" smd rect
			(at -0.635 2.54 270)
			(size 0.635 1.651)
			(layers "F.Cu" "F.Mask" "F.Paste")
			(net "P5V_HDD31")
		)
		(pad "3" smd rect
			(at 0.635 2.54 270)
			(size 0.635 1.651)
			(layers "F.Cu" "F.Mask" "F.Paste")
			(net "P5V_HDD31")
		)
		(pad "4" smd rect
			(at 1.905 2.54 270)
			(size 0.635 1.651)
			(layers "F.Cu" "F.Mask" "F.Paste")
			(net "SW_HDD_P31")
		)
		(pad "5" smd rect
			(at 1.905 -2.54 270)
			(size 0.635 1.651)
			(layers "F.Cu" "F.Mask" "F.Paste")
			(net "P5V_A_4")
		)
		(pad "6" smd rect
			(at 0.635 -2.54 270)
			(size 0.635 1.651)
			(layers "F.Cu" "F.Mask" "F.Paste")
			(net "P5V_A_4")
		)
		(pad "7" smd rect
			(at -0.635 -2.54 270)
			(size 0.635 1.651)
			(layers "F.Cu" "F.Mask" "F.Paste")
			(net "P5V_A_4")
		)
		(pad "8" smd rect
			(at -1.905 -2.54 270)
			(size 0.635 1.651)
			(layers "F.Cu" "F.Mask" "F.Paste")
			(net "P5V_A_4")
		)
	)
	(footprint ""
		(layer "F.Cu")
		(at 46.415706 -279.156922 90)
		(property "Reference" "R169"
			(at 0 0 90)
			(layer "F.SilkS")
			(hide yes)
			(effects
				(font
					(size 1.27 1.27)
				)
			)
		)
		(property "Value" "200KR2F-L-GP"
			(at 0.064008 -3.993896 90)
			(unlocked yes)
			(layer "F.Fab")
			(hide yes)
			(effects
				(font
					(size 1.016 1.016)
					(thickness 0.1524)
				)
			)
		)
		(property "Device Type" "R402H16"
			(at 0.064008 -5.517896 90)
			(unlocked yes)
			(layer "F.Fab")
			(hide yes)
			(effects
				(font
					(size 1.016 1.016)
					(thickness 0.1524)
				)
			)
		)
		(duplicate_pad_numbers_are_jumpers no)
		(fp_line
			(start 0.508 -0.9398)
			(end -0.508 -0.9398)
			(stroke
				(width 0.1524)
				(type default)
			)
			(layer "F.SilkS")
		)
		(fp_line
			(start -0.508 -0.9398)
			(end -0.508 0.9398)
			(stroke
				(width 0.1524)
				(type default)
			)
			(layer "F.SilkS")
		)
		(fp_rect
			(start -0.508 0.9398)
			(end 0.508 -0.9398)
			(stroke
				(width 0)
				(type default)
			)
			(fill no)
			(layer "F.CrtYd")
		)
		(fp_rect
			(start -0.508 0.9398)
			(end 0.508 -0.9398)
			(stroke
				(width 0)
				(type default)
			)
			(fill no)
			(layer "F.Fab")
		)
		(pad "1" smd custom
			(at 0 -0.4445 90)
			(size 0.1397 0.1397)
			(layers "F.Cu" "F.Mask" "F.Paste")
			(net "SW_HDD_R1")
			(options
				(clearance outline)
				(anchor circle)
			)
			(primitives
				(gr_poly
					(pts
						(arc
							(start -0.1778 -0.2794)
							(mid -0.249642 -0.249642)
							(end -0.2794 -0.1778)
						)
						(arc
							(start -0.2794 0.1778)
							(mid -0.249642 0.249642)
							(end -0.1778 0.2794)
						)
						(arc
							(start 0.1778 0.2794)
							(mid 0.249642 0.249642)
							(end 0.2794 0.1778)
						)
						(arc
							(start 0.2794 -0.1778)
							(mid 0.249642 -0.249642)
							(end 0.1778 -0.2794)
						)
					)
					(width 0)
					(fill yes)
				)
			)
		)
		(pad "2" smd custom
			(at 0 0.4445 90)
			(size 0.1397 0.1397)
			(layers "F.Cu" "F.Mask" "F.Paste")
			(net "SW_HDD_N1")
			(options
				(clearance outline)
				(anchor circle)
			)
			(primitives
				(gr_poly
					(pts
						(arc
							(start -0.1778 -0.2794)
							(mid -0.249642 -0.249642)
							(end -0.2794 -0.1778)
						)
						(arc
							(start -0.2794 0.1778)
							(mid -0.249642 0.249642)
							(end -0.1778 0.2794)
						)
						(arc
							(start 0.1778 0.2794)
							(mid 0.249642 0.249642)
							(end 0.2794 0.1778)
						)
						(arc
							(start 0.2794 -0.1778)
							(mid 0.249642 -0.249642)
							(end 0.1778 -0.2794)
						)
					)
					(width 0)
					(fill yes)
				)
			)
		)
	)
	(footprint ""
		(layer "F.Cu")
		(at 237.493302 -261.133082 90)
		(property "Reference" "R40"
			(at 0 0 90)
			(layer "F.SilkS")
			(hide yes)
			(effects
				(font
					(size 1.27 1.27)
				)
			)
		)
		(property "Value" "0R2J-2-GP"
			(at 0.064008 -3.993896 90)
			(unlocked yes)
			(layer "F.Fab")
			(hide yes)
			(effects
				(font
					(size 1.016 1.016)
					(thickness 0.1524)
				)
			)
		)
		(property "Device Type" "R402H16"
			(at 0.064008 -5.517896 90)
			(unlocked yes)
			(layer "F.Fab")
			(hide yes)
			(effects
				(font
					(size 1.016 1.016)
					(thickness 0.1524)
				)
			)
		)
		(duplicate_pad_numbers_are_jumpers no)
		(fp_line
			(start 0.508 -0.9398)
			(end -0.508 -0.9398)
			(stroke
				(width 0.1524)
				(type default)
			)
			(layer "F.SilkS")
		)
		(fp_line
			(start -0.508 -0.9398)
			(end -0.508 0.9398)
			(stroke
				(width 0.1524)
				(type default)
			)
			(layer "F.SilkS")
		)
		(fp_rect
			(start -0.508 0.9398)
			(end 0.508 -0.9398)
			(stroke
				(width 0)
				(type default)
			)
			(fill no)
			(layer "F.CrtYd")
		)
		(fp_rect
			(start -0.508 0.9398)
			(end 0.508 -0.9398)
			(stroke
				(width 0)
				(type default)
			)
			(fill no)
			(layer "F.Fab")
		)
		(pad "1" smd custom
			(at 0 -0.4445 90)
			(size 0.1397 0.1397)
			(layers "F.Cu" "F.Mask" "F.Paste")
			(net "IO_EXP4_INT_N")
			(options
				(clearance outline)
				(anchor circle)
			)
			(primitives
				(gr_poly
					(pts
						(arc
							(start -0.1778 -0.2794)
							(mid -0.249642 -0.249642)
							(end -0.2794 -0.1778)
						)
						(arc
							(start -0.2794 0.1778)
							(mid -0.249642 0.249642)
							(end -0.1778 0.2794)
						)
						(arc
							(start 0.1778 0.2794)
							(mid 0.249642 0.249642)
							(end 0.2794 0.1778)
						)
						(arc
							(start 0.2794 -0.1778)
							(mid 0.249642 -0.249642)
							(end 0.1778 -0.2794)
						)
					)
					(width 0)
					(fill yes)
				)
			)
		)
		(pad "2" smd custom
			(at 0 0.4445 90)
			(size 0.1397 0.1397)
			(layers "F.Cu" "F.Mask" "F.Paste")
			(net "DRIVE_INSERT_ALERT_A_N")
			(options
				(clearance outline)
				(anchor circle)
			)
			(primitives
				(gr_poly
					(pts
						(arc
							(start -0.1778 -0.2794)
							(mid -0.249642 -0.249642)
							(end -0.2794 -0.1778)
						)
						(arc
							(start -0.2794 0.1778)
							(mid -0.249642 0.249642)
							(end -0.1778 0.2794)
						)
						(arc
							(start 0.1778 0.2794)
							(mid 0.249642 0.249642)
							(end 0.2794 0.1778)
						)
						(arc
							(start 0.2794 -0.1778)
							(mid 0.249642 -0.249642)
							(end 0.1778 -0.2794)
						)
					)
					(width 0)
					(fill yes)
				)
			)
		)
	)
	(footprint ""
		(layer "F.Cu")
		(at 118.890796 -189.462918 180)
		(property "Reference" "C242"
			(at 0 0 180)
			(layer "F.SilkS")
			(hide yes)
			(effects
				(font
					(size 1.27 1.27)
				)
			)
		)
		(property "Value" "SC1U25V3KX-GP"
			(at 0 -2.8194 180)
			(unlocked yes)
			(layer "F.Fab")
			(hide yes)
			(effects
				(font
					(size 1.016 1.016)
					(thickness 0.1524)
				)
			)
		)
		(property "Device Type" "C603H36"
			(at 0 -4.3434 180)
			(unlocked yes)
			(layer "F.Fab")
			(hide yes)
			(effects
				(font
					(size 1.016 1.016)
					(thickness 0.1524)
				)
			)
		)
		(duplicate_pad_numbers_are_jumpers no)
		(fp_line
			(start 0.508 0)
			(end -0.508 0)
			(stroke
				(width 0.2032)
				(type default)
			)
			(layer "F.SilkS")
		)
		(fp_rect
			(start -0.5842 1.3335)
			(end 0.5842 -1.3335)
			(stroke
				(width 0)
				(type default)
			)
			(fill no)
			(layer "F.CrtYd")
		)
		(fp_rect
			(start -0.5842 1.3335)
			(end 0.5842 -1.3335)
			(stroke
				(width 0)
				(type default)
			)
			(fill no)
			(layer "F.Fab")
		)
		(pad "1" smd custom
			(at 0 -0.762 180)
			(size 0.2159 0.2159)
			(layers "F.Cu" "F.Mask" "F.Paste")
			(net "P12V_HDD15")
			(options
				(clearance outline)
				(anchor circle)
			)
			(primitives
				(gr_poly
					(pts
						(arc
							(start -0.3302 -0.4318)
							(mid -0.402042 -0.402042)
							(end -0.4318 -0.3302)
						)
						(arc
							(start -0.4318 0.3302)
							(mid -0.402042 0.402042)
							(end -0.3302 0.4318)
						)
						(arc
							(start 0.3302 0.4318)
							(mid 0.402042 0.402042)
							(end 0.4318 0.3302)
						)
						(arc
							(start 0.4318 -0.3302)
							(mid 0.402042 -0.402042)
							(end 0.3302 -0.4318)
						)
					)
					(width 0)
					(fill yes)
				)
			)
		)
		(pad "2" smd custom
			(at 0 0.762 180)
			(size 0.2159 0.2159)
			(layers "F.Cu" "F.Mask" "F.Paste")
			(net "GND")
			(options
				(clearance outline)
				(anchor circle)
			)
			(primitives
				(gr_poly
					(pts
						(arc
							(start -0.3302 -0.4318)
							(mid -0.402042 -0.402042)
							(end -0.4318 -0.3302)
						)
						(arc
							(start -0.4318 0.3302)
							(mid -0.402042 0.402042)
							(end -0.3302 0.4318)
						)
						(arc
							(start 0.3302 0.4318)
							(mid 0.402042 0.402042)
							(end 0.4318 0.3302)
						)
						(arc
							(start 0.4318 -0.3302)
							(mid 0.402042 -0.402042)
							(end 0.3302 -0.4318)
						)
					)
					(width 0)
					(fill yes)
				)
			)
		)
	)
	(footprint ""
		(layer "F.Cu")
		(at 172.72 -170.158918 90)
		(property "Reference" "C270"
			(at 0 0 90)
			(layer "F.SilkS")
			(hide yes)
			(effects
				(font
					(size 1.27 1.27)
				)
			)
		)
		(property "Value" "SCD033U25V2KX-GP"
			(at 1.1811 -2.7051 90)
			(unlocked yes)
			(layer "F.Fab")
			(hide yes)
			(effects
				(font
					(size 1.016 1.016)
					(thickness 0.1524)
				)
			)
		)
		(property "Device Type" "C402H22"
			(at 1.1811 -4.2291 90)
			(unlocked yes)
			(layer "F.Fab")
			(hide yes)
			(effects
				(font
					(size 1.016 1.016)
					(thickness 0.1524)
				)
			)
		)
		(duplicate_pad_numbers_are_jumpers no)
		(fp_rect
			(start -0.4318 0.9525)
			(end 0.4318 -0.9525)
			(stroke
				(width 0)
				(type default)
			)
			(fill no)
			(layer "F.CrtYd")
		)
		(fp_rect
			(start -0.4318 0.9525)
			(end 0.4318 -0.9525)
			(stroke
				(width 0)
				(type default)
			)
			(fill no)
			(layer "F.Fab")
		)
		(pad "1" smd custom
			(at 0 -0.4445 90)
			(size 0.1524 0.1524)
			(layers "F.Cu" "F.Mask" "F.Paste")
			(net "P12V_A")
			(options
				(clearance outline)
				(anchor circle)
			)
			(primitives
				(gr_poly
					(pts
						(arc
							(start 0.3048 -0.2032)
							(mid 0.275042 -0.275042)
							(end 0.2032 -0.3048)
						)
						(arc
							(start -0.2032 -0.3048)
							(mid -0.275042 -0.275042)
							(end -0.3048 -0.2032)
						)
						(arc
							(start -0.3048 0.2032)
							(mid -0.275042 0.275042)
							(end -0.2032 0.3048)
						)
						(arc
							(start 0.2032 0.3048)
							(mid 0.275042 0.275042)
							(end 0.3048 0.2032)
						)
					)
					(width 0)
					(fill yes)
				)
			)
		)
		(pad "2" smd custom
			(at 0 0.4445 90)
			(size 0.1524 0.1524)
			(layers "F.Cu" "F.Mask" "F.Paste")
			(net "SW_HDD_N17")
			(options
				(clearance outline)
				(anchor circle)
			)
			(primitives
				(gr_poly
					(pts
						(arc
							(start 0.3048 -0.2032)
							(mid 0.275042 -0.275042)
							(end 0.2032 -0.3048)
						)
						(arc
							(start -0.2032 -0.3048)
							(mid -0.275042 -0.275042)
							(end -0.3048 -0.2032)
						)
						(arc
							(start -0.3048 0.2032)
							(mid -0.275042 0.275042)
							(end -0.2032 0.3048)
						)
						(arc
							(start 0.2032 0.3048)
							(mid 0.275042 0.275042)
							(end 0.3048 0.2032)
						)
					)
					(width 0)
					(fill yes)
				)
			)
		)
	)
	(footprint ""
		(layer "F.Cu")
		(at 191.135 -292.1)
		(property "Reference" "R245"
			(at 0 0 0)
			(layer "F.SilkS")
			(hide yes)
			(effects
				(font
					(size 1.27 1.27)
				)
			)
		)
		(property "Value" "10KR2F-2-GP"
			(at 0.064008 -3.993896 0)
			(unlocked yes)
			(layer "F.Fab")
			(hide yes)
			(effects
				(font
					(size 1.016 1.016)
					(thickness 0.1524)
				)
			)
		)
		(property "Device Type" "R402H16"
			(at 0.064008 -5.517896 0)
			(unlocked yes)
			(layer "F.Fab")
			(hide yes)
			(effects
				(font
					(size 1.016 1.016)
					(thickness 0.1524)
				)
			)
		)
		(duplicate_pad_numbers_are_jumpers no)
		(fp_line
			(start -0.508 -0.9398)
			(end -0.508 0.9398)
			(stroke
				(width 0.1524)
				(type default)
			)
			(layer "F.SilkS")
		)
		(fp_line
			(start 0.508 -0.9398)
			(end -0.508 -0.9398)
			(stroke
				(width 0.1524)
				(type default)
			)
			(layer "F.SilkS")
		)
		(fp_rect
			(start -0.508 0.9398)
			(end 0.508 -0.9398)
			(stroke
				(width 0)
				(type default)
			)
			(fill no)
			(layer "F.CrtYd")
		)
		(fp_rect
			(start -0.508 0.9398)
			(end 0.508 -0.9398)
			(stroke
				(width 0)
				(type default)
			)
			(fill no)
			(layer "F.Fab")
		)
		(pad "1" smd custom
			(at 0 -0.4445)
			(size 0.1397 0.1397)
			(layers "F.Cu" "F.Mask" "F.Paste")
			(net "P3V3_STBY_A")
			(options
				(clearance outline)
				(anchor circle)
			)
			(primitives
				(gr_poly
					(pts
						(arc
							(start -0.1778 -0.2794)
							(mid -0.249642 -0.249642)
							(end -0.2794 -0.1778)
						)
						(arc
							(start -0.2794 0.1778)
							(mid -0.249642 0.249642)
							(end -0.1778 0.2794)
						)
						(arc
							(start 0.1778 0.2794)
							(mid 0.249642 0.249642)
							(end 0.2794 0.1778)
						)
						(arc
							(start 0.2794 -0.1778)
							(mid 0.249642 -0.249642)
							(end 0.1778 -0.2794)
						)
					)
					(width 0)
					(fill yes)
				)
			)
		)
		(pad "2" smd custom
			(at 0 0.4445)
			(size 0.1397 0.1397)
			(layers "F.Cu" "F.Mask" "F.Paste")
			(net "HDD_PRSNT_5")
			(options
				(clearance outline)
				(anchor circle)
			)
			(primitives
				(gr_poly
					(pts
						(arc
							(start -0.1778 -0.2794)
							(mid -0.249642 -0.249642)
							(end -0.2794 -0.1778)
						)
						(arc
							(start -0.2794 0.1778)
							(mid -0.249642 0.249642)
							(end -0.1778 0.2794)
						)
						(arc
							(start 0.1778 0.2794)
							(mid 0.249642 0.249642)
							(end 0.2794 0.1778)
						)
						(arc
							(start 0.2794 -0.1778)
							(mid 0.249642 -0.249642)
							(end 0.1778 -0.2794)
						)
					)
					(width 0)
					(fill yes)
				)
			)
		)
	)
	(footprint ""
		(layer "F.Cu")
		(at 363.020102 -291.127942 -90)
		(property "Reference" "R290"
			(at 0 0 270)
			(layer "F.SilkS")
			(hide yes)
			(effects
				(font
					(size 1.27 1.27)
				)
			)
		)
		(property "Value" "2R6F-GP"
			(at -0.0508 -4.8514 270)
			(unlocked yes)
			(layer "F.Fab")
			(hide yes)
			(effects
				(font
					(size 1.016 1.016)
					(thickness 0.1524)
				)
			)
		)
		(property "Device Type" "R1206H26"
			(at 0 -6.3754 270)
			(unlocked yes)
			(layer "F.Fab")
			(hide yes)
			(effects
				(font
					(size 1.016 1.016)
					(thickness 0.1524)
				)
			)
		)
		(duplicate_pad_numbers_are_jumpers no)
		(fp_line
			(start -1.016 2.2352)
			(end -1.016 -2.2352)
			(stroke
				(width 0.1524)
				(type default)
			)
			(layer "F.SilkS")
		)
		(fp_line
			(start 1.016 2.2352)
			(end -1.016 2.2352)
			(stroke
				(width 0.1524)
				(type default)
			)
			(layer "F.SilkS")
		)
		(fp_line
			(start -1.016 -2.2352)
			(end 1.016 -2.2352)
			(stroke
				(width 0.1524)
				(type default)
			)
			(layer "F.SilkS")
		)
		(fp_line
			(start 1.016 -2.2352)
			(end 1.016 2.2352)
			(stroke
				(width 0.1524)
				(type default)
			)
			(layer "F.SilkS")
		)
		(fp_rect
			(start -1.0922 2.3114)
			(end 1.0922 -2.3114)
			(stroke
				(width 0)
				(type default)
			)
			(fill no)
			(layer "F.CrtYd")
		)
		(fp_poly
			(pts
				(xy -1.0922 -2.3114) (xy 1.0922 -2.3114) (xy 1.0922 2.3114) (xy -1.0922 2.3114)
			)
			(stroke
				(width 0)
				(type default)
			)
			(fill no)
			(layer "F.Fab")
		)
		(pad "1" smd rect
			(at 0 -1.397 270)
			(size 1.651 1.27)
			(layers "F.Cu" "F.Mask" "F.Paste")
			(net "P5V_HDD7")
		)
		(pad "2" smd rect
			(at 0 1.397 270)
			(size 1.651 1.27)
			(layers "F.Cu" "F.Mask" "F.Paste")
			(net "5V_PRE_7")
		)
	)
	(footprint ""
		(layer "F.Cu")
		(at 400.03095 -160.735518 180)
		(property "Reference" "R604"
			(at 0 0 180)
			(layer "F.SilkS")
			(hide yes)
			(effects
				(font
					(size 1.27 1.27)
				)
			)
		)
		(property "Value" "4K7R2J-2-GP"
			(at 0.064008 -3.993896 180)
			(unlocked yes)
			(layer "F.Fab")
			(hide yes)
			(effects
				(font
					(size 1.016 1.016)
					(thickness 0.1524)
				)
			)
		)
		(property "Device Type" "R402H16"
			(at 0.064008 -5.517896 180)
			(unlocked yes)
			(layer "F.Fab")
			(hide yes)
			(effects
				(font
					(size 1.016 1.016)
					(thickness 0.1524)
				)
			)
		)
		(duplicate_pad_numbers_are_jumpers no)
		(fp_line
			(start 0.508 -0.9398)
			(end -0.508 -0.9398)
			(stroke
				(width 0.1524)
				(type default)
			)
			(layer "F.SilkS")
		)
		(fp_line
			(start -0.508 -0.9398)
			(end -0.508 0.9398)
			(stroke
				(width 0.1524)
				(type default)
			)
			(layer "F.SilkS")
		)
		(fp_rect
			(start -0.508 0.9398)
			(end 0.508 -0.9398)
			(stroke
				(width 0)
				(type default)
			)
			(fill no)
			(layer "F.CrtYd")
		)
		(fp_rect
			(start -0.508 0.9398)
			(end 0.508 -0.9398)
			(stroke
				(width 0)
				(type default)
			)
			(fill no)
			(layer "F.Fab")
		)
		(pad "1" smd custom
			(at 0 -0.4445 180)
			(size 0.1397 0.1397)
			(layers "F.Cu" "F.Mask" "F.Paste")
			(net "P12V_A")
			(options
				(clearance outline)
				(anchor circle)
			)
			(primitives
				(gr_poly
					(pts
						(arc
							(start -0.1778 -0.2794)
							(mid -0.249642 -0.249642)
							(end -0.2794 -0.1778)
						)
						(arc
							(start -0.2794 0.1778)
							(mid -0.249642 0.249642)
							(end -0.1778 0.2794)
						)
						(arc
							(start 0.1778 0.2794)
							(mid 0.249642 0.249642)
							(end 0.2794 0.1778)
						)
						(arc
							(start 0.2794 -0.1778)
							(mid 0.249642 -0.249642)
							(end 0.1778 -0.2794)
						)
					)
					(width 0)
					(fill yes)
				)
			)
		)
		(pad "2" smd custom
			(at 0 0.4445 180)
			(size 0.1397 0.1397)
			(layers "F.Cu" "F.Mask" "F.Paste")
			(net "SW_HDD_R20")
			(options
				(clearance outline)
				(anchor circle)
			)
			(primitives
				(gr_poly
					(pts
						(arc
							(start -0.1778 -0.2794)
							(mid -0.249642 -0.249642)
							(end -0.2794 -0.1778)
						)
						(arc
							(start -0.2794 0.1778)
							(mid -0.249642 0.249642)
							(end -0.1778 0.2794)
						)
						(arc
							(start 0.1778 0.2794)
							(mid 0.249642 0.249642)
							(end 0.2794 0.1778)
						)
						(arc
							(start 0.2794 -0.1778)
							(mid 0.249642 -0.249642)
							(end 0.1778 -0.2794)
						)
					)
					(width 0)
					(fill yes)
				)
			)
		)
	)
	(footprint ""
		(layer "F.Cu")
		(at 381.224028 -136.9314 90)
		(property "Reference" "C95"
			(at 0 0 90)
			(layer "F.SilkS")
			(hide yes)
			(effects
				(font
					(size 1.27 1.27)
				)
			)
		)
		(property "Value" "SC1U16V3KX-5GP"
			(at 0 -2.8194 90)
			(unlocked yes)
			(layer "F.Fab")
			(hide yes)
			(effects
				(font
					(size 1.016 1.016)
					(thickness 0.1524)
				)
			)
		)
		(property "Device Type" "C603H36"
			(at 0 -4.3434 90)
			(unlocked yes)
			(layer "F.Fab")
			(hide yes)
			(effects
				(font
					(size 1.016 1.016)
					(thickness 0.1524)
				)
			)
		)
		(duplicate_pad_numbers_are_jumpers no)
		(fp_line
			(start 0.508 0)
			(end -0.508 0)
			(stroke
				(width 0.2032)
				(type default)
			)
			(layer "F.SilkS")
		)
		(fp_rect
			(start -0.5842 1.3335)
			(end 0.5842 -1.3335)
			(stroke
				(width 0)
				(type default)
			)
			(fill no)
			(layer "F.CrtYd")
		)
		(fp_rect
			(start -0.5842 1.3335)
			(end 0.5842 -1.3335)
			(stroke
				(width 0)
				(type default)
			)
			(fill no)
			(layer "F.Fab")
		)
		(pad "1" smd custom
			(at 0 -0.762 90)
			(size 0.2159 0.2159)
			(layers "F.Cu" "F.Mask" "F.Paste")
			(net "P3V3_B_BIAS")
			(options
				(clearance outline)
				(anchor circle)
			)
			(primitives
				(gr_poly
					(pts
						(arc
							(start -0.3302 -0.4318)
							(mid -0.402042 -0.402042)
							(end -0.4318 -0.3302)
						)
						(arc
							(start -0.4318 0.3302)
							(mid -0.402042 0.402042)
							(end -0.3302 0.4318)
						)
						(arc
							(start 0.3302 0.4318)
							(mid 0.402042 0.402042)
							(end 0.4318 0.3302)
						)
						(arc
							(start 0.4318 -0.3302)
							(mid 0.402042 -0.402042)
							(end 0.3302 -0.4318)
						)
					)
					(width 0)
					(fill yes)
				)
			)
		)
		(pad "2" smd custom
			(at 0 0.762 90)
			(size 0.2159 0.2159)
			(layers "F.Cu" "F.Mask" "F.Paste")
			(net "GND")
			(options
				(clearance outline)
				(anchor circle)
			)
			(primitives
				(gr_poly
					(pts
						(arc
							(start -0.3302 -0.4318)
							(mid -0.402042 -0.402042)
							(end -0.4318 -0.3302)
						)
						(arc
							(start -0.4318 0.3302)
							(mid -0.402042 0.402042)
							(end -0.3302 0.4318)
						)
						(arc
							(start 0.3302 0.4318)
							(mid 0.402042 0.402042)
							(end 0.4318 0.3302)
						)
						(arc
							(start 0.4318 -0.3302)
							(mid 0.402042 -0.402042)
							(end 0.3302 -0.4318)
						)
					)
					(width 0)
					(fill yes)
				)
			)
		)
	)
	(footprint ""
		(layer "F.Cu")
		(at 159.324802 -207.79994)
		(property "Reference" ""
			(at 0 0 0)
			(layer "F.SilkS")
			(hide yes)
			(effects
				(font
					(size 1.27 1.27)
				)
			)
		)
		(property "Value" "*"
			(at -8.398764 -8.057642 0)
			(unlocked yes)
			(layer "F.Fab")
			(hide yes)
			(effects
				(font
					(size 1.016 1.016)
					(thickness 0.1524)
				)
			)
		)
		(duplicate_pad_numbers_are_jumpers no)
		(fp_poly
			(pts
				(arc
					(start 7.3152 0)
					(mid 0 7.3152)
					(end -7.3152 0)
				)
				(arc
					(start -7.3152 -5.9944)
					(mid 0 -13.3096)
					(end 7.3152 -5.9944)
				)
			)
			(stroke
				(width 0)
				(type default)
			)
			(fill no)
			(layer "B.CrtYd")
		)
		(fp_poly
			(pts
				(arc
					(start 7.3152 0)
					(mid 0 7.3152)
					(end -7.3152 0)
				)
				(arc
					(start -7.3152 -5.9944)
					(mid 0 -13.3096)
					(end 7.3152 -5.9944)
				)
			)
			(stroke
				(width 0)
				(type default)
			)
			(fill no)
			(layer "F.CrtYd")
		)
		(fp_poly
			(pts
				(arc
					(start 7.3152 0)
					(mid 0 7.3152)
					(end -7.3152 0)
				)
				(arc
					(start -7.3152 -5.9944)
					(mid 0 -13.3096)
					(end 7.3152 -5.9944)
				)
			)
			(stroke
				(width 0)
				(type default)
			)
			(fill no)
			(layer "B.Fab")
		)
		(fp_poly
			(pts
				(arc
					(start 7.3152 0)
					(mid 0 7.3152)
					(end -7.3152 0)
				)
				(arc
					(start -7.3152 -5.9944)
					(mid 0 -13.3096)
					(end 7.3152 -5.9944)
				)
			)
			(stroke
				(width 0)
				(type default)
			)
			(fill no)
			(layer "F.Fab")
		)
		(pad "1" thru_hole oval
			(at 0 0)
			(size 14.0208 20.0152)
			(drill 0.0254
				(offset 0 -2.9972)
			)
			(layers "*.Cu" "*.Mask")
			(remove_unused_layers no)
			(net "Net_105")
			(clearance -1.002284)
			(thermal_gap 0.1524)
			(padstack
				(mode front_inner_back)
				(layer "Inner"
					(shape custom)
					(size 2.928012 2.928012)
					(options
						(anchor circle)
					)
					(primitives
						(gr_poly
							(pts
								(arc
									(start 4.571746 -2.084324)
									(mid 0.000333 7.430372)
									(end -4.571492 -2.084324)
								)
								(arc
									(start -4.571492 -2.084324)
									(mid -3.570296 -3.611977)
									(end -2.875026 -5.30098)
								)
								(arc
									(start -2.875026 -5.30098)
									(mid 0.000217 -7.43089)
									(end 2.87528 -5.30098)
								)
								(arc
									(start 2.87528 -5.30098)
									(mid 3.570511 -3.611956)
									(end 4.571746 -2.084324)
								)
							)
							(width 0)
							(fill yes)
						)
					)
					(clearance 0.1524)
				)
				(layer "B.Cu"
					(shape oval)
					(size 14.0208 20.0152)
					(offset 0 -2.9972)
					(clearance -1.002284)
				)
			)
		)
		(zone
			(layers "F.Cu" "B.Cu" "In1.Cu" "In2.Cu" "In3.Cu" "In4.Cu" "In5.Cu" "In6.Cu"
				"In7.Cu" "In8.Cu" "In9.Cu" "In10.Cu"
			)
			(hatch none 0.5)
			(connect_pads
				(clearance 0)
			)
			(min_thickness 0.25)
			(keepout
				(tracks not_allowed)
				(vias allowed)
				(pads allowed)
				(copperpour not_allowed)
				(footprints allowed)
			)
			(placement
				(enabled no)
				(sheetname "")
			)
			(fill
				(thermal_gap 0.5)
				(thermal_bridge_width 0.5)
				(island_removal_mode 0)
			)
			(polygon
				(pts
					(arc
						(start 152.314402 -213.79434)
						(mid 159.324802 -220.80474)
						(end 166.335202 -213.79434)
					)
					(arc
						(start 166.335202 -207.79994)
						(mid 159.324802 -200.78954)
						(end 152.314402 -207.79994)
					)
				)
			)
		)
	)
	(footprint ""
		(layer "F.Cu")
		(at 367.338102 -157.585918 180)
		(property "Reference" "R577"
			(at 0 0 180)
			(layer "F.SilkS")
			(hide yes)
			(effects
				(font
					(size 1.27 1.27)
				)
			)
		)
		(property "Value" "0R2J-2-GP"
			(at 0.064008 -3.993896 180)
			(unlocked yes)
			(layer "F.Fab")
			(hide yes)
			(effects
				(font
					(size 1.016 1.016)
					(thickness 0.1524)
				)
			)
		)
		(property "Device Type" "R402H16"
			(at 0.064008 -5.517896 180)
			(unlocked yes)
			(layer "F.Fab")
			(hide yes)
			(effects
				(font
					(size 1.016 1.016)
					(thickness 0.1524)
				)
			)
		)
		(duplicate_pad_numbers_are_jumpers no)
		(fp_line
			(start 0.508 -0.9398)
			(end -0.508 -0.9398)
			(stroke
				(width 0.1524)
				(type default)
			)
			(layer "F.SilkS")
		)
		(fp_line
			(start -0.508 -0.9398)
			(end -0.508 0.9398)
			(stroke
				(width 0.1524)
				(type default)
			)
			(layer "F.SilkS")
		)
		(fp_rect
			(start -0.508 0.9398)
			(end 0.508 -0.9398)
			(stroke
				(width 0)
				(type default)
			)
			(fill no)
			(layer "F.CrtYd")
		)
		(fp_rect
			(start -0.508 0.9398)
			(end 0.508 -0.9398)
			(stroke
				(width 0)
				(type default)
			)
			(fill no)
			(layer "F.Fab")
		)
		(pad "1" smd custom
			(at 0 -0.4445 180)
			(size 0.1397 0.1397)
			(layers "F.Cu" "F.Mask" "F.Paste")
			(net "DRIVE_A_19_PWR")
			(options
				(clearance outline)
				(anchor circle)
			)
			(primitives
				(gr_poly
					(pts
						(arc
							(start -0.1778 -0.2794)
							(mid -0.249642 -0.249642)
							(end -0.2794 -0.1778)
						)
						(arc
							(start -0.2794 0.1778)
							(mid -0.249642 0.249642)
							(end -0.1778 0.2794)
						)
						(arc
							(start 0.1778 0.2794)
							(mid 0.249642 0.249642)
							(end 0.2794 0.1778)
						)
						(arc
							(start 0.2794 -0.1778)
							(mid 0.249642 -0.249642)
							(end 0.1778 -0.2794)
						)
					)
					(width 0)
					(fill yes)
				)
			)
		)
		(pad "2" smd custom
			(at 0 0.4445 180)
			(size 0.1397 0.1397)
			(layers "F.Cu" "F.Mask" "F.Paste")
			(net "SW_PWR_R_HDD19")
			(options
				(clearance outline)
				(anchor circle)
			)
			(primitives
				(gr_poly
					(pts
						(arc
							(start -0.1778 -0.2794)
							(mid -0.249642 -0.249642)
							(end -0.2794 -0.1778)
						)
						(arc
							(start -0.2794 0.1778)
							(mid -0.249642 0.249642)
							(end -0.1778 0.2794)
						)
						(arc
							(start 0.1778 0.2794)
							(mid 0.249642 0.249642)
							(end 0.2794 0.1778)
						)
						(arc
							(start 0.2794 -0.1778)
							(mid 0.249642 -0.249642)
							(end 0.1778 -0.2794)
						)
					)
					(width 0)
					(fill yes)
				)
			)
		)
	)
	(footprint ""
		(layer "F.Cu")
		(at 248.608342 -383.085848 90)
		(property "Reference" "Q225"
			(at 0 0 90)
			(layer "F.SilkS")
			(hide yes)
			(effects
				(font
					(size 1.27 1.27)
				)
			)
		)
		(property "Value" "MMBT3904-3-GP"
			(at 0.10287 -10.29843 90)
			(unlocked yes)
			(layer "F.Fab")
			(hide yes)
			(effects
				(font
					(size 1.016 1.016)
					(thickness 0.1524)
				)
			)
		)
		(property "Device Type" "SOT23CBE2D4H44"
			(at 0.10287 -12.20343 90)
			(unlocked yes)
			(layer "F.Fab")
			(hide yes)
			(effects
				(font
					(size 1.016 1.016)
					(thickness 0.1524)
				)
			)
		)
		(duplicate_pad_numbers_are_jumpers no)
		(fp_line
			(start 1.651 -1.778)
			(end -1.651 -1.778)
			(stroke
				(width 0.1524)
				(type default)
			)
			(layer "F.SilkS")
		)
		(fp_line
			(start -1.651 -1.778)
			(end -1.651 1.778)
			(stroke
				(width 0.1524)
				(type default)
			)
			(layer "F.SilkS")
		)
		(fp_line
			(start 1.651 1.778)
			(end 1.651 -1.778)
			(stroke
				(width 0.1524)
				(type default)
			)
			(layer "F.SilkS")
		)
		(fp_line
			(start -1.651 1.778)
			(end 1.651 1.778)
			(stroke
				(width 0.1524)
				(type default)
			)
			(layer "F.SilkS")
		)
		(fp_poly
			(pts
				(xy -1.778 1.8796) (xy -1.778 -1.8796) (xy 1.778 -1.8796) (xy 1.778 1.8796)
			)
			(stroke
				(width 0)
				(type default)
			)
			(fill no)
			(layer "F.CrtYd")
		)
		(fp_poly
			(pts
				(xy -1.778 1.8796) (xy -1.778 -1.8796) (xy 1.778 -1.8796) (xy 1.778 1.8796)
			)
			(stroke
				(width 0)
				(type default)
			)
			(fill no)
			(layer "F.Fab")
		)
		(pad "B" smd custom
			(at -0.98425 0.9525 90)
			(size 0.1905 0.1905)
			(layers "F.Cu" "F.Mask" "F.Paste")
			(net "MB3_TEMP_B")
			(options
				(clearance outline)
				(anchor circle)
			)
			(primitives
				(gr_poly
					(pts
						(arc
							(start -0.1778 0.5715)
							(mid -0.321484 0.511984)
							(end -0.381 0.3683)
						)
						(arc
							(start -0.381 -0.3683)
							(mid -0.321484 -0.511984)
							(end -0.1778 -0.5715)
						)
						(arc
							(start 0.1778 -0.5715)
							(mid 0.321484 -0.511984)
							(end 0.381 -0.3683)
						)
						(arc
							(start 0.381 0.3683)
							(mid 0.321484 0.511984)
							(end 0.1778 0.5715)
						)
					)
					(width 0)
					(fill yes)
				)
			)
		)
		(pad "C" smd custom
			(at 0 -0.9525 90)
			(size 0.1905 0.1905)
			(layers "F.Cu" "F.Mask" "F.Paste")
			(net "MB3_TEMP_B")
			(options
				(clearance outline)
				(anchor circle)
			)
			(primitives
				(gr_poly
					(pts
						(arc
							(start -0.1778 0.5715)
							(mid -0.321484 0.511984)
							(end -0.381 0.3683)
						)
						(arc
							(start -0.381 -0.3683)
							(mid -0.321484 -0.511984)
							(end -0.1778 -0.5715)
						)
						(arc
							(start 0.1778 -0.5715)
							(mid 0.321484 -0.511984)
							(end 0.381 -0.3683)
						)
						(arc
							(start 0.381 0.3683)
							(mid 0.321484 0.511984)
							(end 0.1778 0.5715)
						)
					)
					(width 0)
					(fill yes)
				)
			)
		)
		(pad "E" smd custom
			(at 0.98425 0.9525 90)
			(size 0.1905 0.1905)
			(layers "F.Cu" "F.Mask" "F.Paste")
			(net "MB3_TEMP_E")
			(options
				(clearance outline)
				(anchor circle)
			)
			(primitives
				(gr_poly
					(pts
						(arc
							(start -0.1778 0.5715)
							(mid -0.321484 0.511984)
							(end -0.381 0.3683)
						)
						(arc
							(start -0.381 -0.3683)
							(mid -0.321484 -0.511984)
							(end -0.1778 -0.5715)
						)
						(arc
							(start 0.1778 -0.5715)
							(mid 0.321484 -0.511984)
							(end 0.381 -0.3683)
						)
						(arc
							(start 0.381 0.3683)
							(mid 0.321484 0.511984)
							(end 0.1778 0.5715)
						)
					)
					(width 0)
					(fill yes)
				)
			)
		)
	)
	(footprint ""
		(layer "F.Cu")
		(at 304.546 -74.676)
		(property "Reference" "R449"
			(at 0 0 0)
			(layer "F.SilkS")
			(hide yes)
			(effects
				(font
					(size 1.27 1.27)
				)
			)
		)
		(property "Value" "0R2J-2-GP"
			(at 0.064008 -3.993896 0)
			(unlocked yes)
			(layer "F.Fab")
			(hide yes)
			(effects
				(font
					(size 1.016 1.016)
					(thickness 0.1524)
				)
			)
		)
		(property "Device Type" "R402H16"
			(at 0.064008 -5.517896 0)
			(unlocked yes)
			(layer "F.Fab")
			(hide yes)
			(effects
				(font
					(size 1.016 1.016)
					(thickness 0.1524)
				)
			)
		)
		(duplicate_pad_numbers_are_jumpers no)
		(fp_line
			(start -0.508 -0.9398)
			(end -0.508 0.9398)
			(stroke
				(width 0.1524)
				(type default)
			)
			(layer "F.SilkS")
		)
		(fp_line
			(start 0.508 -0.9398)
			(end -0.508 -0.9398)
			(stroke
				(width 0.1524)
				(type default)
			)
			(layer "F.SilkS")
		)
		(fp_rect
			(start -0.508 0.9398)
			(end 0.508 -0.9398)
			(stroke
				(width 0)
				(type default)
			)
			(fill no)
			(layer "F.CrtYd")
		)
		(fp_rect
			(start -0.508 0.9398)
			(end 0.508 -0.9398)
			(stroke
				(width 0)
				(type default)
			)
			(fill no)
			(layer "F.Fab")
		)
		(pad "1" smd custom
			(at 0 -0.4445)
			(size 0.1397 0.1397)
			(layers "F.Cu" "F.Mask" "F.Paste")
			(net "COMP_B_PGOOD")
			(options
				(clearance outline)
				(anchor circle)
			)
			(primitives
				(gr_poly
					(pts
						(arc
							(start -0.1778 -0.2794)
							(mid -0.249642 -0.249642)
							(end -0.2794 -0.1778)
						)
						(arc
							(start -0.2794 0.1778)
							(mid -0.249642 0.249642)
							(end -0.1778 0.2794)
						)
						(arc
							(start 0.1778 0.2794)
							(mid 0.249642 0.249642)
							(end 0.2794 0.1778)
						)
						(arc
							(start 0.2794 -0.1778)
							(mid 0.249642 -0.249642)
							(end 0.1778 -0.2794)
						)
					)
					(width 0)
					(fill yes)
				)
			)
		)
		(pad "2" smd custom
			(at 0 0.4445)
			(size 0.1397 0.1397)
			(layers "F.Cu" "F.Mask" "F.Paste")
			(net "TXS0102_B_OE")
			(options
				(clearance outline)
				(anchor circle)
			)
			(primitives
				(gr_poly
					(pts
						(arc
							(start -0.1778 -0.2794)
							(mid -0.249642 -0.249642)
							(end -0.2794 -0.1778)
						)
						(arc
							(start -0.2794 0.1778)
							(mid -0.249642 0.249642)
							(end -0.1778 0.2794)
						)
						(arc
							(start 0.1778 0.2794)
							(mid 0.249642 0.249642)
							(end 0.2794 0.1778)
						)
						(arc
							(start 0.2794 -0.1778)
							(mid 0.249642 -0.249642)
							(end 0.1778 -0.2794)
						)
					)
					(width 0)
					(fill yes)
				)
			)
		)
	)
	(footprint ""
		(layer "F.Cu")
		(at 458.3049 -45.252894 -90)
		(property "Reference" "Q205"
			(at 0 0 270)
			(layer "F.SilkS")
			(hide yes)
			(effects
				(font
					(size 1.27 1.27)
				)
			)
		)
		(property "Value" "2N7002KDW-GP"
			(at -2.3622 -8.2042 270)
			(unlocked yes)
			(layer "F.Fab")
			(hide yes)
			(effects
				(font
					(size 1.016 1.016)
					(thickness 0.1524)
				)
			)
		)
		(property "Device Type" "SOT-363H44"
			(at -2.3622 -10.1092 270)
			(unlocked yes)
			(layer "F.Fab")
			(hide yes)
			(effects
				(font
					(size 1.016 1.016)
					(thickness 0.1524)
				)
			)
		)
		(duplicate_pad_numbers_are_jumpers no)
		(fp_line
			(start -1.4478 1.7018)
			(end 1.4478 1.7018)
			(stroke
				(width 0.1524)
				(type default)
			)
			(layer "F.SilkS")
		)
		(fp_line
			(start 1.4478 1.7018)
			(end 1.4478 -1.7018)
			(stroke
				(width 0.1524)
				(type default)
			)
			(layer "F.SilkS")
		)
		(fp_line
			(start -1.27 1.524)
			(end -1.27 0.6604)
			(stroke
				(width 0.4826)
				(type default)
			)
			(layer "F.SilkS")
		)
		(fp_line
			(start -1.4478 -1.7018)
			(end -1.4478 1.7018)
			(stroke
				(width 0.1524)
				(type default)
			)
			(layer "F.SilkS")
		)
		(fp_line
			(start 1.4478 -1.7018)
			(end -1.4478 -1.7018)
			(stroke
				(width 0.1524)
				(type default)
			)
			(layer "F.SilkS")
		)
		(fp_poly
			(pts
				(xy -1.524 -1.778) (xy 1.524 -1.778) (xy 1.524 1.778) (xy -1.524 1.778)
			)
			(stroke
				(width 0)
				(type default)
			)
			(fill no)
			(layer "F.CrtYd")
		)
		(fp_poly
			(pts
				(xy -1.524 -1.778) (xy 1.524 -1.778) (xy 1.524 1.778) (xy -1.524 1.778)
			)
			(stroke
				(width 0)
				(type default)
			)
			(fill no)
			(layer "F.Fab")
		)
		(pad "1" smd rect
			(at -0.65024 0.9398 270)
			(size 0.4064 1.016)
			(layers "F.Cu" "F.Mask" "F.Paste")
			(net "GND")
		)
		(pad "2" smd rect
			(at 0 0.9398 270)
			(size 0.4064 1.016)
			(layers "F.Cu" "F.Mask" "F.Paste")
			(net "SW_PWR_R_HDD34")
		)
		(pad "3" smd rect
			(at 0.65024 0.9398 270)
			(size 0.4064 1.016)
			(layers "F.Cu" "F.Mask" "F.Paste")
			(net "SW_HDD_P34")
		)
		(pad "4" smd rect
			(at 0.65024 -0.9398 270)
			(size 0.4064 1.016)
			(layers "F.Cu" "F.Mask" "F.Paste")
			(net "GND")
		)
		(pad "5" smd rect
			(at 0 -0.9398 270)
			(size 0.4064 1.016)
			(layers "F.Cu" "F.Mask" "F.Paste")
			(net "SW_HDD_G34")
		)
		(pad "6" smd rect
			(at -0.65024 -0.9398 270)
			(size 0.4064 1.016)
			(layers "F.Cu" "F.Mask" "F.Paste")
			(net "SW_HDD_R34")
		)
	)
	(footprint ""
		(layer "F.Cu")
		(at 264.950448 10.238232)
		(property "Reference" "R134"
			(at 0 0 0)
			(layer "F.SilkS")
			(hide yes)
			(effects
				(font
					(size 1.27 1.27)
				)
			)
		)
		(property "Value" "4K7R2F-GP"
			(at 0.064008 -3.993896 0)
			(unlocked yes)
			(layer "F.Fab")
			(hide yes)
			(effects
				(font
					(size 1.016 1.016)
					(thickness 0.1524)
				)
			)
		)
		(property "Device Type" "R402H16"
			(at 0.064008 -5.517896 0)
			(unlocked yes)
			(layer "F.Fab")
			(hide yes)
			(effects
				(font
					(size 1.016 1.016)
					(thickness 0.1524)
				)
			)
		)
		(duplicate_pad_numbers_are_jumpers no)
		(fp_line
			(start -0.508 -0.9398)
			(end -0.508 0.9398)
			(stroke
				(width 0.1524)
				(type default)
			)
			(layer "F.SilkS")
		)
		(fp_line
			(start 0.508 -0.9398)
			(end -0.508 -0.9398)
			(stroke
				(width 0.1524)
				(type default)
			)
			(layer "F.SilkS")
		)
		(fp_rect
			(start -0.508 0.9398)
			(end 0.508 -0.9398)
			(stroke
				(width 0)
				(type default)
			)
			(fill no)
			(layer "F.CrtYd")
		)
		(fp_rect
			(start -0.508 0.9398)
			(end 0.508 -0.9398)
			(stroke
				(width 0)
				(type default)
			)
			(fill no)
			(layer "F.Fab")
		)
		(pad "1" smd custom
			(at 0 -0.4445)
			(size 0.1397 0.1397)
			(layers "F.Cu" "F.Mask" "F.Paste")
			(net "P5V_A_2")
			(options
				(clearance outline)
				(anchor circle)
			)
			(primitives
				(gr_poly
					(pts
						(arc
							(start -0.1778 -0.2794)
							(mid -0.249642 -0.249642)
							(end -0.2794 -0.1778)
						)
						(arc
							(start -0.2794 0.1778)
							(mid -0.249642 0.249642)
							(end -0.1778 0.2794)
						)
						(arc
							(start 0.1778 0.2794)
							(mid 0.249642 0.249642)
							(end 0.2794 0.1778)
						)
						(arc
							(start 0.2794 -0.1778)
							(mid 0.249642 -0.249642)
							(end 0.1778 -0.2794)
						)
					)
					(width 0)
					(fill yes)
				)
			)
		)
		(pad "2" smd custom
			(at 0 0.4445)
			(size 0.1397 0.1397)
			(layers "F.Cu" "F.Mask" "F.Paste")
			(net "USB_EN_1")
			(options
				(clearance outline)
				(anchor circle)
			)
			(primitives
				(gr_poly
					(pts
						(arc
							(start -0.1778 -0.2794)
							(mid -0.249642 -0.249642)
							(end -0.2794 -0.1778)
						)
						(arc
							(start -0.2794 0.1778)
							(mid -0.249642 0.249642)
							(end -0.1778 0.2794)
						)
						(arc
							(start 0.1778 0.2794)
							(mid 0.249642 0.249642)
							(end 0.2794 0.1778)
						)
						(arc
							(start 0.2794 -0.1778)
							(mid 0.249642 -0.249642)
							(end 0.1778 -0.2794)
						)
					)
					(width 0)
					(fill yes)
				)
			)
		)
	)
	(footprint ""
		(layer "F.Cu")
		(at 48.374046 -52.060094 90)
		(property "Reference" "R712"
			(at 0 0 90)
			(layer "F.SilkS")
			(hide yes)
			(effects
				(font
					(size 1.27 1.27)
				)
			)
		)
		(property "Value" "4K7R2J-2-GP"
			(at 0.064008 -3.993896 90)
			(unlocked yes)
			(layer "F.Fab")
			(hide yes)
			(effects
				(font
					(size 1.016 1.016)
					(thickness 0.1524)
				)
			)
		)
		(property "Device Type" "R402H16"
			(at 0.064008 -5.517896 90)
			(unlocked yes)
			(layer "F.Fab")
			(hide yes)
			(effects
				(font
					(size 1.016 1.016)
					(thickness 0.1524)
				)
			)
		)
		(duplicate_pad_numbers_are_jumpers no)
		(fp_line
			(start 0.508 -0.9398)
			(end -0.508 -0.9398)
			(stroke
				(width 0.1524)
				(type default)
			)
			(layer "F.SilkS")
		)
		(fp_line
			(start -0.508 -0.9398)
			(end -0.508 0.9398)
			(stroke
				(width 0.1524)
				(type default)
			)
			(layer "F.SilkS")
		)
		(fp_rect
			(start -0.508 0.9398)
			(end 0.508 -0.9398)
			(stroke
				(width 0)
				(type default)
			)
			(fill no)
			(layer "F.CrtYd")
		)
		(fp_rect
			(start -0.508 0.9398)
			(end 0.508 -0.9398)
			(stroke
				(width 0)
				(type default)
			)
			(fill no)
			(layer "F.Fab")
		)
		(pad "1" smd custom
			(at 0 -0.4445 90)
			(size 0.1397 0.1397)
			(layers "F.Cu" "F.Mask" "F.Paste")
			(net "P12V_A")
			(options
				(clearance outline)
				(anchor circle)
			)
			(primitives
				(gr_poly
					(pts
						(arc
							(start -0.1778 -0.2794)
							(mid -0.249642 -0.249642)
							(end -0.2794 -0.1778)
						)
						(arc
							(start -0.2794 0.1778)
							(mid -0.249642 0.249642)
							(end -0.1778 0.2794)
						)
						(arc
							(start 0.1778 0.2794)
							(mid 0.249642 0.249642)
							(end 0.2794 0.1778)
						)
						(arc
							(start 0.2794 -0.1778)
							(mid 0.249642 -0.249642)
							(end 0.1778 -0.2794)
						)
					)
					(width 0)
					(fill yes)
				)
			)
		)
		(pad "2" smd custom
			(at 0 0.4445 90)
			(size 0.1397 0.1397)
			(layers "F.Cu" "F.Mask" "F.Paste")
			(net "SW_HDD_P25")
			(options
				(clearance outline)
				(anchor circle)
			)
			(primitives
				(gr_poly
					(pts
						(arc
							(start -0.1778 -0.2794)
							(mid -0.249642 -0.249642)
							(end -0.2794 -0.1778)
						)
						(arc
							(start -0.2794 0.1778)
							(mid -0.249642 0.249642)
							(end -0.1778 0.2794)
						)
						(arc
							(start 0.1778 0.2794)
							(mid 0.249642 0.249642)
							(end 0.2794 0.1778)
						)
						(arc
							(start 0.2794 -0.1778)
							(mid 0.249642 -0.249642)
							(end 0.1778 -0.2794)
						)
					)
					(width 0)
					(fill yes)
				)
			)
		)
	)
	(footprint ""
		(layer "F.Cu")
		(at 161.997898 -177.169318 -90)
		(property "Reference" "R498"
			(at 0 0 270)
			(layer "F.SilkS")
			(hide yes)
			(effects
				(font
					(size 1.27 1.27)
				)
			)
		)
		(property "Value" "10KR2F-2-GP"
			(at 0.064008 -3.993896 270)
			(unlocked yes)
			(layer "F.Fab")
			(hide yes)
			(effects
				(font
					(size 1.016 1.016)
					(thickness 0.1524)
				)
			)
		)
		(property "Device Type" "R402H16"
			(at 0.064008 -5.517896 270)
			(unlocked yes)
			(layer "F.Fab")
			(hide yes)
			(effects
				(font
					(size 1.016 1.016)
					(thickness 0.1524)
				)
			)
		)
		(duplicate_pad_numbers_are_jumpers no)
		(fp_line
			(start -0.508 -0.9398)
			(end -0.508 0.9398)
			(stroke
				(width 0.1524)
				(type default)
			)
			(layer "F.SilkS")
		)
		(fp_line
			(start 0.508 -0.9398)
			(end -0.508 -0.9398)
			(stroke
				(width 0.1524)
				(type default)
			)
			(layer "F.SilkS")
		)
		(fp_rect
			(start -0.508 0.9398)
			(end 0.508 -0.9398)
			(stroke
				(width 0)
				(type default)
			)
			(fill no)
			(layer "F.CrtYd")
		)
		(fp_rect
			(start -0.508 0.9398)
			(end 0.508 -0.9398)
			(stroke
				(width 0)
				(type default)
			)
			(fill no)
			(layer "F.Fab")
		)
		(pad "1" smd custom
			(at 0 -0.4445 270)
			(size 0.1397 0.1397)
			(layers "F.Cu" "F.Mask" "F.Paste")
			(net "P3V3_STBY_A")
			(options
				(clearance outline)
				(anchor circle)
			)
			(primitives
				(gr_poly
					(pts
						(arc
							(start -0.1778 -0.2794)
							(mid -0.249642 -0.249642)
							(end -0.2794 -0.1778)
						)
						(arc
							(start -0.2794 0.1778)
							(mid -0.249642 0.249642)
							(end -0.1778 0.2794)
						)
						(arc
							(start 0.1778 0.2794)
							(mid 0.249642 0.249642)
							(end 0.2794 0.1778)
						)
						(arc
							(start 0.2794 -0.1778)
							(mid 0.249642 -0.249642)
							(end 0.1778 -0.2794)
						)
					)
					(width 0)
					(fill yes)
				)
			)
		)
		(pad "2" smd custom
			(at 0 0.4445 270)
			(size 0.1397 0.1397)
			(layers "F.Cu" "F.Mask" "F.Paste")
			(net "HDD_PRSNT_16")
			(options
				(clearance outline)
				(anchor circle)
			)
			(primitives
				(gr_poly
					(pts
						(arc
							(start -0.1778 -0.2794)
							(mid -0.249642 -0.249642)
							(end -0.2794 -0.1778)
						)
						(arc
							(start -0.2794 0.1778)
							(mid -0.249642 0.249642)
							(end -0.1778 0.2794)
						)
						(arc
							(start 0.1778 0.2794)
							(mid 0.249642 0.249642)
							(end 0.2794 0.1778)
						)
						(arc
							(start 0.2794 -0.1778)
							(mid 0.249642 -0.249642)
							(end 0.1778 -0.2794)
						)
					)
					(width 0)
					(fill yes)
				)
			)
		)
	)
	(footprint ""
		(layer "F.Cu")
		(at 231.668828 -389.763 90)
		(property "Reference" "C69"
			(at 0 0 90)
			(layer "F.SilkS")
			(hide yes)
			(effects
				(font
					(size 1.27 1.27)
				)
			)
		)
		(property "Value" "SC1U16V3KX-5GP"
			(at 0 -2.8194 90)
			(unlocked yes)
			(layer "F.Fab")
			(hide yes)
			(effects
				(font
					(size 1.016 1.016)
					(thickness 0.1524)
				)
			)
		)
		(property "Device Type" "C603H36"
			(at 0 -4.3434 90)
			(unlocked yes)
			(layer "F.Fab")
			(hide yes)
			(effects
				(font
					(size 1.016 1.016)
					(thickness 0.1524)
				)
			)
		)
		(duplicate_pad_numbers_are_jumpers no)
		(fp_line
			(start 0.508 0)
			(end -0.508 0)
			(stroke
				(width 0.2032)
				(type default)
			)
			(layer "F.SilkS")
		)
		(fp_rect
			(start -0.5842 1.3335)
			(end 0.5842 -1.3335)
			(stroke
				(width 0)
				(type default)
			)
			(fill no)
			(layer "F.CrtYd")
		)
		(fp_rect
			(start -0.5842 1.3335)
			(end 0.5842 -1.3335)
			(stroke
				(width 0)
				(type default)
			)
			(fill no)
			(layer "F.Fab")
		)
		(pad "1" smd custom
			(at 0 -0.762 90)
			(size 0.2159 0.2159)
			(layers "F.Cu" "F.Mask" "F.Paste")
			(net "P3V3_IN_BIAS")
			(options
				(clearance outline)
				(anchor circle)
			)
			(primitives
				(gr_poly
					(pts
						(arc
							(start -0.3302 -0.4318)
							(mid -0.402042 -0.402042)
							(end -0.4318 -0.3302)
						)
						(arc
							(start -0.4318 0.3302)
							(mid -0.402042 0.402042)
							(end -0.3302 0.4318)
						)
						(arc
							(start 0.3302 0.4318)
							(mid 0.402042 0.402042)
							(end 0.4318 0.3302)
						)
						(arc
							(start 0.4318 -0.3302)
							(mid 0.402042 -0.402042)
							(end 0.3302 -0.4318)
						)
					)
					(width 0)
					(fill yes)
				)
			)
		)
		(pad "2" smd custom
			(at 0 0.762 90)
			(size 0.2159 0.2159)
			(layers "F.Cu" "F.Mask" "F.Paste")
			(net "GND")
			(options
				(clearance outline)
				(anchor circle)
			)
			(primitives
				(gr_poly
					(pts
						(arc
							(start -0.3302 -0.4318)
							(mid -0.402042 -0.402042)
							(end -0.4318 -0.3302)
						)
						(arc
							(start -0.4318 0.3302)
							(mid -0.402042 0.402042)
							(end -0.3302 0.4318)
						)
						(arc
							(start 0.3302 0.4318)
							(mid 0.402042 0.402042)
							(end 0.4318 0.3302)
						)
						(arc
							(start 0.4318 -0.3302)
							(mid 0.402042 -0.402042)
							(end 0.3302 -0.4318)
						)
					)
					(width 0)
					(fill yes)
				)
			)
		)
	)
	(footprint ""
		(layer "F.Cu")
		(at 456.0189 -74.335894 180)
		(property "Reference" "C489"
			(at 0 0 180)
			(layer "F.SilkS")
			(hide yes)
			(effects
				(font
					(size 1.27 1.27)
				)
			)
		)
		(property "Value" "SC1U25V3KX-GP"
			(at 0 -2.8194 180)
			(unlocked yes)
			(layer "F.Fab")
			(hide yes)
			(effects
				(font
					(size 1.016 1.016)
					(thickness 0.1524)
				)
			)
		)
		(property "Device Type" "C603H36"
			(at 0 -4.3434 180)
			(unlocked yes)
			(layer "F.Fab")
			(hide yes)
			(effects
				(font
					(size 1.016 1.016)
					(thickness 0.1524)
				)
			)
		)
		(duplicate_pad_numbers_are_jumpers no)
		(fp_line
			(start 0.508 0)
			(end -0.508 0)
			(stroke
				(width 0.2032)
				(type default)
			)
			(layer "F.SilkS")
		)
		(fp_rect
			(start -0.5842 1.3335)
			(end 0.5842 -1.3335)
			(stroke
				(width 0)
				(type default)
			)
			(fill no)
			(layer "F.CrtYd")
		)
		(fp_rect
			(start -0.5842 1.3335)
			(end 0.5842 -1.3335)
			(stroke
				(width 0)
				(type default)
			)
			(fill no)
			(layer "F.Fab")
		)
		(pad "1" smd custom
			(at 0 -0.762 180)
			(size 0.2159 0.2159)
			(layers "F.Cu" "F.Mask" "F.Paste")
			(net "P12V_HDD34")
			(options
				(clearance outline)
				(anchor circle)
			)
			(primitives
				(gr_poly
					(pts
						(arc
							(start -0.3302 -0.4318)
							(mid -0.402042 -0.402042)
							(end -0.4318 -0.3302)
						)
						(arc
							(start -0.4318 0.3302)
							(mid -0.402042 0.402042)
							(end -0.3302 0.4318)
						)
						(arc
							(start 0.3302 0.4318)
							(mid 0.402042 0.402042)
							(end 0.4318 0.3302)
						)
						(arc
							(start 0.4318 -0.3302)
							(mid 0.402042 -0.402042)
							(end 0.3302 -0.4318)
						)
					)
					(width 0)
					(fill yes)
				)
			)
		)
		(pad "2" smd custom
			(at 0 0.762 180)
			(size 0.2159 0.2159)
			(layers "F.Cu" "F.Mask" "F.Paste")
			(net "GND")
			(options
				(clearance outline)
				(anchor circle)
			)
			(primitives
				(gr_poly
					(pts
						(arc
							(start -0.3302 -0.4318)
							(mid -0.402042 -0.402042)
							(end -0.4318 -0.3302)
						)
						(arc
							(start -0.4318 0.3302)
							(mid -0.402042 0.402042)
							(end -0.3302 0.4318)
						)
						(arc
							(start 0.3302 0.4318)
							(mid 0.402042 0.402042)
							(end 0.4318 0.3302)
						)
						(arc
							(start 0.4318 -0.3302)
							(mid 0.402042 -0.402042)
							(end 0.3302 -0.4318)
						)
					)
					(width 0)
					(fill yes)
				)
			)
		)
	)
	(footprint ""
		(layer "F.Cu")
		(at 149.196298 -163.554918 90)
		(property "Reference" "R511"
			(at 0 0 90)
			(layer "F.SilkS")
			(hide yes)
			(effects
				(font
					(size 1.27 1.27)
				)
			)
		)
		(property "Value" "4K7R2J-2-GP"
			(at 0.064008 -3.993896 90)
			(unlocked yes)
			(layer "F.Fab")
			(hide yes)
			(effects
				(font
					(size 1.016 1.016)
					(thickness 0.1524)
				)
			)
		)
		(property "Device Type" "R402H16"
			(at 0.064008 -5.517896 90)
			(unlocked yes)
			(layer "F.Fab")
			(hide yes)
			(effects
				(font
					(size 1.016 1.016)
					(thickness 0.1524)
				)
			)
		)
		(duplicate_pad_numbers_are_jumpers no)
		(fp_line
			(start 0.508 -0.9398)
			(end -0.508 -0.9398)
			(stroke
				(width 0.1524)
				(type default)
			)
			(layer "F.SilkS")
		)
		(fp_line
			(start -0.508 -0.9398)
			(end -0.508 0.9398)
			(stroke
				(width 0.1524)
				(type default)
			)
			(layer "F.SilkS")
		)
		(fp_rect
			(start -0.508 0.9398)
			(end 0.508 -0.9398)
			(stroke
				(width 0)
				(type default)
			)
			(fill no)
			(layer "F.CrtYd")
		)
		(fp_rect
			(start -0.508 0.9398)
			(end 0.508 -0.9398)
			(stroke
				(width 0)
				(type default)
			)
			(fill no)
			(layer "F.Fab")
		)
		(pad "1" smd custom
			(at 0 -0.4445 90)
			(size 0.1397 0.1397)
			(layers "F.Cu" "F.Mask" "F.Paste")
			(net "SW_PWR_R_HDD16")
			(options
				(clearance outline)
				(anchor circle)
			)
			(primitives
				(gr_poly
					(pts
						(arc
							(start -0.1778 -0.2794)
							(mid -0.249642 -0.249642)
							(end -0.2794 -0.1778)
						)
						(arc
							(start -0.2794 0.1778)
							(mid -0.249642 0.249642)
							(end -0.1778 0.2794)
						)
						(arc
							(start 0.1778 0.2794)
							(mid 0.249642 0.249642)
							(end 0.2794 0.1778)
						)
						(arc
							(start 0.2794 -0.1778)
							(mid 0.249642 -0.249642)
							(end 0.1778 -0.2794)
						)
					)
					(width 0)
					(fill yes)
				)
			)
		)
		(pad "2" smd custom
			(at 0 0.4445 90)
			(size 0.1397 0.1397)
			(layers "F.Cu" "F.Mask" "F.Paste")
			(net "GND")
			(options
				(clearance outline)
				(anchor circle)
			)
			(primitives
				(gr_poly
					(pts
						(arc
							(start -0.1778 -0.2794)
							(mid -0.249642 -0.249642)
							(end -0.2794 -0.1778)
						)
						(arc
							(start -0.2794 0.1778)
							(mid -0.249642 0.249642)
							(end -0.1778 0.2794)
						)
						(arc
							(start 0.1778 0.2794)
							(mid 0.249642 0.249642)
							(end 0.2794 0.1778)
						)
						(arc
							(start 0.2794 -0.1778)
							(mid 0.249642 -0.249642)
							(end 0.1778 -0.2794)
						)
					)
					(width 0)
					(fill yes)
				)
			)
		)
	)
	(footprint ""
		(layer "F.Cu")
		(at 350.1898 -68.6816)
		(property "Reference" "TP157"
			(at 0 0 0)
			(layer "F.SilkS")
			(hide yes)
			(effects
				(font
					(size 1.27 1.27)
				)
			)
		)
		(property "Value" "TPAD32-GP"
			(at -0.0508 -1.6764 0)
			(unlocked yes)
			(layer "F.Fab")
			(hide yes)
			(effects
				(font
					(size 1.016 1.016)
					(thickness 0.1524)
				)
			)
		)
		(property "Device Type" "TPAD32"
			(at -0.0508 -3.2004 0)
			(unlocked yes)
			(layer "F.Fab")
			(hide yes)
			(effects
				(font
					(size 1.016 1.016)
					(thickness 0.1524)
				)
			)
		)
		(duplicate_pad_numbers_are_jumpers no)
		(fp_poly
			(pts
				(arc
					(start 0.4064 0)
					(mid -0.4064 0)
					(end 0.4064 0)
				)
			)
			(stroke
				(width 0)
				(type default)
			)
			(fill no)
			(layer "F.CrtYd")
		)
		(fp_poly
			(pts
				(arc
					(start 0.7112 0)
					(mid -0.7112 0)
					(end 0.7112 0)
				)
			)
			(stroke
				(width 0)
				(type default)
			)
			(fill no)
			(layer "F.Fab")
		)
		(pad "1" smd circle
			(at 0 0)
			(size 0.8128 0.8128)
			(layers "F.Cu" "F.Mask" "F.Paste")
			(net "ACT_HDD_31")
		)
	)
	(footprint ""
		(layer "F.Cu")
		(at 15.261336 -130.30708 -90)
		(property "Reference" "R503"
			(at 0 0 270)
			(layer "F.SilkS")
			(hide yes)
			(effects
				(font
					(size 1.27 1.27)
				)
			)
		)
		(property "Value" "4K7R2J-2-GP"
			(at 0.064008 -3.993896 270)
			(unlocked yes)
			(layer "F.Fab")
			(hide yes)
			(effects
				(font
					(size 1.016 1.016)
					(thickness 0.1524)
				)
			)
		)
		(property "Device Type" "R402H16"
			(at 0.064008 -5.517896 270)
			(unlocked yes)
			(layer "F.Fab")
			(hide yes)
			(effects
				(font
					(size 1.016 1.016)
					(thickness 0.1524)
				)
			)
		)
		(duplicate_pad_numbers_are_jumpers no)
		(fp_line
			(start -0.508 -0.9398)
			(end -0.508 0.9398)
			(stroke
				(width 0.1524)
				(type default)
			)
			(layer "F.SilkS")
		)
		(fp_line
			(start 0.508 -0.9398)
			(end -0.508 -0.9398)
			(stroke
				(width 0.1524)
				(type default)
			)
			(layer "F.SilkS")
		)
		(fp_rect
			(start -0.508 0.9398)
			(end 0.508 -0.9398)
			(stroke
				(width 0)
				(type default)
			)
			(fill no)
			(layer "F.CrtYd")
		)
		(fp_rect
			(start -0.508 0.9398)
			(end 0.508 -0.9398)
			(stroke
				(width 0)
				(type default)
			)
			(fill no)
			(layer "F.Fab")
		)
		(pad "1" smd custom
			(at 0 -0.4445 270)
			(size 0.1397 0.1397)
			(layers "F.Cu" "F.Mask" "F.Paste")
			(net "DRIVE_A_12_FLT_LED")
			(options
				(clearance outline)
				(anchor circle)
			)
			(primitives
				(gr_poly
					(pts
						(arc
							(start -0.1778 -0.2794)
							(mid -0.249642 -0.249642)
							(end -0.2794 -0.1778)
						)
						(arc
							(start -0.2794 0.1778)
							(mid -0.249642 0.249642)
							(end -0.1778 0.2794)
						)
						(arc
							(start 0.1778 0.2794)
							(mid 0.249642 0.249642)
							(end 0.2794 0.1778)
						)
						(arc
							(start 0.2794 -0.1778)
							(mid 0.249642 -0.249642)
							(end 0.1778 -0.2794)
						)
					)
					(width 0)
					(fill yes)
				)
			)
		)
		(pad "2" smd custom
			(at 0 0.4445 270)
			(size 0.1397 0.1397)
			(layers "F.Cu" "F.Mask" "F.Paste")
			(net "GND")
			(options
				(clearance outline)
				(anchor circle)
			)
			(primitives
				(gr_poly
					(pts
						(arc
							(start -0.1778 -0.2794)
							(mid -0.249642 -0.249642)
							(end -0.2794 -0.1778)
						)
						(arc
							(start -0.2794 0.1778)
							(mid -0.249642 0.249642)
							(end -0.1778 0.2794)
						)
						(arc
							(start 0.1778 0.2794)
							(mid 0.249642 0.249642)
							(end 0.2794 0.1778)
						)
						(arc
							(start 0.2794 -0.1778)
							(mid 0.249642 -0.249642)
							(end 0.1778 -0.2794)
						)
					)
					(width 0)
					(fill yes)
				)
			)
		)
	)
	(footprint ""
		(layer "F.Cu")
		(at 244.200172 -273.205702)
		(property "Reference" ""
			(at 0 0 0)
			(layer "F.SilkS")
			(hide yes)
			(effects
				(font
					(size 1.27 1.27)
				)
			)
		)
		(property "Value" "*"
			(at -8.398764 -8.057642 0)
			(unlocked yes)
			(layer "F.Fab")
			(hide yes)
			(effects
				(font
					(size 1.016 1.016)
					(thickness 0.1524)
				)
			)
		)
		(duplicate_pad_numbers_are_jumpers no)
		(fp_poly
			(pts
				(arc
					(start 7.3152 0)
					(mid 0 7.3152)
					(end -7.3152 0)
				)
				(arc
					(start -7.3152 -5.9944)
					(mid 0 -13.3096)
					(end 7.3152 -5.9944)
				)
			)
			(stroke
				(width 0)
				(type default)
			)
			(fill no)
			(layer "B.CrtYd")
		)
		(fp_poly
			(pts
				(arc
					(start 7.3152 0)
					(mid 0 7.3152)
					(end -7.3152 0)
				)
				(arc
					(start -7.3152 -5.9944)
					(mid 0 -13.3096)
					(end 7.3152 -5.9944)
				)
			)
			(stroke
				(width 0)
				(type default)
			)
			(fill no)
			(layer "F.CrtYd")
		)
		(fp_poly
			(pts
				(arc
					(start 7.3152 0)
					(mid 0 7.3152)
					(end -7.3152 0)
				)
				(arc
					(start -7.3152 -5.9944)
					(mid 0 -13.3096)
					(end 7.3152 -5.9944)
				)
			)
			(stroke
				(width 0)
				(type default)
			)
			(fill no)
			(layer "B.Fab")
		)
		(fp_poly
			(pts
				(arc
					(start 7.3152 0)
					(mid 0 7.3152)
					(end -7.3152 0)
				)
				(arc
					(start -7.3152 -5.9944)
					(mid 0 -13.3096)
					(end 7.3152 -5.9944)
				)
			)
			(stroke
				(width 0)
				(type default)
			)
			(fill no)
			(layer "F.Fab")
		)
		(pad "1" thru_hole oval
			(at 0 0)
			(size 14.0208 20.0152)
			(drill 0.0254
				(offset 0 -2.9972)
			)
			(layers "*.Cu" "*.Mask")
			(remove_unused_layers no)
			(net "Net_66")
			(clearance -1.002284)
			(thermal_gap 0.1524)
			(padstack
				(mode front_inner_back)
				(layer "Inner"
					(shape custom)
					(size 2.928012 2.928012)
					(options
						(anchor circle)
					)
					(primitives
						(gr_poly
							(pts
								(arc
									(start 4.571746 -2.084324)
									(mid 0.000333 7.430372)
									(end -4.571492 -2.084324)
								)
								(arc
									(start -4.571492 -2.084324)
									(mid -3.570296 -3.611977)
									(end -2.875026 -5.30098)
								)
								(arc
									(start -2.875026 -5.30098)
									(mid 0.000217 -7.43089)
									(end 2.87528 -5.30098)
								)
								(arc
									(start 2.87528 -5.30098)
									(mid 3.570511 -3.611956)
									(end 4.571746 -2.084324)
								)
							)
							(width 0)
							(fill yes)
						)
					)
					(clearance 0.1524)
				)
				(layer "B.Cu"
					(shape oval)
					(size 14.0208 20.0152)
					(offset 0 -2.9972)
					(clearance -1.002284)
				)
			)
		)
		(zone
			(layers "F.Cu" "B.Cu" "In1.Cu" "In2.Cu" "In3.Cu" "In4.Cu" "In5.Cu" "In6.Cu"
				"In7.Cu" "In8.Cu" "In9.Cu" "In10.Cu"
			)
			(hatch none 0.5)
			(connect_pads
				(clearance 0)
			)
			(min_thickness 0.25)
			(keepout
				(tracks not_allowed)
				(vias allowed)
				(pads allowed)
				(copperpour not_allowed)
				(footprints allowed)
			)
			(placement
				(enabled no)
				(sheetname "")
			)
			(fill
				(thermal_gap 0.5)
				(thermal_bridge_width 0.5)
				(island_removal_mode 0)
			)
			(polygon
				(pts
					(arc
						(start 237.189772 -279.200102)
						(mid 244.200172 -286.210502)
						(end 251.210572 -279.200102)
					)
					(arc
						(start 251.210572 -273.205702)
						(mid 244.200172 -266.195302)
						(end 237.189772 -273.205702)
					)
				)
			)
		)
	)
	(footprint ""
		(layer "F.Cu")
		(at 396.60195 -188.954918 180)
		(property "Reference" "C306"
			(at 0 0 180)
			(layer "F.SilkS")
			(hide yes)
			(effects
				(font
					(size 1.27 1.27)
				)
			)
		)
		(property "Value" "SC4D7U25V5KX-1-GP"
			(at -0.0762 -6.1214 180)
			(unlocked yes)
			(layer "F.Fab")
			(hide yes)
			(effects
				(font
					(size 1.016 1.016)
					(thickness 0.1524)
				)
			)
		)
		(property "Device Type" "C805H58"
			(at -0.0762 -8.1534 180)
			(unlocked yes)
			(layer "F.Fab")
			(hide yes)
			(effects
				(font
					(size 1.016 1.016)
					(thickness 0.1524)
				)
			)
		)
		(duplicate_pad_numbers_are_jumpers no)
		(fp_line
			(start 0.635 0)
			(end -0.635 0)
			(stroke
				(width 0.508)
				(type default)
			)
			(layer "F.SilkS")
		)
		(fp_rect
			(start -0.9652 1.778)
			(end 0.9652 -1.778)
			(stroke
				(width 0)
				(type default)
			)
			(fill no)
			(layer "F.CrtYd")
		)
		(fp_poly
			(pts
				(xy -0.9652 -1.778) (xy 0.9652 -1.778) (xy 0.9652 1.778) (xy -0.9652 1.778)
			)
			(stroke
				(width 0)
				(type default)
			)
			(fill no)
			(layer "F.Fab")
		)
		(pad "1" smd rect
			(at 0 -0.9652 180)
			(size 1.397 1.143)
			(layers "F.Cu" "F.Mask" "F.Paste")
			(net "P12V_HDD20")
		)
		(pad "2" smd rect
			(at 0 0.9652 180)
			(size 1.397 1.143)
			(layers "F.Cu" "F.Mask" "F.Paste")
			(net "GND")
		)
	)
	(footprint ""
		(layer "F.Cu")
		(at 467.592918 -156.522674 180)
		(property "Reference" "R669"
			(at 0 0 180)
			(layer "F.SilkS")
			(hide yes)
			(effects
				(font
					(size 1.27 1.27)
				)
			)
		)
		(property "Value" "0R2J-2-GP"
			(at 0.064008 -3.993896 180)
			(unlocked yes)
			(layer "F.Fab")
			(hide yes)
			(effects
				(font
					(size 1.016 1.016)
					(thickness 0.1524)
				)
			)
		)
		(property "Device Type" "R402H16"
			(at 0.064008 -5.517896 180)
			(unlocked yes)
			(layer "F.Fab")
			(hide yes)
			(effects
				(font
					(size 1.016 1.016)
					(thickness 0.1524)
				)
			)
		)
		(duplicate_pad_numbers_are_jumpers no)
		(fp_line
			(start 0.508 -0.9398)
			(end -0.508 -0.9398)
			(stroke
				(width 0.1524)
				(type default)
			)
			(layer "F.SilkS")
		)
		(fp_line
			(start -0.508 -0.9398)
			(end -0.508 0.9398)
			(stroke
				(width 0.1524)
				(type default)
			)
			(layer "F.SilkS")
		)
		(fp_rect
			(start -0.508 0.9398)
			(end 0.508 -0.9398)
			(stroke
				(width 0)
				(type default)
			)
			(fill no)
			(layer "F.CrtYd")
		)
		(fp_rect
			(start -0.508 0.9398)
			(end 0.508 -0.9398)
			(stroke
				(width 0)
				(type default)
			)
			(fill no)
			(layer "F.Fab")
		)
		(pad "1" smd custom
			(at 0 -0.4445 180)
			(size 0.1397 0.1397)
			(layers "F.Cu" "F.Mask" "F.Paste")
			(net "DRIVE_A_23_PWR")
			(options
				(clearance outline)
				(anchor circle)
			)
			(primitives
				(gr_poly
					(pts
						(arc
							(start -0.1778 -0.2794)
							(mid -0.249642 -0.249642)
							(end -0.2794 -0.1778)
						)
						(arc
							(start -0.2794 0.1778)
							(mid -0.249642 0.249642)
							(end -0.1778 0.2794)
						)
						(arc
							(start 0.1778 0.2794)
							(mid 0.249642 0.249642)
							(end 0.2794 0.1778)
						)
						(arc
							(start 0.2794 -0.1778)
							(mid 0.249642 -0.249642)
							(end 0.1778 -0.2794)
						)
					)
					(width 0)
					(fill yes)
				)
			)
		)
		(pad "2" smd custom
			(at 0 0.4445 180)
			(size 0.1397 0.1397)
			(layers "F.Cu" "F.Mask" "F.Paste")
			(net "SW_PWR_R_HDD23")
			(options
				(clearance outline)
				(anchor circle)
			)
			(primitives
				(gr_poly
					(pts
						(arc
							(start -0.1778 -0.2794)
							(mid -0.249642 -0.249642)
							(end -0.2794 -0.1778)
						)
						(arc
							(start -0.2794 0.1778)
							(mid -0.249642 0.249642)
							(end -0.1778 0.2794)
						)
						(arc
							(start 0.1778 0.2794)
							(mid 0.249642 0.249642)
							(end 0.2794 0.1778)
						)
						(arc
							(start 0.2794 -0.1778)
							(mid 0.249642 -0.249642)
							(end 0.1778 -0.2794)
						)
					)
					(width 0)
					(fill yes)
				)
			)
		)
	)
	(footprint ""
		(layer "F.Cu")
		(at 265.734038 21.556218 -90)
		(property "Reference" "C76"
			(at 0 0 270)
			(layer "F.SilkS")
			(hide yes)
			(effects
				(font
					(size 1.27 1.27)
				)
			)
		)
		(property "Value" "SC47U16V0MX-GP"
			(at -0.00254 -4.78536 270)
			(unlocked yes)
			(layer "F.Fab")
			(hide yes)
			(effects
				(font
					(size 1.016 1.016)
					(thickness 0.1524)
				)
			)
		)
		(property "Device Type" "C1210H107"
			(at -0.00254 -6.38048 270)
			(unlocked yes)
			(layer "F.Fab")
			(hide yes)
			(effects
				(font
					(size 1.016 1.016)
					(thickness 0.1524)
				)
			)
		)
		(duplicate_pad_numbers_are_jumpers no)
		(fp_line
			(start -1.5748 2.3368)
			(end 1.5748 2.3368)
			(stroke
				(width 0.1524)
				(type default)
			)
			(layer "F.SilkS")
		)
		(fp_line
			(start 1.5748 2.3368)
			(end 1.5748 0.762)
			(stroke
				(width 0.1524)
				(type default)
			)
			(layer "F.SilkS")
		)
		(fp_line
			(start -1.5748 0.762)
			(end -1.5748 2.3368)
			(stroke
				(width 0.1524)
				(type default)
			)
			(layer "F.SilkS")
		)
		(fp_line
			(start 1.5748 -0.762)
			(end 1.5748 -2.3368)
			(stroke
				(width 0.1524)
				(type default)
			)
			(layer "F.SilkS")
		)
		(fp_line
			(start -1.5748 -2.3368)
			(end -1.5748 -0.762)
			(stroke
				(width 0.1524)
				(type default)
			)
			(layer "F.SilkS")
		)
		(fp_line
			(start 1.5748 -2.3368)
			(end -1.5748 -2.3368)
			(stroke
				(width 0.1524)
				(type default)
			)
			(layer "F.SilkS")
		)
		(fp_rect
			(start -1.651 2.413)
			(end 1.651 -2.413)
			(stroke
				(width 0)
				(type default)
			)
			(fill no)
			(layer "F.CrtYd")
		)
		(fp_poly
			(pts
				(xy 1.651 2.413) (xy 1.651 -2.413) (xy -1.651 -2.413) (xy -1.651 2.413)
			)
			(stroke
				(width 0)
				(type default)
			)
			(fill no)
			(layer "F.Fab")
		)
		(pad "1" smd rect
			(at 0 -1.4732 270)
			(size 2.794 1.397)
			(layers "F.Cu" "F.Mask" "F.Paste")
			(net "P5V_USB_B")
		)
		(pad "2" smd rect
			(at 0 1.4732 270)
			(size 2.794 1.397)
			(layers "F.Cu" "F.Mask" "F.Paste")
			(net "GND")
		)
	)
	(footprint ""
		(layer "F.Cu")
		(at 143.049498 -168.126918 -90)
		(property "Reference" "C256"
			(at 0 0 270)
			(layer "F.SilkS")
			(hide yes)
			(effects
				(font
					(size 1.27 1.27)
				)
			)
		)
		(property "Value" "SCD033U25V2KX-GP"
			(at 1.1811 -2.7051 270)
			(unlocked yes)
			(layer "F.Fab")
			(hide yes)
			(effects
				(font
					(size 1.016 1.016)
					(thickness 0.1524)
				)
			)
		)
		(property "Device Type" "C402H22"
			(at 1.1811 -4.2291 270)
			(unlocked yes)
			(layer "F.Fab")
			(hide yes)
			(effects
				(font
					(size 1.016 1.016)
					(thickness 0.1524)
				)
			)
		)
		(duplicate_pad_numbers_are_jumpers no)
		(fp_rect
			(start -0.4318 0.9525)
			(end 0.4318 -0.9525)
			(stroke
				(width 0)
				(type default)
			)
			(fill no)
			(layer "F.CrtYd")
		)
		(fp_rect
			(start -0.4318 0.9525)
			(end 0.4318 -0.9525)
			(stroke
				(width 0)
				(type default)
			)
			(fill no)
			(layer "F.Fab")
		)
		(pad "1" smd custom
			(at 0 -0.4445 270)
			(size 0.1524 0.1524)
			(layers "F.Cu" "F.Mask" "F.Paste")
			(net "SW_HDD_P16")
			(options
				(clearance outline)
				(anchor circle)
			)
			(primitives
				(gr_poly
					(pts
						(arc
							(start 0.3048 -0.2032)
							(mid 0.275042 -0.275042)
							(end 0.2032 -0.3048)
						)
						(arc
							(start -0.2032 -0.3048)
							(mid -0.275042 -0.275042)
							(end -0.3048 -0.2032)
						)
						(arc
							(start -0.3048 0.2032)
							(mid -0.275042 0.275042)
							(end -0.2032 0.3048)
						)
						(arc
							(start 0.2032 0.3048)
							(mid 0.275042 0.275042)
							(end 0.3048 0.2032)
						)
					)
					(width 0)
					(fill yes)
				)
			)
		)
		(pad "2" smd custom
			(at 0 0.4445 270)
			(size 0.1524 0.1524)
			(layers "F.Cu" "F.Mask" "F.Paste")
			(net "GND")
			(options
				(clearance outline)
				(anchor circle)
			)
			(primitives
				(gr_poly
					(pts
						(arc
							(start 0.3048 -0.2032)
							(mid 0.275042 -0.275042)
							(end 0.2032 -0.3048)
						)
						(arc
							(start -0.2032 -0.3048)
							(mid -0.275042 -0.275042)
							(end -0.3048 -0.2032)
						)
						(arc
							(start -0.3048 0.2032)
							(mid -0.275042 0.275042)
							(end -0.2032 0.3048)
						)
						(arc
							(start 0.2032 0.3048)
							(mid 0.275042 0.275042)
							(end 0.3048 0.2032)
						)
					)
					(width 0)
					(fill yes)
				)
			)
		)
	)
	(footprint ""
		(layer "F.Cu")
		(at 255.0414 14.292072)
		(property "Reference" "Q1"
			(at 0 0 0)
			(layer "F.SilkS")
			(hide yes)
			(effects
				(font
					(size 1.27 1.27)
				)
			)
		)
		(property "Value" "2N7002KDW-GP"
			(at -2.3622 -8.2042 0)
			(unlocked yes)
			(layer "F.Fab")
			(hide yes)
			(effects
				(font
					(size 1.016 1.016)
					(thickness 0.1524)
				)
			)
		)
		(property "Device Type" "SOT-363H44"
			(at -2.3622 -10.1092 0)
			(unlocked yes)
			(layer "F.Fab")
			(hide yes)
			(effects
				(font
					(size 1.016 1.016)
					(thickness 0.1524)
				)
			)
		)
		(duplicate_pad_numbers_are_jumpers no)
		(fp_line
			(start -1.4478 -1.7018)
			(end -1.4478 1.7018)
			(stroke
				(width 0.1524)
				(type default)
			)
			(layer "F.SilkS")
		)
		(fp_line
			(start -1.4478 1.7018)
			(end 1.4478 1.7018)
			(stroke
				(width 0.1524)
				(type default)
			)
			(layer "F.SilkS")
		)
		(fp_line
			(start -1.27 1.524)
			(end -1.27 0.6604)
			(stroke
				(width 0.4826)
				(type default)
			)
			(layer "F.SilkS")
		)
		(fp_line
			(start 1.4478 -1.7018)
			(end -1.4478 -1.7018)
			(stroke
				(width 0.1524)
				(type default)
			)
			(layer "F.SilkS")
		)
		(fp_line
			(start 1.4478 1.7018)
			(end 1.4478 -1.7018)
			(stroke
				(width 0.1524)
				(type default)
			)
			(layer "F.SilkS")
		)
		(fp_poly
			(pts
				(xy -1.524 -1.778) (xy 1.524 -1.778) (xy 1.524 1.778) (xy -1.524 1.778)
			)
			(stroke
				(width 0)
				(type default)
			)
			(fill no)
			(layer "F.CrtYd")
		)
		(fp_poly
			(pts
				(xy -1.524 -1.778) (xy 1.524 -1.778) (xy 1.524 1.778) (xy -1.524 1.778)
			)
			(stroke
				(width 0)
				(type default)
			)
			(fill no)
			(layer "F.Fab")
		)
		(pad "1" smd rect
			(at -0.65024 0.9398)
			(size 0.4064 1.016)
			(layers "F.Cu" "F.Mask" "F.Paste")
			(net "GND")
		)
		(pad "2" smd rect
			(at 0 0.9398)
			(size 0.4064 1.016)
			(layers "F.Cu" "F.Mask" "F.Paste")
			(net "SCC_A_PWR_LED")
		)
		(pad "3" smd rect
			(at 0.65024 0.9398)
			(size 0.4064 1.016)
			(layers "F.Cu" "F.Mask" "F.Paste")
			(net "SYS_PWR_LED_A")
		)
		(pad "4" smd rect
			(at 0.65024 -0.9398)
			(size 0.4064 1.016)
			(layers "F.Cu" "F.Mask" "F.Paste")
			(net "GND")
		)
		(pad "5" smd rect
			(at 0 -0.9398)
			(size 0.4064 1.016)
			(layers "F.Cu" "F.Mask" "F.Paste")
			(net "IOM_A_PWR_LED")
		)
		(pad "6" smd rect
			(at -0.65024 -0.9398)
			(size 0.4064 1.016)
			(layers "F.Cu" "F.Mask" "F.Paste")
			(net "SYS_PWR_LED_A")
		)
	)
	(footprint ""
		(layer "F.Cu")
		(at 458.3049 -42.585894)
		(property "Reference" "R924"
			(at 0 0 0)
			(layer "F.SilkS")
			(hide yes)
			(effects
				(font
					(size 1.27 1.27)
				)
			)
		)
		(property "Value" "4K7R2J-2-GP"
			(at 0.064008 -3.993896 0)
			(unlocked yes)
			(layer "F.Fab")
			(hide yes)
			(effects
				(font
					(size 1.016 1.016)
					(thickness 0.1524)
				)
			)
		)
		(property "Device Type" "R402H16"
			(at 0.064008 -5.517896 0)
			(unlocked yes)
			(layer "F.Fab")
			(hide yes)
			(effects
				(font
					(size 1.016 1.016)
					(thickness 0.1524)
				)
			)
		)
		(duplicate_pad_numbers_are_jumpers no)
		(fp_line
			(start -0.508 -0.9398)
			(end -0.508 0.9398)
			(stroke
				(width 0.1524)
				(type default)
			)
			(layer "F.SilkS")
		)
		(fp_line
			(start 0.508 -0.9398)
			(end -0.508 -0.9398)
			(stroke
				(width 0.1524)
				(type default)
			)
			(layer "F.SilkS")
		)
		(fp_rect
			(start -0.508 0.9398)
			(end 0.508 -0.9398)
			(stroke
				(width 0)
				(type default)
			)
			(fill no)
			(layer "F.CrtYd")
		)
		(fp_rect
			(start -0.508 0.9398)
			(end 0.508 -0.9398)
			(stroke
				(width 0)
				(type default)
			)
			(fill no)
			(layer "F.Fab")
		)
		(pad "1" smd custom
			(at 0 -0.4445)
			(size 0.1397 0.1397)
			(layers "F.Cu" "F.Mask" "F.Paste")
			(net "SW_PWR_R_HDD34")
			(options
				(clearance outline)
				(anchor circle)
			)
			(primitives
				(gr_poly
					(pts
						(arc
							(start -0.1778 -0.2794)
							(mid -0.249642 -0.249642)
							(end -0.2794 -0.1778)
						)
						(arc
							(start -0.2794 0.1778)
							(mid -0.249642 0.249642)
							(end -0.1778 0.2794)
						)
						(arc
							(start 0.1778 0.2794)
							(mid 0.249642 0.249642)
							(end 0.2794 0.1778)
						)
						(arc
							(start 0.2794 -0.1778)
							(mid 0.249642 -0.249642)
							(end 0.1778 -0.2794)
						)
					)
					(width 0)
					(fill yes)
				)
			)
		)
		(pad "2" smd custom
			(at 0 0.4445)
			(size 0.1397 0.1397)
			(layers "F.Cu" "F.Mask" "F.Paste")
			(net "GND")
			(options
				(clearance outline)
				(anchor circle)
			)
			(primitives
				(gr_poly
					(pts
						(arc
							(start -0.1778 -0.2794)
							(mid -0.249642 -0.249642)
							(end -0.2794 -0.1778)
						)
						(arc
							(start -0.2794 0.1778)
							(mid -0.249642 0.249642)
							(end -0.1778 0.2794)
						)
						(arc
							(start 0.1778 0.2794)
							(mid 0.249642 0.249642)
							(end 0.2794 0.1778)
						)
						(arc
							(start 0.2794 -0.1778)
							(mid 0.249642 -0.249642)
							(end 0.1778 -0.2794)
						)
					)
					(width 0)
					(fill yes)
				)
			)
		)
	)
	(footprint ""
		(layer "F.Cu")
		(at 246.207788 -385.310126 90)
		(property "Reference" "C583"
			(at 0 0 90)
			(layer "F.SilkS")
			(hide yes)
			(effects
				(font
					(size 1.27 1.27)
				)
			)
		)
		(property "Value" "SC1KP50V2KX-1GP"
			(at 1.1811 -2.7051 90)
			(unlocked yes)
			(layer "F.Fab")
			(hide yes)
			(effects
				(font
					(size 1.016 1.016)
					(thickness 0.1524)
				)
			)
		)
		(property "Device Type" "C402H22"
			(at 1.1811 -4.2291 90)
			(unlocked yes)
			(layer "F.Fab")
			(hide yes)
			(effects
				(font
					(size 1.016 1.016)
					(thickness 0.1524)
				)
			)
		)
		(duplicate_pad_numbers_are_jumpers no)
		(fp_rect
			(start -0.4318 0.9525)
			(end 0.4318 -0.9525)
			(stroke
				(width 0)
				(type default)
			)
			(fill no)
			(layer "F.CrtYd")
		)
		(fp_rect
			(start -0.4318 0.9525)
			(end 0.4318 -0.9525)
			(stroke
				(width 0)
				(type default)
			)
			(fill no)
			(layer "F.Fab")
		)
		(pad "1" smd custom
			(at 0 -0.4445 90)
			(size 0.1524 0.1524)
			(layers "F.Cu" "F.Mask" "F.Paste")
			(net "MB3_TEMP_B")
			(options
				(clearance outline)
				(anchor circle)
			)
			(primitives
				(gr_poly
					(pts
						(arc
							(start 0.3048 -0.2032)
							(mid 0.275042 -0.275042)
							(end 0.2032 -0.3048)
						)
						(arc
							(start -0.2032 -0.3048)
							(mid -0.275042 -0.275042)
							(end -0.3048 -0.2032)
						)
						(arc
							(start -0.3048 0.2032)
							(mid -0.275042 0.275042)
							(end -0.2032 0.3048)
						)
						(arc
							(start 0.2032 0.3048)
							(mid 0.275042 0.275042)
							(end 0.3048 0.2032)
						)
					)
					(width 0)
					(fill yes)
				)
			)
		)
		(pad "2" smd custom
			(at 0 0.4445 90)
			(size 0.1524 0.1524)
			(layers "F.Cu" "F.Mask" "F.Paste")
			(net "MB3_TEMP_E")
			(options
				(clearance outline)
				(anchor circle)
			)
			(primitives
				(gr_poly
					(pts
						(arc
							(start 0.3048 -0.2032)
							(mid 0.275042 -0.275042)
							(end 0.2032 -0.3048)
						)
						(arc
							(start -0.2032 -0.3048)
							(mid -0.275042 -0.275042)
							(end -0.3048 -0.2032)
						)
						(arc
							(start -0.3048 0.2032)
							(mid -0.275042 0.275042)
							(end -0.2032 0.3048)
						)
						(arc
							(start 0.2032 0.3048)
							(mid 0.275042 0.275042)
							(end 0.3048 0.2032)
						)
					)
					(width 0)
					(fill yes)
				)
			)
		)
	)
	(footprint ""
		(layer "F.Cu")
		(at 231.902 -254.635 180)
		(property "Reference" "U4"
			(at 0 0 180)
			(layer "F.SilkS")
			(hide yes)
			(effects
				(font
					(size 1.27 1.27)
				)
			)
		)
		(property "Value" "TCA9555PWR-GP"
			(at 0 -6.9342 180)
			(unlocked yes)
			(layer "F.Fab")
			(hide yes)
			(effects
				(font
					(size 1.016 1.016)
					(thickness 0.1524)
				)
			)
		)
		(property "Device Type" "TSOIC24H48"
			(at 0 -8.5852 180)
			(unlocked yes)
			(layer "F.Fab")
			(hide yes)
			(effects
				(font
					(size 1.016 1.016)
					(thickness 0.1524)
				)
			)
		)
		(duplicate_pad_numbers_are_jumpers no)
		(fp_line
			(start 3.81 1.397)
			(end -4.2291 1.397)
			(stroke
				(width 0.1524)
				(type default)
			)
			(layer "F.SilkS")
		)
		(fp_line
			(start 3.81 -1.397)
			(end 3.81 1.397)
			(stroke
				(width 0.1524)
				(type default)
			)
			(layer "F.SilkS")
		)
		(fp_line
			(start -3.429 0)
			(end -4.2291 0.8001)
			(stroke
				(width 0.1524)
				(type default)
			)
			(layer "F.SilkS")
		)
		(fp_line
			(start -4.22656 3.81)
			(end -4.2291 1.397)
			(stroke
				(width 0.508)
				(type default)
			)
			(layer "F.SilkS")
		)
		(fp_line
			(start -4.2291 3.937)
			(end -4.2291 -1.397)
			(stroke
				(width 0.1524)
				(type default)
			)
			(layer "F.SilkS")
		)
		(fp_line
			(start -4.2291 -0.8001)
			(end -3.429 0)
			(stroke
				(width 0.1524)
				(type default)
			)
			(layer "F.SilkS")
		)
		(fp_line
			(start -4.2291 -1.397)
			(end 3.81 -1.397)
			(stroke
				(width 0.1524)
				(type default)
			)
			(layer "F.SilkS")
		)
		(fp_poly
			(pts
				(xy -3.90652 -1.8542) (xy 3.90652 -1.8542) (xy 3.90652 1.8542) (xy -3.90652 1.8542)
			)
			(stroke
				(width 0)
				(type default)
			)
			(fill yes)
			(layer "F.SilkS")
		)
		(fp_poly
			(pts
				(xy -4.2164 3.81) (xy 4.2164 3.81) (xy 4.22656 -3.81) (xy -4.2164 -3.81)
			)
			(stroke
				(width 0)
				(type default)
			)
			(fill no)
			(layer "F.CrtYd")
		)
		(fp_poly
			(pts
				(xy -4.22656 -3.81) (xy 4.22656 -3.81) (xy 4.22656 3.81) (xy -4.22656 3.81)
			)
			(stroke
				(width 0)
				(type default)
			)
			(fill no)
			(layer "F.Fab")
		)
		(pad "1" smd rect
			(at -3.57632 2.8194 180)
			(size 0.3556 1.524)
			(layers "F.Cu" "F.Mask" "F.Paste")
			(net "IO_EXP4_INT_N")
		)
		(pad "2" smd rect
			(at -2.92608 2.8194 180)
			(size 0.3556 1.524)
			(layers "F.Cu" "F.Mask" "F.Paste")
			(net "IO_EXP4_A1")
		)
		(pad "3" smd rect
			(at -2.27584 2.8194 180)
			(size 0.3556 1.524)
			(layers "F.Cu" "F.Mask" "F.Paste")
			(net "IO_EXP4_A2")
		)
		(pad "4" smd rect
			(at -1.6256 2.8194 180)
			(size 0.3556 1.524)
			(layers "F.Cu" "F.Mask" "F.Paste")
			(net "DRIVE_A_0_INS")
		)
		(pad "5" smd rect
			(at -0.97536 2.8194 180)
			(size 0.3556 1.524)
			(layers "F.Cu" "F.Mask" "F.Paste")
			(net "DRIVE_A_1_INS")
		)
		(pad "6" smd rect
			(at -0.32512 2.8194 180)
			(size 0.3556 1.524)
			(layers "F.Cu" "F.Mask" "F.Paste")
			(net "DRIVE_A_2_INS")
		)
		(pad "7" smd rect
			(at 0.32512 2.8194 180)
			(size 0.3556 1.524)
			(layers "F.Cu" "F.Mask" "F.Paste")
			(net "DRIVE_A_3_INS")
		)
		(pad "8" smd rect
			(at 0.97536 2.8194 180)
			(size 0.3556 1.524)
			(layers "F.Cu" "F.Mask" "F.Paste")
			(net "DRIVE_A_4_INS")
		)
		(pad "9" smd rect
			(at 1.6256 2.8194 180)
			(size 0.3556 1.524)
			(layers "F.Cu" "F.Mask" "F.Paste")
			(net "DRIVE_A_5_INS")
		)
		(pad "10" smd rect
			(at 2.27584 2.8194 180)
			(size 0.3556 1.524)
			(layers "F.Cu" "F.Mask" "F.Paste")
			(net "DRIVE_A_6_INS")
		)
		(pad "11" smd rect
			(at 2.92608 2.8194 180)
			(size 0.3556 1.524)
			(layers "F.Cu" "F.Mask" "F.Paste")
			(net "DRIVE_A_7_INS")
		)
		(pad "12" smd rect
			(at 3.57632 2.8194 180)
			(size 0.3556 1.524)
			(layers "F.Cu" "F.Mask" "F.Paste")
			(net "GND")
		)
		(pad "13" smd rect
			(at 3.57632 -2.8194 180)
			(size 0.3556 1.524)
			(layers "F.Cu" "F.Mask" "F.Paste")
			(net "DRIVE_A_8_INS")
		)
		(pad "14" smd rect
			(at 2.92608 -2.8194 180)
			(size 0.3556 1.524)
			(layers "F.Cu" "F.Mask" "F.Paste")
			(net "DRIVE_A_9_INS")
		)
		(pad "15" smd rect
			(at 2.27584 -2.8194 180)
			(size 0.3556 1.524)
			(layers "F.Cu" "F.Mask" "F.Paste")
			(net "DRIVE_A_10_INS")
		)
		(pad "16" smd rect
			(at 1.6256 -2.8194 180)
			(size 0.3556 1.524)
			(layers "F.Cu" "F.Mask" "F.Paste")
			(net "DRIVE_A_11_INS")
		)
		(pad "17" smd rect
			(at 0.97536 -2.8194 180)
			(size 0.3556 1.524)
			(layers "F.Cu" "F.Mask" "F.Paste")
			(net "DRIVE_A_12_INS")
		)
		(pad "18" smd rect
			(at 0.32512 -2.8194 180)
			(size 0.3556 1.524)
			(layers "F.Cu" "F.Mask" "F.Paste")
			(net "DRIVE_A_13_INS")
		)
		(pad "19" smd rect
			(at -0.32512 -2.8194 180)
			(size 0.3556 1.524)
			(layers "F.Cu" "F.Mask" "F.Paste")
			(net "DRIVE_A_14_INS")
		)
		(pad "20" smd rect
			(at -0.97536 -2.8194 180)
			(size 0.3556 1.524)
			(layers "F.Cu" "F.Mask" "F.Paste")
			(net "DRIVE_A_15_INS")
		)
		(pad "21" smd rect
			(at -1.6256 -2.8194 180)
			(size 0.3556 1.524)
			(layers "F.Cu" "F.Mask" "F.Paste")
			(net "IO_EXP4_A0")
		)
		(pad "22" smd rect
			(at -2.27584 -2.8194 180)
			(size 0.3556 1.524)
			(layers "F.Cu" "F.Mask" "F.Paste")
			(net "IO_EXP4_SCL")
		)
		(pad "23" smd rect
			(at -2.92608 -2.8194 180)
			(size 0.3556 1.524)
			(layers "F.Cu" "F.Mask" "F.Paste")
			(net "IO_EXP4_SDA")
		)
		(pad "24" smd rect
			(at -3.57632 -2.8194 180)
			(size 0.3556 1.524)
			(layers "F.Cu" "F.Mask" "F.Paste")
			(net "P3V3_STBY_A")
		)
	)
	(footprint ""
		(layer "F.Cu")
		(at 133.313424 -127.78867 180)
		(property "Reference" "Q243"
			(at 0 0 180)
			(layer "F.SilkS")
			(hide yes)
			(effects
				(font
					(size 1.27 1.27)
				)
			)
		)
		(property "Value" "2N7002K-2-GP"
			(at 0.127 -8.9662 180)
			(unlocked yes)
			(layer "F.Fab")
			(hide yes)
			(effects
				(font
					(size 1.016 1.016)
					(thickness 0.1524)
				)
			)
		)
		(property "Device Type" "SOT23DGS2D4H44"
			(at 0.127 -10.4902 180)
			(unlocked yes)
			(layer "F.Fab")
			(hide yes)
			(effects
				(font
					(size 1.016 1.016)
					(thickness 0.1524)
				)
			)
		)
		(duplicate_pad_numbers_are_jumpers no)
		(fp_line
			(start 1.651 1.778)
			(end 1.651 -1.778)
			(stroke
				(width 0.1524)
				(type default)
			)
			(layer "F.SilkS")
		)
		(fp_line
			(start 1.651 -1.778)
			(end -1.651 -1.778)
			(stroke
				(width 0.1524)
				(type default)
			)
			(layer "F.SilkS")
		)
		(fp_line
			(start -1.651 1.778)
			(end 1.651 1.778)
			(stroke
				(width 0.1524)
				(type default)
			)
			(layer "F.SilkS")
		)
		(fp_line
			(start -1.651 -1.778)
			(end -1.651 1.778)
			(stroke
				(width 0.1524)
				(type default)
			)
			(layer "F.SilkS")
		)
		(fp_poly
			(pts
				(xy -1.778 1.8796) (xy -1.778 -1.8796) (xy 1.778 -1.8796) (xy 1.778 1.8796)
			)
			(stroke
				(width 0)
				(type default)
			)
			(fill no)
			(layer "F.CrtYd")
		)
		(fp_poly
			(pts
				(xy -1.778 1.8796) (xy -1.778 -1.8796) (xy 1.778 -1.8796) (xy 1.778 1.8796)
			)
			(stroke
				(width 0)
				(type default)
			)
			(fill no)
			(layer "F.Fab")
		)
		(pad "D" smd custom
			(at 0 -0.9525 180)
			(size 0.1905 0.1905)
			(layers "F.Cu" "F.Mask" "F.Paste")
			(net "FLT_HDD16_N")
			(options
				(clearance outline)
				(anchor circle)
			)
			(primitives
				(gr_poly
					(pts
						(arc
							(start -0.1778 0.5715)
							(mid -0.321484 0.511984)
							(end -0.381 0.3683)
						)
						(arc
							(start -0.381 -0.3683)
							(mid -0.321484 -0.511984)
							(end -0.1778 -0.5715)
						)
						(arc
							(start 0.1778 -0.5715)
							(mid 0.321484 -0.511984)
							(end 0.381 -0.3683)
						)
						(arc
							(start 0.381 0.3683)
							(mid 0.321484 0.511984)
							(end 0.1778 0.5715)
						)
					)
					(width 0)
					(fill yes)
				)
			)
		)
		(pad "G" smd custom
			(at -0.98425 0.9525 180)
			(size 0.1905 0.1905)
			(layers "F.Cu" "F.Mask" "F.Paste")
			(net "DRIVE_A_16_FLT_LED")
			(options
				(clearance outline)
				(anchor circle)
			)
			(primitives
				(gr_poly
					(pts
						(arc
							(start -0.1778 0.5715)
							(mid -0.321484 0.511984)
							(end -0.381 0.3683)
						)
						(arc
							(start -0.381 -0.3683)
							(mid -0.321484 -0.511984)
							(end -0.1778 -0.5715)
						)
						(arc
							(start 0.1778 -0.5715)
							(mid 0.321484 -0.511984)
							(end 0.381 -0.3683)
						)
						(arc
							(start 0.381 0.3683)
							(mid 0.321484 0.511984)
							(end 0.1778 0.5715)
						)
					)
					(width 0)
					(fill yes)
				)
			)
		)
		(pad "S" smd custom
			(at 0.98425 0.9525 180)
			(size 0.1905 0.1905)
			(layers "F.Cu" "F.Mask" "F.Paste")
			(net "GND")
			(options
				(clearance outline)
				(anchor circle)
			)
			(primitives
				(gr_poly
					(pts
						(arc
							(start -0.1778 0.5715)
							(mid -0.321484 0.511984)
							(end -0.381 0.3683)
						)
						(arc
							(start -0.381 -0.3683)
							(mid -0.321484 -0.511984)
							(end -0.1778 -0.5715)
						)
						(arc
							(start 0.1778 -0.5715)
							(mid 0.321484 -0.511984)
							(end 0.381 -0.3683)
						)
						(arc
							(start 0.381 0.3683)
							(mid 0.321484 0.511984)
							(end 0.1778 0.5715)
						)
					)
					(width 0)
					(fill yes)
				)
			)
		)
	)
	(footprint ""
		(layer "F.Cu")
		(at 364.290102 -48.554894 -90)
		(property "Reference" "R850"
			(at 0 0 270)
			(layer "F.SilkS")
			(hide yes)
			(effects
				(font
					(size 1.27 1.27)
				)
			)
		)
		(property "Value" "4K7R2J-2-GP"
			(at 0.064008 -3.993896 270)
			(unlocked yes)
			(layer "F.Fab")
			(hide yes)
			(effects
				(font
					(size 1.016 1.016)
					(thickness 0.1524)
				)
			)
		)
		(property "Device Type" "R402H16"
			(at 0.064008 -5.517896 270)
			(unlocked yes)
			(layer "F.Fab")
			(hide yes)
			(effects
				(font
					(size 1.016 1.016)
					(thickness 0.1524)
				)
			)
		)
		(duplicate_pad_numbers_are_jumpers no)
		(fp_line
			(start -0.508 -0.9398)
			(end -0.508 0.9398)
			(stroke
				(width 0.1524)
				(type default)
			)
			(layer "F.SilkS")
		)
		(fp_line
			(start 0.508 -0.9398)
			(end -0.508 -0.9398)
			(stroke
				(width 0.1524)
				(type default)
			)
			(layer "F.SilkS")
		)
		(fp_rect
			(start -0.508 0.9398)
			(end 0.508 -0.9398)
			(stroke
				(width 0)
				(type default)
			)
			(fill no)
			(layer "F.CrtYd")
		)
		(fp_rect
			(start -0.508 0.9398)
			(end 0.508 -0.9398)
			(stroke
				(width 0)
				(type default)
			)
			(fill no)
			(layer "F.Fab")
		)
		(pad "1" smd custom
			(at 0 -0.4445 270)
			(size 0.1397 0.1397)
			(layers "F.Cu" "F.Mask" "F.Paste")
			(net "P12V_A")
			(options
				(clearance outline)
				(anchor circle)
			)
			(primitives
				(gr_poly
					(pts
						(arc
							(start -0.1778 -0.2794)
							(mid -0.249642 -0.249642)
							(end -0.2794 -0.1778)
						)
						(arc
							(start -0.2794 0.1778)
							(mid -0.249642 0.249642)
							(end -0.1778 0.2794)
						)
						(arc
							(start 0.1778 0.2794)
							(mid 0.249642 0.249642)
							(end 0.2794 0.1778)
						)
						(arc
							(start 0.2794 -0.1778)
							(mid 0.249642 -0.249642)
							(end 0.1778 -0.2794)
						)
					)
					(width 0)
					(fill yes)
				)
			)
		)
		(pad "2" smd custom
			(at 0 0.4445 270)
			(size 0.1397 0.1397)
			(layers "F.Cu" "F.Mask" "F.Paste")
			(net "SW_HDD_P31")
			(options
				(clearance outline)
				(anchor circle)
			)
			(primitives
				(gr_poly
					(pts
						(arc
							(start -0.1778 -0.2794)
							(mid -0.249642 -0.249642)
							(end -0.2794 -0.1778)
						)
						(arc
							(start -0.2794 0.1778)
							(mid -0.249642 0.249642)
							(end -0.1778 0.2794)
						)
						(arc
							(start 0.1778 0.2794)
							(mid 0.249642 0.249642)
							(end 0.2794 0.1778)
						)
						(arc
							(start 0.2794 -0.1778)
							(mid 0.249642 -0.249642)
							(end 0.1778 -0.2794)
						)
					)
					(width 0)
					(fill yes)
				)
			)
		)
	)
	(footprint ""
		(layer "F.Cu")
		(at 384.631438 -139.448794)
		(property "Reference" "D43"
			(at 0 0 0)
			(layer "F.SilkS")
			(hide yes)
			(effects
				(font
					(size 1.27 1.27)
				)
			)
		)
		(property "Value" "MMPZ5228BPT-GP"
			(at 0 -6.7818 0)
			(unlocked yes)
			(layer "F.Fab")
			(hide yes)
			(effects
				(font
					(size 1.016 1.016)
					(thickness 0.1524)
				)
			)
		)
		(property "Device Type" "SOD323AKH40"
			(at 0 -8.6868 0)
			(unlocked yes)
			(layer "F.Fab")
			(hide yes)
			(effects
				(font
					(size 1.016 1.016)
					(thickness 0.1524)
				)
			)
		)
		(duplicate_pad_numbers_are_jumpers no)
		(fp_line
			(start -0.889 -1.9304)
			(end 0.889 -1.9304)
			(stroke
				(width 0.1524)
				(type default)
			)
			(layer "F.SilkS")
		)
		(fp_line
			(start -0.889 2.159)
			(end -0.889 -1.9304)
			(stroke
				(width 0.1524)
				(type default)
			)
			(layer "F.SilkS")
		)
		(fp_line
			(start 0.762 2.0574)
			(end -0.762 2.0574)
			(stroke
				(width 0.508)
				(type default)
			)
			(layer "F.SilkS")
		)
		(fp_line
			(start 0.889 -1.9304)
			(end 0.889 2.159)
			(stroke
				(width 0.1524)
				(type default)
			)
			(layer "F.SilkS")
		)
		(fp_line
			(start 0.889 2.159)
			(end -0.889 2.159)
			(stroke
				(width 0.1524)
				(type default)
			)
			(layer "F.SilkS")
		)
		(fp_rect
			(start -1.016 2.3114)
			(end 1.016 -2.0066)
			(stroke
				(width 0)
				(type default)
			)
			(fill no)
			(layer "F.CrtYd")
		)
		(fp_poly
			(pts
				(xy -1.016 -2.0066) (xy 1.016 -2.0066) (xy 1.016 2.3114) (xy -1.016 2.3114)
			)
			(stroke
				(width 0)
				(type default)
			)
			(fill no)
			(layer "F.Fab")
		)
		(pad "A" smd rect
			(at 0 -1.143)
			(size 0.5588 1.016)
			(layers "F.Cu" "F.Mask" "F.Paste")
			(net "GND")
		)
		(pad "K" smd rect
			(at 0 1.143)
			(size 0.5588 1.016)
			(layers "F.Cu" "F.Mask" "F.Paste")
			(net "VCCP_B")
		)
	)
	(footprint ""
		(layer "F.Cu")
		(at 185.950098 -287.910016 -90)
		(property "Reference" "HDDSAS5"
			(at 0 0 270)
			(layer "F.SilkS")
			(hide yes)
			(effects
				(font
					(size 1.27 1.27)
				)
			)
		)
		(property "Value" "SKT-SAS15P-14P-45-GP"
			(at -20.7645 -8.9789 270)
			(unlocked yes)
			(layer "F.Fab")
			(hide yes)
			(effects
				(font
					(size 1.016 1.016)
					(thickness 0.1524)
				)
			)
		)
		(property "Device Type" "10120818-001C-TRLF"
			(at -20.7645 -10.5029 270)
			(unlocked yes)
			(layer "F.Fab")
			(hide yes)
			(effects
				(font
					(size 1.016 1.016)
					(thickness 0.1524)
				)
			)
		)
		(duplicate_pad_numbers_are_jumpers no)
		(fp_line
			(start 1.651 4.2926)
			(end 1.651 3.0099)
			(stroke
				(width 0.1524)
				(type default)
			)
			(layer "F.SilkS")
		)
		(fp_line
			(start 8.509 4.2926)
			(end 1.651 4.2926)
			(stroke
				(width 0.1524)
				(type default)
			)
			(layer "F.SilkS")
		)
		(fp_line
			(start -23.4188 3.0099)
			(end -23.4188 -3.2512)
			(stroke
				(width 0.1524)
				(type default)
			)
			(layer "F.SilkS")
		)
		(fp_line
			(start 1.651 3.0099)
			(end -23.4188 3.0099)
			(stroke
				(width 0.1524)
				(type default)
			)
			(layer "F.SilkS")
		)
		(fp_line
			(start 8.509 3.0099)
			(end 8.509 4.2926)
			(stroke
				(width 0.1524)
				(type default)
			)
			(layer "F.SilkS")
		)
		(fp_line
			(start 23.4188 3.0099)
			(end 8.509 3.0099)
			(stroke
				(width 0.1524)
				(type default)
			)
			(layer "F.SilkS")
		)
		(fp_line
			(start -23.4188 -3.2512)
			(end 23.4188 -3.2512)
			(stroke
				(width 0.1524)
				(type default)
			)
			(layer "F.SilkS")
		)
		(fp_line
			(start 23.4188 -3.2512)
			(end 23.4188 3.0099)
			(stroke
				(width 0.1524)
				(type default)
			)
			(layer "F.SilkS")
		)
		(fp_line
			(start 15.5067 -3.3401)
			(end 16.2687 -3.3401)
			(stroke
				(width 0.3302)
				(type default)
			)
			(layer "F.SilkS")
		)
		(fp_poly
			(pts
				(xy 15.868904 -3.230372) (xy 16.503904 -3.865372) (xy 15.233904 -3.865372)
			)
			(stroke
				(width 0)
				(type default)
			)
			(fill yes)
			(layer "F.SilkS")
		)
		(fp_poly
			(pts
				(xy -22.8727 -2.7559) (xy 22.8727 -2.7559) (xy 22.8727 2.7559) (xy 8.255 2.7559) (xy 8.255 3.5179)
				(xy 1.905 3.5179) (xy 1.905 2.7559) (xy -22.8727 2.7559)
			)
			(stroke
				(width 0)
				(type default)
			)
			(fill no)
			(layer "F.CrtYd")
		)
		(fp_poly
			(pts
				(xy 1.397 4.5466) (xy 1.397 3.2639) (xy -23.6728 3.2639) (xy -23.6728 -3.5052) (xy 23.6728 -3.5052)
				(xy 23.6728 -0.00635) (xy 22.8727 -0.00635) (xy 22.8727 -2.7559) (xy -22.8727 -2.7559) (xy -22.8727 2.7559)
				(xy 1.905 2.7559) (xy 1.905 3.5179) (xy 8.255 3.5179) (xy 8.255 2.7559) (xy 22.8727 2.7559) (xy 22.8727 0.00635)
				(xy 23.6728 0.00635) (xy 23.6728 3.2639) (xy 8.763 3.2639) (xy 8.763 4.5466)
			)
			(stroke
				(width 0)
				(type default)
			)
			(fill no)
			(layer "F.CrtYd")
		)
		(fp_poly
			(pts
				(xy 1.397 4.5466) (xy 1.397 3.2639) (xy -23.6728 3.2639) (xy -23.6728 -3.5052) (xy 23.6728 -3.5052)
				(xy 23.6728 3.2639) (xy 8.763 3.2639) (xy 8.763 4.5466)
			)
			(stroke
				(width 0)
				(type default)
			)
			(fill no)
			(layer "F.Fab")
		)
		(pad "" np_thru_hole circle
			(at -18.874994 0 270)
			(size 0.254 0.254)
			(drill 1.3462)
			(layers "*.Cu" "*.Mask")
			(clearance 0.9017)
			(thermal_gap 0.9017)
		)
		(pad "" np_thru_hole circle
			(at 18.874994 0 270)
			(size 0.254 0.254)
			(drill 0.9398)
			(layers "*.Cu" "*.Mask")
			(clearance 0.6985)
			(thermal_gap 0.6985)
		)
		(pad "G1" smd rect
			(at 21.874988 0 270)
			(size 2.5908 2.5908)
			(layers "F.Cu" "F.Mask" "F.Paste")
			(net "GND")
		)
		(pad "G2" smd rect
			(at -21.874988 0 270)
			(size 2.5908 2.5908)
			(layers "F.Cu" "F.Mask" "F.Paste")
			(net "GND")
		)
		(pad "P1" smd rect
			(at 1.905 -1.82499 270)
			(size 0.6096 2.3622)
			(layers "F.Cu" "F.Mask" "F.Paste")
			(net "Net_2016")
		)
		(pad "P2" smd rect
			(at 0.635 -1.82499 270)
			(size 0.6096 2.3622)
			(layers "F.Cu" "F.Mask" "F.Paste")
			(net "Net_2017")
		)
		(pad "P3" smd rect
			(at -0.635 -1.82499 270)
			(size 0.6096 2.3622)
			(layers "F.Cu" "F.Mask" "F.Paste")
			(net "Net_2018")
		)
		(pad "P4" smd rect
			(at -1.905 -1.82499 270)
			(size 0.6096 2.3622)
			(layers "F.Cu" "F.Mask" "F.Paste")
			(net "GND")
		)
		(pad "P5" smd rect
			(at -3.175 -1.82499 270)
			(size 0.6096 2.3622)
			(layers "F.Cu" "F.Mask" "F.Paste")
			(net "HDD_PRSNT_5")
		)
		(pad "P6" smd rect
			(at -4.445 -1.82499 270)
			(size 0.6096 2.3622)
			(layers "F.Cu" "F.Mask" "F.Paste")
			(net "GND")
		)
		(pad "P7" smd rect
			(at -5.715 -1.82499 270)
			(size 0.6096 2.3622)
			(layers "F.Cu" "F.Mask" "F.Paste")
			(net "5V_PRE_5")
		)
		(pad "P8" smd rect
			(at -6.985 -1.82499 270)
			(size 0.6096 2.3622)
			(layers "F.Cu" "F.Mask" "F.Paste")
			(net "P5V_HDD5")
		)
		(pad "P9" smd rect
			(at -8.255 -1.82499 270)
			(size 0.6096 2.3622)
			(layers "F.Cu" "F.Mask" "F.Paste")
			(net "P5V_HDD5")
		)
		(pad "P10" smd rect
			(at -9.525 -1.82499 270)
			(size 0.6096 2.3622)
			(layers "F.Cu" "F.Mask" "F.Paste")
			(net "GND")
		)
		(pad "P11" smd rect
			(at -10.795 -1.82499 270)
			(size 0.6096 2.3622)
			(layers "F.Cu" "F.Mask" "F.Paste")
			(net "ACT_HDD_5")
		)
		(pad "P12" smd rect
			(at -12.065 -1.82499 270)
			(size 0.6096 2.3622)
			(layers "F.Cu" "F.Mask" "F.Paste")
			(net "GND")
		)
		(pad "P13" smd rect
			(at -13.335 -1.82499 270)
			(size 0.6096 2.3622)
			(layers "F.Cu" "F.Mask" "F.Paste")
			(net "12V_PRE_5")
		)
		(pad "P14" smd rect
			(at -14.605 -1.82499 270)
			(size 0.6096 2.3622)
			(layers "F.Cu" "F.Mask" "F.Paste")
			(net "P12V_HDD5")
		)
		(pad "P15" smd rect
			(at -15.875 -1.82499 270)
			(size 0.6096 2.3622)
			(layers "F.Cu" "F.Mask" "F.Paste")
			(net "P12V_HDD5")
		)
		(pad "S1" smd rect
			(at 15.875 -1.82499 270)
			(size 0.6096 2.3622)
			(layers "F.Cu" "F.Mask" "F.Paste")
			(net "GND")
		)
		(pad "S2" smd rect
			(at 14.605 -1.82499 270)
			(size 0.6096 2.3622)
			(layers "F.Cu" "F.Mask" "F.Paste")
			(net "SAS_HDD_RX_P5")
		)
		(pad "S3" smd rect
			(at 13.335 -1.82499 270)
			(size 0.6096 2.3622)
			(layers "F.Cu" "F.Mask" "F.Paste")
			(net "SAS_HDD_RX_N5")
		)
		(pad "S4" smd rect
			(at 12.065 -1.82499 270)
			(size 0.6096 2.3622)
			(layers "F.Cu" "F.Mask" "F.Paste")
			(net "GND")
		)
		(pad "S5" smd rect
			(at 10.795 -1.82499 270)
			(size 0.6096 2.3622)
			(layers "F.Cu" "F.Mask" "F.Paste")
			(net "PHY_DRV_A_TO_SCC_A_5_DN")
		)
		(pad "S6" smd rect
			(at 9.525 -1.82499 270)
			(size 0.6096 2.3622)
			(layers "F.Cu" "F.Mask" "F.Paste")
			(net "PHY_DRV_A_TO_SCC_A_5_DP")
		)
		(pad "S7" smd rect
			(at 8.255 -1.82499 270)
			(size 0.6096 2.3622)
			(layers "F.Cu" "F.Mask" "F.Paste")
			(net "GND")
		)
		(pad "S8" smd rect
			(at 7.480046 2.845054 270)
			(size 0.508 2.3622)
			(layers "F.Cu" "F.Mask" "F.Paste")
			(net "GND")
		)
		(pad "S9" smd rect
			(at 6.679946 2.845054 270)
			(size 0.508 2.3622)
			(layers "F.Cu" "F.Mask" "F.Paste")
			(net "Net_477")
		)
		(pad "S10" smd rect
			(at 5.8801 2.845054 270)
			(size 0.508 2.3622)
			(layers "F.Cu" "F.Mask" "F.Paste")
			(net "Net_369")
		)
		(pad "S11" smd rect
			(at 5.08 2.845054 270)
			(size 0.508 2.3622)
			(layers "F.Cu" "F.Mask" "F.Paste")
			(net "GND")
		)
		(pad "S12" smd rect
			(at 4.2799 2.845054 270)
			(size 0.508 2.3622)
			(layers "F.Cu" "F.Mask" "F.Paste")
			(net "Net_405")
		)
		(pad "S13" smd rect
			(at 3.480054 2.845054 270)
			(size 0.508 2.3622)
			(layers "F.Cu" "F.Mask" "F.Paste")
			(net "Net_441")
		)
		(pad "S14" smd rect
			(at 2.679954 2.845054 270)
			(size 0.508 2.3622)
			(layers "F.Cu" "F.Mask" "F.Paste")
			(net "GND")
		)
		(zone
			(layer "F.Cu")
			(hatch none 0.5)
			(connect_pads
				(clearance 0)
			)
			(min_thickness 0.25)
			(keepout
				(tracks allowed)
				(vias not_allowed)
				(pads allowed)
				(copperpour not_allowed)
				(footprints allowed)
			)
			(placement
				(enabled no)
				(sheetname "")
			)
			(fill
				(thermal_gap 0.5)
				(thermal_bridge_width 0.5)
				(island_removal_mode 0)
			)
			(polygon
				(pts
					(xy 189.607698 -304.648616) (xy 182.533798 -304.648616) (xy 182.533798 -311.582816) (xy 183.638698 -311.582816)
					(xy 183.638698 -307.468016) (xy 188.261498 -307.468016) (xy 188.261498 -311.582816) (xy 189.607698 -311.582816)
				)
			)
		)
		(zone
			(layer "F.Cu")
			(hatch none 0.5)
			(connect_pads
				(clearance 0)
			)
			(min_thickness 0.25)
			(keepout
				(tracks not_allowed)
				(vias allowed)
				(pads allowed)
				(copperpour not_allowed)
				(footprints allowed)
			)
			(placement
				(enabled no)
				(sheetname "")
			)
			(fill
				(thermal_gap 0.5)
				(thermal_bridge_width 0.5)
				(island_removal_mode 0)
			)
			(polygon
				(pts
					(xy 189.607698 -304.648616) (xy 182.533798 -304.648616) (xy 182.533798 -311.582816) (xy 183.638698 -311.582816)
					(xy 183.638698 -307.468016) (xy 188.261498 -307.468016) (xy 188.261498 -311.582816) (xy 189.607698 -311.582816)
				)
			)
		)
		(zone
			(layer "F.Cu")
			(hatch none 0.5)
			(connect_pads
				(clearance 0)
			)
			(min_thickness 0.25)
			(keepout
				(tracks allowed)
				(vias not_allowed)
				(pads allowed)
				(copperpour not_allowed)
				(footprints allowed)
			)
			(placement
				(enabled no)
				(sheetname "")
			)
			(fill
				(thermal_gap 0.5)
				(thermal_bridge_width 0.5)
				(island_removal_mode 0)
			)
			(polygon
				(pts
					(xy 189.607698 -271.171416) (xy 182.533798 -271.171416) (xy 182.533798 -264.237216) (xy 183.638698 -264.237216)
					(xy 183.638698 -268.352016) (xy 188.261498 -268.352016) (xy 188.261498 -264.237216) (xy 189.607698 -264.237216)
				)
			)
		)
		(zone
			(layer "F.Cu")
			(hatch none 0.5)
			(connect_pads
				(clearance 0)
			)
			(min_thickness 0.25)
			(keepout
				(tracks not_allowed)
				(vias allowed)
				(pads allowed)
				(copperpour not_allowed)
				(footprints allowed)
			)
			(placement
				(enabled no)
				(sheetname "")
			)
			(fill
				(thermal_gap 0.5)
				(thermal_bridge_width 0.5)
				(island_removal_mode 0)
			)
			(polygon
				(pts
					(xy 189.607698 -271.171416) (xy 182.533798 -271.171416) (xy 182.533798 -264.237216) (xy 183.638698 -264.237216)
					(xy 183.638698 -268.352016) (xy 188.261498 -268.352016) (xy 188.261498 -264.237216) (xy 189.607698 -264.237216)
				)
			)
		)
		(zone
			(layers "F.Cu" "B.Cu" "In1.Cu" "In2.Cu" "In3.Cu" "In4.Cu" "In5.Cu" "In6.Cu"
				"In7.Cu" "In8.Cu" "In9.Cu" "In10.Cu"
			)
			(hatch none 0.5)
			(connect_pads
				(clearance 0)
			)
			(min_thickness 0.25)
			(keepout
				(tracks not_allowed)
				(vias allowed)
				(pads allowed)
				(copperpour not_allowed)
				(footprints allowed)
			)
			(placement
				(enabled no)
				(sheetname "")
			)
			(fill
				(thermal_gap 0.5)
				(thermal_bridge_width 0.5)
				(island_removal_mode 0)
			)
			(polygon
				(pts
					(arc
						(start 186.724798 -269.035022)
						(mid 185.175398 -269.035022)
						(end 186.724798 -269.035022)
					)
				)
			)
		)
		(zone
			(layers "F.Cu" "B.Cu" "In1.Cu" "In2.Cu" "In3.Cu" "In4.Cu" "In5.Cu" "In6.Cu"
				"In7.Cu" "In8.Cu" "In9.Cu" "In10.Cu"
			)
			(hatch none 0.5)
			(connect_pads
				(clearance 0)
			)
			(min_thickness 0.25)
			(keepout
				(tracks not_allowed)
				(vias allowed)
				(pads allowed)
				(copperpour not_allowed)
				(footprints allowed)
			)
			(placement
				(enabled no)
				(sheetname "")
			)
			(fill
				(thermal_gap 0.5)
				(thermal_bridge_width 0.5)
				(island_removal_mode 0)
			)
			(polygon
				(pts
					(arc
						(start 186.927998 -306.78501)
						(mid 184.972198 -306.78501)
						(end 186.927998 -306.78501)
					)
				)
			)
		)
	)
	(footprint ""
		(layer "F.Cu")
		(at 131.006596 -292.270942)
		(property "Reference" "R198"
			(at 0 0 0)
			(layer "F.SilkS")
			(hide yes)
			(effects
				(font
					(size 1.27 1.27)
				)
			)
		)
		(property "Value" "2R6F-GP"
			(at -0.0508 -4.8514 0)
			(unlocked yes)
			(layer "F.Fab")
			(hide yes)
			(effects
				(font
					(size 1.016 1.016)
					(thickness 0.1524)
				)
			)
		)
		(property "Device Type" "R1206H26"
			(at 0 -6.3754 0)
			(unlocked yes)
			(layer "F.Fab")
			(hide yes)
			(effects
				(font
					(size 1.016 1.016)
					(thickness 0.1524)
				)
			)
		)
		(duplicate_pad_numbers_are_jumpers no)
		(fp_line
			(start -1.016 -2.2352)
			(end 1.016 -2.2352)
			(stroke
				(width 0.1524)
				(type default)
			)
			(layer "F.SilkS")
		)
		(fp_line
			(start -1.016 2.2352)
			(end -1.016 -2.2352)
			(stroke
				(width 0.1524)
				(type default)
			)
			(layer "F.SilkS")
		)
		(fp_line
			(start 1.016 -2.2352)
			(end 1.016 2.2352)
			(stroke
				(width 0.1524)
				(type default)
			)
			(layer "F.SilkS")
		)
		(fp_line
			(start 1.016 2.2352)
			(end -1.016 2.2352)
			(stroke
				(width 0.1524)
				(type default)
			)
			(layer "F.SilkS")
		)
		(fp_rect
			(start -1.0922 2.3114)
			(end 1.0922 -2.3114)
			(stroke
				(width 0)
				(type default)
			)
			(fill no)
			(layer "F.CrtYd")
		)
		(fp_poly
			(pts
				(xy -1.0922 -2.3114) (xy 1.0922 -2.3114) (xy 1.0922 2.3114) (xy -1.0922 2.3114)
			)
			(stroke
				(width 0)
				(type default)
			)
			(fill no)
			(layer "F.Fab")
		)
		(pad "1" smd rect
			(at 0 -1.397)
			(size 1.651 1.27)
			(layers "F.Cu" "F.Mask" "F.Paste")
			(net "P5V_HDD3")
		)
		(pad "2" smd rect
			(at 0 1.397)
			(size 1.651 1.27)
			(layers "F.Cu" "F.Mask" "F.Paste")
			(net "5V_PRE_3")
		)
	)
	(footprint ""
		(layer "F.Cu")
		(at 28.575 -253.30912 180)
		(property "Reference" "R1223"
			(at 0 0 180)
			(layer "F.SilkS")
			(hide yes)
			(effects
				(font
					(size 1.27 1.27)
				)
			)
		)
		(property "Value" "0R2J-2-GP"
			(at 0.064008 -3.993896 180)
			(unlocked yes)
			(layer "F.Fab")
			(hide yes)
			(effects
				(font
					(size 1.016 1.016)
					(thickness 0.1524)
				)
			)
		)
		(property "Device Type" "R402H16"
			(at 0.064008 -5.517896 180)
			(unlocked yes)
			(layer "F.Fab")
			(hide yes)
			(effects
				(font
					(size 1.016 1.016)
					(thickness 0.1524)
				)
			)
		)
		(duplicate_pad_numbers_are_jumpers no)
		(fp_line
			(start 0.508 -0.9398)
			(end -0.508 -0.9398)
			(stroke
				(width 0.1524)
				(type default)
			)
			(layer "F.SilkS")
		)
		(fp_line
			(start -0.508 -0.9398)
			(end -0.508 0.9398)
			(stroke
				(width 0.1524)
				(type default)
			)
			(layer "F.SilkS")
		)
		(fp_rect
			(start -0.508 0.9398)
			(end 0.508 -0.9398)
			(stroke
				(width 0)
				(type default)
			)
			(fill no)
			(layer "F.CrtYd")
		)
		(fp_rect
			(start -0.508 0.9398)
			(end 0.508 -0.9398)
			(stroke
				(width 0)
				(type default)
			)
			(fill no)
			(layer "F.Fab")
		)
		(pad "1" smd custom
			(at 0 -0.4445 180)
			(size 0.1397 0.1397)
			(layers "F.Cu" "F.Mask" "F.Paste")
			(net "P5V_A_ROVP")
			(options
				(clearance outline)
				(anchor circle)
			)
			(primitives
				(gr_poly
					(pts
						(arc
							(start -0.1778 -0.2794)
							(mid -0.249642 -0.249642)
							(end -0.2794 -0.1778)
						)
						(arc
							(start -0.2794 0.1778)
							(mid -0.249642 0.249642)
							(end -0.1778 0.2794)
						)
						(arc
							(start 0.1778 0.2794)
							(mid 0.249642 0.249642)
							(end 0.2794 0.1778)
						)
						(arc
							(start 0.2794 -0.1778)
							(mid 0.249642 -0.249642)
							(end 0.1778 -0.2794)
						)
					)
					(width 0)
					(fill yes)
				)
			)
		)
		(pad "2" smd custom
			(at 0 0.4445 180)
			(size 0.1397 0.1397)
			(layers "F.Cu" "F.Mask" "F.Paste")
			(net "AGND_P5V_A")
			(options
				(clearance outline)
				(anchor circle)
			)
			(primitives
				(gr_poly
					(pts
						(arc
							(start -0.1778 -0.2794)
							(mid -0.249642 -0.249642)
							(end -0.2794 -0.1778)
						)
						(arc
							(start -0.2794 0.1778)
							(mid -0.249642 0.249642)
							(end -0.1778 0.2794)
						)
						(arc
							(start 0.1778 0.2794)
							(mid 0.249642 0.249642)
							(end 0.2794 0.1778)
						)
						(arc
							(start 0.2794 -0.1778)
							(mid 0.249642 -0.249642)
							(end 0.1778 -0.2794)
						)
					)
					(width 0)
					(fill yes)
				)
			)
		)
	)
	(footprint ""
		(layer "F.Cu")
		(at 49.466246 -158.982918 180)
		(property "Reference" "D13"
			(at 0 0 180)
			(layer "F.SilkS")
			(hide yes)
			(effects
				(font
					(size 1.27 1.27)
				)
			)
		)
		(property "Value" "RB551V30-GP"
			(at 0 -6.7818 180)
			(unlocked yes)
			(layer "F.Fab")
			(hide yes)
			(effects
				(font
					(size 1.016 1.016)
					(thickness 0.1524)
				)
			)
		)
		(property "Device Type" "SOD323AKH38"
			(at 0 -8.6868 180)
			(unlocked yes)
			(layer "F.Fab")
			(hide yes)
			(effects
				(font
					(size 1.016 1.016)
					(thickness 0.1524)
				)
			)
		)
		(duplicate_pad_numbers_are_jumpers no)
		(fp_line
			(start 0.889 2.159)
			(end -0.889 2.159)
			(stroke
				(width 0.1524)
				(type default)
			)
			(layer "F.SilkS")
		)
		(fp_line
			(start 0.889 -1.9304)
			(end 0.889 2.159)
			(stroke
				(width 0.1524)
				(type default)
			)
			(layer "F.SilkS")
		)
		(fp_line
			(start 0.762 2.0574)
			(end -0.762 2.0574)
			(stroke
				(width 0.508)
				(type default)
			)
			(layer "F.SilkS")
		)
		(fp_line
			(start -0.889 2.159)
			(end -0.889 -1.9304)
			(stroke
				(width 0.1524)
				(type default)
			)
			(layer "F.SilkS")
		)
		(fp_line
			(start -0.889 -1.9304)
			(end 0.889 -1.9304)
			(stroke
				(width 0.1524)
				(type default)
			)
			(layer "F.SilkS")
		)
		(fp_rect
			(start -1.016 2.3114)
			(end 1.016 -2.0066)
			(stroke
				(width 0)
				(type default)
			)
			(fill no)
			(layer "F.CrtYd")
		)
		(fp_poly
			(pts
				(xy -1.016 -2.0066) (xy 1.016 -2.0066) (xy 1.016 2.3114) (xy -1.016 2.3114)
			)
			(stroke
				(width 0)
				(type default)
			)
			(fill no)
			(layer "F.Fab")
		)
		(pad "A" smd rect
			(at 0 -1.143 180)
			(size 0.5588 1.016)
			(layers "F.Cu" "F.Mask" "F.Paste")
			(net "SW_HDD_R13")
		)
		(pad "K" smd rect
			(at 0 1.143 180)
			(size 0.5588 1.016)
			(layers "F.Cu" "F.Mask" "F.Paste")
			(net "SW_HDD_N13")
		)
	)
	(footprint ""
		(layer "F.Cu")
		(at 242.57 -249.174 180)
		(property "Reference" "R45"
			(at 0 0 180)
			(layer "F.SilkS")
			(hide yes)
			(effects
				(font
					(size 1.27 1.27)
				)
			)
		)
		(property "Value" "4K7R2F-GP"
			(at 0.064008 -3.993896 180)
			(unlocked yes)
			(layer "F.Fab")
			(hide yes)
			(effects
				(font
					(size 1.016 1.016)
					(thickness 0.1524)
				)
			)
		)
		(property "Device Type" "R402H16"
			(at 0.064008 -5.517896 180)
			(unlocked yes)
			(layer "F.Fab")
			(hide yes)
			(effects
				(font
					(size 1.016 1.016)
					(thickness 0.1524)
				)
			)
		)
		(duplicate_pad_numbers_are_jumpers no)
		(fp_line
			(start 0.508 -0.9398)
			(end -0.508 -0.9398)
			(stroke
				(width 0.1524)
				(type default)
			)
			(layer "F.SilkS")
		)
		(fp_line
			(start -0.508 -0.9398)
			(end -0.508 0.9398)
			(stroke
				(width 0.1524)
				(type default)
			)
			(layer "F.SilkS")
		)
		(fp_rect
			(start -0.508 0.9398)
			(end 0.508 -0.9398)
			(stroke
				(width 0)
				(type default)
			)
			(fill no)
			(layer "F.CrtYd")
		)
		(fp_rect
			(start -0.508 0.9398)
			(end 0.508 -0.9398)
			(stroke
				(width 0)
				(type default)
			)
			(fill no)
			(layer "F.Fab")
		)
		(pad "1" smd custom
			(at 0 -0.4445 180)
			(size 0.1397 0.1397)
			(layers "F.Cu" "F.Mask" "F.Paste")
			(net "P3V3_STBY_A")
			(options
				(clearance outline)
				(anchor circle)
			)
			(primitives
				(gr_poly
					(pts
						(arc
							(start -0.1778 -0.2794)
							(mid -0.249642 -0.249642)
							(end -0.2794 -0.1778)
						)
						(arc
							(start -0.2794 0.1778)
							(mid -0.249642 0.249642)
							(end -0.1778 0.2794)
						)
						(arc
							(start 0.1778 0.2794)
							(mid 0.249642 0.249642)
							(end 0.2794 0.1778)
						)
						(arc
							(start 0.2794 -0.1778)
							(mid 0.249642 -0.249642)
							(end 0.1778 -0.2794)
						)
					)
					(width 0)
					(fill yes)
				)
			)
		)
		(pad "2" smd custom
			(at 0 0.4445 180)
			(size 0.1397 0.1397)
			(layers "F.Cu" "F.Mask" "F.Paste")
			(net "IO_EXP5_A1")
			(options
				(clearance outline)
				(anchor circle)
			)
			(primitives
				(gr_poly
					(pts
						(arc
							(start -0.1778 -0.2794)
							(mid -0.249642 -0.249642)
							(end -0.2794 -0.1778)
						)
						(arc
							(start -0.2794 0.1778)
							(mid -0.249642 0.249642)
							(end -0.1778 0.2794)
						)
						(arc
							(start 0.1778 0.2794)
							(mid 0.249642 0.249642)
							(end 0.2794 0.1778)
						)
						(arc
							(start 0.2794 -0.1778)
							(mid 0.249642 -0.249642)
							(end 0.1778 -0.2794)
						)
					)
					(width 0)
					(fill yes)
				)
			)
		)
	)
	(footprint ""
		(layer "F.Cu")
		(at 70.204584 -301.29988 90)
		(property "Reference" "R565"
			(at 0 0 90)
			(layer "F.SilkS")
			(hide yes)
			(effects
				(font
					(size 1.27 1.27)
				)
			)
		)
		(property "Value" "4K7R2J-2-GP"
			(at 0.064008 -3.993896 90)
			(unlocked yes)
			(layer "F.Fab")
			(hide yes)
			(effects
				(font
					(size 1.016 1.016)
					(thickness 0.1524)
				)
			)
		)
		(property "Device Type" "R402H16"
			(at 0.064008 -5.517896 90)
			(unlocked yes)
			(layer "F.Fab")
			(hide yes)
			(effects
				(font
					(size 1.016 1.016)
					(thickness 0.1524)
				)
			)
		)
		(duplicate_pad_numbers_are_jumpers no)
		(fp_line
			(start 0.508 -0.9398)
			(end -0.508 -0.9398)
			(stroke
				(width 0.1524)
				(type default)
			)
			(layer "F.SilkS")
		)
		(fp_line
			(start -0.508 -0.9398)
			(end -0.508 0.9398)
			(stroke
				(width 0.1524)
				(type default)
			)
			(layer "F.SilkS")
		)
		(fp_rect
			(start -0.508 0.9398)
			(end 0.508 -0.9398)
			(stroke
				(width 0)
				(type default)
			)
			(fill no)
			(layer "F.CrtYd")
		)
		(fp_rect
			(start -0.508 0.9398)
			(end 0.508 -0.9398)
			(stroke
				(width 0)
				(type default)
			)
			(fill no)
			(layer "F.Fab")
		)
		(pad "1" smd custom
			(at 0 -0.4445 90)
			(size 0.1397 0.1397)
			(layers "F.Cu" "F.Mask" "F.Paste")
			(net "DRIVE_B_26_FLT_LED")
			(options
				(clearance outline)
				(anchor circle)
			)
			(primitives
				(gr_poly
					(pts
						(arc
							(start -0.1778 -0.2794)
							(mid -0.249642 -0.249642)
							(end -0.2794 -0.1778)
						)
						(arc
							(start -0.2794 0.1778)
							(mid -0.249642 0.249642)
							(end -0.1778 0.2794)
						)
						(arc
							(start 0.1778 0.2794)
							(mid 0.249642 0.249642)
							(end 0.2794 0.1778)
						)
						(arc
							(start 0.2794 -0.1778)
							(mid 0.249642 -0.249642)
							(end 0.1778 -0.2794)
						)
					)
					(width 0)
					(fill yes)
				)
			)
		)
		(pad "2" smd custom
			(at 0 0.4445 90)
			(size 0.1397 0.1397)
			(layers "F.Cu" "F.Mask" "F.Paste")
			(net "GND")
			(options
				(clearance outline)
				(anchor circle)
			)
			(primitives
				(gr_poly
					(pts
						(arc
							(start -0.1778 -0.2794)
							(mid -0.249642 -0.249642)
							(end -0.2794 -0.1778)
						)
						(arc
							(start -0.2794 0.1778)
							(mid -0.249642 0.249642)
							(end -0.1778 0.2794)
						)
						(arc
							(start 0.1778 0.2794)
							(mid 0.249642 0.249642)
							(end 0.2794 0.1778)
						)
						(arc
							(start 0.2794 -0.1778)
							(mid 0.249642 -0.249642)
							(end 0.1778 -0.2794)
						)
					)
					(width 0)
					(fill yes)
				)
			)
		)
	)
	(footprint ""
		(layer "F.Cu")
		(at 24.240998 -74.462894 180)
		(property "Reference" "C359"
			(at 0 0 180)
			(layer "F.SilkS")
			(hide yes)
			(effects
				(font
					(size 1.27 1.27)
				)
			)
		)
		(property "Value" "SC1U25V3KX-GP"
			(at 0 -2.8194 180)
			(unlocked yes)
			(layer "F.Fab")
			(hide yes)
			(effects
				(font
					(size 1.016 1.016)
					(thickness 0.1524)
				)
			)
		)
		(property "Device Type" "C603H36"
			(at 0 -4.3434 180)
			(unlocked yes)
			(layer "F.Fab")
			(hide yes)
			(effects
				(font
					(size 1.016 1.016)
					(thickness 0.1524)
				)
			)
		)
		(duplicate_pad_numbers_are_jumpers no)
		(fp_line
			(start 0.508 0)
			(end -0.508 0)
			(stroke
				(width 0.2032)
				(type default)
			)
			(layer "F.SilkS")
		)
		(fp_rect
			(start -0.5842 1.3335)
			(end 0.5842 -1.3335)
			(stroke
				(width 0)
				(type default)
			)
			(fill no)
			(layer "F.CrtYd")
		)
		(fp_rect
			(start -0.5842 1.3335)
			(end 0.5842 -1.3335)
			(stroke
				(width 0)
				(type default)
			)
			(fill no)
			(layer "F.Fab")
		)
		(pad "1" smd custom
			(at 0 -0.762 180)
			(size 0.2159 0.2159)
			(layers "F.Cu" "F.Mask" "F.Paste")
			(net "P12V_HDD24")
			(options
				(clearance outline)
				(anchor circle)
			)
			(primitives
				(gr_poly
					(pts
						(arc
							(start -0.3302 -0.4318)
							(mid -0.402042 -0.402042)
							(end -0.4318 -0.3302)
						)
						(arc
							(start -0.4318 0.3302)
							(mid -0.402042 0.402042)
							(end -0.3302 0.4318)
						)
						(arc
							(start 0.3302 0.4318)
							(mid 0.402042 0.402042)
							(end 0.4318 0.3302)
						)
						(arc
							(start 0.4318 -0.3302)
							(mid 0.402042 -0.402042)
							(end 0.3302 -0.4318)
						)
					)
					(width 0)
					(fill yes)
				)
			)
		)
		(pad "2" smd custom
			(at 0 0.762 180)
			(size 0.2159 0.2159)
			(layers "F.Cu" "F.Mask" "F.Paste")
			(net "GND")
			(options
				(clearance outline)
				(anchor circle)
			)
			(primitives
				(gr_poly
					(pts
						(arc
							(start -0.3302 -0.4318)
							(mid -0.402042 -0.402042)
							(end -0.4318 -0.3302)
						)
						(arc
							(start -0.4318 0.3302)
							(mid -0.402042 0.402042)
							(end -0.3302 0.4318)
						)
						(arc
							(start 0.3302 0.4318)
							(mid 0.402042 0.402042)
							(end 0.4318 0.3302)
						)
						(arc
							(start 0.4318 -0.3302)
							(mid 0.402042 -0.402042)
							(end 0.3302 -0.4318)
						)
					)
					(width 0)
					(fill yes)
				)
			)
		)
	)
	(footprint ""
		(layer "F.Cu")
		(at 14.715998 -64.683894 -90)
		(property "Reference" "C356"
			(at 0 0 270)
			(layer "F.SilkS")
			(hide yes)
			(effects
				(font
					(size 1.27 1.27)
				)
			)
		)
		(property "Value" "SC4D7U25V5KX-1-GP"
			(at -0.0762 -6.1214 270)
			(unlocked yes)
			(layer "F.Fab")
			(hide yes)
			(effects
				(font
					(size 1.016 1.016)
					(thickness 0.1524)
				)
			)
		)
		(property "Device Type" "C805H58"
			(at -0.0762 -8.1534 270)
			(unlocked yes)
			(layer "F.Fab")
			(hide yes)
			(effects
				(font
					(size 1.016 1.016)
					(thickness 0.1524)
				)
			)
		)
		(duplicate_pad_numbers_are_jumpers no)
		(fp_line
			(start 0.635 0)
			(end -0.635 0)
			(stroke
				(width 0.508)
				(type default)
			)
			(layer "F.SilkS")
		)
		(fp_rect
			(start -0.9652 1.778)
			(end 0.9652 -1.778)
			(stroke
				(width 0)
				(type default)
			)
			(fill no)
			(layer "F.CrtYd")
		)
		(fp_poly
			(pts
				(xy -0.9652 -1.778) (xy 0.9652 -1.778) (xy 0.9652 1.778) (xy -0.9652 1.778)
			)
			(stroke
				(width 0)
				(type default)
			)
			(fill no)
			(layer "F.Fab")
		)
		(pad "1" smd rect
			(at 0 -0.9652 270)
			(size 1.397 1.143)
			(layers "F.Cu" "F.Mask" "F.Paste")
			(net "P12V_HDD24")
		)
		(pad "2" smd rect
			(at 0 0.9652 270)
			(size 1.397 1.143)
			(layers "F.Cu" "F.Mask" "F.Paste")
			(net "GND")
		)
	)
	(footprint ""
		(layer "F.Cu")
		(at 433.359052 -57.851294 90)
		(property "Reference" "C478"
			(at 0 0 90)
			(layer "F.SilkS")
			(hide yes)
			(effects
				(font
					(size 1.27 1.27)
				)
			)
		)
		(property "Value" "SCD033U25V2KX-GP"
			(at 1.1811 -2.7051 90)
			(unlocked yes)
			(layer "F.Fab")
			(hide yes)
			(effects
				(font
					(size 1.016 1.016)
					(thickness 0.1524)
				)
			)
		)
		(property "Device Type" "C402H22"
			(at 1.1811 -4.2291 90)
			(unlocked yes)
			(layer "F.Fab")
			(hide yes)
			(effects
				(font
					(size 1.016 1.016)
					(thickness 0.1524)
				)
			)
		)
		(duplicate_pad_numbers_are_jumpers no)
		(fp_rect
			(start -0.4318 0.9525)
			(end 0.4318 -0.9525)
			(stroke
				(width 0)
				(type default)
			)
			(fill no)
			(layer "F.CrtYd")
		)
		(fp_rect
			(start -0.4318 0.9525)
			(end 0.4318 -0.9525)
			(stroke
				(width 0)
				(type default)
			)
			(fill no)
			(layer "F.Fab")
		)
		(pad "1" smd custom
			(at 0 -0.4445 90)
			(size 0.1524 0.1524)
			(layers "F.Cu" "F.Mask" "F.Paste")
			(net "P12V_A")
			(options
				(clearance outline)
				(anchor circle)
			)
			(primitives
				(gr_poly
					(pts
						(arc
							(start 0.3048 -0.2032)
							(mid 0.275042 -0.275042)
							(end 0.2032 -0.3048)
						)
						(arc
							(start -0.2032 -0.3048)
							(mid -0.275042 -0.275042)
							(end -0.3048 -0.2032)
						)
						(arc
							(start -0.3048 0.2032)
							(mid -0.275042 0.275042)
							(end -0.2032 0.3048)
						)
						(arc
							(start 0.2032 0.3048)
							(mid 0.275042 0.275042)
							(end 0.3048 0.2032)
						)
					)
					(width 0)
					(fill yes)
				)
			)
		)
		(pad "2" smd custom
			(at 0 0.4445 90)
			(size 0.1524 0.1524)
			(layers "F.Cu" "F.Mask" "F.Paste")
			(net "SW_HDD_N33")
			(options
				(clearance outline)
				(anchor circle)
			)
			(primitives
				(gr_poly
					(pts
						(arc
							(start 0.3048 -0.2032)
							(mid 0.275042 -0.275042)
							(end 0.2032 -0.3048)
						)
						(arc
							(start -0.2032 -0.3048)
							(mid -0.275042 -0.275042)
							(end -0.3048 -0.2032)
						)
						(arc
							(start -0.3048 0.2032)
							(mid -0.275042 0.275042)
							(end -0.2032 0.3048)
						)
						(arc
							(start 0.2032 0.3048)
							(mid 0.275042 0.275042)
							(end 0.3048 0.2032)
						)
					)
					(width 0)
					(fill yes)
				)
			)
		)
	)
	(footprint ""
		(layer "F.Cu")
		(at 345.410028 -127.254)
		(property "Reference" "R319"
			(at 0 0 0)
			(layer "F.SilkS")
			(hide yes)
			(effects
				(font
					(size 1.27 1.27)
				)
			)
		)
		(property "Value" "130R3F-GP"
			(at -0.0254 -2.5146 0)
			(unlocked yes)
			(layer "F.Fab")
			(hide yes)
			(effects
				(font
					(size 1.016 1.016)
					(thickness 0.1524)
				)
			)
		)
		(property "Device Type" "R603H22"
			(at -0.0254 -4.0386 0)
			(unlocked yes)
			(layer "F.Fab")
			(hide yes)
			(effects
				(font
					(size 1.016 1.016)
					(thickness 0.1524)
				)
			)
		)
		(duplicate_pad_numbers_are_jumpers no)
		(fp_line
			(start -0.4826 0)
			(end -0.2032 0)
			(stroke
				(width 0.2032)
				(type default)
			)
			(layer "F.SilkS")
		)
		(fp_line
			(start 0.2032 0)
			(end 0.4826 0)
			(stroke
				(width 0.2032)
				(type default)
			)
			(layer "F.SilkS")
		)
		(fp_rect
			(start -0.5842 1.3335)
			(end 0.5842 -1.3335)
			(stroke
				(width 0)
				(type default)
			)
			(fill no)
			(layer "F.CrtYd")
		)
		(fp_rect
			(start -0.5842 1.3335)
			(end 0.5842 -1.3335)
			(stroke
				(width 0)
				(type default)
			)
			(fill no)
			(layer "F.Fab")
		)
		(pad "1" smd custom
			(at 0 -0.762)
			(size 0.2159 0.2159)
			(layers "F.Cu" "F.Mask" "F.Paste")
			(net "P5V_A_3")
			(options
				(clearance outline)
				(anchor circle)
			)
			(primitives
				(gr_poly
					(pts
						(arc
							(start -0.3302 -0.4318)
							(mid -0.402042 -0.402042)
							(end -0.4318 -0.3302)
						)
						(arc
							(start -0.4318 0.3302)
							(mid -0.402042 0.402042)
							(end -0.3302 0.4318)
						)
						(arc
							(start 0.3302 0.4318)
							(mid 0.402042 0.402042)
							(end 0.4318 0.3302)
						)
						(arc
							(start 0.4318 -0.3302)
							(mid 0.402042 -0.402042)
							(end 0.3302 -0.4318)
						)
					)
					(width 0)
					(fill yes)
				)
			)
		)
		(pad "2" smd custom
			(at 0 0.762)
			(size 0.2159 0.2159)
			(layers "F.Cu" "F.Mask" "F.Paste")
			(net "FLT_HDD19")
			(options
				(clearance outline)
				(anchor circle)
			)
			(primitives
				(gr_poly
					(pts
						(arc
							(start -0.3302 -0.4318)
							(mid -0.402042 -0.402042)
							(end -0.4318 -0.3302)
						)
						(arc
							(start -0.4318 0.3302)
							(mid -0.402042 0.402042)
							(end -0.3302 0.4318)
						)
						(arc
							(start 0.3302 0.4318)
							(mid 0.402042 0.402042)
							(end 0.4318 0.3302)
						)
						(arc
							(start 0.4318 -0.3302)
							(mid 0.402042 -0.402042)
							(end 0.3302 -0.4318)
						)
					)
					(width 0)
					(fill yes)
				)
			)
		)
	)
	(footprint ""
		(layer "F.Cu")
		(at 369.624102 -49.443894 90)
		(property "Reference" "R859"
			(at 0 0 90)
			(layer "F.SilkS")
			(hide yes)
			(effects
				(font
					(size 1.27 1.27)
				)
			)
		)
		(property "Value" "200KR2F-L-GP"
			(at 0.064008 -3.993896 90)
			(unlocked yes)
			(layer "F.Fab")
			(hide yes)
			(effects
				(font
					(size 1.016 1.016)
					(thickness 0.1524)
				)
			)
		)
		(property "Device Type" "R402H16"
			(at 0.064008 -5.517896 90)
			(unlocked yes)
			(layer "F.Fab")
			(hide yes)
			(effects
				(font
					(size 1.016 1.016)
					(thickness 0.1524)
				)
			)
		)
		(duplicate_pad_numbers_are_jumpers no)
		(fp_line
			(start 0.508 -0.9398)
			(end -0.508 -0.9398)
			(stroke
				(width 0.1524)
				(type default)
			)
			(layer "F.SilkS")
		)
		(fp_line
			(start -0.508 -0.9398)
			(end -0.508 0.9398)
			(stroke
				(width 0.1524)
				(type default)
			)
			(layer "F.SilkS")
		)
		(fp_rect
			(start -0.508 0.9398)
			(end 0.508 -0.9398)
			(stroke
				(width 0)
				(type default)
			)
			(fill no)
			(layer "F.CrtYd")
		)
		(fp_rect
			(start -0.508 0.9398)
			(end 0.508 -0.9398)
			(stroke
				(width 0)
				(type default)
			)
			(fill no)
			(layer "F.Fab")
		)
		(pad "1" smd custom
			(at 0 -0.4445 90)
			(size 0.1397 0.1397)
			(layers "F.Cu" "F.Mask" "F.Paste")
			(net "SW_HDD_R31")
			(options
				(clearance outline)
				(anchor circle)
			)
			(primitives
				(gr_poly
					(pts
						(arc
							(start -0.1778 -0.2794)
							(mid -0.249642 -0.249642)
							(end -0.2794 -0.1778)
						)
						(arc
							(start -0.2794 0.1778)
							(mid -0.249642 0.249642)
							(end -0.1778 0.2794)
						)
						(arc
							(start 0.1778 0.2794)
							(mid 0.249642 0.249642)
							(end 0.2794 0.1778)
						)
						(arc
							(start 0.2794 -0.1778)
							(mid 0.249642 -0.249642)
							(end 0.1778 -0.2794)
						)
					)
					(width 0)
					(fill yes)
				)
			)
		)
		(pad "2" smd custom
			(at 0 0.4445 90)
			(size 0.1397 0.1397)
			(layers "F.Cu" "F.Mask" "F.Paste")
			(net "SW_HDD_N31")
			(options
				(clearance outline)
				(anchor circle)
			)
			(primitives
				(gr_poly
					(pts
						(arc
							(start -0.1778 -0.2794)
							(mid -0.249642 -0.249642)
							(end -0.2794 -0.1778)
						)
						(arc
							(start -0.2794 0.1778)
							(mid -0.249642 0.249642)
							(end -0.1778 0.2794)
						)
						(arc
							(start 0.1778 0.2794)
							(mid 0.249642 0.249642)
							(end 0.2794 0.1778)
						)
						(arc
							(start 0.2794 -0.1778)
							(mid 0.249642 -0.249642)
							(end 0.1778 -0.2794)
						)
					)
					(width 0)
					(fill yes)
				)
			)
		)
	)
	(footprint ""
		(layer "F.Cu")
		(at 14.792198 -275.608542 90)
		(property "Reference" "R972"
			(at 0 0 90)
			(layer "F.SilkS")
			(hide yes)
			(effects
				(font
					(size 1.27 1.27)
				)
			)
		)
		(property "Value" "4K7R2J-2-GP"
			(at 0.064008 -3.993896 90)
			(unlocked yes)
			(layer "F.Fab")
			(hide yes)
			(effects
				(font
					(size 1.016 1.016)
					(thickness 0.1524)
				)
			)
		)
		(property "Device Type" "R402H16"
			(at 0.064008 -5.517896 90)
			(unlocked yes)
			(layer "F.Fab")
			(hide yes)
			(effects
				(font
					(size 1.016 1.016)
					(thickness 0.1524)
				)
			)
		)
		(duplicate_pad_numbers_are_jumpers no)
		(fp_line
			(start 0.508 -0.9398)
			(end -0.508 -0.9398)
			(stroke
				(width 0.1524)
				(type default)
			)
			(layer "F.SilkS")
		)
		(fp_line
			(start -0.508 -0.9398)
			(end -0.508 0.9398)
			(stroke
				(width 0.1524)
				(type default)
			)
			(layer "F.SilkS")
		)
		(fp_rect
			(start -0.508 0.9398)
			(end 0.508 -0.9398)
			(stroke
				(width 0)
				(type default)
			)
			(fill no)
			(layer "F.CrtYd")
		)
		(fp_rect
			(start -0.508 0.9398)
			(end 0.508 -0.9398)
			(stroke
				(width 0)
				(type default)
			)
			(fill no)
			(layer "F.Fab")
		)
		(pad "1" smd custom
			(at 0 -0.4445 90)
			(size 0.1397 0.1397)
			(layers "F.Cu" "F.Mask" "F.Paste")
			(net "P12V_A")
			(options
				(clearance outline)
				(anchor circle)
			)
			(primitives
				(gr_poly
					(pts
						(arc
							(start -0.1778 -0.2794)
							(mid -0.249642 -0.249642)
							(end -0.2794 -0.1778)
						)
						(arc
							(start -0.2794 0.1778)
							(mid -0.249642 0.249642)
							(end -0.1778 0.2794)
						)
						(arc
							(start 0.1778 0.2794)
							(mid 0.249642 0.249642)
							(end 0.2794 0.1778)
						)
						(arc
							(start 0.2794 -0.1778)
							(mid 0.249642 -0.249642)
							(end 0.1778 -0.2794)
						)
					)
					(width 0)
					(fill yes)
				)
			)
		)
		(pad "2" smd custom
			(at 0 0.4445 90)
			(size 0.1397 0.1397)
			(layers "F.Cu" "F.Mask" "F.Paste")
			(net "SW_HDD_R0")
			(options
				(clearance outline)
				(anchor circle)
			)
			(primitives
				(gr_poly
					(pts
						(arc
							(start -0.1778 -0.2794)
							(mid -0.249642 -0.249642)
							(end -0.2794 -0.1778)
						)
						(arc
							(start -0.2794 0.1778)
							(mid -0.249642 0.249642)
							(end -0.1778 0.2794)
						)
						(arc
							(start 0.1778 0.2794)
							(mid 0.249642 0.249642)
							(end 0.2794 0.1778)
						)
						(arc
							(start 0.2794 -0.1778)
							(mid 0.249642 -0.249642)
							(end 0.1778 -0.2794)
						)
					)
					(width 0)
					(fill yes)
				)
			)
		)
	)
	(footprint ""
		(layer "F.Cu")
		(at 401.8534 -281.2288 90)
		(property "Reference" "Q50"
			(at 0 0 90)
			(layer "F.SilkS")
			(hide yes)
			(effects
				(font
					(size 1.27 1.27)
				)
			)
		)
		(property "Value" "AO4407AL-GP"
			(at -3.707384 -1.5367 90)
			(unlocked yes)
			(layer "F.Fab")
			(hide yes)
			(effects
				(font
					(size 1.016 1.016)
					(thickness 0.1524)
				)
			)
		)
		(property "Device Type" "SOIC8H69"
			(at -3.707384 -3.0607 90)
			(unlocked yes)
			(layer "F.Fab")
			(hide yes)
			(effects
				(font
					(size 1.016 1.016)
					(thickness 0.1524)
				)
			)
		)
		(duplicate_pad_numbers_are_jumpers no)
		(fp_line
			(start 2.1336 -1.4224)
			(end -2.7432 -1.4224)
			(stroke
				(width 0.1524)
				(type default)
			)
			(layer "F.SilkS")
		)
		(fp_line
			(start -2.7432 -1.4224)
			(end -2.7432 1.4224)
			(stroke
				(width 0.1524)
				(type default)
			)
			(layer "F.SilkS")
		)
		(fp_line
			(start -2.7178 -0.508)
			(end -2.1844 -0.0508)
			(stroke
				(width 0.1524)
				(type default)
			)
			(layer "F.SilkS")
		)
		(fp_line
			(start -2.1844 -0.0508)
			(end -2.7178 0.508)
			(stroke
				(width 0.1524)
				(type default)
			)
			(layer "F.SilkS")
		)
		(fp_line
			(start 2.1336 1.4224)
			(end 2.1336 -1.4224)
			(stroke
				(width 0.1524)
				(type default)
			)
			(layer "F.SilkS")
		)
		(fp_line
			(start -2.7432 1.4224)
			(end 2.1336 1.4224)
			(stroke
				(width 0.1524)
				(type default)
			)
			(layer "F.SilkS")
		)
		(fp_line
			(start -2.7432 1.4224)
			(end -2.6416 1.4224)
			(stroke
				(width 0.1524)
				(type default)
			)
			(layer "F.SilkS")
		)
		(fp_line
			(start -2.6289 3.4417)
			(end -2.6289 1.4732)
			(stroke
				(width 0.381)
				(type default)
			)
			(layer "F.SilkS")
		)
		(fp_poly
			(pts
				(xy -2.2098 -1.4224) (xy -2.2098 1.4224) (xy 2.2098 1.4224) (xy 2.2098 -1.4224)
			)
			(stroke
				(width 0)
				(type default)
			)
			(fill yes)
			(layer "F.SilkS")
		)
		(fp_rect
			(start -2.450084 2.999994)
			(end 2.450084 -2.999994)
			(stroke
				(width 0)
				(type default)
			)
			(fill no)
			(layer "F.CrtYd")
		)
		(fp_poly
			(pts
				(xy -2.8194 3.6322) (xy -2.8194 -3.6322) (xy 2.8194 -3.6322) (xy 2.8194 1.18364) (xy 2.450084 1.18364)
				(xy 2.450084 -2.999994) (xy -2.450084 -2.999994) (xy -2.450084 2.999994) (xy 2.450084 2.999994)
				(xy 2.450084 1.18618) (xy 2.8194 1.18618) (xy 2.8194 3.6322)
			)
			(stroke
				(width 0)
				(type default)
			)
			(fill no)
			(layer "F.CrtYd")
		)
		(fp_rect
			(start -2.8194 3.6322)
			(end 2.8194 -3.6322)
			(stroke
				(width 0)
				(type default)
			)
			(fill no)
			(layer "F.Fab")
		)
		(pad "1" smd rect
			(at -1.905 2.54 90)
			(size 0.635 1.651)
			(layers "F.Cu" "F.Mask" "F.Paste")
			(net "P12V_A")
		)
		(pad "2" smd rect
			(at -0.635 2.54 90)
			(size 0.635 1.651)
			(layers "F.Cu" "F.Mask" "F.Paste")
			(net "P12V_A")
		)
		(pad "3" smd rect
			(at 0.635 2.54 90)
			(size 0.635 1.651)
			(layers "F.Cu" "F.Mask" "F.Paste")
			(net "P12V_A")
		)
		(pad "4" smd rect
			(at 1.905 2.54 90)
			(size 0.635 1.651)
			(layers "F.Cu" "F.Mask" "F.Paste")
			(net "SW_HDD_N8")
		)
		(pad "5" smd rect
			(at 1.905 -2.54 90)
			(size 0.635 1.651)
			(layers "F.Cu" "F.Mask" "F.Paste")
			(net "P12V_HDD8")
		)
		(pad "6" smd rect
			(at 0.635 -2.54 90)
			(size 0.635 1.651)
			(layers "F.Cu" "F.Mask" "F.Paste")
			(net "P12V_HDD8")
		)
		(pad "7" smd rect
			(at -0.635 -2.54 90)
			(size 0.635 1.651)
			(layers "F.Cu" "F.Mask" "F.Paste")
			(net "P12V_HDD8")
		)
		(pad "8" smd rect
			(at -1.905 -2.54 90)
			(size 0.635 1.651)
			(layers "F.Cu" "F.Mask" "F.Paste")
			(net "P12V_HDD8")
		)
	)
	(footprint ""
		(layer "F.Cu")
		(at 51.980846 -177.778918 -90)
		(property "Reference" "C209"
			(at 0 0 270)
			(layer "F.SilkS")
			(hide yes)
			(effects
				(font
					(size 1.27 1.27)
				)
			)
		)
		(property "Value" "SC1U16V3KX-5GP"
			(at 0 -2.8194 270)
			(unlocked yes)
			(layer "F.Fab")
			(hide yes)
			(effects
				(font
					(size 1.016 1.016)
					(thickness 0.1524)
				)
			)
		)
		(property "Device Type" "C603H36"
			(at 0 -4.3434 270)
			(unlocked yes)
			(layer "F.Fab")
			(hide yes)
			(effects
				(font
					(size 1.016 1.016)
					(thickness 0.1524)
				)
			)
		)
		(duplicate_pad_numbers_are_jumpers no)
		(fp_line
			(start 0.508 0)
			(end -0.508 0)
			(stroke
				(width 0.2032)
				(type default)
			)
			(layer "F.SilkS")
		)
		(fp_rect
			(start -0.5842 1.3335)
			(end 0.5842 -1.3335)
			(stroke
				(width 0)
				(type default)
			)
			(fill no)
			(layer "F.CrtYd")
		)
		(fp_rect
			(start -0.5842 1.3335)
			(end 0.5842 -1.3335)
			(stroke
				(width 0)
				(type default)
			)
			(fill no)
			(layer "F.Fab")
		)
		(pad "1" smd custom
			(at 0 -0.762 270)
			(size 0.2159 0.2159)
			(layers "F.Cu" "F.Mask" "F.Paste")
			(net "P5V_HDD13")
			(options
				(clearance outline)
				(anchor circle)
			)
			(primitives
				(gr_poly
					(pts
						(arc
							(start -0.3302 -0.4318)
							(mid -0.402042 -0.402042)
							(end -0.4318 -0.3302)
						)
						(arc
							(start -0.4318 0.3302)
							(mid -0.402042 0.402042)
							(end -0.3302 0.4318)
						)
						(arc
							(start 0.3302 0.4318)
							(mid 0.402042 0.402042)
							(end 0.4318 0.3302)
						)
						(arc
							(start 0.4318 -0.3302)
							(mid 0.402042 -0.402042)
							(end 0.3302 -0.4318)
						)
					)
					(width 0)
					(fill yes)
				)
			)
		)
		(pad "2" smd custom
			(at 0 0.762 270)
			(size 0.2159 0.2159)
			(layers "F.Cu" "F.Mask" "F.Paste")
			(net "GND")
			(options
				(clearance outline)
				(anchor circle)
			)
			(primitives
				(gr_poly
					(pts
						(arc
							(start -0.3302 -0.4318)
							(mid -0.402042 -0.402042)
							(end -0.4318 -0.3302)
						)
						(arc
							(start -0.4318 0.3302)
							(mid -0.402042 0.402042)
							(end -0.3302 0.4318)
						)
						(arc
							(start 0.3302 0.4318)
							(mid 0.402042 0.402042)
							(end 0.4318 0.3302)
						)
						(arc
							(start 0.4318 -0.3302)
							(mid 0.402042 -0.402042)
							(end 0.3302 -0.4318)
						)
					)
					(width 0)
					(fill yes)
				)
			)
		)
	)
	(footprint ""
		(layer "F.Cu")
		(at 224.1296 -219.295472)
		(property "Reference" "R608"
			(at 0 0 0)
			(layer "F.SilkS")
			(hide yes)
			(effects
				(font
					(size 1.27 1.27)
				)
			)
		)
		(property "Value" "2K2R2F-GP"
			(at 0.064008 -3.993896 0)
			(unlocked yes)
			(layer "F.Fab")
			(hide yes)
			(effects
				(font
					(size 1.016 1.016)
					(thickness 0.1524)
				)
			)
		)
		(property "Device Type" "R402H16"
			(at 0.064008 -5.517896 0)
			(unlocked yes)
			(layer "F.Fab")
			(hide yes)
			(effects
				(font
					(size 1.016 1.016)
					(thickness 0.1524)
				)
			)
		)
		(duplicate_pad_numbers_are_jumpers no)
		(fp_line
			(start -0.508 -0.9398)
			(end -0.508 0.9398)
			(stroke
				(width 0.1524)
				(type default)
			)
			(layer "F.SilkS")
		)
		(fp_line
			(start 0.508 -0.9398)
			(end -0.508 -0.9398)
			(stroke
				(width 0.1524)
				(type default)
			)
			(layer "F.SilkS")
		)
		(fp_rect
			(start -0.508 0.9398)
			(end 0.508 -0.9398)
			(stroke
				(width 0)
				(type default)
			)
			(fill no)
			(layer "F.CrtYd")
		)
		(fp_rect
			(start -0.508 0.9398)
			(end 0.508 -0.9398)
			(stroke
				(width 0)
				(type default)
			)
			(fill no)
			(layer "F.Fab")
		)
		(pad "1" smd custom
			(at 0 -0.4445)
			(size 0.1397 0.1397)
			(layers "F.Cu" "F.Mask" "F.Paste")
			(net "P3V3_STBY_A")
			(options
				(clearance outline)
				(anchor circle)
			)
			(primitives
				(gr_poly
					(pts
						(arc
							(start -0.1778 -0.2794)
							(mid -0.249642 -0.249642)
							(end -0.2794 -0.1778)
						)
						(arc
							(start -0.2794 0.1778)
							(mid -0.249642 0.249642)
							(end -0.1778 0.2794)
						)
						(arc
							(start 0.1778 0.2794)
							(mid 0.249642 0.249642)
							(end 0.2794 0.1778)
						)
						(arc
							(start 0.2794 -0.1778)
							(mid 0.249642 -0.249642)
							(end 0.1778 -0.2794)
						)
					)
					(width 0)
					(fill yes)
				)
			)
		)
		(pad "2" smd custom
			(at 0 0.4445)
			(size 0.1397 0.1397)
			(layers "F.Cu" "F.Mask" "F.Paste")
			(net "I2C_SCC_A_SDA")
			(options
				(clearance outline)
				(anchor circle)
			)
			(primitives
				(gr_poly
					(pts
						(arc
							(start -0.1778 -0.2794)
							(mid -0.249642 -0.249642)
							(end -0.2794 -0.1778)
						)
						(arc
							(start -0.2794 0.1778)
							(mid -0.249642 0.249642)
							(end -0.1778 0.2794)
						)
						(arc
							(start 0.1778 0.2794)
							(mid 0.249642 0.249642)
							(end 0.2794 0.1778)
						)
						(arc
							(start 0.2794 -0.1778)
							(mid 0.249642 -0.249642)
							(end 0.1778 -0.2794)
						)
					)
					(width 0)
					(fill yes)
				)
			)
		)
	)
	(footprint ""
		(layer "F.Cu")
		(at 372.2878 -132.1054)
		(property "Reference" "C556"
			(at 0 0 0)
			(layer "F.SilkS")
			(hide yes)
			(effects
				(font
					(size 1.27 1.27)
				)
			)
		)
		(property "Value" "SCD01U25V2KX-3GP"
			(at 1.1811 -2.7051 0)
			(unlocked yes)
			(layer "F.Fab")
			(hide yes)
			(effects
				(font
					(size 1.016 1.016)
					(thickness 0.1524)
				)
			)
		)
		(property "Device Type" "C402H22"
			(at 1.1811 -4.2291 0)
			(unlocked yes)
			(layer "F.Fab")
			(hide yes)
			(effects
				(font
					(size 1.016 1.016)
					(thickness 0.1524)
				)
			)
		)
		(duplicate_pad_numbers_are_jumpers no)
		(fp_rect
			(start -0.4318 0.9525)
			(end 0.4318 -0.9525)
			(stroke
				(width 0)
				(type default)
			)
			(fill no)
			(layer "F.CrtYd")
		)
		(fp_rect
			(start -0.4318 0.9525)
			(end 0.4318 -0.9525)
			(stroke
				(width 0)
				(type default)
			)
			(fill no)
			(layer "F.Fab")
		)
		(pad "1" smd custom
			(at 0 -0.4445)
			(size 0.1524 0.1524)
			(layers "F.Cu" "F.Mask" "F.Paste")
			(net "MB1_TIME_R")
			(options
				(clearance outline)
				(anchor circle)
			)
			(primitives
				(gr_poly
					(pts
						(arc
							(start 0.3048 -0.2032)
							(mid 0.275042 -0.275042)
							(end 0.2032 -0.3048)
						)
						(arc
							(start -0.2032 -0.3048)
							(mid -0.275042 -0.275042)
							(end -0.3048 -0.2032)
						)
						(arc
							(start -0.3048 0.2032)
							(mid -0.275042 0.275042)
							(end -0.2032 0.3048)
						)
						(arc
							(start 0.2032 0.3048)
							(mid 0.275042 0.275042)
							(end 0.3048 0.2032)
						)
					)
					(width 0)
					(fill yes)
				)
			)
		)
		(pad "2" smd custom
			(at 0 0.4445)
			(size 0.1524 0.1524)
			(layers "F.Cu" "F.Mask" "F.Paste")
			(net "AGND_CURRENT_MONOB")
			(options
				(clearance outline)
				(anchor circle)
			)
			(primitives
				(gr_poly
					(pts
						(arc
							(start 0.3048 -0.2032)
							(mid 0.275042 -0.275042)
							(end 0.2032 -0.3048)
						)
						(arc
							(start -0.2032 -0.3048)
							(mid -0.275042 -0.275042)
							(end -0.3048 -0.2032)
						)
						(arc
							(start -0.3048 0.2032)
							(mid -0.275042 0.275042)
							(end -0.2032 0.3048)
						)
						(arc
							(start 0.2032 0.3048)
							(mid 0.275042 0.275042)
							(end 0.3048 0.2032)
						)
					)
					(width 0)
					(fill yes)
				)
			)
		)
	)
	(footprint ""
		(layer "F.Cu")
		(at 23.732998 -62.270894)
		(property "Reference" "R681"
			(at 0 0 0)
			(layer "F.SilkS")
			(hide yes)
			(effects
				(font
					(size 1.27 1.27)
				)
			)
		)
		(property "Value" "2R6F-GP"
			(at -0.0508 -4.8514 0)
			(unlocked yes)
			(layer "F.Fab")
			(hide yes)
			(effects
				(font
					(size 1.016 1.016)
					(thickness 0.1524)
				)
			)
		)
		(property "Device Type" "R1206H26"
			(at 0 -6.3754 0)
			(unlocked yes)
			(layer "F.Fab")
			(hide yes)
			(effects
				(font
					(size 1.016 1.016)
					(thickness 0.1524)
				)
			)
		)
		(duplicate_pad_numbers_are_jumpers no)
		(fp_line
			(start -1.016 -2.2352)
			(end 1.016 -2.2352)
			(stroke
				(width 0.1524)
				(type default)
			)
			(layer "F.SilkS")
		)
		(fp_line
			(start -1.016 2.2352)
			(end -1.016 -2.2352)
			(stroke
				(width 0.1524)
				(type default)
			)
			(layer "F.SilkS")
		)
		(fp_line
			(start 1.016 -2.2352)
			(end 1.016 2.2352)
			(stroke
				(width 0.1524)
				(type default)
			)
			(layer "F.SilkS")
		)
		(fp_line
			(start 1.016 2.2352)
			(end -1.016 2.2352)
			(stroke
				(width 0.1524)
				(type default)
			)
			(layer "F.SilkS")
		)
		(fp_rect
			(start -1.0922 2.3114)
			(end 1.0922 -2.3114)
			(stroke
				(width 0)
				(type default)
			)
			(fill no)
			(layer "F.CrtYd")
		)
		(fp_poly
			(pts
				(xy -1.0922 -2.3114) (xy 1.0922 -2.3114) (xy 1.0922 2.3114) (xy -1.0922 2.3114)
			)
			(stroke
				(width 0)
				(type default)
			)
			(fill no)
			(layer "F.Fab")
		)
		(pad "1" smd rect
			(at 0 -1.397)
			(size 1.651 1.27)
			(layers "F.Cu" "F.Mask" "F.Paste")
			(net "P5V_HDD24")
		)
		(pad "2" smd rect
			(at 0 1.397)
			(size 1.651 1.27)
			(layers "F.Cu" "F.Mask" "F.Paste")
			(net "5V_PRE_24")
		)
	)
	(footprint ""
		(layer "F.Cu")
		(at 332.105 -45.252894 -90)
		(property "Reference" "Q181"
			(at 0 0 270)
			(layer "F.SilkS")
			(hide yes)
			(effects
				(font
					(size 1.27 1.27)
				)
			)
		)
		(property "Value" "2N7002KDW-GP"
			(at -2.3622 -8.2042 270)
			(unlocked yes)
			(layer "F.Fab")
			(hide yes)
			(effects
				(font
					(size 1.016 1.016)
					(thickness 0.1524)
				)
			)
		)
		(property "Device Type" "SOT-363H44"
			(at -2.3622 -10.1092 270)
			(unlocked yes)
			(layer "F.Fab")
			(hide yes)
			(effects
				(font
					(size 1.016 1.016)
					(thickness 0.1524)
				)
			)
		)
		(duplicate_pad_numbers_are_jumpers no)
		(fp_line
			(start -1.4478 1.7018)
			(end 1.4478 1.7018)
			(stroke
				(width 0.1524)
				(type default)
			)
			(layer "F.SilkS")
		)
		(fp_line
			(start 1.4478 1.7018)
			(end 1.4478 -1.7018)
			(stroke
				(width 0.1524)
				(type default)
			)
			(layer "F.SilkS")
		)
		(fp_line
			(start -1.27 1.524)
			(end -1.27 0.6604)
			(stroke
				(width 0.4826)
				(type default)
			)
			(layer "F.SilkS")
		)
		(fp_line
			(start -1.4478 -1.7018)
			(end -1.4478 1.7018)
			(stroke
				(width 0.1524)
				(type default)
			)
			(layer "F.SilkS")
		)
		(fp_line
			(start 1.4478 -1.7018)
			(end -1.4478 -1.7018)
			(stroke
				(width 0.1524)
				(type default)
			)
			(layer "F.SilkS")
		)
		(fp_poly
			(pts
				(xy -1.524 -1.778) (xy 1.524 -1.778) (xy 1.524 1.778) (xy -1.524 1.778)
			)
			(stroke
				(width 0)
				(type default)
			)
			(fill no)
			(layer "F.CrtYd")
		)
		(fp_poly
			(pts
				(xy -1.524 -1.778) (xy 1.524 -1.778) (xy 1.524 1.778) (xy -1.524 1.778)
			)
			(stroke
				(width 0)
				(type default)
			)
			(fill no)
			(layer "F.Fab")
		)
		(pad "1" smd rect
			(at -0.65024 0.9398 270)
			(size 0.4064 1.016)
			(layers "F.Cu" "F.Mask" "F.Paste")
			(net "GND")
		)
		(pad "2" smd rect
			(at 0 0.9398 270)
			(size 0.4064 1.016)
			(layers "F.Cu" "F.Mask" "F.Paste")
			(net "SW_PWR_R_HDD30")
		)
		(pad "3" smd rect
			(at 0.65024 0.9398 270)
			(size 0.4064 1.016)
			(layers "F.Cu" "F.Mask" "F.Paste")
			(net "SW_HDD_P30")
		)
		(pad "4" smd rect
			(at 0.65024 -0.9398 270)
			(size 0.4064 1.016)
			(layers "F.Cu" "F.Mask" "F.Paste")
			(net "GND")
		)
		(pad "5" smd rect
			(at 0 -0.9398 270)
			(size 0.4064 1.016)
			(layers "F.Cu" "F.Mask" "F.Paste")
			(net "SW_HDD_G30")
		)
		(pad "6" smd rect
			(at -0.65024 -0.9398 270)
			(size 0.4064 1.016)
			(layers "F.Cu" "F.Mask" "F.Paste")
			(net "SW_HDD_R30")
		)
	)
	(footprint ""
		(layer "F.Cu")
		(at 79.924148 -283.152342 -90)
		(property "Reference" "C74"
			(at 0 0 270)
			(layer "F.SilkS")
			(hide yes)
			(effects
				(font
					(size 1.27 1.27)
				)
			)
		)
		(property "Value" "SCD033U25V2KX-GP"
			(at 1.1811 -2.7051 270)
			(unlocked yes)
			(layer "F.Fab")
			(hide yes)
			(effects
				(font
					(size 1.016 1.016)
					(thickness 0.1524)
				)
			)
		)
		(property "Device Type" "C402H22"
			(at 1.1811 -4.2291 270)
			(unlocked yes)
			(layer "F.Fab")
			(hide yes)
			(effects
				(font
					(size 1.016 1.016)
					(thickness 0.1524)
				)
			)
		)
		(duplicate_pad_numbers_are_jumpers no)
		(fp_rect
			(start -0.4318 0.9525)
			(end 0.4318 -0.9525)
			(stroke
				(width 0)
				(type default)
			)
			(fill no)
			(layer "F.CrtYd")
		)
		(fp_rect
			(start -0.4318 0.9525)
			(end 0.4318 -0.9525)
			(stroke
				(width 0)
				(type default)
			)
			(fill no)
			(layer "F.Fab")
		)
		(pad "1" smd custom
			(at 0 -0.4445 270)
			(size 0.1524 0.1524)
			(layers "F.Cu" "F.Mask" "F.Paste")
			(net "SW_HDD_P2")
			(options
				(clearance outline)
				(anchor circle)
			)
			(primitives
				(gr_poly
					(pts
						(arc
							(start 0.3048 -0.2032)
							(mid 0.275042 -0.275042)
							(end 0.2032 -0.3048)
						)
						(arc
							(start -0.2032 -0.3048)
							(mid -0.275042 -0.275042)
							(end -0.3048 -0.2032)
						)
						(arc
							(start -0.3048 0.2032)
							(mid -0.275042 0.275042)
							(end -0.2032 0.3048)
						)
						(arc
							(start 0.2032 0.3048)
							(mid 0.275042 0.275042)
							(end 0.3048 0.2032)
						)
					)
					(width 0)
					(fill yes)
				)
			)
		)
		(pad "2" smd custom
			(at 0 0.4445 270)
			(size 0.1524 0.1524)
			(layers "F.Cu" "F.Mask" "F.Paste")
			(net "GND")
			(options
				(clearance outline)
				(anchor circle)
			)
			(primitives
				(gr_poly
					(pts
						(arc
							(start 0.3048 -0.2032)
							(mid 0.275042 -0.275042)
							(end 0.2032 -0.3048)
						)
						(arc
							(start -0.2032 -0.3048)
							(mid -0.275042 -0.275042)
							(end -0.3048 -0.2032)
						)
						(arc
							(start -0.3048 0.2032)
							(mid -0.275042 0.275042)
							(end -0.2032 0.3048)
						)
						(arc
							(start 0.2032 0.3048)
							(mid 0.275042 0.275042)
							(end 0.3048 0.2032)
						)
					)
					(width 0)
					(fill yes)
				)
			)
		)
	)
	(footprint ""
		(layer "F.Cu")
		(at 272.8976 15.273528)
		(property "Reference" "Q4"
			(at 0 0 0)
			(layer "F.SilkS")
			(hide yes)
			(effects
				(font
					(size 1.27 1.27)
				)
			)
		)
		(property "Value" "2N7002KDW-GP"
			(at -2.3622 -8.2042 0)
			(unlocked yes)
			(layer "F.Fab")
			(hide yes)
			(effects
				(font
					(size 1.016 1.016)
					(thickness 0.1524)
				)
			)
		)
		(property "Device Type" "SOT-363H44"
			(at -2.3622 -10.1092 0)
			(unlocked yes)
			(layer "F.Fab")
			(hide yes)
			(effects
				(font
					(size 1.016 1.016)
					(thickness 0.1524)
				)
			)
		)
		(duplicate_pad_numbers_are_jumpers no)
		(fp_line
			(start -1.4478 -1.7018)
			(end -1.4478 1.7018)
			(stroke
				(width 0.1524)
				(type default)
			)
			(layer "F.SilkS")
		)
		(fp_line
			(start -1.4478 1.7018)
			(end 1.4478 1.7018)
			(stroke
				(width 0.1524)
				(type default)
			)
			(layer "F.SilkS")
		)
		(fp_line
			(start -1.27 1.524)
			(end -1.27 0.6604)
			(stroke
				(width 0.4826)
				(type default)
			)
			(layer "F.SilkS")
		)
		(fp_line
			(start 1.4478 -1.7018)
			(end -1.4478 -1.7018)
			(stroke
				(width 0.1524)
				(type default)
			)
			(layer "F.SilkS")
		)
		(fp_line
			(start 1.4478 1.7018)
			(end 1.4478 -1.7018)
			(stroke
				(width 0.1524)
				(type default)
			)
			(layer "F.SilkS")
		)
		(fp_poly
			(pts
				(xy -1.524 -1.778) (xy 1.524 -1.778) (xy 1.524 1.778) (xy -1.524 1.778)
			)
			(stroke
				(width 0)
				(type default)
			)
			(fill no)
			(layer "F.CrtYd")
		)
		(fp_poly
			(pts
				(xy -1.524 -1.778) (xy 1.524 -1.778) (xy 1.524 1.778) (xy -1.524 1.778)
			)
			(stroke
				(width 0)
				(type default)
			)
			(fill no)
			(layer "F.Fab")
		)
		(pad "1" smd rect
			(at -0.65024 0.9398)
			(size 0.4064 1.016)
			(layers "F.Cu" "F.Mask" "F.Paste")
			(net "GND")
		)
		(pad "2" smd rect
			(at 0 0.9398)
			(size 0.4064 1.016)
			(layers "F.Cu" "F.Mask" "F.Paste")
			(net "SCC_B_FAULT_LED")
		)
		(pad "3" smd rect
			(at 0.65024 0.9398)
			(size 0.4064 1.016)
			(layers "F.Cu" "F.Mask" "F.Paste")
			(net "ENCL_FAULT_LED_B")
		)
		(pad "4" smd rect
			(at 0.65024 -0.9398)
			(size 0.4064 1.016)
			(layers "F.Cu" "F.Mask" "F.Paste")
			(net "GND")
		)
		(pad "5" smd rect
			(at 0 -0.9398)
			(size 0.4064 1.016)
			(layers "F.Cu" "F.Mask" "F.Paste")
			(net "IOM_B_FAULT_LED")
		)
		(pad "6" smd rect
			(at -0.65024 -0.9398)
			(size 0.4064 1.016)
			(layers "F.Cu" "F.Mask" "F.Paste")
			(net "ENCL_FAULT_LED_B")
		)
	)
	(footprint ""
		(layer "F.Cu")
		(at 232.3084 -231.3178 180)
		(property "Reference" "R67"
			(at 0 0 180)
			(layer "F.SilkS")
			(hide yes)
			(effects
				(font
					(size 1.27 1.27)
				)
			)
		)
		(property "Value" "4K7R2F-GP"
			(at 0.064008 -3.993896 180)
			(unlocked yes)
			(layer "F.Fab")
			(hide yes)
			(effects
				(font
					(size 1.016 1.016)
					(thickness 0.1524)
				)
			)
		)
		(property "Device Type" "R402H16"
			(at 0.064008 -5.517896 180)
			(unlocked yes)
			(layer "F.Fab")
			(hide yes)
			(effects
				(font
					(size 1.016 1.016)
					(thickness 0.1524)
				)
			)
		)
		(duplicate_pad_numbers_are_jumpers no)
		(fp_line
			(start 0.508 -0.9398)
			(end -0.508 -0.9398)
			(stroke
				(width 0.1524)
				(type default)
			)
			(layer "F.SilkS")
		)
		(fp_line
			(start -0.508 -0.9398)
			(end -0.508 0.9398)
			(stroke
				(width 0.1524)
				(type default)
			)
			(layer "F.SilkS")
		)
		(fp_rect
			(start -0.508 0.9398)
			(end 0.508 -0.9398)
			(stroke
				(width 0)
				(type default)
			)
			(fill no)
			(layer "F.CrtYd")
		)
		(fp_rect
			(start -0.508 0.9398)
			(end 0.508 -0.9398)
			(stroke
				(width 0)
				(type default)
			)
			(fill no)
			(layer "F.Fab")
		)
		(pad "1" smd custom
			(at 0 -0.4445 180)
			(size 0.1397 0.1397)
			(layers "F.Cu" "F.Mask" "F.Paste")
			(net "P3V3_STBY_A")
			(options
				(clearance outline)
				(anchor circle)
			)
			(primitives
				(gr_poly
					(pts
						(arc
							(start -0.1778 -0.2794)
							(mid -0.249642 -0.249642)
							(end -0.2794 -0.1778)
						)
						(arc
							(start -0.2794 0.1778)
							(mid -0.249642 0.249642)
							(end -0.1778 0.2794)
						)
						(arc
							(start 0.1778 0.2794)
							(mid 0.249642 0.249642)
							(end 0.2794 0.1778)
						)
						(arc
							(start 0.2794 -0.1778)
							(mid 0.249642 -0.249642)
							(end 0.1778 -0.2794)
						)
					)
					(width 0)
					(fill yes)
				)
			)
		)
		(pad "2" smd custom
			(at 0 0.4445 180)
			(size 0.1397 0.1397)
			(layers "F.Cu" "F.Mask" "F.Paste")
			(net "IO_EXP1_A0")
			(options
				(clearance outline)
				(anchor circle)
			)
			(primitives
				(gr_poly
					(pts
						(arc
							(start -0.1778 -0.2794)
							(mid -0.249642 -0.249642)
							(end -0.2794 -0.1778)
						)
						(arc
							(start -0.2794 0.1778)
							(mid -0.249642 0.249642)
							(end -0.1778 0.2794)
						)
						(arc
							(start 0.1778 0.2794)
							(mid 0.249642 0.249642)
							(end 0.2794 0.1778)
						)
						(arc
							(start 0.2794 -0.1778)
							(mid 0.249642 -0.249642)
							(end 0.1778 -0.2794)
						)
					)
					(width 0)
					(fill yes)
				)
			)
		)
	)
	(footprint ""
		(layer "F.Cu")
		(at 150.565866 -145.372074 180)
		(property "Reference" "R1057"
			(at 0 0 180)
			(layer "F.SilkS")
			(hide yes)
			(effects
				(font
					(size 1.27 1.27)
				)
			)
		)
		(property "Value" "137KR2F-1-GP"
			(at 0.064008 -3.993896 180)
			(unlocked yes)
			(layer "F.Fab")
			(hide yes)
			(effects
				(font
					(size 1.016 1.016)
					(thickness 0.1524)
				)
			)
		)
		(property "Device Type" "R402H16"
			(at 0.064008 -5.517896 180)
			(unlocked yes)
			(layer "F.Fab")
			(hide yes)
			(effects
				(font
					(size 1.016 1.016)
					(thickness 0.1524)
				)
			)
		)
		(duplicate_pad_numbers_are_jumpers no)
		(fp_line
			(start 0.508 -0.9398)
			(end -0.508 -0.9398)
			(stroke
				(width 0.1524)
				(type default)
			)
			(layer "F.SilkS")
		)
		(fp_line
			(start -0.508 -0.9398)
			(end -0.508 0.9398)
			(stroke
				(width 0.1524)
				(type default)
			)
			(layer "F.SilkS")
		)
		(fp_rect
			(start -0.508 0.9398)
			(end 0.508 -0.9398)
			(stroke
				(width 0)
				(type default)
			)
			(fill no)
			(layer "F.CrtYd")
		)
		(fp_rect
			(start -0.508 0.9398)
			(end 0.508 -0.9398)
			(stroke
				(width 0)
				(type default)
			)
			(fill no)
			(layer "F.Fab")
		)
		(pad "1" smd custom
			(at 0 -0.4445 180)
			(size 0.1397 0.1397)
			(layers "F.Cu" "F.Mask" "F.Paste")
			(net "MB0_PSET_R")
			(options
				(clearance outline)
				(anchor circle)
			)
			(primitives
				(gr_poly
					(pts
						(arc
							(start -0.1778 -0.2794)
							(mid -0.249642 -0.249642)
							(end -0.2794 -0.1778)
						)
						(arc
							(start -0.2794 0.1778)
							(mid -0.249642 0.249642)
							(end -0.1778 0.2794)
						)
						(arc
							(start 0.1778 0.2794)
							(mid 0.249642 0.249642)
							(end 0.2794 0.1778)
						)
						(arc
							(start 0.2794 -0.1778)
							(mid 0.249642 -0.249642)
							(end 0.1778 -0.2794)
						)
					)
					(width 0)
					(fill yes)
				)
			)
		)
		(pad "2" smd custom
			(at 0 0.4445 180)
			(size 0.1397 0.1397)
			(layers "F.Cu" "F.Mask" "F.Paste")
			(net "AGND_CURRENT_MONOA")
			(options
				(clearance outline)
				(anchor circle)
			)
			(primitives
				(gr_poly
					(pts
						(arc
							(start -0.1778 -0.2794)
							(mid -0.249642 -0.249642)
							(end -0.2794 -0.1778)
						)
						(arc
							(start -0.2794 0.1778)
							(mid -0.249642 0.249642)
							(end -0.1778 0.2794)
						)
						(arc
							(start 0.1778 0.2794)
							(mid 0.249642 0.249642)
							(end 0.2794 0.1778)
						)
						(arc
							(start 0.2794 -0.1778)
							(mid 0.249642 -0.249642)
							(end 0.1778 -0.2794)
						)
					)
					(width 0)
					(fill yes)
				)
			)
		)
	)
	(footprint ""
		(layer "F.Cu")
		(at 30.149038 -252.730254 -90)
		(property "Reference" "R1212"
			(at 0 0 270)
			(layer "F.SilkS")
			(hide yes)
			(effects
				(font
					(size 1.27 1.27)
				)
			)
		)
		(property "Value" "200KR2F-L-GP"
			(at 0.064008 -3.993896 270)
			(unlocked yes)
			(layer "F.Fab")
			(hide yes)
			(effects
				(font
					(size 1.016 1.016)
					(thickness 0.1524)
				)
			)
		)
		(property "Device Type" "R402H16"
			(at 0.064008 -5.517896 270)
			(unlocked yes)
			(layer "F.Fab")
			(hide yes)
			(effects
				(font
					(size 1.016 1.016)
					(thickness 0.1524)
				)
			)
		)
		(duplicate_pad_numbers_are_jumpers no)
		(fp_line
			(start -0.508 -0.9398)
			(end -0.508 0.9398)
			(stroke
				(width 0.1524)
				(type default)
			)
			(layer "F.SilkS")
		)
		(fp_line
			(start 0.508 -0.9398)
			(end -0.508 -0.9398)
			(stroke
				(width 0.1524)
				(type default)
			)
			(layer "F.SilkS")
		)
		(fp_rect
			(start -0.508 0.9398)
			(end 0.508 -0.9398)
			(stroke
				(width 0)
				(type default)
			)
			(fill no)
			(layer "F.CrtYd")
		)
		(fp_rect
			(start -0.508 0.9398)
			(end 0.508 -0.9398)
			(stroke
				(width 0)
				(type default)
			)
			(fill no)
			(layer "F.Fab")
		)
		(pad "1" smd custom
			(at 0 -0.4445 270)
			(size 0.1397 0.1397)
			(layers "F.Cu" "F.Mask" "F.Paste")
			(net "P5V_A_MODE")
			(options
				(clearance outline)
				(anchor circle)
			)
			(primitives
				(gr_poly
					(pts
						(arc
							(start -0.1778 -0.2794)
							(mid -0.249642 -0.249642)
							(end -0.2794 -0.1778)
						)
						(arc
							(start -0.2794 0.1778)
							(mid -0.249642 0.249642)
							(end -0.1778 0.2794)
						)
						(arc
							(start 0.1778 0.2794)
							(mid 0.249642 0.249642)
							(end 0.2794 0.1778)
						)
						(arc
							(start 0.2794 -0.1778)
							(mid 0.249642 -0.249642)
							(end 0.1778 -0.2794)
						)
					)
					(width 0)
					(fill yes)
				)
			)
		)
		(pad "2" smd custom
			(at 0 0.4445 270)
			(size 0.1397 0.1397)
			(layers "F.Cu" "F.Mask" "F.Paste")
			(net "P5V_A_1_PGOOD")
			(options
				(clearance outline)
				(anchor circle)
			)
			(primitives
				(gr_poly
					(pts
						(arc
							(start -0.1778 -0.2794)
							(mid -0.249642 -0.249642)
							(end -0.2794 -0.1778)
						)
						(arc
							(start -0.2794 0.1778)
							(mid -0.249642 0.249642)
							(end -0.1778 0.2794)
						)
						(arc
							(start 0.1778 0.2794)
							(mid 0.249642 0.249642)
							(end 0.2794 0.1778)
						)
						(arc
							(start 0.2794 -0.1778)
							(mid 0.249642 -0.249642)
							(end 0.1778 -0.2794)
						)
					)
					(width 0)
					(fill yes)
				)
			)
		)
	)
	(footprint ""
		(layer "F.Cu")
		(at 478.282 -48.067976)
		(property "Reference" "C497"
			(at 0 0 0)
			(layer "F.SilkS")
			(hide yes)
			(effects
				(font
					(size 1.27 1.27)
				)
			)
		)
		(property "Value" "SCD01U50V2KX-1GP"
			(at 1.1811 -2.7051 0)
			(unlocked yes)
			(layer "F.Fab")
			(hide yes)
			(effects
				(font
					(size 1.016 1.016)
					(thickness 0.1524)
				)
			)
		)
		(property "Device Type" "C402H22"
			(at 1.1811 -4.2291 0)
			(unlocked yes)
			(layer "F.Fab")
			(hide yes)
			(effects
				(font
					(size 1.016 1.016)
					(thickness 0.1524)
				)
			)
		)
		(duplicate_pad_numbers_are_jumpers no)
		(fp_rect
			(start -0.4318 0.9525)
			(end 0.4318 -0.9525)
			(stroke
				(width 0)
				(type default)
			)
			(fill no)
			(layer "F.CrtYd")
		)
		(fp_rect
			(start -0.4318 0.9525)
			(end 0.4318 -0.9525)
			(stroke
				(width 0)
				(type default)
			)
			(fill no)
			(layer "F.Fab")
		)
		(pad "1" smd custom
			(at 0 -0.4445)
			(size 0.1524 0.1524)
			(layers "F.Cu" "F.Mask" "F.Paste")
			(net "HDD_PRSNT_35")
			(options
				(clearance outline)
				(anchor circle)
			)
			(primitives
				(gr_poly
					(pts
						(arc
							(start 0.3048 -0.2032)
							(mid 0.275042 -0.275042)
							(end 0.2032 -0.3048)
						)
						(arc
							(start -0.2032 -0.3048)
							(mid -0.275042 -0.275042)
							(end -0.3048 -0.2032)
						)
						(arc
							(start -0.3048 0.2032)
							(mid -0.275042 0.275042)
							(end -0.2032 0.3048)
						)
						(arc
							(start 0.2032 0.3048)
							(mid 0.275042 0.275042)
							(end 0.3048 0.2032)
						)
					)
					(width 0)
					(fill yes)
				)
			)
		)
		(pad "2" smd custom
			(at 0 0.4445)
			(size 0.1524 0.1524)
			(layers "F.Cu" "F.Mask" "F.Paste")
			(net "GND")
			(options
				(clearance outline)
				(anchor circle)
			)
			(primitives
				(gr_poly
					(pts
						(arc
							(start 0.3048 -0.2032)
							(mid 0.275042 -0.275042)
							(end 0.2032 -0.3048)
						)
						(arc
							(start -0.2032 -0.3048)
							(mid -0.275042 -0.275042)
							(end -0.3048 -0.2032)
						)
						(arc
							(start -0.3048 0.2032)
							(mid -0.275042 0.275042)
							(end -0.2032 0.3048)
						)
						(arc
							(start 0.2032 0.3048)
							(mid 0.275042 0.275042)
							(end 0.3048 0.2032)
						)
					)
					(width 0)
					(fill yes)
				)
			)
		)
	)
	(footprint ""
		(layer "F.Cu")
		(at 474.853 -47.686976)
		(property "Reference" "R939"
			(at 0 0 0)
			(layer "F.SilkS")
			(hide yes)
			(effects
				(font
					(size 1.27 1.27)
				)
			)
		)
		(property "Value" "220R3F-1-GP"
			(at -0.0254 -2.5146 0)
			(unlocked yes)
			(layer "F.Fab")
			(hide yes)
			(effects
				(font
					(size 1.016 1.016)
					(thickness 0.1524)
				)
			)
		)
		(property "Device Type" "R603H22"
			(at -0.0254 -4.0386 0)
			(unlocked yes)
			(layer "F.Fab")
			(hide yes)
			(effects
				(font
					(size 1.016 1.016)
					(thickness 0.1524)
				)
			)
		)
		(duplicate_pad_numbers_are_jumpers no)
		(fp_line
			(start -0.4826 0)
			(end -0.2032 0)
			(stroke
				(width 0.2032)
				(type default)
			)
			(layer "F.SilkS")
		)
		(fp_line
			(start 0.2032 0)
			(end 0.4826 0)
			(stroke
				(width 0.2032)
				(type default)
			)
			(layer "F.SilkS")
		)
		(fp_rect
			(start -0.5842 1.3335)
			(end 0.5842 -1.3335)
			(stroke
				(width 0)
				(type default)
			)
			(fill no)
			(layer "F.CrtYd")
		)
		(fp_rect
			(start -0.5842 1.3335)
			(end 0.5842 -1.3335)
			(stroke
				(width 0)
				(type default)
			)
			(fill no)
			(layer "F.Fab")
		)
		(pad "1" smd custom
			(at 0 -0.762)
			(size 0.2159 0.2159)
			(layers "F.Cu" "F.Mask" "F.Paste")
			(net "HDD_PRSNT_35")
			(options
				(clearance outline)
				(anchor circle)
			)
			(primitives
				(gr_poly
					(pts
						(arc
							(start -0.3302 -0.4318)
							(mid -0.402042 -0.402042)
							(end -0.4318 -0.3302)
						)
						(arc
							(start -0.4318 0.3302)
							(mid -0.402042 0.402042)
							(end -0.3302 0.4318)
						)
						(arc
							(start 0.3302 0.4318)
							(mid 0.402042 0.402042)
							(end 0.4318 0.3302)
						)
						(arc
							(start 0.4318 -0.3302)
							(mid 0.402042 -0.402042)
							(end 0.3302 -0.4318)
						)
					)
					(width 0)
					(fill yes)
				)
			)
		)
		(pad "2" smd custom
			(at 0 0.762)
			(size 0.2159 0.2159)
			(layers "F.Cu" "F.Mask" "F.Paste")
			(net "DRIVE_A_35_INS")
			(options
				(clearance outline)
				(anchor circle)
			)
			(primitives
				(gr_poly
					(pts
						(arc
							(start -0.3302 -0.4318)
							(mid -0.402042 -0.402042)
							(end -0.4318 -0.3302)
						)
						(arc
							(start -0.4318 0.3302)
							(mid -0.402042 0.402042)
							(end -0.3302 0.4318)
						)
						(arc
							(start 0.3302 0.4318)
							(mid 0.402042 0.402042)
							(end 0.4318 0.3302)
						)
						(arc
							(start 0.4318 -0.3302)
							(mid 0.402042 -0.402042)
							(end 0.3302 -0.4318)
						)
					)
					(width 0)
					(fill yes)
				)
			)
		)
	)
	(footprint ""
		(layer "F.Cu")
		(at 337.38693 -17.368266 180)
		(property "Reference" "U29"
			(at 0 0 180)
			(layer "F.SilkS")
			(hide yes)
			(effects
				(font
					(size 1.27 1.27)
				)
			)
		)
		(property "Value" "74LVC1G32DC-1GP"
			(at -2.3368 -8.6868 180)
			(unlocked yes)
			(layer "F.Fab")
			(hide yes)
			(effects
				(font
					(size 1.016 1.016)
					(thickness 0.1524)
				)
			)
		)
		(property "Device Type" "SC70-5H44"
			(at -2.3114 -10.414 180)
			(unlocked yes)
			(layer "F.Fab")
			(hide yes)
			(effects
				(font
					(size 1.016 1.016)
					(thickness 0.1524)
				)
			)
		)
		(duplicate_pad_numbers_are_jumpers no)
		(fp_line
			(start 1.3843 -1.8034)
			(end 1.3843 -1.1176)
			(stroke
				(width 0.3302)
				(type default)
			)
			(layer "F.SilkS")
		)
		(fp_line
			(start 1.27 1.7018)
			(end -1.27 1.7018)
			(stroke
				(width 0.1524)
				(type default)
			)
			(layer "F.SilkS")
		)
		(fp_line
			(start 1.27 -1.7018)
			(end 1.27 1.7018)
			(stroke
				(width 0.1524)
				(type default)
			)
			(layer "F.SilkS")
		)
		(fp_line
			(start 0.6604 -1.8034)
			(end 1.3843 -1.8034)
			(stroke
				(width 0.3302)
				(type default)
			)
			(layer "F.SilkS")
		)
		(fp_line
			(start -1.27 1.7018)
			(end -1.27 -1.7018)
			(stroke
				(width 0.1524)
				(type default)
			)
			(layer "F.SilkS")
		)
		(fp_line
			(start -1.27 -1.7018)
			(end 1.27 -1.7018)
			(stroke
				(width 0.1524)
				(type default)
			)
			(layer "F.SilkS")
		)
		(fp_rect
			(start -1.524 1.9558)
			(end 1.524 -1.9558)
			(stroke
				(width 0)
				(type default)
			)
			(fill no)
			(layer "F.CrtYd")
		)
		(fp_poly
			(pts
				(xy -1.524 -1.9558) (xy 1.524 -1.9558) (xy 1.524 1.9558) (xy -1.524 1.9558)
			)
			(stroke
				(width 0)
				(type default)
			)
			(fill no)
			(layer "F.Fab")
		)
		(pad "1" smd rect
			(at 0.65024 -0.8255 180)
			(size 0.4064 1.2192)
			(layers "F.Cu" "F.Mask" "F.Paste")
			(net "COMP_B_PRI_INS_N")
		)
		(pad "2" smd rect
			(at 0 -0.8255 180)
			(size 0.4064 1.2192)
			(layers "F.Cu" "F.Mask" "F.Paste")
			(net "COMP_B_SEC_INS_N")
		)
		(pad "3" smd rect
			(at -0.65024 -0.8255 180)
			(size 0.4064 1.2192)
			(layers "F.Cu" "F.Mask" "F.Paste")
			(net "GND")
		)
		(pad "4" smd rect
			(at -0.65024 0.8255 180)
			(size 0.4064 1.2192)
			(layers "F.Cu" "F.Mask" "F.Paste")
			(net "COMP_B_INS_N")
		)
		(pad "5" smd rect
			(at 0.65024 0.8255 180)
			(size 0.4064 1.2192)
			(layers "F.Cu" "F.Mask" "F.Paste")
			(net "P3V3_STBY_B")
		)
	)
	(footprint ""
		(layer "F.Cu")
		(at 255.386078 -9.720834 180)
		(property "Reference" "TP218"
			(at 0 0 180)
			(layer "F.SilkS")
			(hide yes)
			(effects
				(font
					(size 1.27 1.27)
				)
			)
		)
		(property "Value" "TPAD32-GP"
			(at -0.0508 -1.6764 180)
			(unlocked yes)
			(layer "F.Fab")
			(hide yes)
			(effects
				(font
					(size 1.016 1.016)
					(thickness 0.1524)
				)
			)
		)
		(property "Device Type" "TPAD32"
			(at -0.0508 -3.2004 180)
			(unlocked yes)
			(layer "F.Fab")
			(hide yes)
			(effects
				(font
					(size 1.016 1.016)
					(thickness 0.1524)
				)
			)
		)
		(duplicate_pad_numbers_are_jumpers no)
		(fp_poly
			(pts
				(arc
					(start -0.4064 0)
					(mid 0.4064 0)
					(end -0.4064 0)
				)
			)
			(stroke
				(width 0)
				(type default)
			)
			(fill no)
			(layer "F.CrtYd")
		)
		(fp_poly
			(pts
				(arc
					(start -0.7112 0)
					(mid 0.7112 0)
					(end -0.7112 0)
				)
			)
			(stroke
				(width 0)
				(type default)
			)
			(fill no)
			(layer "F.Fab")
		)
		(pad "1" smd circle
			(at 0 0 180)
			(size 0.8128 0.8128)
			(layers "F.Cu" "F.Mask" "F.Paste")
			(net "TP_COMP_A_NCSI_CRSDV")
		)
	)
	(footprint ""
		(layer "F.Cu")
		(at 272.542 -334.304894 180)
		(property "Reference" "VIA49"
			(at 0 0 180)
			(layer "F.SilkS")
			(hide yes)
			(effects
				(font
					(size 1.27 1.27)
				)
			)
		)
		(property "Value" "100OHM-8L-1D6MM-L18L16-GP"
			(at -3.7211 -4.5085 180)
			(unlocked yes)
			(layer "F.Fab")
			(hide yes)
			(effects
				(font
					(size 1.016 1.016)
					(thickness 0.1524)
				)
			)
		)
		(property "Device Type" "VIA-PCIE-4P-394076"
			(at -3.7211 -6.0325 180)
			(unlocked yes)
			(layer "F.Fab")
			(hide yes)
			(effects
				(font
					(size 1.016 1.016)
					(thickness 0.1524)
				)
			)
		)
		(duplicate_pad_numbers_are_jumpers no)
		(fp_rect
			(start -1.9685 0.381)
			(end 1.9685 -0.381)
			(stroke
				(width 0)
				(type default)
			)
			(fill no)
			(layer "F.CrtYd")
		)
		(fp_rect
			(start -1.9685 0.381)
			(end 1.9685 -0.381)
			(stroke
				(width 0)
				(type default)
			)
			(fill no)
			(layer "F.Fab")
		)
		(pad "1" thru_hole circle
			(at -1.5875 0 180)
			(size 0.508 0.508)
			(drill 0.254)
			(layers "*.Cu" "*.Mask")
			(remove_unused_layers no)
			(net "GND")
			(clearance 0.127)
			(thermal_gap 0.127)
		)
		(pad "2" thru_hole circle
			(at -0.5715 0 180)
			(size 0.508 0.508)
			(drill 0.254)
			(layers "*.Cu" "*.Mask")
			(remove_unused_layers no)
			(net "PHY_SCC_A_TO_DRV_A_14_DP")
			(clearance 0.127)
			(thermal_gap 0.127)
		)
		(pad "3" thru_hole circle
			(at 0.5715 0 180)
			(size 0.508 0.508)
			(drill 0.254)
			(layers "*.Cu" "*.Mask")
			(remove_unused_layers no)
			(net "PHY_SCC_A_TO_DRV_A_14_DN")
			(clearance 0.127)
			(thermal_gap 0.127)
		)
		(pad "4" thru_hole circle
			(at 1.5875 0 180)
			(size 0.508 0.508)
			(drill 0.254)
			(layers "*.Cu" "*.Mask")
			(remove_unused_layers no)
			(net "GND")
			(clearance 0.127)
			(thermal_gap 0.127)
		)
	)
	(footprint ""
		(layer "F.Cu")
		(at 367.287302 -275.735542 180)
		(property "Reference" "R308"
			(at 0 0 180)
			(layer "F.SilkS")
			(hide yes)
			(effects
				(font
					(size 1.27 1.27)
				)
			)
		)
		(property "Value" "0R2J-2-GP"
			(at 0.064008 -3.993896 180)
			(unlocked yes)
			(layer "F.Fab")
			(hide yes)
			(effects
				(font
					(size 1.016 1.016)
					(thickness 0.1524)
				)
			)
		)
		(property "Device Type" "R402H16"
			(at 0.064008 -5.517896 180)
			(unlocked yes)
			(layer "F.Fab")
			(hide yes)
			(effects
				(font
					(size 1.016 1.016)
					(thickness 0.1524)
				)
			)
		)
		(duplicate_pad_numbers_are_jumpers no)
		(fp_line
			(start 0.508 -0.9398)
			(end -0.508 -0.9398)
			(stroke
				(width 0.1524)
				(type default)
			)
			(layer "F.SilkS")
		)
		(fp_line
			(start -0.508 -0.9398)
			(end -0.508 0.9398)
			(stroke
				(width 0.1524)
				(type default)
			)
			(layer "F.SilkS")
		)
		(fp_rect
			(start -0.508 0.9398)
			(end 0.508 -0.9398)
			(stroke
				(width 0)
				(type default)
			)
			(fill no)
			(layer "F.CrtYd")
		)
		(fp_rect
			(start -0.508 0.9398)
			(end 0.508 -0.9398)
			(stroke
				(width 0)
				(type default)
			)
			(fill no)
			(layer "F.Fab")
		)
		(pad "1" smd custom
			(at 0 -0.4445 180)
			(size 0.1397 0.1397)
			(layers "F.Cu" "F.Mask" "F.Paste")
			(net "SW_HDD_G7")
			(options
				(clearance outline)
				(anchor circle)
			)
			(primitives
				(gr_poly
					(pts
						(arc
							(start -0.1778 -0.2794)
							(mid -0.249642 -0.249642)
							(end -0.2794 -0.1778)
						)
						(arc
							(start -0.2794 0.1778)
							(mid -0.249642 0.249642)
							(end -0.1778 0.2794)
						)
						(arc
							(start 0.1778 0.2794)
							(mid 0.249642 0.249642)
							(end 0.2794 0.1778)
						)
						(arc
							(start 0.2794 -0.1778)
							(mid 0.249642 -0.249642)
							(end 0.1778 -0.2794)
						)
					)
					(width 0)
					(fill yes)
				)
			)
		)
		(pad "2" smd custom
			(at 0 0.4445 180)
			(size 0.1397 0.1397)
			(layers "F.Cu" "F.Mask" "F.Paste")
			(net "SW_HDD_R7")
			(options
				(clearance outline)
				(anchor circle)
			)
			(primitives
				(gr_poly
					(pts
						(arc
							(start -0.1778 -0.2794)
							(mid -0.249642 -0.249642)
							(end -0.2794 -0.1778)
						)
						(arc
							(start -0.2794 0.1778)
							(mid -0.249642 0.249642)
							(end -0.1778 0.2794)
						)
						(arc
							(start 0.1778 0.2794)
							(mid 0.249642 0.249642)
							(end 0.2794 0.1778)
						)
						(arc
							(start 0.2794 -0.1778)
							(mid 0.249642 -0.249642)
							(end 0.1778 -0.2794)
						)
					)
					(width 0)
					(fill yes)
				)
			)
		)
	)
	(footprint ""
		(layer "F.Cu")
		(at 274.283932 -392.79068 -90)
		(property "Reference" "D40"
			(at 0 0 270)
			(layer "F.SilkS")
			(hide yes)
			(effects
				(font
					(size 1.27 1.27)
				)
			)
		)
		(property "Value" "SMCJ14A-13-F-GP"
			(at -4.445 1.1684 270)
			(unlocked yes)
			(layer "F.Fab")
			(hide yes)
			(effects
				(font
					(size 1.016 1.016)
					(thickness 0.1524)
				)
			)
		)
		(property "Device Type" "D795930AKH104"
			(at -4.445 -0.3556 270)
			(unlocked yes)
			(layer "F.Fab")
			(hide yes)
			(effects
				(font
					(size 1.016 1.016)
					(thickness 0.1524)
				)
			)
		)
		(duplicate_pad_numbers_are_jumpers no)
		(fp_line
			(start 3.2004 5.0419)
			(end -3.2004 5.0419)
			(stroke
				(width 0.508)
				(type default)
			)
			(layer "F.SilkS")
		)
		(fp_line
			(start -3.2004 4.8641)
			(end 3.2004 4.8641)
			(stroke
				(width 0.1524)
				(type default)
			)
			(layer "F.SilkS")
		)
		(fp_line
			(start 3.2004 4.8641)
			(end 3.2004 -4.8641)
			(stroke
				(width 0.1524)
				(type default)
			)
			(layer "F.SilkS")
		)
		(fp_line
			(start -3.2004 -4.8641)
			(end -3.2004 4.8641)
			(stroke
				(width 0.1524)
				(type default)
			)
			(layer "F.SilkS")
		)
		(fp_line
			(start 3.2004 -4.8641)
			(end -3.2004 -4.8641)
			(stroke
				(width 0.1524)
				(type default)
			)
			(layer "F.SilkS")
		)
		(fp_poly
			(pts
				(xy -2.9464 3.429) (xy -1.4859 3.429) (xy -1.4859 3.9751) (xy 1.4859 3.9751) (xy 1.4859 3.429) (xy 2.9464 3.429)
				(xy 2.9464 -3.429) (xy 1.4859 -3.429) (xy 1.4859 -3.9751) (xy -1.4859 -3.9751) (xy -1.4859 -3.429)
				(xy -2.9464 -3.429)
			)
			(stroke
				(width 0)
				(type default)
			)
			(fill no)
			(layer "F.CrtYd")
		)
		(fp_poly
			(pts
				(xy -3.4544 4.9403) (xy -3.4544 -4.9403) (xy 3.4544 -4.9403) (xy 3.4544 -3.429) (xy 1.4859 -3.429)
				(xy 1.4859 -3.9751) (xy -1.4859 -3.9751) (xy -1.4859 -3.429) (xy -2.9464 -3.429) (xy -2.9464 3.429)
				(xy -1.4859 3.429) (xy -1.4859 3.9751) (xy 1.4859 3.9751) (xy 1.4859 3.429) (xy 2.9464 3.429) (xy 2.9464 -3.4163)
				(xy 3.4544 -3.4163) (xy 3.4544 4.9403)
			)
			(stroke
				(width 0)
				(type default)
			)
			(fill no)
			(layer "F.CrtYd")
		)
		(fp_rect
			(start -3.4544 4.9403)
			(end 3.4544 -4.9403)
			(stroke
				(width 0)
				(type default)
			)
			(fill no)
			(layer "F.Fab")
		)
		(pad "A" smd rect
			(at 0 -3.592068 270)
			(size 3.2258 2.032)
			(layers "F.Cu" "F.Mask" "F.Paste")
			(net "GND")
		)
		(pad "K" smd rect
			(at 0 3.592068 270)
			(size 3.2258 2.032)
			(layers "F.Cu" "F.Mask" "F.Paste")
			(net "P12V_IN")
		)
	)
	(footprint ""
		(layer "F.Cu")
		(at 242.896644 -382.70815)
		(property "Reference" "R1177"
			(at 0 0 0)
			(layer "F.SilkS")
			(hide yes)
			(effects
				(font
					(size 1.27 1.27)
				)
			)
		)
		(property "Value" "0R5J-5-GP"
			(at 0 -8.9535 0)
			(unlocked yes)
			(layer "F.Fab")
			(hide yes)
			(effects
				(font
					(size 1.27 1.016)
					(thickness 0.1524)
				)
			)
		)
		(property "Device Type" "R805H24"
			(at 0 -10.6299 0)
			(unlocked yes)
			(layer "F.Fab")
			(hide yes)
			(effects
				(font
					(size 1.27 1.016)
					(thickness 0.1524)
				)
			)
		)
		(duplicate_pad_numbers_are_jumpers no)
		(fp_line
			(start -0.889 -1.7018)
			(end -0.889 0.2794)
			(stroke
				(width 0.1524)
				(type default)
			)
			(layer "F.SilkS")
		)
		(fp_line
			(start -0.889 0.0762)
			(end -0.889 1.7018)
			(stroke
				(width 0.1524)
				(type default)
			)
			(layer "F.SilkS")
		)
		(fp_line
			(start -0.889 1.7018)
			(end 0.889 1.7018)
			(stroke
				(width 0.1524)
				(type default)
			)
			(layer "F.SilkS")
		)
		(fp_line
			(start 0.889 -1.7018)
			(end -0.889 -1.7018)
			(stroke
				(width 0.1524)
				(type default)
			)
			(layer "F.SilkS")
		)
		(fp_line
			(start 0.889 -1.7018)
			(end 0.889 -0.381)
			(stroke
				(width 0.1524)
				(type default)
			)
			(layer "F.SilkS")
		)
		(fp_line
			(start 0.889 1.7018)
			(end 0.889 -0.508)
			(stroke
				(width 0.1524)
				(type default)
			)
			(layer "F.SilkS")
		)
		(fp_poly
			(pts
				(xy 0.9652 -1.778) (xy 0.9652 1.778) (xy -0.9652 1.778) (xy -0.9652 -1.778)
			)
			(stroke
				(width 0)
				(type default)
			)
			(fill no)
			(layer "F.CrtYd")
		)
		(fp_rect
			(start -0.9652 1.778)
			(end 0.9652 -1.778)
			(stroke
				(width 0)
				(type default)
			)
			(fill no)
			(layer "F.Fab")
		)
		(pad "1" smd rect
			(at 0 -0.9652)
			(size 1.397 1.143)
			(layers "F.Cu" "F.Mask" "F.Paste")
			(net "MB3_CM_GATE")
		)
		(pad "2" smd rect
			(at 0 0.9652)
			(size 1.397 1.143)
			(layers "F.Cu" "F.Mask" "F.Paste")
			(net "MB3_CM_GATE_R")
		)
	)
	(footprint ""
		(layer "F.Cu")
		(at 365.052102 -303.954942 180)
		(property "Reference" "C137"
			(at 0 0 180)
			(layer "F.SilkS")
			(hide yes)
			(effects
				(font
					(size 1.27 1.27)
				)
			)
		)
		(property "Value" "SC4D7U25V5KX-1-GP"
			(at -0.0762 -6.1214 180)
			(unlocked yes)
			(layer "F.Fab")
			(hide yes)
			(effects
				(font
					(size 1.016 1.016)
					(thickness 0.1524)
				)
			)
		)
		(property "Device Type" "C805H58"
			(at -0.0762 -8.1534 180)
			(unlocked yes)
			(layer "F.Fab")
			(hide yes)
			(effects
				(font
					(size 1.016 1.016)
					(thickness 0.1524)
				)
			)
		)
		(duplicate_pad_numbers_are_jumpers no)
		(fp_line
			(start 0.635 0)
			(end -0.635 0)
			(stroke
				(width 0.508)
				(type default)
			)
			(layer "F.SilkS")
		)
		(fp_rect
			(start -0.9652 1.778)
			(end 0.9652 -1.778)
			(stroke
				(width 0)
				(type default)
			)
			(fill no)
			(layer "F.CrtYd")
		)
		(fp_poly
			(pts
				(xy -0.9652 -1.778) (xy 0.9652 -1.778) (xy 0.9652 1.778) (xy -0.9652 1.778)
			)
			(stroke
				(width 0)
				(type default)
			)
			(fill no)
			(layer "F.Fab")
		)
		(pad "1" smd rect
			(at 0 -0.9652 180)
			(size 1.397 1.143)
			(layers "F.Cu" "F.Mask" "F.Paste")
			(net "P12V_HDD7")
		)
		(pad "2" smd rect
			(at 0 0.9652 180)
			(size 1.397 1.143)
			(layers "F.Cu" "F.Mask" "F.Paste")
			(net "GND")
		)
	)
	(footprint ""
		(layer "F.Cu")
		(at 255.700276 -248.87936 180)
		(property "Reference" "R62"
			(at 0 0 180)
			(layer "F.SilkS")
			(hide yes)
			(effects
				(font
					(size 1.27 1.27)
				)
			)
		)
		(property "Value" "4K7R2F-GP"
			(at 0.064008 -3.993896 180)
			(unlocked yes)
			(layer "F.Fab")
			(hide yes)
			(effects
				(font
					(size 1.016 1.016)
					(thickness 0.1524)
				)
			)
		)
		(property "Device Type" "R402H16"
			(at 0.064008 -5.517896 180)
			(unlocked yes)
			(layer "F.Fab")
			(hide yes)
			(effects
				(font
					(size 1.016 1.016)
					(thickness 0.1524)
				)
			)
		)
		(duplicate_pad_numbers_are_jumpers no)
		(fp_line
			(start 0.508 -0.9398)
			(end -0.508 -0.9398)
			(stroke
				(width 0.1524)
				(type default)
			)
			(layer "F.SilkS")
		)
		(fp_line
			(start -0.508 -0.9398)
			(end -0.508 0.9398)
			(stroke
				(width 0.1524)
				(type default)
			)
			(layer "F.SilkS")
		)
		(fp_rect
			(start -0.508 0.9398)
			(end 0.508 -0.9398)
			(stroke
				(width 0)
				(type default)
			)
			(fill no)
			(layer "F.CrtYd")
		)
		(fp_rect
			(start -0.508 0.9398)
			(end 0.508 -0.9398)
			(stroke
				(width 0)
				(type default)
			)
			(fill no)
			(layer "F.Fab")
		)
		(pad "1" smd custom
			(at 0 -0.4445 180)
			(size 0.1397 0.1397)
			(layers "F.Cu" "F.Mask" "F.Paste")
			(net "P3V3_STBY_A")
			(options
				(clearance outline)
				(anchor circle)
			)
			(primitives
				(gr_poly
					(pts
						(arc
							(start -0.1778 -0.2794)
							(mid -0.249642 -0.249642)
							(end -0.2794 -0.1778)
						)
						(arc
							(start -0.2794 0.1778)
							(mid -0.249642 0.249642)
							(end -0.1778 0.2794)
						)
						(arc
							(start 0.1778 0.2794)
							(mid 0.249642 0.249642)
							(end 0.2794 0.1778)
						)
						(arc
							(start 0.2794 -0.1778)
							(mid 0.249642 -0.249642)
							(end 0.1778 -0.2794)
						)
					)
					(width 0)
					(fill yes)
				)
			)
		)
		(pad "2" smd custom
			(at 0 0.4445 180)
			(size 0.1397 0.1397)
			(layers "F.Cu" "F.Mask" "F.Paste")
			(net "IO_EXP6_A2")
			(options
				(clearance outline)
				(anchor circle)
			)
			(primitives
				(gr_poly
					(pts
						(arc
							(start -0.1778 -0.2794)
							(mid -0.249642 -0.249642)
							(end -0.2794 -0.1778)
						)
						(arc
							(start -0.2794 0.1778)
							(mid -0.249642 0.249642)
							(end -0.1778 0.2794)
						)
						(arc
							(start 0.1778 0.2794)
							(mid 0.249642 0.249642)
							(end 0.2794 0.1778)
						)
						(arc
							(start 0.2794 -0.1778)
							(mid 0.249642 -0.249642)
							(end 0.1778 -0.2794)
						)
					)
					(width 0)
					(fill yes)
				)
			)
		)
	)
	(footprint ""
		(layer "F.Cu")
		(at 99.278948 -180.064918 90)
		(property "Reference" "R456"
			(at 0 0 90)
			(layer "F.SilkS")
			(hide yes)
			(effects
				(font
					(size 1.27 1.27)
				)
			)
		)
		(property "Value" "220R3F-1-GP"
			(at -0.0254 -2.5146 90)
			(unlocked yes)
			(layer "F.Fab")
			(hide yes)
			(effects
				(font
					(size 1.016 1.016)
					(thickness 0.1524)
				)
			)
		)
		(property "Device Type" "R603H22"
			(at -0.0254 -4.0386 90)
			(unlocked yes)
			(layer "F.Fab")
			(hide yes)
			(effects
				(font
					(size 1.016 1.016)
					(thickness 0.1524)
				)
			)
		)
		(duplicate_pad_numbers_are_jumpers no)
		(fp_line
			(start 0.2032 0)
			(end 0.4826 0)
			(stroke
				(width 0.2032)
				(type default)
			)
			(layer "F.SilkS")
		)
		(fp_line
			(start -0.4826 0)
			(end -0.2032 0)
			(stroke
				(width 0.2032)
				(type default)
			)
			(layer "F.SilkS")
		)
		(fp_rect
			(start -0.5842 1.3335)
			(end 0.5842 -1.3335)
			(stroke
				(width 0)
				(type default)
			)
			(fill no)
			(layer "F.CrtYd")
		)
		(fp_rect
			(start -0.5842 1.3335)
			(end 0.5842 -1.3335)
			(stroke
				(width 0)
				(type default)
			)
			(fill no)
			(layer "F.Fab")
		)
		(pad "1" smd custom
			(at 0 -0.762 90)
			(size 0.2159 0.2159)
			(layers "F.Cu" "F.Mask" "F.Paste")
			(net "HDD_PRSNT_14")
			(options
				(clearance outline)
				(anchor circle)
			)
			(primitives
				(gr_poly
					(pts
						(arc
							(start -0.3302 -0.4318)
							(mid -0.402042 -0.402042)
							(end -0.4318 -0.3302)
						)
						(arc
							(start -0.4318 0.3302)
							(mid -0.402042 0.402042)
							(end -0.3302 0.4318)
						)
						(arc
							(start 0.3302 0.4318)
							(mid 0.402042 0.402042)
							(end 0.4318 0.3302)
						)
						(arc
							(start 0.4318 -0.3302)
							(mid 0.402042 -0.402042)
							(end 0.3302 -0.4318)
						)
					)
					(width 0)
					(fill yes)
				)
			)
		)
		(pad "2" smd custom
			(at 0 0.762 90)
			(size 0.2159 0.2159)
			(layers "F.Cu" "F.Mask" "F.Paste")
			(net "DRIVE_A_14_INS")
			(options
				(clearance outline)
				(anchor circle)
			)
			(primitives
				(gr_poly
					(pts
						(arc
							(start -0.3302 -0.4318)
							(mid -0.402042 -0.402042)
							(end -0.4318 -0.3302)
						)
						(arc
							(start -0.4318 0.3302)
							(mid -0.402042 0.402042)
							(end -0.3302 0.4318)
						)
						(arc
							(start 0.3302 0.4318)
							(mid 0.402042 0.402042)
							(end 0.4318 0.3302)
						)
						(arc
							(start 0.4318 -0.3302)
							(mid 0.402042 -0.402042)
							(end 0.3302 -0.4318)
						)
					)
					(width 0)
					(fill yes)
				)
			)
		)
	)
	(footprint ""
		(layer "F.Cu")
		(at 67.728846 -65.064894 90)
		(property "Reference" "R709"
			(at 0 0 90)
			(layer "F.SilkS")
			(hide yes)
			(effects
				(font
					(size 1.27 1.27)
				)
			)
		)
		(property "Value" "220R3F-1-GP"
			(at -0.0254 -2.5146 90)
			(unlocked yes)
			(layer "F.Fab")
			(hide yes)
			(effects
				(font
					(size 1.016 1.016)
					(thickness 0.1524)
				)
			)
		)
		(property "Device Type" "R603H22"
			(at -0.0254 -4.0386 90)
			(unlocked yes)
			(layer "F.Fab")
			(hide yes)
			(effects
				(font
					(size 1.016 1.016)
					(thickness 0.1524)
				)
			)
		)
		(duplicate_pad_numbers_are_jumpers no)
		(fp_line
			(start 0.2032 0)
			(end 0.4826 0)
			(stroke
				(width 0.2032)
				(type default)
			)
			(layer "F.SilkS")
		)
		(fp_line
			(start -0.4826 0)
			(end -0.2032 0)
			(stroke
				(width 0.2032)
				(type default)
			)
			(layer "F.SilkS")
		)
		(fp_rect
			(start -0.5842 1.3335)
			(end 0.5842 -1.3335)
			(stroke
				(width 0)
				(type default)
			)
			(fill no)
			(layer "F.CrtYd")
		)
		(fp_rect
			(start -0.5842 1.3335)
			(end 0.5842 -1.3335)
			(stroke
				(width 0)
				(type default)
			)
			(fill no)
			(layer "F.Fab")
		)
		(pad "1" smd custom
			(at 0 -0.762 90)
			(size 0.2159 0.2159)
			(layers "F.Cu" "F.Mask" "F.Paste")
			(net "HDD_PRSNT_25")
			(options
				(clearance outline)
				(anchor circle)
			)
			(primitives
				(gr_poly
					(pts
						(arc
							(start -0.3302 -0.4318)
							(mid -0.402042 -0.402042)
							(end -0.4318 -0.3302)
						)
						(arc
							(start -0.4318 0.3302)
							(mid -0.402042 0.402042)
							(end -0.3302 0.4318)
						)
						(arc
							(start 0.3302 0.4318)
							(mid 0.402042 0.402042)
							(end 0.4318 0.3302)
						)
						(arc
							(start 0.4318 -0.3302)
							(mid 0.402042 -0.402042)
							(end 0.3302 -0.4318)
						)
					)
					(width 0)
					(fill yes)
				)
			)
		)
		(pad "2" smd custom
			(at 0 0.762 90)
			(size 0.2159 0.2159)
			(layers "F.Cu" "F.Mask" "F.Paste")
			(net "DRIVE_A_25_INS")
			(options
				(clearance outline)
				(anchor circle)
			)
			(primitives
				(gr_poly
					(pts
						(arc
							(start -0.3302 -0.4318)
							(mid -0.402042 -0.402042)
							(end -0.4318 -0.3302)
						)
						(arc
							(start -0.4318 0.3302)
							(mid -0.402042 0.402042)
							(end -0.3302 0.4318)
						)
						(arc
							(start 0.3302 0.4318)
							(mid 0.402042 0.402042)
							(end 0.4318 0.3302)
						)
						(arc
							(start 0.4318 -0.3302)
							(mid 0.402042 -0.402042)
							(end 0.3302 -0.4318)
						)
					)
					(width 0)
					(fill yes)
				)
			)
		)
	)
	(footprint ""
		(layer "F.Cu")
		(at 165.776402 -129.286)
		(property "Reference" "R312"
			(at 0 0 0)
			(layer "F.SilkS")
			(hide yes)
			(effects
				(font
					(size 1.27 1.27)
				)
			)
		)
		(property "Value" "91R3F-1-GP"
			(at -0.0254 -2.5146 0)
			(unlocked yes)
			(layer "F.Fab")
			(hide yes)
			(effects
				(font
					(size 1.016 1.016)
					(thickness 0.1524)
				)
			)
		)
		(property "Device Type" "R603H22"
			(at -0.0254 -4.0386 0)
			(unlocked yes)
			(layer "F.Fab")
			(hide yes)
			(effects
				(font
					(size 1.016 1.016)
					(thickness 0.1524)
				)
			)
		)
		(duplicate_pad_numbers_are_jumpers no)
		(fp_line
			(start -0.4826 0)
			(end -0.2032 0)
			(stroke
				(width 0.2032)
				(type default)
			)
			(layer "F.SilkS")
		)
		(fp_line
			(start 0.2032 0)
			(end 0.4826 0)
			(stroke
				(width 0.2032)
				(type default)
			)
			(layer "F.SilkS")
		)
		(fp_rect
			(start -0.5842 1.3335)
			(end 0.5842 -1.3335)
			(stroke
				(width 0)
				(type default)
			)
			(fill no)
			(layer "F.CrtYd")
		)
		(fp_rect
			(start -0.5842 1.3335)
			(end 0.5842 -1.3335)
			(stroke
				(width 0)
				(type default)
			)
			(fill no)
			(layer "F.Fab")
		)
		(pad "1" smd custom
			(at 0 -0.762)
			(size 0.2159 0.2159)
			(layers "F.Cu" "F.Mask" "F.Paste")
			(net "P5V_A_2")
			(options
				(clearance outline)
				(anchor circle)
			)
			(primitives
				(gr_poly
					(pts
						(arc
							(start -0.3302 -0.4318)
							(mid -0.402042 -0.402042)
							(end -0.4318 -0.3302)
						)
						(arc
							(start -0.4318 0.3302)
							(mid -0.402042 0.402042)
							(end -0.3302 0.4318)
						)
						(arc
							(start 0.3302 0.4318)
							(mid 0.402042 0.402042)
							(end 0.4318 0.3302)
						)
						(arc
							(start 0.4318 -0.3302)
							(mid 0.402042 -0.402042)
							(end 0.3302 -0.4318)
						)
					)
					(width 0)
					(fill yes)
				)
			)
		)
		(pad "2" smd custom
			(at 0 0.762)
			(size 0.2159 0.2159)
			(layers "F.Cu" "F.Mask" "F.Paste")
			(net "DRV_ACT_17")
			(options
				(clearance outline)
				(anchor circle)
			)
			(primitives
				(gr_poly
					(pts
						(arc
							(start -0.3302 -0.4318)
							(mid -0.402042 -0.402042)
							(end -0.4318 -0.3302)
						)
						(arc
							(start -0.4318 0.3302)
							(mid -0.402042 0.402042)
							(end -0.3302 0.4318)
						)
						(arc
							(start 0.3302 0.4318)
							(mid 0.402042 0.402042)
							(end 0.4318 0.3302)
						)
						(arc
							(start 0.4318 -0.3302)
							(mid 0.402042 -0.402042)
							(end 0.3302 -0.4318)
						)
					)
					(width 0)
					(fill yes)
				)
			)
		)
	)
	(footprint ""
		(layer "F.Cu")
		(at 268.6558 -230.3018 180)
		(property "Reference" "R91"
			(at 0 0 180)
			(layer "F.SilkS")
			(hide yes)
			(effects
				(font
					(size 1.27 1.27)
				)
			)
		)
		(property "Value" "4K7R2F-GP"
			(at 0.064008 -3.993896 180)
			(unlocked yes)
			(layer "F.Fab")
			(hide yes)
			(effects
				(font
					(size 1.016 1.016)
					(thickness 0.1524)
				)
			)
		)
		(property "Device Type" "R402H16"
			(at 0.064008 -5.517896 180)
			(unlocked yes)
			(layer "F.Fab")
			(hide yes)
			(effects
				(font
					(size 1.016 1.016)
					(thickness 0.1524)
				)
			)
		)
		(duplicate_pad_numbers_are_jumpers no)
		(fp_line
			(start 0.508 -0.9398)
			(end -0.508 -0.9398)
			(stroke
				(width 0.1524)
				(type default)
			)
			(layer "F.SilkS")
		)
		(fp_line
			(start -0.508 -0.9398)
			(end -0.508 0.9398)
			(stroke
				(width 0.1524)
				(type default)
			)
			(layer "F.SilkS")
		)
		(fp_rect
			(start -0.508 0.9398)
			(end 0.508 -0.9398)
			(stroke
				(width 0)
				(type default)
			)
			(fill no)
			(layer "F.CrtYd")
		)
		(fp_rect
			(start -0.508 0.9398)
			(end 0.508 -0.9398)
			(stroke
				(width 0)
				(type default)
			)
			(fill no)
			(layer "F.Fab")
		)
		(pad "1" smd custom
			(at 0 -0.4445 180)
			(size 0.1397 0.1397)
			(layers "F.Cu" "F.Mask" "F.Paste")
			(net "P3V3_STBY_A")
			(options
				(clearance outline)
				(anchor circle)
			)
			(primitives
				(gr_poly
					(pts
						(arc
							(start -0.1778 -0.2794)
							(mid -0.249642 -0.249642)
							(end -0.2794 -0.1778)
						)
						(arc
							(start -0.2794 0.1778)
							(mid -0.249642 0.249642)
							(end -0.1778 0.2794)
						)
						(arc
							(start 0.1778 0.2794)
							(mid 0.249642 0.249642)
							(end 0.2794 0.1778)
						)
						(arc
							(start 0.2794 -0.1778)
							(mid 0.249642 -0.249642)
							(end 0.1778 -0.2794)
						)
					)
					(width 0)
					(fill yes)
				)
			)
		)
		(pad "2" smd custom
			(at 0 0.4445 180)
			(size 0.1397 0.1397)
			(layers "F.Cu" "F.Mask" "F.Paste")
			(net "IO_EXP3_A2")
			(options
				(clearance outline)
				(anchor circle)
			)
			(primitives
				(gr_poly
					(pts
						(arc
							(start -0.1778 -0.2794)
							(mid -0.249642 -0.249642)
							(end -0.2794 -0.1778)
						)
						(arc
							(start -0.2794 0.1778)
							(mid -0.249642 0.249642)
							(end -0.1778 0.2794)
						)
						(arc
							(start 0.1778 0.2794)
							(mid 0.249642 0.249642)
							(end 0.2794 0.1778)
						)
						(arc
							(start 0.2794 -0.1778)
							(mid 0.249642 -0.249642)
							(end 0.1778 -0.2794)
						)
					)
					(width 0)
					(fill yes)
				)
			)
		)
	)
	(footprint ""
		(layer "F.Cu")
		(at 267.197078 -130.124708 90)
		(property "Reference" "TP183"
			(at 0 0 90)
			(layer "F.SilkS")
			(hide yes)
			(effects
				(font
					(size 1.27 1.27)
				)
			)
		)
		(property "Value" "TPAD32-GP"
			(at -0.0508 -1.6764 90)
			(unlocked yes)
			(layer "F.Fab")
			(hide yes)
			(effects
				(font
					(size 1.016 1.016)
					(thickness 0.1524)
				)
			)
		)
		(property "Device Type" "TPAD32"
			(at -0.0508 -3.2004 90)
			(unlocked yes)
			(layer "F.Fab")
			(hide yes)
			(effects
				(font
					(size 1.016 1.016)
					(thickness 0.1524)
				)
			)
		)
		(duplicate_pad_numbers_are_jumpers no)
		(fp_poly
			(pts
				(arc
					(start 0 0.4064)
					(mid 0 -0.4064)
					(end 0 0.4064)
				)
			)
			(stroke
				(width 0)
				(type default)
			)
			(fill no)
			(layer "F.CrtYd")
		)
		(fp_poly
			(pts
				(arc
					(start 0 0.7112)
					(mid 0 -0.7112)
					(end 0 0.7112)
				)
			)
			(stroke
				(width 0)
				(type default)
			)
			(fill no)
			(layer "F.Fab")
		)
		(pad "1" smd circle
			(at 0 0 90)
			(size 0.8128 0.8128)
			(layers "F.Cu" "F.Mask" "F.Paste")
			(net "TP_COMP_B_SATA_P0_TX_DP")
		)
	)
	(footprint ""
		(layer "F.Cu")
		(at 272.542 -357.704898 180)
		(property "Reference" "VIA35"
			(at 0 0 180)
			(layer "F.SilkS")
			(hide yes)
			(effects
				(font
					(size 1.27 1.27)
				)
			)
		)
		(property "Value" "100OHM-8L-1D6MM-L18L16-GP"
			(at -3.7211 -4.5085 180)
			(unlocked yes)
			(layer "F.Fab")
			(hide yes)
			(effects
				(font
					(size 1.016 1.016)
					(thickness 0.1524)
				)
			)
		)
		(property "Device Type" "VIA-PCIE-4P-394076"
			(at -3.7211 -6.0325 180)
			(unlocked yes)
			(layer "F.Fab")
			(hide yes)
			(effects
				(font
					(size 1.016 1.016)
					(thickness 0.1524)
				)
			)
		)
		(duplicate_pad_numbers_are_jumpers no)
		(fp_rect
			(start -1.9685 0.381)
			(end 1.9685 -0.381)
			(stroke
				(width 0)
				(type default)
			)
			(fill no)
			(layer "F.CrtYd")
		)
		(fp_rect
			(start -1.9685 0.381)
			(end 1.9685 -0.381)
			(stroke
				(width 0)
				(type default)
			)
			(fill no)
			(layer "F.Fab")
		)
		(pad "1" thru_hole circle
			(at -1.5875 0 180)
			(size 0.508 0.508)
			(drill 0.254)
			(layers "*.Cu" "*.Mask")
			(remove_unused_layers no)
			(net "GND")
			(clearance 0.127)
			(thermal_gap 0.127)
		)
		(pad "2" thru_hole circle
			(at -0.5715 0 180)
			(size 0.508 0.508)
			(drill 0.254)
			(layers "*.Cu" "*.Mask")
			(remove_unused_layers no)
			(net "PHY_SCC_A_TO_DRV_A_1_DP")
			(clearance 0.127)
			(thermal_gap 0.127)
		)
		(pad "3" thru_hole circle
			(at 0.5715 0 180)
			(size 0.508 0.508)
			(drill 0.254)
			(layers "*.Cu" "*.Mask")
			(remove_unused_layers no)
			(net "PHY_SCC_A_TO_DRV_A_1_DN")
			(clearance 0.127)
			(thermal_gap 0.127)
		)
		(pad "4" thru_hole circle
			(at 1.5875 0 180)
			(size 0.508 0.508)
			(drill 0.254)
			(layers "*.Cu" "*.Mask")
			(remove_unused_layers no)
			(net "GND")
			(clearance 0.127)
			(thermal_gap 0.127)
		)
	)
	(footprint ""
		(layer "F.Cu")
		(at 364.798102 -157.585918 180)
		(property "Reference" "R575"
			(at 0 0 180)
			(layer "F.SilkS")
			(hide yes)
			(effects
				(font
					(size 1.27 1.27)
				)
			)
		)
		(property "Value" "1KR2F-3-GP"
			(at 0.064008 -3.993896 180)
			(unlocked yes)
			(layer "F.Fab")
			(hide yes)
			(effects
				(font
					(size 1.016 1.016)
					(thickness 0.1524)
				)
			)
		)
		(property "Device Type" "R402H16"
			(at 0.064008 -5.517896 180)
			(unlocked yes)
			(layer "F.Fab")
			(hide yes)
			(effects
				(font
					(size 1.016 1.016)
					(thickness 0.1524)
				)
			)
		)
		(duplicate_pad_numbers_are_jumpers no)
		(fp_line
			(start 0.508 -0.9398)
			(end -0.508 -0.9398)
			(stroke
				(width 0.1524)
				(type default)
			)
			(layer "F.SilkS")
		)
		(fp_line
			(start -0.508 -0.9398)
			(end -0.508 0.9398)
			(stroke
				(width 0.1524)
				(type default)
			)
			(layer "F.SilkS")
		)
		(fp_rect
			(start -0.508 0.9398)
			(end 0.508 -0.9398)
			(stroke
				(width 0)
				(type default)
			)
			(fill no)
			(layer "F.CrtYd")
		)
		(fp_rect
			(start -0.508 0.9398)
			(end 0.508 -0.9398)
			(stroke
				(width 0)
				(type default)
			)
			(fill no)
			(layer "F.Fab")
		)
		(pad "1" smd custom
			(at 0 -0.4445 180)
			(size 0.1397 0.1397)
			(layers "F.Cu" "F.Mask" "F.Paste")
			(net "P3V3_STBY_A")
			(options
				(clearance outline)
				(anchor circle)
			)
			(primitives
				(gr_poly
					(pts
						(arc
							(start -0.1778 -0.2794)
							(mid -0.249642 -0.249642)
							(end -0.2794 -0.1778)
						)
						(arc
							(start -0.2794 0.1778)
							(mid -0.249642 0.249642)
							(end -0.1778 0.2794)
						)
						(arc
							(start 0.1778 0.2794)
							(mid 0.249642 0.249642)
							(end 0.2794 0.1778)
						)
						(arc
							(start 0.2794 -0.1778)
							(mid 0.249642 -0.249642)
							(end 0.1778 -0.2794)
						)
					)
					(width 0)
					(fill yes)
				)
			)
		)
		(pad "2" smd custom
			(at 0 0.4445 180)
			(size 0.1397 0.1397)
			(layers "F.Cu" "F.Mask" "F.Paste")
			(net "SW_PWR_R_HDD19")
			(options
				(clearance outline)
				(anchor circle)
			)
			(primitives
				(gr_poly
					(pts
						(arc
							(start -0.1778 -0.2794)
							(mid -0.249642 -0.249642)
							(end -0.2794 -0.1778)
						)
						(arc
							(start -0.2794 0.1778)
							(mid -0.249642 0.249642)
							(end -0.1778 0.2794)
						)
						(arc
							(start 0.1778 0.2794)
							(mid 0.249642 0.249642)
							(end 0.2794 0.1778)
						)
						(arc
							(start 0.2794 -0.1778)
							(mid 0.249642 -0.249642)
							(end 0.1778 -0.2794)
						)
					)
					(width 0)
					(fill yes)
				)
			)
		)
	)
	(footprint ""
		(layer "F.Cu")
		(at 463.1309 -160.735518 180)
		(property "Reference" "R650"
			(at 0 0 180)
			(layer "F.SilkS")
			(hide yes)
			(effects
				(font
					(size 1.27 1.27)
				)
			)
		)
		(property "Value" "4K7R2J-2-GP"
			(at 0.064008 -3.993896 180)
			(unlocked yes)
			(layer "F.Fab")
			(hide yes)
			(effects
				(font
					(size 1.016 1.016)
					(thickness 0.1524)
				)
			)
		)
		(property "Device Type" "R402H16"
			(at 0.064008 -5.517896 180)
			(unlocked yes)
			(layer "F.Fab")
			(hide yes)
			(effects
				(font
					(size 1.016 1.016)
					(thickness 0.1524)
				)
			)
		)
		(duplicate_pad_numbers_are_jumpers no)
		(fp_line
			(start 0.508 -0.9398)
			(end -0.508 -0.9398)
			(stroke
				(width 0.1524)
				(type default)
			)
			(layer "F.SilkS")
		)
		(fp_line
			(start -0.508 -0.9398)
			(end -0.508 0.9398)
			(stroke
				(width 0.1524)
				(type default)
			)
			(layer "F.SilkS")
		)
		(fp_rect
			(start -0.508 0.9398)
			(end 0.508 -0.9398)
			(stroke
				(width 0)
				(type default)
			)
			(fill no)
			(layer "F.CrtYd")
		)
		(fp_rect
			(start -0.508 0.9398)
			(end 0.508 -0.9398)
			(stroke
				(width 0)
				(type default)
			)
			(fill no)
			(layer "F.Fab")
		)
		(pad "1" smd custom
			(at 0 -0.4445 180)
			(size 0.1397 0.1397)
			(layers "F.Cu" "F.Mask" "F.Paste")
			(net "P12V_A")
			(options
				(clearance outline)
				(anchor circle)
			)
			(primitives
				(gr_poly
					(pts
						(arc
							(start -0.1778 -0.2794)
							(mid -0.249642 -0.249642)
							(end -0.2794 -0.1778)
						)
						(arc
							(start -0.2794 0.1778)
							(mid -0.249642 0.249642)
							(end -0.1778 0.2794)
						)
						(arc
							(start 0.1778 0.2794)
							(mid 0.249642 0.249642)
							(end 0.2794 0.1778)
						)
						(arc
							(start 0.2794 -0.1778)
							(mid 0.249642 -0.249642)
							(end 0.1778 -0.2794)
						)
					)
					(width 0)
					(fill yes)
				)
			)
		)
		(pad "2" smd custom
			(at 0 0.4445 180)
			(size 0.1397 0.1397)
			(layers "F.Cu" "F.Mask" "F.Paste")
			(net "SW_HDD_R22")
			(options
				(clearance outline)
				(anchor circle)
			)
			(primitives
				(gr_poly
					(pts
						(arc
							(start -0.1778 -0.2794)
							(mid -0.249642 -0.249642)
							(end -0.2794 -0.1778)
						)
						(arc
							(start -0.2794 0.1778)
							(mid -0.249642 0.249642)
							(end -0.1778 0.2794)
						)
						(arc
							(start 0.1778 0.2794)
							(mid 0.249642 0.249642)
							(end 0.2794 0.1778)
						)
						(arc
							(start 0.2794 -0.1778)
							(mid 0.249642 -0.249642)
							(end 0.1778 -0.2794)
						)
					)
					(width 0)
					(fill yes)
				)
			)
		)
	)
	(footprint ""
		(layer "F.Cu")
		(at 22.970998 -46.014894 -90)
		(property "Reference" "R690"
			(at 0 0 270)
			(layer "F.SilkS")
			(hide yes)
			(effects
				(font
					(size 1.27 1.27)
				)
			)
		)
		(property "Value" "1KR2F-3-GP"
			(at 0.064008 -3.993896 270)
			(unlocked yes)
			(layer "F.Fab")
			(hide yes)
			(effects
				(font
					(size 1.016 1.016)
					(thickness 0.1524)
				)
			)
		)
		(property "Device Type" "R402H16"
			(at 0.064008 -5.517896 270)
			(unlocked yes)
			(layer "F.Fab")
			(hide yes)
			(effects
				(font
					(size 1.016 1.016)
					(thickness 0.1524)
				)
			)
		)
		(duplicate_pad_numbers_are_jumpers no)
		(fp_line
			(start -0.508 -0.9398)
			(end -0.508 0.9398)
			(stroke
				(width 0.1524)
				(type default)
			)
			(layer "F.SilkS")
		)
		(fp_line
			(start 0.508 -0.9398)
			(end -0.508 -0.9398)
			(stroke
				(width 0.1524)
				(type default)
			)
			(layer "F.SilkS")
		)
		(fp_rect
			(start -0.508 0.9398)
			(end 0.508 -0.9398)
			(stroke
				(width 0)
				(type default)
			)
			(fill no)
			(layer "F.CrtYd")
		)
		(fp_rect
			(start -0.508 0.9398)
			(end 0.508 -0.9398)
			(stroke
				(width 0)
				(type default)
			)
			(fill no)
			(layer "F.Fab")
		)
		(pad "1" smd custom
			(at 0 -0.4445 270)
			(size 0.1397 0.1397)
			(layers "F.Cu" "F.Mask" "F.Paste")
			(net "P3V3_STBY_A")
			(options
				(clearance outline)
				(anchor circle)
			)
			(primitives
				(gr_poly
					(pts
						(arc
							(start -0.1778 -0.2794)
							(mid -0.249642 -0.249642)
							(end -0.2794 -0.1778)
						)
						(arc
							(start -0.2794 0.1778)
							(mid -0.249642 0.249642)
							(end -0.1778 0.2794)
						)
						(arc
							(start 0.1778 0.2794)
							(mid 0.249642 0.249642)
							(end 0.2794 0.1778)
						)
						(arc
							(start 0.2794 -0.1778)
							(mid 0.249642 -0.249642)
							(end 0.1778 -0.2794)
						)
					)
					(width 0)
					(fill yes)
				)
			)
		)
		(pad "2" smd custom
			(at 0 0.4445 270)
			(size 0.1397 0.1397)
			(layers "F.Cu" "F.Mask" "F.Paste")
			(net "SW_PWR_R_HDD24")
			(options
				(clearance outline)
				(anchor circle)
			)
			(primitives
				(gr_poly
					(pts
						(arc
							(start -0.1778 -0.2794)
							(mid -0.249642 -0.249642)
							(end -0.2794 -0.1778)
						)
						(arc
							(start -0.2794 0.1778)
							(mid -0.249642 0.249642)
							(end -0.1778 0.2794)
						)
						(arc
							(start 0.1778 0.2794)
							(mid 0.249642 0.249642)
							(end 0.2794 0.1778)
						)
						(arc
							(start 0.2794 -0.1778)
							(mid 0.249642 -0.249642)
							(end 0.1778 -0.2794)
						)
					)
					(width 0)
					(fill yes)
				)
			)
		)
	)
	(footprint ""
		(layer "F.Cu")
		(at 150.136098 -71.287894)
		(property "Reference" "C409"
			(at 0 0 0)
			(layer "F.SilkS")
			(hide yes)
			(effects
				(font
					(size 1.27 1.27)
				)
			)
		)
		(property "Value" "SC4D7U25V5KX-1-GP"
			(at -0.0762 -6.1214 0)
			(unlocked yes)
			(layer "F.Fab")
			(hide yes)
			(effects
				(font
					(size 1.016 1.016)
					(thickness 0.1524)
				)
			)
		)
		(property "Device Type" "C805H58"
			(at -0.0762 -8.1534 0)
			(unlocked yes)
			(layer "F.Fab")
			(hide yes)
			(effects
				(font
					(size 1.016 1.016)
					(thickness 0.1524)
				)
			)
		)
		(duplicate_pad_numbers_are_jumpers no)
		(fp_line
			(start 0.635 0)
			(end -0.635 0)
			(stroke
				(width 0.508)
				(type default)
			)
			(layer "F.SilkS")
		)
		(fp_rect
			(start -0.9652 1.778)
			(end 0.9652 -1.778)
			(stroke
				(width 0)
				(type default)
			)
			(fill no)
			(layer "F.CrtYd")
		)
		(fp_poly
			(pts
				(xy -0.9652 -1.778) (xy 0.9652 -1.778) (xy 0.9652 1.778) (xy -0.9652 1.778)
			)
			(stroke
				(width 0)
				(type default)
			)
			(fill no)
			(layer "F.Fab")
		)
		(pad "1" smd rect
			(at 0 -0.9652)
			(size 1.397 1.143)
			(layers "F.Cu" "F.Mask" "F.Paste")
			(net "P12V_HDD28")
		)
		(pad "2" smd rect
			(at 0 0.9652)
			(size 1.397 1.143)
			(layers "F.Cu" "F.Mask" "F.Paste")
			(net "GND")
		)
	)
	(footprint ""
		(layer "F.Cu")
		(at 276.225 -278.384)
		(property "Reference" "U11"
			(at 0 0 0)
			(layer "F.SilkS")
			(hide yes)
			(effects
				(font
					(size 1.27 1.27)
				)
			)
		)
		(property "Value" "TCA9555PWR-GP"
			(at 0 -6.9342 0)
			(unlocked yes)
			(layer "F.Fab")
			(hide yes)
			(effects
				(font
					(size 1.016 1.016)
					(thickness 0.1524)
				)
			)
		)
		(property "Device Type" "TSOIC24H48"
			(at 0 -8.5852 0)
			(unlocked yes)
			(layer "F.Fab")
			(hide yes)
			(effects
				(font
					(size 1.016 1.016)
					(thickness 0.1524)
				)
			)
		)
		(duplicate_pad_numbers_are_jumpers no)
		(fp_line
			(start -4.2291 -1.397)
			(end 3.81 -1.397)
			(stroke
				(width 0.1524)
				(type default)
			)
			(layer "F.SilkS")
		)
		(fp_line
			(start -4.2291 -0.8001)
			(end -3.429 0)
			(stroke
				(width 0.1524)
				(type default)
			)
			(layer "F.SilkS")
		)
		(fp_line
			(start -4.2291 3.937)
			(end -4.2291 -1.397)
			(stroke
				(width 0.1524)
				(type default)
			)
			(layer "F.SilkS")
		)
		(fp_line
			(start -4.22656 3.81)
			(end -4.2291 1.397)
			(stroke
				(width 0.508)
				(type default)
			)
			(layer "F.SilkS")
		)
		(fp_line
			(start -3.429 0)
			(end -4.2291 0.8001)
			(stroke
				(width 0.1524)
				(type default)
			)
			(layer "F.SilkS")
		)
		(fp_line
			(start 3.81 -1.397)
			(end 3.81 1.397)
			(stroke
				(width 0.1524)
				(type default)
			)
			(layer "F.SilkS")
		)
		(fp_line
			(start 3.81 1.397)
			(end -4.2291 1.397)
			(stroke
				(width 0.1524)
				(type default)
			)
			(layer "F.SilkS")
		)
		(fp_poly
			(pts
				(xy -3.90652 -1.8542) (xy 3.90652 -1.8542) (xy 3.90652 1.8542) (xy -3.90652 1.8542)
			)
			(stroke
				(width 0)
				(type default)
			)
			(fill yes)
			(layer "F.SilkS")
		)
		(fp_poly
			(pts
				(xy -4.2164 3.81) (xy 4.2164 3.81) (xy 4.22656 -3.81) (xy -4.2164 -3.81)
			)
			(stroke
				(width 0)
				(type default)
			)
			(fill no)
			(layer "F.CrtYd")
		)
		(fp_poly
			(pts
				(xy -4.22656 -3.81) (xy 4.22656 -3.81) (xy 4.22656 3.81) (xy -4.22656 3.81)
			)
			(stroke
				(width 0)
				(type default)
			)
			(fill no)
			(layer "F.Fab")
		)
		(pad "1" smd rect
			(at -3.57632 2.8194)
			(size 0.3556 1.524)
			(layers "F.Cu" "F.Mask" "F.Paste")
			(net "IO_EXP1_HDD_FAULT_INT_N")
		)
		(pad "2" smd rect
			(at -2.92608 2.8194)
			(size 0.3556 1.524)
			(layers "F.Cu" "F.Mask" "F.Paste")
			(net "IO_EXP1_HDD_FAULT_A1")
		)
		(pad "3" smd rect
			(at -2.27584 2.8194)
			(size 0.3556 1.524)
			(layers "F.Cu" "F.Mask" "F.Paste")
			(net "IO_EXP1_HDD_FAULT_A2")
		)
		(pad "4" smd rect
			(at -1.6256 2.8194)
			(size 0.3556 1.524)
			(layers "F.Cu" "F.Mask" "F.Paste")
			(net "DRIVE_A_16_FLT_LED")
		)
		(pad "5" smd rect
			(at -0.97536 2.8194)
			(size 0.3556 1.524)
			(layers "F.Cu" "F.Mask" "F.Paste")
			(net "DRIVE_A_17_FLT_LED")
		)
		(pad "6" smd rect
			(at -0.32512 2.8194)
			(size 0.3556 1.524)
			(layers "F.Cu" "F.Mask" "F.Paste")
			(net "DRIVE_A_18_FLT_LED")
		)
		(pad "7" smd rect
			(at 0.32512 2.8194)
			(size 0.3556 1.524)
			(layers "F.Cu" "F.Mask" "F.Paste")
			(net "DRIVE_A_19_FLT_LED")
		)
		(pad "8" smd rect
			(at 0.97536 2.8194)
			(size 0.3556 1.524)
			(layers "F.Cu" "F.Mask" "F.Paste")
			(net "DRIVE_A_20_FLT_LED")
		)
		(pad "9" smd rect
			(at 1.6256 2.8194)
			(size 0.3556 1.524)
			(layers "F.Cu" "F.Mask" "F.Paste")
			(net "DRIVE_A_21_FLT_LED")
		)
		(pad "10" smd rect
			(at 2.27584 2.8194)
			(size 0.3556 1.524)
			(layers "F.Cu" "F.Mask" "F.Paste")
			(net "DRIVE_A_22_FLT_LED")
		)
		(pad "11" smd rect
			(at 2.92608 2.8194)
			(size 0.3556 1.524)
			(layers "F.Cu" "F.Mask" "F.Paste")
			(net "DRIVE_A_23_FLT_LED")
		)
		(pad "12" smd rect
			(at 3.57632 2.8194)
			(size 0.3556 1.524)
			(layers "F.Cu" "F.Mask" "F.Paste")
			(net "GND")
		)
		(pad "13" smd rect
			(at 3.57632 -2.8194)
			(size 0.3556 1.524)
			(layers "F.Cu" "F.Mask" "F.Paste")
			(net "FRONT_FAN_LED0")
		)
		(pad "14" smd rect
			(at 2.92608 -2.8194)
			(size 0.3556 1.524)
			(layers "F.Cu" "F.Mask" "F.Paste")
			(net "FRONT_FAN_LED1")
		)
		(pad "15" smd rect
			(at 2.27584 -2.8194)
			(size 0.3556 1.524)
			(layers "F.Cu" "F.Mask" "F.Paste")
			(net "FRONT_FAN_LED2")
		)
		(pad "16" smd rect
			(at 1.6256 -2.8194)
			(size 0.3556 1.524)
			(layers "F.Cu" "F.Mask" "F.Paste")
			(net "FRONT_FAN_LED3")
		)
		(pad "17" smd rect
			(at 0.97536 -2.8194)
			(size 0.3556 1.524)
			(layers "F.Cu" "F.Mask" "F.Paste")
			(net "Net_241")
		)
		(pad "18" smd rect
			(at 0.32512 -2.8194)
			(size 0.3556 1.524)
			(layers "F.Cu" "F.Mask" "F.Paste")
			(net "Net_242")
		)
		(pad "19" smd rect
			(at -0.32512 -2.8194)
			(size 0.3556 1.524)
			(layers "F.Cu" "F.Mask" "F.Paste")
			(net "Net_243")
		)
		(pad "20" smd rect
			(at -0.97536 -2.8194)
			(size 0.3556 1.524)
			(layers "F.Cu" "F.Mask" "F.Paste")
			(net "Net_244")
		)
		(pad "21" smd rect
			(at -1.6256 -2.8194)
			(size 0.3556 1.524)
			(layers "F.Cu" "F.Mask" "F.Paste")
			(net "IO_EXP1_HDD_FAULT_A0")
		)
		(pad "22" smd rect
			(at -2.27584 -2.8194)
			(size 0.3556 1.524)
			(layers "F.Cu" "F.Mask" "F.Paste")
			(net "IO_EXP1_LED_SCL")
		)
		(pad "23" smd rect
			(at -2.92608 -2.8194)
			(size 0.3556 1.524)
			(layers "F.Cu" "F.Mask" "F.Paste")
			(net "IO_EXP1_LED_SDA")
		)
		(pad "24" smd rect
			(at -3.57632 -2.8194)
			(size 0.3556 1.524)
			(layers "F.Cu" "F.Mask" "F.Paste")
			(net "P3V3_STBY_A")
		)
	)
	(footprint ""
		(layer "F.Cu")
		(at 83.530948 -62.778894 -90)
		(property "Reference" "C378"
			(at 0 0 270)
			(layer "F.SilkS")
			(hide yes)
			(effects
				(font
					(size 1.27 1.27)
				)
			)
		)
		(property "Value" "SC1U16V3KX-5GP"
			(at 0 -2.8194 270)
			(unlocked yes)
			(layer "F.Fab")
			(hide yes)
			(effects
				(font
					(size 1.016 1.016)
					(thickness 0.1524)
				)
			)
		)
		(property "Device Type" "C603H36"
			(at 0 -4.3434 270)
			(unlocked yes)
			(layer "F.Fab")
			(hide yes)
			(effects
				(font
					(size 1.016 1.016)
					(thickness 0.1524)
				)
			)
		)
		(duplicate_pad_numbers_are_jumpers no)
		(fp_line
			(start 0.508 0)
			(end -0.508 0)
			(stroke
				(width 0.2032)
				(type default)
			)
			(layer "F.SilkS")
		)
		(fp_rect
			(start -0.5842 1.3335)
			(end 0.5842 -1.3335)
			(stroke
				(width 0)
				(type default)
			)
			(fill no)
			(layer "F.CrtYd")
		)
		(fp_rect
			(start -0.5842 1.3335)
			(end 0.5842 -1.3335)
			(stroke
				(width 0)
				(type default)
			)
			(fill no)
			(layer "F.Fab")
		)
		(pad "1" smd custom
			(at 0 -0.762 270)
			(size 0.2159 0.2159)
			(layers "F.Cu" "F.Mask" "F.Paste")
			(net "P5V_HDD26")
			(options
				(clearance outline)
				(anchor circle)
			)
			(primitives
				(gr_poly
					(pts
						(arc
							(start -0.3302 -0.4318)
							(mid -0.402042 -0.402042)
							(end -0.4318 -0.3302)
						)
						(arc
							(start -0.4318 0.3302)
							(mid -0.402042 0.402042)
							(end -0.3302 0.4318)
						)
						(arc
							(start 0.3302 0.4318)
							(mid 0.402042 0.402042)
							(end 0.4318 0.3302)
						)
						(arc
							(start 0.4318 -0.3302)
							(mid 0.402042 -0.402042)
							(end 0.3302 -0.4318)
						)
					)
					(width 0)
					(fill yes)
				)
			)
		)
		(pad "2" smd custom
			(at 0 0.762 270)
			(size 0.2159 0.2159)
			(layers "F.Cu" "F.Mask" "F.Paste")
			(net "GND")
			(options
				(clearance outline)
				(anchor circle)
			)
			(primitives
				(gr_poly
					(pts
						(arc
							(start -0.3302 -0.4318)
							(mid -0.402042 -0.402042)
							(end -0.4318 -0.3302)
						)
						(arc
							(start -0.4318 0.3302)
							(mid -0.402042 0.402042)
							(end -0.3302 0.4318)
						)
						(arc
							(start 0.3302 0.4318)
							(mid 0.402042 0.402042)
							(end 0.4318 0.3302)
						)
						(arc
							(start 0.4318 -0.3302)
							(mid 0.402042 -0.402042)
							(end 0.3302 -0.4318)
						)
					)
					(width 0)
					(fill yes)
				)
			)
		)
	)
	(footprint ""
		(layer "F.Cu")
		(at 181.991 -189.462918 180)
		(property "Reference" "C268"
			(at 0 0 180)
			(layer "F.SilkS")
			(hide yes)
			(effects
				(font
					(size 1.27 1.27)
				)
			)
		)
		(property "Value" "SC1U25V3KX-GP"
			(at 0 -2.8194 180)
			(unlocked yes)
			(layer "F.Fab")
			(hide yes)
			(effects
				(font
					(size 1.016 1.016)
					(thickness 0.1524)
				)
			)
		)
		(property "Device Type" "C603H36"
			(at 0 -4.3434 180)
			(unlocked yes)
			(layer "F.Fab")
			(hide yes)
			(effects
				(font
					(size 1.016 1.016)
					(thickness 0.1524)
				)
			)
		)
		(duplicate_pad_numbers_are_jumpers no)
		(fp_line
			(start 0.508 0)
			(end -0.508 0)
			(stroke
				(width 0.2032)
				(type default)
			)
			(layer "F.SilkS")
		)
		(fp_rect
			(start -0.5842 1.3335)
			(end 0.5842 -1.3335)
			(stroke
				(width 0)
				(type default)
			)
			(fill no)
			(layer "F.CrtYd")
		)
		(fp_rect
			(start -0.5842 1.3335)
			(end 0.5842 -1.3335)
			(stroke
				(width 0)
				(type default)
			)
			(fill no)
			(layer "F.Fab")
		)
		(pad "1" smd custom
			(at 0 -0.762 180)
			(size 0.2159 0.2159)
			(layers "F.Cu" "F.Mask" "F.Paste")
			(net "P12V_HDD17")
			(options
				(clearance outline)
				(anchor circle)
			)
			(primitives
				(gr_poly
					(pts
						(arc
							(start -0.3302 -0.4318)
							(mid -0.402042 -0.402042)
							(end -0.4318 -0.3302)
						)
						(arc
							(start -0.4318 0.3302)
							(mid -0.402042 0.402042)
							(end -0.3302 0.4318)
						)
						(arc
							(start 0.3302 0.4318)
							(mid 0.402042 0.402042)
							(end 0.4318 0.3302)
						)
						(arc
							(start 0.4318 -0.3302)
							(mid 0.402042 -0.402042)
							(end 0.3302 -0.4318)
						)
					)
					(width 0)
					(fill yes)
				)
			)
		)
		(pad "2" smd custom
			(at 0 0.762 180)
			(size 0.2159 0.2159)
			(layers "F.Cu" "F.Mask" "F.Paste")
			(net "GND")
			(options
				(clearance outline)
				(anchor circle)
			)
			(primitives
				(gr_poly
					(pts
						(arc
							(start -0.3302 -0.4318)
							(mid -0.402042 -0.402042)
							(end -0.4318 -0.3302)
						)
						(arc
							(start -0.4318 0.3302)
							(mid -0.402042 0.402042)
							(end -0.3302 0.4318)
						)
						(arc
							(start 0.3302 0.4318)
							(mid 0.402042 0.402042)
							(end 0.4318 0.3302)
						)
						(arc
							(start 0.4318 -0.3302)
							(mid 0.402042 -0.402042)
							(end 0.3302 -0.4318)
						)
					)
					(width 0)
					(fill yes)
				)
			)
		)
	)
	(footprint ""
		(layer "F.Cu")
		(at 83.149948 -176.000918 -90)
		(property "Reference" "C223"
			(at 0 0 270)
			(layer "F.SilkS")
			(hide yes)
			(effects
				(font
					(size 1.27 1.27)
				)
			)
		)
		(property "Value" "SC10U16V6KX-2GP"
			(at -0.0762 -5.1308 270)
			(unlocked yes)
			(layer "F.Fab")
			(hide yes)
			(effects
				(font
					(size 1.016 1.016)
					(thickness 0.1524)
				)
			)
		)
		(property "Device Type" "C1206H71"
			(at -0.127 -6.6548 270)
			(unlocked yes)
			(layer "F.Fab")
			(hide yes)
			(effects
				(font
					(size 1.016 1.016)
					(thickness 0.1524)
				)
			)
		)
		(duplicate_pad_numbers_are_jumpers no)
		(fp_line
			(start -1.016 2.2352)
			(end -1.016 0.8382)
			(stroke
				(width 0.1524)
				(type default)
			)
			(layer "F.SilkS")
		)
		(fp_line
			(start 1.016 2.2352)
			(end -1.016 2.2352)
			(stroke
				(width 0.1524)
				(type default)
			)
			(layer "F.SilkS")
		)
		(fp_line
			(start 1.016 0.8382)
			(end 1.016 2.2352)
			(stroke
				(width 0.1524)
				(type default)
			)
			(layer "F.SilkS")
		)
		(fp_line
			(start -1.016 -0.8382)
			(end -1.016 -2.2352)
			(stroke
				(width 0.1524)
				(type default)
			)
			(layer "F.SilkS")
		)
		(fp_line
			(start -1.016 -2.2352)
			(end 1.016 -2.2352)
			(stroke
				(width 0.1524)
				(type default)
			)
			(layer "F.SilkS")
		)
		(fp_line
			(start 1.016 -2.2352)
			(end 1.016 -0.8382)
			(stroke
				(width 0.1524)
				(type default)
			)
			(layer "F.SilkS")
		)
		(fp_rect
			(start -1.0922 2.3114)
			(end 1.0922 -2.3114)
			(stroke
				(width 0)
				(type default)
			)
			(fill no)
			(layer "F.CrtYd")
		)
		(fp_poly
			(pts
				(xy 1.0922 -2.3114) (xy 1.0922 2.3114) (xy -1.0922 2.3114) (xy -1.0922 -2.3114)
			)
			(stroke
				(width 0)
				(type default)
			)
			(fill no)
			(layer "F.Fab")
		)
		(pad "1" smd rect
			(at 0 -1.397 270)
			(size 1.651 1.27)
			(layers "F.Cu" "F.Mask" "F.Paste")
			(net "P5V_HDD14")
		)
		(pad "2" smd rect
			(at 0 1.397 270)
			(size 1.651 1.27)
			(layers "F.Cu" "F.Mask" "F.Paste")
			(net "GND")
		)
	)
	(footprint ""
		(layer "F.Cu")
		(at 218.059 -384.81 180)
		(property "Reference" "Q21"
			(at 0 0 180)
			(layer "F.SilkS")
			(hide yes)
			(effects
				(font
					(size 1.27 1.27)
				)
			)
		)
		(property "Value" "2N7002K-1-GP"
			(at 0.127 -8.9662 180)
			(unlocked yes)
			(layer "F.Fab")
			(hide yes)
			(effects
				(font
					(size 1.016 1.016)
					(thickness 0.1524)
				)
			)
		)
		(property "Device Type" "SOT23DGS2D4H44"
			(at 0.127 -10.4902 180)
			(unlocked yes)
			(layer "F.Fab")
			(hide yes)
			(effects
				(font
					(size 1.016 1.016)
					(thickness 0.1524)
				)
			)
		)
		(duplicate_pad_numbers_are_jumpers no)
		(fp_line
			(start 1.651 1.778)
			(end 1.651 -1.778)
			(stroke
				(width 0.1524)
				(type default)
			)
			(layer "F.SilkS")
		)
		(fp_line
			(start 1.651 -1.778)
			(end -1.651 -1.778)
			(stroke
				(width 0.1524)
				(type default)
			)
			(layer "F.SilkS")
		)
		(fp_line
			(start -1.651 1.778)
			(end 1.651 1.778)
			(stroke
				(width 0.1524)
				(type default)
			)
			(layer "F.SilkS")
		)
		(fp_line
			(start -1.651 -1.778)
			(end -1.651 1.778)
			(stroke
				(width 0.1524)
				(type default)
			)
			(layer "F.SilkS")
		)
		(fp_poly
			(pts
				(xy -1.778 1.8796) (xy -1.778 -1.8796) (xy 1.778 -1.8796) (xy 1.778 1.8796)
			)
			(stroke
				(width 0)
				(type default)
			)
			(fill no)
			(layer "F.CrtYd")
		)
		(fp_poly
			(pts
				(xy -1.778 1.8796) (xy -1.778 -1.8796) (xy 1.778 -1.8796) (xy 1.778 1.8796)
			)
			(stroke
				(width 0)
				(type default)
			)
			(fill no)
			(layer "F.Fab")
		)
		(pad "D" smd custom
			(at 0 -0.9525 180)
			(size 0.1905 0.1905)
			(layers "F.Cu" "F.Mask" "F.Paste")
			(net "SCC_FULL_PWR_EN_5V_R")
			(options
				(clearance outline)
				(anchor circle)
			)
			(primitives
				(gr_poly
					(pts
						(arc
							(start -0.1778 0.5715)
							(mid -0.321484 0.511984)
							(end -0.381 0.3683)
						)
						(arc
							(start -0.381 -0.3683)
							(mid -0.321484 -0.511984)
							(end -0.1778 -0.5715)
						)
						(arc
							(start 0.1778 -0.5715)
							(mid 0.321484 -0.511984)
							(end 0.381 -0.3683)
						)
						(arc
							(start 0.381 0.3683)
							(mid 0.321484 0.511984)
							(end 0.1778 0.5715)
						)
					)
					(width 0)
					(fill yes)
				)
			)
		)
		(pad "G" smd custom
			(at -0.98425 0.9525 180)
			(size 0.1905 0.1905)
			(layers "F.Cu" "F.Mask" "F.Paste")
			(net "SCC_A_FULL_PWR_EN_12V")
			(options
				(clearance outline)
				(anchor circle)
			)
			(primitives
				(gr_poly
					(pts
						(arc
							(start -0.1778 0.5715)
							(mid -0.321484 0.511984)
							(end -0.381 0.3683)
						)
						(arc
							(start -0.381 -0.3683)
							(mid -0.321484 -0.511984)
							(end -0.1778 -0.5715)
						)
						(arc
							(start 0.1778 -0.5715)
							(mid 0.321484 -0.511984)
							(end 0.381 -0.3683)
						)
						(arc
							(start 0.381 0.3683)
							(mid 0.321484 0.511984)
							(end 0.1778 0.5715)
						)
					)
					(width 0)
					(fill yes)
				)
			)
		)
		(pad "S" smd custom
			(at 0.98425 0.9525 180)
			(size 0.1905 0.1905)
			(layers "F.Cu" "F.Mask" "F.Paste")
			(net "GND")
			(options
				(clearance outline)
				(anchor circle)
			)
			(primitives
				(gr_poly
					(pts
						(arc
							(start -0.1778 0.5715)
							(mid -0.321484 0.511984)
							(end -0.381 0.3683)
						)
						(arc
							(start -0.381 -0.3683)
							(mid -0.321484 -0.511984)
							(end -0.1778 -0.5715)
						)
						(arc
							(start 0.1778 -0.5715)
							(mid 0.321484 -0.511984)
							(end 0.381 -0.3683)
						)
						(arc
							(start 0.381 0.3683)
							(mid 0.321484 0.511984)
							(end 0.1778 0.5715)
						)
					)
					(width 0)
					(fill yes)
				)
			)
		)
	)
	(footprint ""
		(layer "F.Cu")
		(at 364.798102 -42.585894 180)
		(property "Reference" "R851"
			(at 0 0 180)
			(layer "F.SilkS")
			(hide yes)
			(effects
				(font
					(size 1.27 1.27)
				)
			)
		)
		(property "Value" "1KR2F-3-GP"
			(at 0.064008 -3.993896 180)
			(unlocked yes)
			(layer "F.Fab")
			(hide yes)
			(effects
				(font
					(size 1.016 1.016)
					(thickness 0.1524)
				)
			)
		)
		(property "Device Type" "R402H16"
			(at 0.064008 -5.517896 180)
			(unlocked yes)
			(layer "F.Fab")
			(hide yes)
			(effects
				(font
					(size 1.016 1.016)
					(thickness 0.1524)
				)
			)
		)
		(duplicate_pad_numbers_are_jumpers no)
		(fp_line
			(start 0.508 -0.9398)
			(end -0.508 -0.9398)
			(stroke
				(width 0.1524)
				(type default)
			)
			(layer "F.SilkS")
		)
		(fp_line
			(start -0.508 -0.9398)
			(end -0.508 0.9398)
			(stroke
				(width 0.1524)
				(type default)
			)
			(layer "F.SilkS")
		)
		(fp_rect
			(start -0.508 0.9398)
			(end 0.508 -0.9398)
			(stroke
				(width 0)
				(type default)
			)
			(fill no)
			(layer "F.CrtYd")
		)
		(fp_rect
			(start -0.508 0.9398)
			(end 0.508 -0.9398)
			(stroke
				(width 0)
				(type default)
			)
			(fill no)
			(layer "F.Fab")
		)
		(pad "1" smd custom
			(at 0 -0.4445 180)
			(size 0.1397 0.1397)
			(layers "F.Cu" "F.Mask" "F.Paste")
			(net "P3V3_STBY_A")
			(options
				(clearance outline)
				(anchor circle)
			)
			(primitives
				(gr_poly
					(pts
						(arc
							(start -0.1778 -0.2794)
							(mid -0.249642 -0.249642)
							(end -0.2794 -0.1778)
						)
						(arc
							(start -0.2794 0.1778)
							(mid -0.249642 0.249642)
							(end -0.1778 0.2794)
						)
						(arc
							(start 0.1778 0.2794)
							(mid 0.249642 0.249642)
							(end 0.2794 0.1778)
						)
						(arc
							(start 0.2794 -0.1778)
							(mid 0.249642 -0.249642)
							(end 0.1778 -0.2794)
						)
					)
					(width 0)
					(fill yes)
				)
			)
		)
		(pad "2" smd custom
			(at 0 0.4445 180)
			(size 0.1397 0.1397)
			(layers "F.Cu" "F.Mask" "F.Paste")
			(net "SW_PWR_R_HDD31")
			(options
				(clearance outline)
				(anchor circle)
			)
			(primitives
				(gr_poly
					(pts
						(arc
							(start -0.1778 -0.2794)
							(mid -0.249642 -0.249642)
							(end -0.2794 -0.1778)
						)
						(arc
							(start -0.2794 0.1778)
							(mid -0.249642 0.249642)
							(end -0.1778 0.2794)
						)
						(arc
							(start 0.1778 0.2794)
							(mid 0.249642 0.249642)
							(end 0.2794 0.1778)
						)
						(arc
							(start 0.2794 -0.1778)
							(mid 0.249642 -0.249642)
							(end 0.1778 -0.2794)
						)
					)
					(width 0)
					(fill yes)
				)
			)
		)
	)
	(footprint ""
		(layer "F.Cu")
		(at 146.884898 -170.285918 180)
		(property "Reference" "Q96"
			(at 0 0 180)
			(layer "F.SilkS")
			(hide yes)
			(effects
				(font
					(size 1.27 1.27)
				)
			)
		)
		(property "Value" "AO4406AL-GP"
			(at -3.707384 -1.5367 180)
			(unlocked yes)
			(layer "F.Fab")
			(hide yes)
			(effects
				(font
					(size 1.016 1.016)
					(thickness 0.1524)
				)
			)
		)
		(property "Device Type" "SOIC8H69"
			(at -3.707384 -3.0607 180)
			(unlocked yes)
			(layer "F.Fab")
			(hide yes)
			(effects
				(font
					(size 1.016 1.016)
					(thickness 0.1524)
				)
			)
		)
		(duplicate_pad_numbers_are_jumpers no)
		(fp_line
			(start 2.1336 1.4224)
			(end 2.1336 -1.4224)
			(stroke
				(width 0.1524)
				(type default)
			)
			(layer "F.SilkS")
		)
		(fp_line
			(start 2.1336 -1.4224)
			(end -2.7432 -1.4224)
			(stroke
				(width 0.1524)
				(type default)
			)
			(layer "F.SilkS")
		)
		(fp_line
			(start -2.1844 -0.0508)
			(end -2.7178 0.508)
			(stroke
				(width 0.1524)
				(type default)
			)
			(layer "F.SilkS")
		)
		(fp_line
			(start -2.6289 3.4417)
			(end -2.6289 1.4732)
			(stroke
				(width 0.381)
				(type default)
			)
			(layer "F.SilkS")
		)
		(fp_line
			(start -2.7178 -0.508)
			(end -2.1844 -0.0508)
			(stroke
				(width 0.1524)
				(type default)
			)
			(layer "F.SilkS")
		)
		(fp_line
			(start -2.7432 1.4224)
			(end 2.1336 1.4224)
			(stroke
				(width 0.1524)
				(type default)
			)
			(layer "F.SilkS")
		)
		(fp_line
			(start -2.7432 1.4224)
			(end -2.6416 1.4224)
			(stroke
				(width 0.1524)
				(type default)
			)
			(layer "F.SilkS")
		)
		(fp_line
			(start -2.7432 -1.4224)
			(end -2.7432 1.4224)
			(stroke
				(width 0.1524)
				(type default)
			)
			(layer "F.SilkS")
		)
		(fp_poly
			(pts
				(xy -2.2098 -1.4224) (xy -2.2098 1.4224) (xy 2.2098 1.4224) (xy 2.2098 -1.4224)
			)
			(stroke
				(width 0)
				(type default)
			)
			(fill yes)
			(layer "F.SilkS")
		)
		(fp_rect
			(start -2.450084 2.999994)
			(end 2.450084 -2.999994)
			(stroke
				(width 0)
				(type default)
			)
			(fill no)
			(layer "F.CrtYd")
		)
		(fp_poly
			(pts
				(xy -2.8194 3.6322) (xy -2.8194 -3.6322) (xy 2.8194 -3.6322) (xy 2.8194 1.18364) (xy 2.450084 1.18364)
				(xy 2.450084 -2.999994) (xy -2.450084 -2.999994) (xy -2.450084 2.999994) (xy 2.450084 2.999994)
				(xy 2.450084 1.18618) (xy 2.8194 1.18618) (xy 2.8194 3.6322)
			)
			(stroke
				(width 0)
				(type default)
			)
			(fill no)
			(layer "F.CrtYd")
		)
		(fp_rect
			(start -2.8194 3.6322)
			(end 2.8194 -3.6322)
			(stroke
				(width 0)
				(type default)
			)
			(fill no)
			(layer "F.Fab")
		)
		(pad "1" smd rect
			(at -1.905 2.54 180)
			(size 0.635 1.651)
			(layers "F.Cu" "F.Mask" "F.Paste")
			(net "P5V_HDD16")
		)
		(pad "2" smd rect
			(at -0.635 2.54 180)
			(size 0.635 1.651)
			(layers "F.Cu" "F.Mask" "F.Paste")
			(net "P5V_HDD16")
		)
		(pad "3" smd rect
			(at 0.635 2.54 180)
			(size 0.635 1.651)
			(layers "F.Cu" "F.Mask" "F.Paste")
			(net "P5V_HDD16")
		)
		(pad "4" smd rect
			(at 1.905 2.54 180)
			(size 0.635 1.651)
			(layers "F.Cu" "F.Mask" "F.Paste")
			(net "SW_HDD_P16")
		)
		(pad "5" smd rect
			(at 1.905 -2.54 180)
			(size 0.635 1.651)
			(layers "F.Cu" "F.Mask" "F.Paste")
			(net "P5V_A_2")
		)
		(pad "6" smd rect
			(at 0.635 -2.54 180)
			(size 0.635 1.651)
			(layers "F.Cu" "F.Mask" "F.Paste")
			(net "P5V_A_2")
		)
		(pad "7" smd rect
			(at -0.635 -2.54 180)
			(size 0.635 1.651)
			(layers "F.Cu" "F.Mask" "F.Paste")
			(net "P5V_A_2")
		)
		(pad "8" smd rect
			(at -1.905 -2.54 180)
			(size 0.635 1.651)
			(layers "F.Cu" "F.Mask" "F.Paste")
			(net "P5V_A_2")
		)
	)
	(footprint ""
		(layer "F.Cu")
		(at 317.60414 -59.616086 180)
		(property "Reference" "R393"
			(at 0 0 180)
			(layer "F.SilkS")
			(hide yes)
			(effects
				(font
					(size 1.27 1.27)
				)
			)
		)
		(property "Value" "10KR2F-2-GP"
			(at 0.064008 -3.993896 180)
			(unlocked yes)
			(layer "F.Fab")
			(hide yes)
			(effects
				(font
					(size 1.016 1.016)
					(thickness 0.1524)
				)
			)
		)
		(property "Device Type" "R402H16"
			(at 0.064008 -5.517896 180)
			(unlocked yes)
			(layer "F.Fab")
			(hide yes)
			(effects
				(font
					(size 1.016 1.016)
					(thickness 0.1524)
				)
			)
		)
		(duplicate_pad_numbers_are_jumpers no)
		(fp_line
			(start 0.508 -0.9398)
			(end -0.508 -0.9398)
			(stroke
				(width 0.1524)
				(type default)
			)
			(layer "F.SilkS")
		)
		(fp_line
			(start -0.508 -0.9398)
			(end -0.508 0.9398)
			(stroke
				(width 0.1524)
				(type default)
			)
			(layer "F.SilkS")
		)
		(fp_rect
			(start -0.508 0.9398)
			(end 0.508 -0.9398)
			(stroke
				(width 0)
				(type default)
			)
			(fill no)
			(layer "F.CrtYd")
		)
		(fp_rect
			(start -0.508 0.9398)
			(end 0.508 -0.9398)
			(stroke
				(width 0)
				(type default)
			)
			(fill no)
			(layer "F.Fab")
		)
		(pad "1" smd custom
			(at 0 -0.4445 180)
			(size 0.1397 0.1397)
			(layers "F.Cu" "F.Mask" "F.Paste")
			(net "SYS_B_RESET_N")
			(options
				(clearance outline)
				(anchor circle)
			)
			(primitives
				(gr_poly
					(pts
						(arc
							(start -0.1778 -0.2794)
							(mid -0.249642 -0.249642)
							(end -0.2794 -0.1778)
						)
						(arc
							(start -0.2794 0.1778)
							(mid -0.249642 0.249642)
							(end -0.1778 0.2794)
						)
						(arc
							(start 0.1778 0.2794)
							(mid 0.249642 0.249642)
							(end 0.2794 0.1778)
						)
						(arc
							(start 0.2794 -0.1778)
							(mid 0.249642 -0.249642)
							(end 0.1778 -0.2794)
						)
					)
					(width 0)
					(fill yes)
				)
			)
		)
		(pad "2" smd custom
			(at 0 0.4445 180)
			(size 0.1397 0.1397)
			(layers "F.Cu" "F.Mask" "F.Paste")
			(net "GND")
			(options
				(clearance outline)
				(anchor circle)
			)
			(primitives
				(gr_poly
					(pts
						(arc
							(start -0.1778 -0.2794)
							(mid -0.249642 -0.249642)
							(end -0.2794 -0.1778)
						)
						(arc
							(start -0.2794 0.1778)
							(mid -0.249642 0.249642)
							(end -0.1778 0.2794)
						)
						(arc
							(start 0.1778 0.2794)
							(mid 0.249642 0.249642)
							(end 0.2794 0.1778)
						)
						(arc
							(start 0.2794 -0.1778)
							(mid 0.249642 -0.249642)
							(end 0.1778 -0.2794)
						)
					)
					(width 0)
					(fill yes)
				)
			)
		)
	)
	(footprint ""
		(layer "F.Cu")
		(at 109.895386 -130.261614 -90)
		(property "Reference" "R517"
			(at 0 0 270)
			(layer "F.SilkS")
			(hide yes)
			(effects
				(font
					(size 1.27 1.27)
				)
			)
		)
		(property "Value" "4K7R2J-2-GP"
			(at 0.064008 -3.993896 270)
			(unlocked yes)
			(layer "F.Fab")
			(hide yes)
			(effects
				(font
					(size 1.016 1.016)
					(thickness 0.1524)
				)
			)
		)
		(property "Device Type" "R402H16"
			(at 0.064008 -5.517896 270)
			(unlocked yes)
			(layer "F.Fab")
			(hide yes)
			(effects
				(font
					(size 1.016 1.016)
					(thickness 0.1524)
				)
			)
		)
		(duplicate_pad_numbers_are_jumpers no)
		(fp_line
			(start -0.508 -0.9398)
			(end -0.508 0.9398)
			(stroke
				(width 0.1524)
				(type default)
			)
			(layer "F.SilkS")
		)
		(fp_line
			(start 0.508 -0.9398)
			(end -0.508 -0.9398)
			(stroke
				(width 0.1524)
				(type default)
			)
			(layer "F.SilkS")
		)
		(fp_rect
			(start -0.508 0.9398)
			(end 0.508 -0.9398)
			(stroke
				(width 0)
				(type default)
			)
			(fill no)
			(layer "F.CrtYd")
		)
		(fp_rect
			(start -0.508 0.9398)
			(end 0.508 -0.9398)
			(stroke
				(width 0)
				(type default)
			)
			(fill no)
			(layer "F.Fab")
		)
		(pad "1" smd custom
			(at 0 -0.4445 270)
			(size 0.1397 0.1397)
			(layers "F.Cu" "F.Mask" "F.Paste")
			(net "DRIVE_A_15_FLT_LED")
			(options
				(clearance outline)
				(anchor circle)
			)
			(primitives
				(gr_poly
					(pts
						(arc
							(start -0.1778 -0.2794)
							(mid -0.249642 -0.249642)
							(end -0.2794 -0.1778)
						)
						(arc
							(start -0.2794 0.1778)
							(mid -0.249642 0.249642)
							(end -0.1778 0.2794)
						)
						(arc
							(start 0.1778 0.2794)
							(mid 0.249642 0.249642)
							(end 0.2794 0.1778)
						)
						(arc
							(start 0.2794 -0.1778)
							(mid 0.249642 -0.249642)
							(end 0.1778 -0.2794)
						)
					)
					(width 0)
					(fill yes)
				)
			)
		)
		(pad "2" smd custom
			(at 0 0.4445 270)
			(size 0.1397 0.1397)
			(layers "F.Cu" "F.Mask" "F.Paste")
			(net "GND")
			(options
				(clearance outline)
				(anchor circle)
			)
			(primitives
				(gr_poly
					(pts
						(arc
							(start -0.1778 -0.2794)
							(mid -0.249642 -0.249642)
							(end -0.2794 -0.1778)
						)
						(arc
							(start -0.2794 0.1778)
							(mid -0.249642 0.249642)
							(end -0.1778 0.2794)
						)
						(arc
							(start 0.1778 0.2794)
							(mid 0.249642 0.249642)
							(end 0.2794 0.1778)
						)
						(arc
							(start 0.2794 -0.1778)
							(mid 0.249642 -0.249642)
							(end 0.1778 -0.2794)
						)
					)
					(width 0)
					(fill yes)
				)
			)
		)
	)
	(footprint ""
		(layer "F.Cu")
		(at 238.099346 -228.96703 180)
		(property "Reference" "Q15"
			(at 0 0 180)
			(layer "F.SilkS")
			(hide yes)
			(effects
				(font
					(size 1.27 1.27)
				)
			)
		)
		(property "Value" "SSM3K324R-GP"
			(at 0.127 -8.9662 180)
			(unlocked yes)
			(layer "F.Fab")
			(hide yes)
			(effects
				(font
					(size 1.016 1.016)
					(thickness 0.1524)
				)
			)
		)
		(property "Device Type" "SOT23DGS2D4H35"
			(at 0.127 -10.4902 180)
			(unlocked yes)
			(layer "F.Fab")
			(hide yes)
			(effects
				(font
					(size 1.016 1.016)
					(thickness 0.1524)
				)
			)
		)
		(duplicate_pad_numbers_are_jumpers no)
		(fp_line
			(start 1.651 1.778)
			(end 1.651 -1.778)
			(stroke
				(width 0.1524)
				(type default)
			)
			(layer "F.SilkS")
		)
		(fp_line
			(start 1.651 -1.778)
			(end -1.651 -1.778)
			(stroke
				(width 0.1524)
				(type default)
			)
			(layer "F.SilkS")
		)
		(fp_line
			(start -1.651 1.778)
			(end 1.651 1.778)
			(stroke
				(width 0.1524)
				(type default)
			)
			(layer "F.SilkS")
		)
		(fp_line
			(start -1.651 -1.778)
			(end -1.651 1.778)
			(stroke
				(width 0.1524)
				(type default)
			)
			(layer "F.SilkS")
		)
		(fp_poly
			(pts
				(xy -1.778 1.8796) (xy -1.778 -1.8796) (xy 1.778 -1.8796) (xy 1.778 1.8796)
			)
			(stroke
				(width 0)
				(type default)
			)
			(fill no)
			(layer "F.CrtYd")
		)
		(fp_poly
			(pts
				(xy -1.778 1.8796) (xy -1.778 -1.8796) (xy 1.778 -1.8796) (xy 1.778 1.8796)
			)
			(stroke
				(width 0)
				(type default)
			)
			(fill no)
			(layer "F.Fab")
		)
		(pad "D" smd custom
			(at 0 -0.9525 180)
			(size 0.1905 0.1905)
			(layers "F.Cu" "F.Mask" "F.Paste")
			(net "P3V3_STBY_A")
			(options
				(clearance outline)
				(anchor circle)
			)
			(primitives
				(gr_poly
					(pts
						(arc
							(start -0.1778 0.5715)
							(mid -0.321484 0.511984)
							(end -0.381 0.3683)
						)
						(arc
							(start -0.381 -0.3683)
							(mid -0.321484 -0.511984)
							(end -0.1778 -0.5715)
						)
						(arc
							(start 0.1778 -0.5715)
							(mid 0.321484 -0.511984)
							(end 0.381 -0.3683)
						)
						(arc
							(start 0.381 0.3683)
							(mid 0.321484 0.511984)
							(end 0.1778 0.5715)
						)
					)
					(width 0)
					(fill yes)
				)
			)
		)
		(pad "G" smd custom
			(at -0.98425 0.9525 180)
			(size 0.1905 0.1905)
			(layers "F.Cu" "F.Mask" "F.Paste")
			(net "SCC_FULL_PWR_EN_5V")
			(options
				(clearance outline)
				(anchor circle)
			)
			(primitives
				(gr_poly
					(pts
						(arc
							(start -0.1778 0.5715)
							(mid -0.321484 0.511984)
							(end -0.381 0.3683)
						)
						(arc
							(start -0.381 -0.3683)
							(mid -0.321484 -0.511984)
							(end -0.1778 -0.5715)
						)
						(arc
							(start 0.1778 -0.5715)
							(mid 0.321484 -0.511984)
							(end 0.381 -0.3683)
						)
						(arc
							(start 0.381 0.3683)
							(mid 0.321484 0.511984)
							(end 0.1778 0.5715)
						)
					)
					(width 0)
					(fill yes)
				)
			)
		)
		(pad "S" smd custom
			(at 0.98425 0.9525 180)
			(size 0.1905 0.1905)
			(layers "F.Cu" "F.Mask" "F.Paste")
			(net "GPIO_VCC_U7")
			(options
				(clearance outline)
				(anchor circle)
			)
			(primitives
				(gr_poly
					(pts
						(arc
							(start -0.1778 0.5715)
							(mid -0.321484 0.511984)
							(end -0.381 0.3683)
						)
						(arc
							(start -0.381 -0.3683)
							(mid -0.321484 -0.511984)
							(end -0.1778 -0.5715)
						)
						(arc
							(start 0.1778 -0.5715)
							(mid 0.321484 -0.511984)
							(end 0.381 -0.3683)
						)
						(arc
							(start 0.381 0.3683)
							(mid 0.321484 0.511984)
							(end 0.1778 0.5715)
						)
					)
					(width 0)
					(fill yes)
				)
			)
		)
	)
	(footprint ""
		(layer "F.Cu")
		(at 20.430998 -278.554942 180)
		(property "Reference" "Q217"
			(at 0 0 180)
			(layer "F.SilkS")
			(hide yes)
			(effects
				(font
					(size 1.27 1.27)
				)
			)
		)
		(property "Value" "2N7002KDW-GP"
			(at -2.3622 -8.2042 180)
			(unlocked yes)
			(layer "F.Fab")
			(hide yes)
			(effects
				(font
					(size 1.016 1.016)
					(thickness 0.1524)
				)
			)
		)
		(property "Device Type" "SOT-363H44"
			(at -2.3622 -10.1092 180)
			(unlocked yes)
			(layer "F.Fab")
			(hide yes)
			(effects
				(font
					(size 1.016 1.016)
					(thickness 0.1524)
				)
			)
		)
		(duplicate_pad_numbers_are_jumpers no)
		(fp_line
			(start 1.4478 1.7018)
			(end 1.4478 -1.7018)
			(stroke
				(width 0.1524)
				(type default)
			)
			(layer "F.SilkS")
		)
		(fp_line
			(start 1.4478 -1.7018)
			(end -1.4478 -1.7018)
			(stroke
				(width 0.1524)
				(type default)
			)
			(layer "F.SilkS")
		)
		(fp_line
			(start -1.27 1.524)
			(end -1.27 0.6604)
			(stroke
				(width 0.4826)
				(type default)
			)
			(layer "F.SilkS")
		)
		(fp_line
			(start -1.4478 1.7018)
			(end 1.4478 1.7018)
			(stroke
				(width 0.1524)
				(type default)
			)
			(layer "F.SilkS")
		)
		(fp_line
			(start -1.4478 -1.7018)
			(end -1.4478 1.7018)
			(stroke
				(width 0.1524)
				(type default)
			)
			(layer "F.SilkS")
		)
		(fp_poly
			(pts
				(xy -1.524 -1.778) (xy 1.524 -1.778) (xy 1.524 1.778) (xy -1.524 1.778)
			)
			(stroke
				(width 0)
				(type default)
			)
			(fill no)
			(layer "F.CrtYd")
		)
		(fp_poly
			(pts
				(xy -1.524 -1.778) (xy 1.524 -1.778) (xy 1.524 1.778) (xy -1.524 1.778)
			)
			(stroke
				(width 0)
				(type default)
			)
			(fill no)
			(layer "F.Fab")
		)
		(pad "1" smd rect
			(at -0.65024 0.9398 180)
			(size 0.4064 1.016)
			(layers "F.Cu" "F.Mask" "F.Paste")
			(net "GND")
		)
		(pad "2" smd rect
			(at 0 0.9398 180)
			(size 0.4064 1.016)
			(layers "F.Cu" "F.Mask" "F.Paste")
			(net "SW_PWR_R_HDD0")
		)
		(pad "3" smd rect
			(at 0.65024 0.9398 180)
			(size 0.4064 1.016)
			(layers "F.Cu" "F.Mask" "F.Paste")
			(net "SW_HDD_P0")
		)
		(pad "4" smd rect
			(at 0.65024 -0.9398 180)
			(size 0.4064 1.016)
			(layers "F.Cu" "F.Mask" "F.Paste")
			(net "GND")
		)
		(pad "5" smd rect
			(at 0 -0.9398 180)
			(size 0.4064 1.016)
			(layers "F.Cu" "F.Mask" "F.Paste")
			(net "SW_HDD_G0")
		)
		(pad "6" smd rect
			(at -0.65024 -0.9398 180)
			(size 0.4064 1.016)
			(layers "F.Cu" "F.Mask" "F.Paste")
			(net "SW_HDD_R0")
		)
	)
	(footprint ""
		(layer "F.Cu")
		(at 267.822426 -211.824062 180)
		(property "Reference" "R603"
			(at 0 0 180)
			(layer "F.SilkS")
			(hide yes)
			(effects
				(font
					(size 1.27 1.27)
				)
			)
		)
		(property "Value" "2K2R2F-GP"
			(at 0.064008 -3.993896 180)
			(unlocked yes)
			(layer "F.Fab")
			(hide yes)
			(effects
				(font
					(size 1.016 1.016)
					(thickness 0.1524)
				)
			)
		)
		(property "Device Type" "R402H16"
			(at 0.064008 -5.517896 180)
			(unlocked yes)
			(layer "F.Fab")
			(hide yes)
			(effects
				(font
					(size 1.016 1.016)
					(thickness 0.1524)
				)
			)
		)
		(duplicate_pad_numbers_are_jumpers no)
		(fp_line
			(start 0.508 -0.9398)
			(end -0.508 -0.9398)
			(stroke
				(width 0.1524)
				(type default)
			)
			(layer "F.SilkS")
		)
		(fp_line
			(start -0.508 -0.9398)
			(end -0.508 0.9398)
			(stroke
				(width 0.1524)
				(type default)
			)
			(layer "F.SilkS")
		)
		(fp_rect
			(start -0.508 0.9398)
			(end 0.508 -0.9398)
			(stroke
				(width 0)
				(type default)
			)
			(fill no)
			(layer "F.CrtYd")
		)
		(fp_rect
			(start -0.508 0.9398)
			(end 0.508 -0.9398)
			(stroke
				(width 0)
				(type default)
			)
			(fill no)
			(layer "F.Fab")
		)
		(pad "1" smd custom
			(at 0 -0.4445 180)
			(size 0.1397 0.1397)
			(layers "F.Cu" "F.Mask" "F.Paste")
			(net "P3V3_STBY_A")
			(options
				(clearance outline)
				(anchor circle)
			)
			(primitives
				(gr_poly
					(pts
						(arc
							(start -0.1778 -0.2794)
							(mid -0.249642 -0.249642)
							(end -0.2794 -0.1778)
						)
						(arc
							(start -0.2794 0.1778)
							(mid -0.249642 0.249642)
							(end -0.1778 0.2794)
						)
						(arc
							(start 0.1778 0.2794)
							(mid 0.249642 0.249642)
							(end 0.2794 0.1778)
						)
						(arc
							(start 0.2794 -0.1778)
							(mid 0.249642 -0.249642)
							(end 0.1778 -0.2794)
						)
					)
					(width 0)
					(fill yes)
				)
			)
		)
		(pad "2" smd custom
			(at 0 0.4445 180)
			(size 0.1397 0.1397)
			(layers "F.Cu" "F.Mask" "F.Paste")
			(net "I2C_DPB_A_SCL")
			(options
				(clearance outline)
				(anchor circle)
			)
			(primitives
				(gr_poly
					(pts
						(arc
							(start -0.1778 -0.2794)
							(mid -0.249642 -0.249642)
							(end -0.2794 -0.1778)
						)
						(arc
							(start -0.2794 0.1778)
							(mid -0.249642 0.249642)
							(end -0.1778 0.2794)
						)
						(arc
							(start 0.1778 0.2794)
							(mid 0.249642 0.249642)
							(end 0.2794 0.1778)
						)
						(arc
							(start 0.2794 -0.1778)
							(mid 0.249642 -0.249642)
							(end 0.1778 -0.2794)
						)
					)
					(width 0)
					(fill yes)
				)
			)
		)
	)
	(footprint ""
		(layer "F.Cu")
		(at 115.080796 -48.554894 180)
		(property "Reference" "Q163"
			(at 0 0 180)
			(layer "F.SilkS")
			(hide yes)
			(effects
				(font
					(size 1.27 1.27)
				)
			)
		)
		(property "Value" "2N7002KDW-GP"
			(at -2.3622 -8.2042 180)
			(unlocked yes)
			(layer "F.Fab")
			(hide yes)
			(effects
				(font
					(size 1.016 1.016)
					(thickness 0.1524)
				)
			)
		)
		(property "Device Type" "SOT-363H44"
			(at -2.3622 -10.1092 180)
			(unlocked yes)
			(layer "F.Fab")
			(hide yes)
			(effects
				(font
					(size 1.016 1.016)
					(thickness 0.1524)
				)
			)
		)
		(duplicate_pad_numbers_are_jumpers no)
		(fp_line
			(start 1.4478 1.7018)
			(end 1.4478 -1.7018)
			(stroke
				(width 0.1524)
				(type default)
			)
			(layer "F.SilkS")
		)
		(fp_line
			(start 1.4478 -1.7018)
			(end -1.4478 -1.7018)
			(stroke
				(width 0.1524)
				(type default)
			)
			(layer "F.SilkS")
		)
		(fp_line
			(start -1.27 1.524)
			(end -1.27 0.6604)
			(stroke
				(width 0.4826)
				(type default)
			)
			(layer "F.SilkS")
		)
		(fp_line
			(start -1.4478 1.7018)
			(end 1.4478 1.7018)
			(stroke
				(width 0.1524)
				(type default)
			)
			(layer "F.SilkS")
		)
		(fp_line
			(start -1.4478 -1.7018)
			(end -1.4478 1.7018)
			(stroke
				(width 0.1524)
				(type default)
			)
			(layer "F.SilkS")
		)
		(fp_poly
			(pts
				(xy -1.524 -1.778) (xy 1.524 -1.778) (xy 1.524 1.778) (xy -1.524 1.778)
			)
			(stroke
				(width 0)
				(type default)
			)
			(fill no)
			(layer "F.CrtYd")
		)
		(fp_poly
			(pts
				(xy -1.524 -1.778) (xy 1.524 -1.778) (xy 1.524 1.778) (xy -1.524 1.778)
			)
			(stroke
				(width 0)
				(type default)
			)
			(fill no)
			(layer "F.Fab")
		)
		(pad "1" smd rect
			(at -0.65024 0.9398 180)
			(size 0.4064 1.016)
			(layers "F.Cu" "F.Mask" "F.Paste")
			(net "GND")
		)
		(pad "2" smd rect
			(at 0 0.9398 180)
			(size 0.4064 1.016)
			(layers "F.Cu" "F.Mask" "F.Paste")
			(net "SW_PWR_R_HDD27")
		)
		(pad "3" smd rect
			(at 0.65024 0.9398 180)
			(size 0.4064 1.016)
			(layers "F.Cu" "F.Mask" "F.Paste")
			(net "SW_HDD_P27")
		)
		(pad "4" smd rect
			(at 0.65024 -0.9398 180)
			(size 0.4064 1.016)
			(layers "F.Cu" "F.Mask" "F.Paste")
			(net "GND")
		)
		(pad "5" smd rect
			(at 0 -0.9398 180)
			(size 0.4064 1.016)
			(layers "F.Cu" "F.Mask" "F.Paste")
			(net "SW_HDD_G27")
		)
		(pad "6" smd rect
			(at -0.65024 -0.9398 180)
			(size 0.4064 1.016)
			(layers "F.Cu" "F.Mask" "F.Paste")
			(net "SW_HDD_R27")
		)
	)
	(footprint ""
		(layer "F.Cu")
		(at 64.013334 -159.219392 90)
		(property "Reference" "C207"
			(at 0 0 90)
			(layer "F.SilkS")
			(hide yes)
			(effects
				(font
					(size 1.27 1.27)
				)
			)
		)
		(property "Value" "SCD01U16V1KX-GP"
			(at -2.8321 -1.7399 90)
			(unlocked yes)
			(layer "F.Fab")
			(hide yes)
			(effects
				(font
					(size 1.016 1.016)
					(thickness 0.1524)
				)
			)
		)
		(property "Device Type" "C0201H13"
			(at -2.8321 -3.2639 90)
			(unlocked yes)
			(layer "F.Fab")
			(hide yes)
			(effects
				(font
					(size 1.016 1.016)
					(thickness 0.1524)
				)
			)
		)
		(duplicate_pad_numbers_are_jumpers no)
		(fp_rect
			(start -0.2794 0.6477)
			(end 0.2794 -0.6477)
			(stroke
				(width 0)
				(type default)
			)
			(fill no)
			(layer "F.CrtYd")
		)
		(fp_rect
			(start -0.2794 0.6477)
			(end 0.2794 -0.6477)
			(stroke
				(width 0)
				(type default)
			)
			(fill no)
			(layer "F.Fab")
		)
		(pad "1" smd custom
			(at 0 -0.2794 90)
			(size 0.0762 0.0762)
			(layers "F.Cu" "F.Mask" "F.Paste")
			(net "SAS_HDD_RX_N13")
			(options
				(clearance outline)
				(anchor circle)
			)
			(primitives
				(gr_poly
					(pts
						(arc
							(start 0.1524 -0.127)
							(mid 0.137521 -0.162921)
							(end 0.1016 -0.1778)
						)
						(arc
							(start -0.1016 -0.1778)
							(mid -0.137521 -0.162921)
							(end -0.1524 -0.127)
						)
						(arc
							(start -0.1524 0.127)
							(mid -0.137521 0.162921)
							(end -0.1016 0.1778)
						)
						(arc
							(start 0.1016 0.1778)
							(mid 0.137521 0.162921)
							(end 0.1524 0.127)
						)
					)
					(width 0)
					(fill yes)
				)
			)
		)
		(pad "2" smd custom
			(at 0 0.2794 90)
			(size 0.0762 0.0762)
			(layers "F.Cu" "F.Mask" "F.Paste")
			(net "PHY_SCC_A_TO_DRV_A_13_DN")
			(options
				(clearance outline)
				(anchor circle)
			)
			(primitives
				(gr_poly
					(pts
						(arc
							(start 0.1524 -0.127)
							(mid 0.137521 -0.162921)
							(end 0.1016 -0.1778)
						)
						(arc
							(start -0.1016 -0.1778)
							(mid -0.137521 -0.162921)
							(end -0.1524 -0.127)
						)
						(arc
							(start -0.1524 0.127)
							(mid -0.137521 0.162921)
							(end -0.1016 0.1778)
						)
						(arc
							(start 0.1016 0.1778)
							(mid 0.137521 0.162921)
							(end 0.1524 0.127)
						)
					)
					(width 0)
					(fill yes)
				)
			)
		)
	)
	(footprint ""
		(layer "F.Cu")
		(at 23.936198 -71.287894)
		(property "Reference" "C357"
			(at 0 0 0)
			(layer "F.SilkS")
			(hide yes)
			(effects
				(font
					(size 1.27 1.27)
				)
			)
		)
		(property "Value" "SC4D7U25V5KX-1-GP"
			(at -0.0762 -6.1214 0)
			(unlocked yes)
			(layer "F.Fab")
			(hide yes)
			(effects
				(font
					(size 1.016 1.016)
					(thickness 0.1524)
				)
			)
		)
		(property "Device Type" "C805H58"
			(at -0.0762 -8.1534 0)
			(unlocked yes)
			(layer "F.Fab")
			(hide yes)
			(effects
				(font
					(size 1.016 1.016)
					(thickness 0.1524)
				)
			)
		)
		(duplicate_pad_numbers_are_jumpers no)
		(fp_line
			(start 0.635 0)
			(end -0.635 0)
			(stroke
				(width 0.508)
				(type default)
			)
			(layer "F.SilkS")
		)
		(fp_rect
			(start -0.9652 1.778)
			(end 0.9652 -1.778)
			(stroke
				(width 0)
				(type default)
			)
			(fill no)
			(layer "F.CrtYd")
		)
		(fp_poly
			(pts
				(xy -0.9652 -1.778) (xy 0.9652 -1.778) (xy 0.9652 1.778) (xy -0.9652 1.778)
			)
			(stroke
				(width 0)
				(type default)
			)
			(fill no)
			(layer "F.Fab")
		)
		(pad "1" smd rect
			(at 0 -0.9652)
			(size 1.397 1.143)
			(layers "F.Cu" "F.Mask" "F.Paste")
			(net "P12V_HDD24")
		)
		(pad "2" smd rect
			(at 0 0.9652)
			(size 1.397 1.143)
			(layers "F.Cu" "F.Mask" "F.Paste")
			(net "GND")
		)
	)
	(footprint ""
		(layer "F.Cu")
		(at 26.381202 -254.84455 -90)
		(property "Reference" "R1218"
			(at 0 0 270)
			(layer "F.SilkS")
			(hide yes)
			(effects
				(font
					(size 1.27 1.27)
				)
			)
		)
		(property "Value" "143KR2F-L-1-GP"
			(at 0.064008 -3.993896 270)
			(unlocked yes)
			(layer "F.Fab")
			(hide yes)
			(effects
				(font
					(size 1.016 1.016)
					(thickness 0.1524)
				)
			)
		)
		(property "Device Type" "R402H16"
			(at 0.064008 -5.517896 270)
			(unlocked yes)
			(layer "F.Fab")
			(hide yes)
			(effects
				(font
					(size 1.016 1.016)
					(thickness 0.1524)
				)
			)
		)
		(duplicate_pad_numbers_are_jumpers no)
		(fp_line
			(start -0.508 -0.9398)
			(end -0.508 0.9398)
			(stroke
				(width 0.1524)
				(type default)
			)
			(layer "F.SilkS")
		)
		(fp_line
			(start 0.508 -0.9398)
			(end -0.508 -0.9398)
			(stroke
				(width 0.1524)
				(type default)
			)
			(layer "F.SilkS")
		)
		(fp_rect
			(start -0.508 0.9398)
			(end 0.508 -0.9398)
			(stroke
				(width 0)
				(type default)
			)
			(fill no)
			(layer "F.CrtYd")
		)
		(fp_rect
			(start -0.508 0.9398)
			(end 0.508 -0.9398)
			(stroke
				(width 0)
				(type default)
			)
			(fill no)
			(layer "F.Fab")
		)
		(pad "1" smd custom
			(at 0 -0.4445 270)
			(size 0.1397 0.1397)
			(layers "F.Cu" "F.Mask" "F.Paste")
			(net "AGND_P5V_A")
			(options
				(clearance outline)
				(anchor circle)
			)
			(primitives
				(gr_poly
					(pts
						(arc
							(start -0.1778 -0.2794)
							(mid -0.249642 -0.249642)
							(end -0.2794 -0.1778)
						)
						(arc
							(start -0.2794 0.1778)
							(mid -0.249642 0.249642)
							(end -0.1778 0.2794)
						)
						(arc
							(start 0.1778 0.2794)
							(mid 0.249642 0.249642)
							(end 0.2794 0.1778)
						)
						(arc
							(start 0.2794 -0.1778)
							(mid 0.249642 -0.249642)
							(end 0.1778 -0.2794)
						)
					)
					(width 0)
					(fill yes)
				)
			)
		)
		(pad "2" smd custom
			(at 0 0.4445 270)
			(size 0.1397 0.1397)
			(layers "F.Cu" "F.Mask" "F.Paste")
			(net "P5V_A_TRIP")
			(options
				(clearance outline)
				(anchor circle)
			)
			(primitives
				(gr_poly
					(pts
						(arc
							(start -0.1778 -0.2794)
							(mid -0.249642 -0.249642)
							(end -0.2794 -0.1778)
						)
						(arc
							(start -0.2794 0.1778)
							(mid -0.249642 0.249642)
							(end -0.1778 0.2794)
						)
						(arc
							(start 0.1778 0.2794)
							(mid 0.249642 0.249642)
							(end 0.2794 0.1778)
						)
						(arc
							(start 0.2794 -0.1778)
							(mid 0.249642 -0.249642)
							(end 0.1778 -0.2794)
						)
					)
					(width 0)
					(fill yes)
				)
			)
		)
	)
	(footprint ""
		(layer "F.Cu")
		(at 130.2385 -130.269996 -90)
		(property "Reference" "R518"
			(at 0 0 270)
			(layer "F.SilkS")
			(hide yes)
			(effects
				(font
					(size 1.27 1.27)
				)
			)
		)
		(property "Value" "4K7R2J-2-GP"
			(at 0.064008 -3.993896 270)
			(unlocked yes)
			(layer "F.Fab")
			(hide yes)
			(effects
				(font
					(size 1.016 1.016)
					(thickness 0.1524)
				)
			)
		)
		(property "Device Type" "R402H16"
			(at 0.064008 -5.517896 270)
			(unlocked yes)
			(layer "F.Fab")
			(hide yes)
			(effects
				(font
					(size 1.016 1.016)
					(thickness 0.1524)
				)
			)
		)
		(duplicate_pad_numbers_are_jumpers no)
		(fp_line
			(start -0.508 -0.9398)
			(end -0.508 0.9398)
			(stroke
				(width 0.1524)
				(type default)
			)
			(layer "F.SilkS")
		)
		(fp_line
			(start 0.508 -0.9398)
			(end -0.508 -0.9398)
			(stroke
				(width 0.1524)
				(type default)
			)
			(layer "F.SilkS")
		)
		(fp_rect
			(start -0.508 0.9398)
			(end 0.508 -0.9398)
			(stroke
				(width 0)
				(type default)
			)
			(fill no)
			(layer "F.CrtYd")
		)
		(fp_rect
			(start -0.508 0.9398)
			(end 0.508 -0.9398)
			(stroke
				(width 0)
				(type default)
			)
			(fill no)
			(layer "F.Fab")
		)
		(pad "1" smd custom
			(at 0 -0.4445 270)
			(size 0.1397 0.1397)
			(layers "F.Cu" "F.Mask" "F.Paste")
			(net "DRIVE_A_16_ACT")
			(options
				(clearance outline)
				(anchor circle)
			)
			(primitives
				(gr_poly
					(pts
						(arc
							(start -0.1778 -0.2794)
							(mid -0.249642 -0.249642)
							(end -0.2794 -0.1778)
						)
						(arc
							(start -0.2794 0.1778)
							(mid -0.249642 0.249642)
							(end -0.1778 0.2794)
						)
						(arc
							(start 0.1778 0.2794)
							(mid 0.249642 0.249642)
							(end 0.2794 0.1778)
						)
						(arc
							(start 0.2794 -0.1778)
							(mid 0.249642 -0.249642)
							(end 0.1778 -0.2794)
						)
					)
					(width 0)
					(fill yes)
				)
			)
		)
		(pad "2" smd custom
			(at 0 0.4445 270)
			(size 0.1397 0.1397)
			(layers "F.Cu" "F.Mask" "F.Paste")
			(net "GND")
			(options
				(clearance outline)
				(anchor circle)
			)
			(primitives
				(gr_poly
					(pts
						(arc
							(start -0.1778 -0.2794)
							(mid -0.249642 -0.249642)
							(end -0.2794 -0.1778)
						)
						(arc
							(start -0.2794 0.1778)
							(mid -0.249642 0.249642)
							(end -0.1778 0.2794)
						)
						(arc
							(start 0.1778 0.2794)
							(mid 0.249642 0.249642)
							(end 0.2794 0.1778)
						)
						(arc
							(start 0.2794 -0.1778)
							(mid 0.249642 -0.249642)
							(end 0.1778 -0.2794)
						)
					)
					(width 0)
					(fill yes)
				)
			)
		)
	)
	(footprint ""
		(layer "F.Cu")
		(at 430.387252 -45.735494 180)
		(property "Reference" "R906"
			(at 0 0 180)
			(layer "F.SilkS")
			(hide yes)
			(effects
				(font
					(size 1.27 1.27)
				)
			)
		)
		(property "Value" "0R2J-2-GP"
			(at 0.064008 -3.993896 180)
			(unlocked yes)
			(layer "F.Fab")
			(hide yes)
			(effects
				(font
					(size 1.016 1.016)
					(thickness 0.1524)
				)
			)
		)
		(property "Device Type" "R402H16"
			(at 0.064008 -5.517896 180)
			(unlocked yes)
			(layer "F.Fab")
			(hide yes)
			(effects
				(font
					(size 1.016 1.016)
					(thickness 0.1524)
				)
			)
		)
		(duplicate_pad_numbers_are_jumpers no)
		(fp_line
			(start 0.508 -0.9398)
			(end -0.508 -0.9398)
			(stroke
				(width 0.1524)
				(type default)
			)
			(layer "F.SilkS")
		)
		(fp_line
			(start -0.508 -0.9398)
			(end -0.508 0.9398)
			(stroke
				(width 0.1524)
				(type default)
			)
			(layer "F.SilkS")
		)
		(fp_rect
			(start -0.508 0.9398)
			(end 0.508 -0.9398)
			(stroke
				(width 0)
				(type default)
			)
			(fill no)
			(layer "F.CrtYd")
		)
		(fp_rect
			(start -0.508 0.9398)
			(end 0.508 -0.9398)
			(stroke
				(width 0)
				(type default)
			)
			(fill no)
			(layer "F.Fab")
		)
		(pad "1" smd custom
			(at 0 -0.4445 180)
			(size 0.1397 0.1397)
			(layers "F.Cu" "F.Mask" "F.Paste")
			(net "SW_HDD_G33")
			(options
				(clearance outline)
				(anchor circle)
			)
			(primitives
				(gr_poly
					(pts
						(arc
							(start -0.1778 -0.2794)
							(mid -0.249642 -0.249642)
							(end -0.2794 -0.1778)
						)
						(arc
							(start -0.2794 0.1778)
							(mid -0.249642 0.249642)
							(end -0.1778 0.2794)
						)
						(arc
							(start 0.1778 0.2794)
							(mid 0.249642 0.249642)
							(end 0.2794 0.1778)
						)
						(arc
							(start 0.2794 -0.1778)
							(mid 0.249642 -0.249642)
							(end 0.1778 -0.2794)
						)
					)
					(width 0)
					(fill yes)
				)
			)
		)
		(pad "2" smd custom
			(at 0 0.4445 180)
			(size 0.1397 0.1397)
			(layers "F.Cu" "F.Mask" "F.Paste")
			(net "SW_HDD_R33")
			(options
				(clearance outline)
				(anchor circle)
			)
			(primitives
				(gr_poly
					(pts
						(arc
							(start -0.1778 -0.2794)
							(mid -0.249642 -0.249642)
							(end -0.2794 -0.1778)
						)
						(arc
							(start -0.2794 0.1778)
							(mid -0.249642 0.249642)
							(end -0.1778 0.2794)
						)
						(arc
							(start 0.1778 0.2794)
							(mid 0.249642 0.249642)
							(end 0.2794 0.1778)
						)
						(arc
							(start 0.2794 -0.1778)
							(mid 0.249642 -0.249642)
							(end 0.1778 -0.2794)
						)
					)
					(width 0)
					(fill yes)
				)
			)
		)
	)
	(footprint ""
		(layer "F.Cu")
		(at 38.608762 -181.44617 90)
		(property "Reference" "R147"
			(at 0 0 90)
			(layer "F.SilkS")
			(hide yes)
			(effects
				(font
					(size 1.27 1.27)
				)
			)
		)
		(property "Value" "4K7R2J-2-GP"
			(at 0.064008 -3.993896 90)
			(unlocked yes)
			(layer "F.Fab")
			(hide yes)
			(effects
				(font
					(size 1.016 1.016)
					(thickness 0.1524)
				)
			)
		)
		(property "Device Type" "R402H16"
			(at 0.064008 -5.517896 90)
			(unlocked yes)
			(layer "F.Fab")
			(hide yes)
			(effects
				(font
					(size 1.016 1.016)
					(thickness 0.1524)
				)
			)
		)
		(duplicate_pad_numbers_are_jumpers no)
		(fp_line
			(start 0.508 -0.9398)
			(end -0.508 -0.9398)
			(stroke
				(width 0.1524)
				(type default)
			)
			(layer "F.SilkS")
		)
		(fp_line
			(start -0.508 -0.9398)
			(end -0.508 0.9398)
			(stroke
				(width 0.1524)
				(type default)
			)
			(layer "F.SilkS")
		)
		(fp_rect
			(start -0.508 0.9398)
			(end 0.508 -0.9398)
			(stroke
				(width 0)
				(type default)
			)
			(fill no)
			(layer "F.CrtYd")
		)
		(fp_rect
			(start -0.508 0.9398)
			(end 0.508 -0.9398)
			(stroke
				(width 0)
				(type default)
			)
			(fill no)
			(layer "F.Fab")
		)
		(pad "1" smd custom
			(at 0 -0.4445 90)
			(size 0.1397 0.1397)
			(layers "F.Cu" "F.Mask" "F.Paste")
			(net "DRIVE_A_1_ACT")
			(options
				(clearance outline)
				(anchor circle)
			)
			(primitives
				(gr_poly
					(pts
						(arc
							(start -0.1778 -0.2794)
							(mid -0.249642 -0.249642)
							(end -0.2794 -0.1778)
						)
						(arc
							(start -0.2794 0.1778)
							(mid -0.249642 0.249642)
							(end -0.1778 0.2794)
						)
						(arc
							(start 0.1778 0.2794)
							(mid 0.249642 0.249642)
							(end 0.2794 0.1778)
						)
						(arc
							(start 0.2794 -0.1778)
							(mid 0.249642 -0.249642)
							(end 0.1778 -0.2794)
						)
					)
					(width 0)
					(fill yes)
				)
			)
		)
		(pad "2" smd custom
			(at 0 0.4445 90)
			(size 0.1397 0.1397)
			(layers "F.Cu" "F.Mask" "F.Paste")
			(net "GND")
			(options
				(clearance outline)
				(anchor circle)
			)
			(primitives
				(gr_poly
					(pts
						(arc
							(start -0.1778 -0.2794)
							(mid -0.249642 -0.249642)
							(end -0.2794 -0.1778)
						)
						(arc
							(start -0.2794 0.1778)
							(mid -0.249642 0.249642)
							(end -0.1778 0.2794)
						)
						(arc
							(start 0.1778 0.2794)
							(mid 0.249642 0.249642)
							(end 0.2794 0.1778)
						)
						(arc
							(start 0.2794 -0.1778)
							(mid 0.249642 -0.249642)
							(end 0.1778 -0.2794)
						)
					)
					(width 0)
					(fill yes)
				)
			)
		)
	)
	(footprint ""
		(layer "F.Cu")
		(at 165.67531 -146.676618 90)
		(property "Reference" "R1067"
			(at 0 0 90)
			(layer "F.SilkS")
			(hide yes)
			(effects
				(font
					(size 1.27 1.27)
				)
			)
		)
		(property "Value" "10R5F-1-GP"
			(at 0 -8.9535 90)
			(unlocked yes)
			(layer "F.Fab")
			(hide yes)
			(effects
				(font
					(size 1.27 1.016)
					(thickness 0.1524)
				)
			)
		)
		(property "Device Type" "R805H24"
			(at 0 -10.6299 90)
			(unlocked yes)
			(layer "F.Fab")
			(hide yes)
			(effects
				(font
					(size 1.27 1.016)
					(thickness 0.1524)
				)
			)
		)
		(duplicate_pad_numbers_are_jumpers no)
		(fp_line
			(start 0.889 -1.7018)
			(end -0.889 -1.7018)
			(stroke
				(width 0.1524)
				(type default)
			)
			(layer "F.SilkS")
		)
		(fp_line
			(start 0.889 -1.7018)
			(end 0.889 -0.381)
			(stroke
				(width 0.1524)
				(type default)
			)
			(layer "F.SilkS")
		)
		(fp_line
			(start -0.889 -1.7018)
			(end -0.889 0.2794)
			(stroke
				(width 0.1524)
				(type default)
			)
			(layer "F.SilkS")
		)
		(fp_line
			(start -0.889 0.0762)
			(end -0.889 1.7018)
			(stroke
				(width 0.1524)
				(type default)
			)
			(layer "F.SilkS")
		)
		(fp_line
			(start 0.889 1.7018)
			(end 0.889 -0.508)
			(stroke
				(width 0.1524)
				(type default)
			)
			(layer "F.SilkS")
		)
		(fp_line
			(start -0.889 1.7018)
			(end 0.889 1.7018)
			(stroke
				(width 0.1524)
				(type default)
			)
			(layer "F.SilkS")
		)
		(fp_poly
			(pts
				(xy 0.9652 -1.778) (xy 0.9652 1.778) (xy -0.9652 1.778) (xy -0.9652 -1.778)
			)
			(stroke
				(width 0)
				(type default)
			)
			(fill no)
			(layer "F.CrtYd")
		)
		(fp_rect
			(start -0.9652 1.778)
			(end 0.9652 -1.778)
			(stroke
				(width 0)
				(type default)
			)
			(fill no)
			(layer "F.Fab")
		)
		(pad "1" smd rect
			(at 0 -0.9652 90)
			(size 1.397 1.143)
			(layers "F.Cu" "F.Mask" "F.Paste")
			(net "MB0_12V_CTRL_GATE1")
		)
		(pad "2" smd rect
			(at 0 0.9652 90)
			(size 1.397 1.143)
			(layers "F.Cu" "F.Mask" "F.Paste")
			(net "MB0_CM_GATE_R")
		)
	)
	(footprint ""
		(layer "F.Cu")
		(at 429.549052 -282.872942 -90)
		(property "Reference" "Q54"
			(at 0 0 270)
			(layer "F.SilkS")
			(hide yes)
			(effects
				(font
					(size 1.27 1.27)
				)
			)
		)
		(property "Value" "AO4406AL-GP"
			(at -3.707384 -1.5367 270)
			(unlocked yes)
			(layer "F.Fab")
			(hide yes)
			(effects
				(font
					(size 1.016 1.016)
					(thickness 0.1524)
				)
			)
		)
		(property "Device Type" "SOIC8H69"
			(at -3.707384 -3.0607 270)
			(unlocked yes)
			(layer "F.Fab")
			(hide yes)
			(effects
				(font
					(size 1.016 1.016)
					(thickness 0.1524)
				)
			)
		)
		(duplicate_pad_numbers_are_jumpers no)
		(fp_line
			(start -2.6289 3.4417)
			(end -2.6289 1.4732)
			(stroke
				(width 0.381)
				(type default)
			)
			(layer "F.SilkS")
		)
		(fp_line
			(start -2.7432 1.4224)
			(end -2.6416 1.4224)
			(stroke
				(width 0.1524)
				(type default)
			)
			(layer "F.SilkS")
		)
		(fp_line
			(start -2.7432 1.4224)
			(end 2.1336 1.4224)
			(stroke
				(width 0.1524)
				(type default)
			)
			(layer "F.SilkS")
		)
		(fp_line
			(start 2.1336 1.4224)
			(end 2.1336 -1.4224)
			(stroke
				(width 0.1524)
				(type default)
			)
			(layer "F.SilkS")
		)
		(fp_line
			(start -2.1844 -0.0508)
			(end -2.7178 0.508)
			(stroke
				(width 0.1524)
				(type default)
			)
			(layer "F.SilkS")
		)
		(fp_line
			(start -2.7178 -0.508)
			(end -2.1844 -0.0508)
			(stroke
				(width 0.1524)
				(type default)
			)
			(layer "F.SilkS")
		)
		(fp_line
			(start -2.7432 -1.4224)
			(end -2.7432 1.4224)
			(stroke
				(width 0.1524)
				(type default)
			)
			(layer "F.SilkS")
		)
		(fp_line
			(start 2.1336 -1.4224)
			(end -2.7432 -1.4224)
			(stroke
				(width 0.1524)
				(type default)
			)
			(layer "F.SilkS")
		)
		(fp_poly
			(pts
				(xy -2.2098 -1.4224) (xy -2.2098 1.4224) (xy 2.2098 1.4224) (xy 2.2098 -1.4224)
			)
			(stroke
				(width 0)
				(type default)
			)
			(fill yes)
			(layer "F.SilkS")
		)
		(fp_rect
			(start -2.450084 2.999994)
			(end 2.450084 -2.999994)
			(stroke
				(width 0)
				(type default)
			)
			(fill no)
			(layer "F.CrtYd")
		)
		(fp_poly
			(pts
				(xy -2.8194 3.6322) (xy -2.8194 -3.6322) (xy 2.8194 -3.6322) (xy 2.8194 1.18364) (xy 2.450084 1.18364)
				(xy 2.450084 -2.999994) (xy -2.450084 -2.999994) (xy -2.450084 2.999994) (xy 2.450084 2.999994)
				(xy 2.450084 1.18618) (xy 2.8194 1.18618) (xy 2.8194 3.6322)
			)
			(stroke
				(width 0)
				(type default)
			)
			(fill no)
			(layer "F.CrtYd")
		)
		(fp_rect
			(start -2.8194 3.6322)
			(end 2.8194 -3.6322)
			(stroke
				(width 0)
				(type default)
			)
			(fill no)
			(layer "F.Fab")
		)
		(pad "1" smd rect
			(at -1.905 2.54 270)
			(size 0.635 1.651)
			(layers "F.Cu" "F.Mask" "F.Paste")
			(net "P5V_HDD9")
		)
		(pad "2" smd rect
			(at -0.635 2.54 270)
			(size 0.635 1.651)
			(layers "F.Cu" "F.Mask" "F.Paste")
			(net "P5V_HDD9")
		)
		(pad "3" smd rect
			(at 0.635 2.54 270)
			(size 0.635 1.651)
			(layers "F.Cu" "F.Mask" "F.Paste")
			(net "P5V_HDD9")
		)
		(pad "4" smd rect
			(at 1.905 2.54 270)
			(size 0.635 1.651)
			(layers "F.Cu" "F.Mask" "F.Paste")
			(net "SW_HDD_P9")
		)
		(pad "5" smd rect
			(at 1.905 -2.54 270)
			(size 0.635 1.651)
			(layers "F.Cu" "F.Mask" "F.Paste")
			(net "P5V_A_3")
		)
		(pad "6" smd rect
			(at 0.635 -2.54 270)
			(size 0.635 1.651)
			(layers "F.Cu" "F.Mask" "F.Paste")
			(net "P5V_A_3")
		)
		(pad "7" smd rect
			(at -0.635 -2.54 270)
			(size 0.635 1.651)
			(layers "F.Cu" "F.Mask" "F.Paste")
			(net "P5V_A_3")
		)
		(pad "8" smd rect
			(at -1.905 -2.54 270)
			(size 0.635 1.651)
			(layers "F.Cu" "F.Mask" "F.Paste")
			(net "P5V_A_3")
		)
	)
	(footprint ""
		(layer "F.Cu")
		(at 47.090838 -148.082254 -90)
		(property "Reference" "R1232"
			(at 0 0 270)
			(layer "F.SilkS")
			(hide yes)
			(effects
				(font
					(size 1.27 1.27)
				)
			)
		)
		(property "Value" "200KR2F-L-GP"
			(at 0.064008 -3.993896 270)
			(unlocked yes)
			(layer "F.Fab")
			(hide yes)
			(effects
				(font
					(size 1.016 1.016)
					(thickness 0.1524)
				)
			)
		)
		(property "Device Type" "R402H16"
			(at 0.064008 -5.517896 270)
			(unlocked yes)
			(layer "F.Fab")
			(hide yes)
			(effects
				(font
					(size 1.016 1.016)
					(thickness 0.1524)
				)
			)
		)
		(duplicate_pad_numbers_are_jumpers no)
		(fp_line
			(start -0.508 -0.9398)
			(end -0.508 0.9398)
			(stroke
				(width 0.1524)
				(type default)
			)
			(layer "F.SilkS")
		)
		(fp_line
			(start 0.508 -0.9398)
			(end -0.508 -0.9398)
			(stroke
				(width 0.1524)
				(type default)
			)
			(layer "F.SilkS")
		)
		(fp_rect
			(start -0.508 0.9398)
			(end 0.508 -0.9398)
			(stroke
				(width 0)
				(type default)
			)
			(fill no)
			(layer "F.CrtYd")
		)
		(fp_rect
			(start -0.508 0.9398)
			(end 0.508 -0.9398)
			(stroke
				(width 0)
				(type default)
			)
			(fill no)
			(layer "F.Fab")
		)
		(pad "1" smd custom
			(at 0 -0.4445 270)
			(size 0.1397 0.1397)
			(layers "F.Cu" "F.Mask" "F.Paste")
			(net "P5V_B_MODE")
			(options
				(clearance outline)
				(anchor circle)
			)
			(primitives
				(gr_poly
					(pts
						(arc
							(start -0.1778 -0.2794)
							(mid -0.249642 -0.249642)
							(end -0.2794 -0.1778)
						)
						(arc
							(start -0.2794 0.1778)
							(mid -0.249642 0.249642)
							(end -0.1778 0.2794)
						)
						(arc
							(start 0.1778 0.2794)
							(mid 0.249642 0.249642)
							(end 0.2794 0.1778)
						)
						(arc
							(start 0.2794 -0.1778)
							(mid 0.249642 -0.249642)
							(end 0.1778 -0.2794)
						)
					)
					(width 0)
					(fill yes)
				)
			)
		)
		(pad "2" smd custom
			(at 0 0.4445 270)
			(size 0.1397 0.1397)
			(layers "F.Cu" "F.Mask" "F.Paste")
			(net "P5V_A_2_PGOOD")
			(options
				(clearance outline)
				(anchor circle)
			)
			(primitives
				(gr_poly
					(pts
						(arc
							(start -0.1778 -0.2794)
							(mid -0.249642 -0.249642)
							(end -0.2794 -0.1778)
						)
						(arc
							(start -0.2794 0.1778)
							(mid -0.249642 0.249642)
							(end -0.1778 0.2794)
						)
						(arc
							(start 0.1778 0.2794)
							(mid 0.249642 0.249642)
							(end 0.2794 0.1778)
						)
						(arc
							(start 0.2794 -0.1778)
							(mid 0.249642 -0.249642)
							(end 0.1778 -0.2794)
						)
					)
					(width 0)
					(fill yes)
				)
			)
		)
	)
	(footprint ""
		(layer "F.Cu")
		(at 366.449102 -282.872942 -90)
		(property "Reference" "Q42"
			(at 0 0 270)
			(layer "F.SilkS")
			(hide yes)
			(effects
				(font
					(size 1.27 1.27)
				)
			)
		)
		(property "Value" "AO4406AL-GP"
			(at -3.707384 -1.5367 270)
			(unlocked yes)
			(layer "F.Fab")
			(hide yes)
			(effects
				(font
					(size 1.016 1.016)
					(thickness 0.1524)
				)
			)
		)
		(property "Device Type" "SOIC8H69"
			(at -3.707384 -3.0607 270)
			(unlocked yes)
			(layer "F.Fab")
			(hide yes)
			(effects
				(font
					(size 1.016 1.016)
					(thickness 0.1524)
				)
			)
		)
		(duplicate_pad_numbers_are_jumpers no)
		(fp_line
			(start -2.6289 3.4417)
			(end -2.6289 1.4732)
			(stroke
				(width 0.381)
				(type default)
			)
			(layer "F.SilkS")
		)
		(fp_line
			(start -2.7432 1.4224)
			(end -2.6416 1.4224)
			(stroke
				(width 0.1524)
				(type default)
			)
			(layer "F.SilkS")
		)
		(fp_line
			(start -2.7432 1.4224)
			(end 2.1336 1.4224)
			(stroke
				(width 0.1524)
				(type default)
			)
			(layer "F.SilkS")
		)
		(fp_line
			(start 2.1336 1.4224)
			(end 2.1336 -1.4224)
			(stroke
				(width 0.1524)
				(type default)
			)
			(layer "F.SilkS")
		)
		(fp_line
			(start -2.1844 -0.0508)
			(end -2.7178 0.508)
			(stroke
				(width 0.1524)
				(type default)
			)
			(layer "F.SilkS")
		)
		(fp_line
			(start -2.7178 -0.508)
			(end -2.1844 -0.0508)
			(stroke
				(width 0.1524)
				(type default)
			)
			(layer "F.SilkS")
		)
		(fp_line
			(start -2.7432 -1.4224)
			(end -2.7432 1.4224)
			(stroke
				(width 0.1524)
				(type default)
			)
			(layer "F.SilkS")
		)
		(fp_line
			(start 2.1336 -1.4224)
			(end -2.7432 -1.4224)
			(stroke
				(width 0.1524)
				(type default)
			)
			(layer "F.SilkS")
		)
		(fp_poly
			(pts
				(xy -2.2098 -1.4224) (xy -2.2098 1.4224) (xy 2.2098 1.4224) (xy 2.2098 -1.4224)
			)
			(stroke
				(width 0)
				(type default)
			)
			(fill yes)
			(layer "F.SilkS")
		)
		(fp_rect
			(start -2.450084 2.999994)
			(end 2.450084 -2.999994)
			(stroke
				(width 0)
				(type default)
			)
			(fill no)
			(layer "F.CrtYd")
		)
		(fp_poly
			(pts
				(xy -2.8194 3.6322) (xy -2.8194 -3.6322) (xy 2.8194 -3.6322) (xy 2.8194 1.18364) (xy 2.450084 1.18364)
				(xy 2.450084 -2.999994) (xy -2.450084 -2.999994) (xy -2.450084 2.999994) (xy 2.450084 2.999994)
				(xy 2.450084 1.18618) (xy 2.8194 1.18618) (xy 2.8194 3.6322)
			)
			(stroke
				(width 0)
				(type default)
			)
			(fill no)
			(layer "F.CrtYd")
		)
		(fp_rect
			(start -2.8194 3.6322)
			(end 2.8194 -3.6322)
			(stroke
				(width 0)
				(type default)
			)
			(fill no)
			(layer "F.Fab")
		)
		(pad "1" smd rect
			(at -1.905 2.54 270)
			(size 0.635 1.651)
			(layers "F.Cu" "F.Mask" "F.Paste")
			(net "P5V_HDD7")
		)
		(pad "2" smd rect
			(at -0.635 2.54 270)
			(size 0.635 1.651)
			(layers "F.Cu" "F.Mask" "F.Paste")
			(net "P5V_HDD7")
		)
		(pad "3" smd rect
			(at 0.635 2.54 270)
			(size 0.635 1.651)
			(layers "F.Cu" "F.Mask" "F.Paste")
			(net "P5V_HDD7")
		)
		(pad "4" smd rect
			(at 1.905 2.54 270)
			(size 0.635 1.651)
			(layers "F.Cu" "F.Mask" "F.Paste")
			(net "SW_HDD_P7")
		)
		(pad "5" smd rect
			(at 1.905 -2.54 270)
			(size 0.635 1.651)
			(layers "F.Cu" "F.Mask" "F.Paste")
			(net "P5V_A_3")
		)
		(pad "6" smd rect
			(at 0.635 -2.54 270)
			(size 0.635 1.651)
			(layers "F.Cu" "F.Mask" "F.Paste")
			(net "P5V_A_3")
		)
		(pad "7" smd rect
			(at -0.635 -2.54 270)
			(size 0.635 1.651)
			(layers "F.Cu" "F.Mask" "F.Paste")
			(net "P5V_A_3")
		)
		(pad "8" smd rect
			(at -1.905 -2.54 270)
			(size 0.635 1.651)
			(layers "F.Cu" "F.Mask" "F.Paste")
			(net "P5V_A_3")
		)
	)
	(footprint ""
		(layer "F.Cu")
		(at 67.347846 -292.169342 -90)
		(property "Reference" "R153"
			(at 0 0 270)
			(layer "F.SilkS")
			(hide yes)
			(effects
				(font
					(size 1.27 1.27)
				)
			)
		)
		(property "Value" "10KR2F-2-GP"
			(at 0.064008 -3.993896 270)
			(unlocked yes)
			(layer "F.Fab")
			(hide yes)
			(effects
				(font
					(size 1.016 1.016)
					(thickness 0.1524)
				)
			)
		)
		(property "Device Type" "R402H16"
			(at 0.064008 -5.517896 270)
			(unlocked yes)
			(layer "F.Fab")
			(hide yes)
			(effects
				(font
					(size 1.016 1.016)
					(thickness 0.1524)
				)
			)
		)
		(duplicate_pad_numbers_are_jumpers no)
		(fp_line
			(start -0.508 -0.9398)
			(end -0.508 0.9398)
			(stroke
				(width 0.1524)
				(type default)
			)
			(layer "F.SilkS")
		)
		(fp_line
			(start 0.508 -0.9398)
			(end -0.508 -0.9398)
			(stroke
				(width 0.1524)
				(type default)
			)
			(layer "F.SilkS")
		)
		(fp_rect
			(start -0.508 0.9398)
			(end 0.508 -0.9398)
			(stroke
				(width 0)
				(type default)
			)
			(fill no)
			(layer "F.CrtYd")
		)
		(fp_rect
			(start -0.508 0.9398)
			(end 0.508 -0.9398)
			(stroke
				(width 0)
				(type default)
			)
			(fill no)
			(layer "F.Fab")
		)
		(pad "1" smd custom
			(at 0 -0.4445 270)
			(size 0.1397 0.1397)
			(layers "F.Cu" "F.Mask" "F.Paste")
			(net "P3V3_STBY_A")
			(options
				(clearance outline)
				(anchor circle)
			)
			(primitives
				(gr_poly
					(pts
						(arc
							(start -0.1778 -0.2794)
							(mid -0.249642 -0.249642)
							(end -0.2794 -0.1778)
						)
						(arc
							(start -0.2794 0.1778)
							(mid -0.249642 0.249642)
							(end -0.1778 0.2794)
						)
						(arc
							(start 0.1778 0.2794)
							(mid 0.249642 0.249642)
							(end 0.2794 0.1778)
						)
						(arc
							(start 0.2794 -0.1778)
							(mid 0.249642 -0.249642)
							(end 0.1778 -0.2794)
						)
					)
					(width 0)
					(fill yes)
				)
			)
		)
		(pad "2" smd custom
			(at 0 0.4445 270)
			(size 0.1397 0.1397)
			(layers "F.Cu" "F.Mask" "F.Paste")
			(net "HDD_PRSNT_1")
			(options
				(clearance outline)
				(anchor circle)
			)
			(primitives
				(gr_poly
					(pts
						(arc
							(start -0.1778 -0.2794)
							(mid -0.249642 -0.249642)
							(end -0.2794 -0.1778)
						)
						(arc
							(start -0.2794 0.1778)
							(mid -0.249642 0.249642)
							(end -0.1778 0.2794)
						)
						(arc
							(start 0.1778 0.2794)
							(mid 0.249642 0.249642)
							(end 0.2794 0.1778)
						)
						(arc
							(start 0.2794 -0.1778)
							(mid 0.249642 -0.249642)
							(end 0.1778 -0.2794)
						)
					)
					(width 0)
					(fill yes)
				)
			)
		)
	)
	(footprint ""
		(layer "F.Cu")
		(at 322.549012 -127.360934)
		(property "Reference" "R316"
			(at 0 0 0)
			(layer "F.SilkS")
			(hide yes)
			(effects
				(font
					(size 1.27 1.27)
				)
			)
		)
		(property "Value" "91R3F-1-GP"
			(at -0.0254 -2.5146 0)
			(unlocked yes)
			(layer "F.Fab")
			(hide yes)
			(effects
				(font
					(size 1.016 1.016)
					(thickness 0.1524)
				)
			)
		)
		(property "Device Type" "R603H22"
			(at -0.0254 -4.0386 0)
			(unlocked yes)
			(layer "F.Fab")
			(hide yes)
			(effects
				(font
					(size 1.016 1.016)
					(thickness 0.1524)
				)
			)
		)
		(duplicate_pad_numbers_are_jumpers no)
		(fp_line
			(start -0.4826 0)
			(end -0.2032 0)
			(stroke
				(width 0.2032)
				(type default)
			)
			(layer "F.SilkS")
		)
		(fp_line
			(start 0.2032 0)
			(end 0.4826 0)
			(stroke
				(width 0.2032)
				(type default)
			)
			(layer "F.SilkS")
		)
		(fp_rect
			(start -0.5842 1.3335)
			(end 0.5842 -1.3335)
			(stroke
				(width 0)
				(type default)
			)
			(fill no)
			(layer "F.CrtYd")
		)
		(fp_rect
			(start -0.5842 1.3335)
			(end 0.5842 -1.3335)
			(stroke
				(width 0)
				(type default)
			)
			(fill no)
			(layer "F.Fab")
		)
		(pad "1" smd custom
			(at 0 -0.762)
			(size 0.2159 0.2159)
			(layers "F.Cu" "F.Mask" "F.Paste")
			(net "P5V_A_3")
			(options
				(clearance outline)
				(anchor circle)
			)
			(primitives
				(gr_poly
					(pts
						(arc
							(start -0.3302 -0.4318)
							(mid -0.402042 -0.402042)
							(end -0.4318 -0.3302)
						)
						(arc
							(start -0.4318 0.3302)
							(mid -0.402042 0.402042)
							(end -0.3302 0.4318)
						)
						(arc
							(start 0.3302 0.4318)
							(mid 0.402042 0.402042)
							(end 0.4318 0.3302)
						)
						(arc
							(start 0.4318 -0.3302)
							(mid 0.402042 -0.402042)
							(end 0.3302 -0.4318)
						)
					)
					(width 0)
					(fill yes)
				)
			)
		)
		(pad "2" smd custom
			(at 0 0.762)
			(size 0.2159 0.2159)
			(layers "F.Cu" "F.Mask" "F.Paste")
			(net "DRV_ACT_18")
			(options
				(clearance outline)
				(anchor circle)
			)
			(primitives
				(gr_poly
					(pts
						(arc
							(start -0.3302 -0.4318)
							(mid -0.402042 -0.402042)
							(end -0.4318 -0.3302)
						)
						(arc
							(start -0.4318 0.3302)
							(mid -0.402042 0.402042)
							(end -0.3302 0.4318)
						)
						(arc
							(start 0.3302 0.4318)
							(mid 0.402042 0.402042)
							(end 0.4318 0.3302)
						)
						(arc
							(start 0.4318 -0.3302)
							(mid 0.402042 -0.402042)
							(end 0.3302 -0.4318)
						)
					)
					(width 0)
					(fill yes)
				)
			)
		)
	)
	(footprint ""
		(layer "F.Cu")
		(at 114.724942 -280.498804 90)
		(property "Reference" "R215"
			(at 0 0 90)
			(layer "F.SilkS")
			(hide yes)
			(effects
				(font
					(size 1.27 1.27)
				)
			)
		)
		(property "Value" "200KR2F-L-GP"
			(at 0.064008 -3.993896 90)
			(unlocked yes)
			(layer "F.Fab")
			(hide yes)
			(effects
				(font
					(size 1.016 1.016)
					(thickness 0.1524)
				)
			)
		)
		(property "Device Type" "R402H16"
			(at 0.064008 -5.517896 90)
			(unlocked yes)
			(layer "F.Fab")
			(hide yes)
			(effects
				(font
					(size 1.016 1.016)
					(thickness 0.1524)
				)
			)
		)
		(duplicate_pad_numbers_are_jumpers no)
		(fp_line
			(start 0.508 -0.9398)
			(end -0.508 -0.9398)
			(stroke
				(width 0.1524)
				(type default)
			)
			(layer "F.SilkS")
		)
		(fp_line
			(start -0.508 -0.9398)
			(end -0.508 0.9398)
			(stroke
				(width 0.1524)
				(type default)
			)
			(layer "F.SilkS")
		)
		(fp_rect
			(start -0.508 0.9398)
			(end 0.508 -0.9398)
			(stroke
				(width 0)
				(type default)
			)
			(fill no)
			(layer "F.CrtYd")
		)
		(fp_rect
			(start -0.508 0.9398)
			(end 0.508 -0.9398)
			(stroke
				(width 0)
				(type default)
			)
			(fill no)
			(layer "F.Fab")
		)
		(pad "1" smd custom
			(at 0 -0.4445 90)
			(size 0.1397 0.1397)
			(layers "F.Cu" "F.Mask" "F.Paste")
			(net "SW_HDD_R3")
			(options
				(clearance outline)
				(anchor circle)
			)
			(primitives
				(gr_poly
					(pts
						(arc
							(start -0.1778 -0.2794)
							(mid -0.249642 -0.249642)
							(end -0.2794 -0.1778)
						)
						(arc
							(start -0.2794 0.1778)
							(mid -0.249642 0.249642)
							(end -0.1778 0.2794)
						)
						(arc
							(start 0.1778 0.2794)
							(mid 0.249642 0.249642)
							(end 0.2794 0.1778)
						)
						(arc
							(start 0.2794 -0.1778)
							(mid 0.249642 -0.249642)
							(end 0.1778 -0.2794)
						)
					)
					(width 0)
					(fill yes)
				)
			)
		)
		(pad "2" smd custom
			(at 0 0.4445 90)
			(size 0.1397 0.1397)
			(layers "F.Cu" "F.Mask" "F.Paste")
			(net "SW_HDD_N3")
			(options
				(clearance outline)
				(anchor circle)
			)
			(primitives
				(gr_poly
					(pts
						(arc
							(start -0.1778 -0.2794)
							(mid -0.249642 -0.249642)
							(end -0.2794 -0.1778)
						)
						(arc
							(start -0.2794 0.1778)
							(mid -0.249642 0.249642)
							(end -0.1778 0.2794)
						)
						(arc
							(start 0.1778 0.2794)
							(mid 0.249642 0.249642)
							(end 0.2794 0.1778)
						)
						(arc
							(start 0.2794 -0.1778)
							(mid 0.249642 -0.249642)
							(end 0.1778 -0.2794)
						)
					)
					(width 0)
					(fill yes)
				)
			)
		)
	)
	(footprint ""
		(layer "F.Cu")
		(at 241.68735 -349.162878 180)
		(property "Reference" "R25"
			(at 0 0 180)
			(layer "F.SilkS")
			(hide yes)
			(effects
				(font
					(size 1.27 1.27)
				)
			)
		)
		(property "Value" "16K2R2F-GP"
			(at 0.064008 -3.993896 180)
			(unlocked yes)
			(layer "F.Fab")
			(hide yes)
			(effects
				(font
					(size 1.016 1.016)
					(thickness 0.1524)
				)
			)
		)
		(property "Device Type" "R402H16"
			(at 0.064008 -5.517896 180)
			(unlocked yes)
			(layer "F.Fab")
			(hide yes)
			(effects
				(font
					(size 1.016 1.016)
					(thickness 0.1524)
				)
			)
		)
		(duplicate_pad_numbers_are_jumpers no)
		(fp_line
			(start 0.508 -0.9398)
			(end -0.508 -0.9398)
			(stroke
				(width 0.1524)
				(type default)
			)
			(layer "F.SilkS")
		)
		(fp_line
			(start -0.508 -0.9398)
			(end -0.508 0.9398)
			(stroke
				(width 0.1524)
				(type default)
			)
			(layer "F.SilkS")
		)
		(fp_rect
			(start -0.508 0.9398)
			(end 0.508 -0.9398)
			(stroke
				(width 0)
				(type default)
			)
			(fill no)
			(layer "F.CrtYd")
		)
		(fp_rect
			(start -0.508 0.9398)
			(end 0.508 -0.9398)
			(stroke
				(width 0)
				(type default)
			)
			(fill no)
			(layer "F.Fab")
		)
		(pad "1" smd custom
			(at 0 -0.4445 180)
			(size 0.1397 0.1397)
			(layers "F.Cu" "F.Mask" "F.Paste")
			(net "P5V_A_1")
			(options
				(clearance outline)
				(anchor circle)
			)
			(primitives
				(gr_poly
					(pts
						(arc
							(start -0.1778 -0.2794)
							(mid -0.249642 -0.249642)
							(end -0.2794 -0.1778)
						)
						(arc
							(start -0.2794 0.1778)
							(mid -0.249642 0.249642)
							(end -0.1778 0.2794)
						)
						(arc
							(start 0.1778 0.2794)
							(mid 0.249642 0.249642)
							(end 0.2794 0.1778)
						)
						(arc
							(start 0.2794 -0.1778)
							(mid 0.249642 -0.249642)
							(end 0.1778 -0.2794)
						)
					)
					(width 0)
					(fill yes)
				)
			)
		)
		(pad "2" smd custom
			(at 0 0.4445 180)
			(size 0.1397 0.1397)
			(layers "F.Cu" "F.Mask" "F.Paste")
			(net "P5V_A_1_SENSE")
			(options
				(clearance outline)
				(anchor circle)
			)
			(primitives
				(gr_poly
					(pts
						(arc
							(start -0.1778 -0.2794)
							(mid -0.249642 -0.249642)
							(end -0.2794 -0.1778)
						)
						(arc
							(start -0.2794 0.1778)
							(mid -0.249642 0.249642)
							(end -0.1778 0.2794)
						)
						(arc
							(start 0.1778 0.2794)
							(mid 0.249642 0.249642)
							(end 0.2794 0.1778)
						)
						(arc
							(start 0.2794 -0.1778)
							(mid 0.249642 -0.249642)
							(end 0.1778 -0.2794)
						)
					)
					(width 0)
					(fill yes)
				)
			)
		)
	)
	(footprint ""
		(layer "F.Cu")
		(at 231.267 -236.982 180)
		(property "Reference" "U7"
			(at 0 0 180)
			(layer "F.SilkS")
			(hide yes)
			(effects
				(font
					(size 1.27 1.27)
				)
			)
		)
		(property "Value" "TCA9555PWR-GP"
			(at 0 -6.9342 180)
			(unlocked yes)
			(layer "F.Fab")
			(hide yes)
			(effects
				(font
					(size 1.016 1.016)
					(thickness 0.1524)
				)
			)
		)
		(property "Device Type" "TSOIC24H48"
			(at 0 -8.5852 180)
			(unlocked yes)
			(layer "F.Fab")
			(hide yes)
			(effects
				(font
					(size 1.016 1.016)
					(thickness 0.1524)
				)
			)
		)
		(duplicate_pad_numbers_are_jumpers no)
		(fp_line
			(start 3.81 1.397)
			(end -4.2291 1.397)
			(stroke
				(width 0.1524)
				(type default)
			)
			(layer "F.SilkS")
		)
		(fp_line
			(start 3.81 -1.397)
			(end 3.81 1.397)
			(stroke
				(width 0.1524)
				(type default)
			)
			(layer "F.SilkS")
		)
		(fp_line
			(start -3.429 0)
			(end -4.2291 0.8001)
			(stroke
				(width 0.1524)
				(type default)
			)
			(layer "F.SilkS")
		)
		(fp_line
			(start -4.22656 3.81)
			(end -4.2291 1.397)
			(stroke
				(width 0.508)
				(type default)
			)
			(layer "F.SilkS")
		)
		(fp_line
			(start -4.2291 3.937)
			(end -4.2291 -1.397)
			(stroke
				(width 0.1524)
				(type default)
			)
			(layer "F.SilkS")
		)
		(fp_line
			(start -4.2291 -0.8001)
			(end -3.429 0)
			(stroke
				(width 0.1524)
				(type default)
			)
			(layer "F.SilkS")
		)
		(fp_line
			(start -4.2291 -1.397)
			(end 3.81 -1.397)
			(stroke
				(width 0.1524)
				(type default)
			)
			(layer "F.SilkS")
		)
		(fp_poly
			(pts
				(xy -3.90652 -1.8542) (xy 3.90652 -1.8542) (xy 3.90652 1.8542) (xy -3.90652 1.8542)
			)
			(stroke
				(width 0)
				(type default)
			)
			(fill yes)
			(layer "F.SilkS")
		)
		(fp_poly
			(pts
				(xy -4.2164 3.81) (xy 4.2164 3.81) (xy 4.22656 -3.81) (xy -4.2164 -3.81)
			)
			(stroke
				(width 0)
				(type default)
			)
			(fill no)
			(layer "F.CrtYd")
		)
		(fp_poly
			(pts
				(xy -4.22656 -3.81) (xy 4.22656 -3.81) (xy 4.22656 3.81) (xy -4.22656 3.81)
			)
			(stroke
				(width 0)
				(type default)
			)
			(fill no)
			(layer "F.Fab")
		)
		(pad "1" smd rect
			(at -3.57632 2.8194 180)
			(size 0.3556 1.524)
			(layers "F.Cu" "F.Mask" "F.Paste")
			(net "IO_EXP1_INT_N")
		)
		(pad "2" smd rect
			(at -2.92608 2.8194 180)
			(size 0.3556 1.524)
			(layers "F.Cu" "F.Mask" "F.Paste")
			(net "IO_EXP1_A1")
		)
		(pad "3" smd rect
			(at -2.27584 2.8194 180)
			(size 0.3556 1.524)
			(layers "F.Cu" "F.Mask" "F.Paste")
			(net "IO_EXP1_A2")
		)
		(pad "4" smd rect
			(at -1.6256 2.8194 180)
			(size 0.3556 1.524)
			(layers "F.Cu" "F.Mask" "F.Paste")
			(net "DRIVE_A_0_PWR")
		)
		(pad "5" smd rect
			(at -0.97536 2.8194 180)
			(size 0.3556 1.524)
			(layers "F.Cu" "F.Mask" "F.Paste")
			(net "DRIVE_A_1_PWR")
		)
		(pad "6" smd rect
			(at -0.32512 2.8194 180)
			(size 0.3556 1.524)
			(layers "F.Cu" "F.Mask" "F.Paste")
			(net "DRIVE_A_2_PWR")
		)
		(pad "7" smd rect
			(at 0.32512 2.8194 180)
			(size 0.3556 1.524)
			(layers "F.Cu" "F.Mask" "F.Paste")
			(net "DRIVE_A_3_PWR")
		)
		(pad "8" smd rect
			(at 0.97536 2.8194 180)
			(size 0.3556 1.524)
			(layers "F.Cu" "F.Mask" "F.Paste")
			(net "DRIVE_A_4_PWR")
		)
		(pad "9" smd rect
			(at 1.6256 2.8194 180)
			(size 0.3556 1.524)
			(layers "F.Cu" "F.Mask" "F.Paste")
			(net "DRIVE_A_5_PWR")
		)
		(pad "10" smd rect
			(at 2.27584 2.8194 180)
			(size 0.3556 1.524)
			(layers "F.Cu" "F.Mask" "F.Paste")
			(net "DRIVE_A_6_PWR")
		)
		(pad "11" smd rect
			(at 2.92608 2.8194 180)
			(size 0.3556 1.524)
			(layers "F.Cu" "F.Mask" "F.Paste")
			(net "DRIVE_A_7_PWR")
		)
		(pad "12" smd rect
			(at 3.57632 2.8194 180)
			(size 0.3556 1.524)
			(layers "F.Cu" "F.Mask" "F.Paste")
			(net "GND")
		)
		(pad "13" smd rect
			(at 3.57632 -2.8194 180)
			(size 0.3556 1.524)
			(layers "F.Cu" "F.Mask" "F.Paste")
			(net "DRIVE_A_8_PWR")
		)
		(pad "14" smd rect
			(at 2.92608 -2.8194 180)
			(size 0.3556 1.524)
			(layers "F.Cu" "F.Mask" "F.Paste")
			(net "DRIVE_A_9_PWR")
		)
		(pad "15" smd rect
			(at 2.27584 -2.8194 180)
			(size 0.3556 1.524)
			(layers "F.Cu" "F.Mask" "F.Paste")
			(net "DRIVE_A_10_PWR")
		)
		(pad "16" smd rect
			(at 1.6256 -2.8194 180)
			(size 0.3556 1.524)
			(layers "F.Cu" "F.Mask" "F.Paste")
			(net "DRIVE_A_11_PWR")
		)
		(pad "17" smd rect
			(at 0.97536 -2.8194 180)
			(size 0.3556 1.524)
			(layers "F.Cu" "F.Mask" "F.Paste")
			(net "DRIVE_A_12_PWR")
		)
		(pad "18" smd rect
			(at 0.32512 -2.8194 180)
			(size 0.3556 1.524)
			(layers "F.Cu" "F.Mask" "F.Paste")
			(net "DRIVE_A_13_PWR")
		)
		(pad "19" smd rect
			(at -0.32512 -2.8194 180)
			(size 0.3556 1.524)
			(layers "F.Cu" "F.Mask" "F.Paste")
			(net "DRIVE_A_14_PWR")
		)
		(pad "20" smd rect
			(at -0.97536 -2.8194 180)
			(size 0.3556 1.524)
			(layers "F.Cu" "F.Mask" "F.Paste")
			(net "DRIVE_A_15_PWR")
		)
		(pad "21" smd rect
			(at -1.6256 -2.8194 180)
			(size 0.3556 1.524)
			(layers "F.Cu" "F.Mask" "F.Paste")
			(net "IO_EXP1_A0")
		)
		(pad "22" smd rect
			(at -2.27584 -2.8194 180)
			(size 0.3556 1.524)
			(layers "F.Cu" "F.Mask" "F.Paste")
			(net "IO_EXP1_SCL")
		)
		(pad "23" smd rect
			(at -2.92608 -2.8194 180)
			(size 0.3556 1.524)
			(layers "F.Cu" "F.Mask" "F.Paste")
			(net "IO_EXP1_SDA")
		)
		(pad "24" smd rect
			(at -3.57632 -2.8194 180)
			(size 0.3556 1.524)
			(layers "F.Cu" "F.Mask" "F.Paste")
			(net "GPIO_VCC_U7")
		)
	)
	(footprint ""
		(layer "F.Cu")
		(at 134.460996 -291.077142 90)
		(property "Reference" "C80"
			(at 0 0 90)
			(layer "F.SilkS")
			(hide yes)
			(effects
				(font
					(size 1.27 1.27)
				)
			)
		)
		(property "Value" "SC10U16V6KX-2GP"
			(at -0.0762 -5.1308 90)
			(unlocked yes)
			(layer "F.Fab")
			(hide yes)
			(effects
				(font
					(size 1.016 1.016)
					(thickness 0.1524)
				)
			)
		)
		(property "Device Type" "C1206H71"
			(at -0.127 -6.6548 90)
			(unlocked yes)
			(layer "F.Fab")
			(hide yes)
			(effects
				(font
					(size 1.016 1.016)
					(thickness 0.1524)
				)
			)
		)
		(duplicate_pad_numbers_are_jumpers no)
		(fp_line
			(start 1.016 -2.2352)
			(end 1.016 -0.8382)
			(stroke
				(width 0.1524)
				(type default)
			)
			(layer "F.SilkS")
		)
		(fp_line
			(start -1.016 -2.2352)
			(end 1.016 -2.2352)
			(stroke
				(width 0.1524)
				(type default)
			)
			(layer "F.SilkS")
		)
		(fp_line
			(start -1.016 -0.8382)
			(end -1.016 -2.2352)
			(stroke
				(width 0.1524)
				(type default)
			)
			(layer "F.SilkS")
		)
		(fp_line
			(start 1.016 0.8382)
			(end 1.016 2.2352)
			(stroke
				(width 0.1524)
				(type default)
			)
			(layer "F.SilkS")
		)
		(fp_line
			(start 1.016 2.2352)
			(end -1.016 2.2352)
			(stroke
				(width 0.1524)
				(type default)
			)
			(layer "F.SilkS")
		)
		(fp_line
			(start -1.016 2.2352)
			(end -1.016 0.8382)
			(stroke
				(width 0.1524)
				(type default)
			)
			(layer "F.SilkS")
		)
		(fp_rect
			(start -1.0922 2.3114)
			(end 1.0922 -2.3114)
			(stroke
				(width 0)
				(type default)
			)
			(fill no)
			(layer "F.CrtYd")
		)
		(fp_poly
			(pts
				(xy 1.0922 -2.3114) (xy 1.0922 2.3114) (xy -1.0922 2.3114) (xy -1.0922 -2.3114)
			)
			(stroke
				(width 0)
				(type default)
			)
			(fill no)
			(layer "F.Fab")
		)
		(pad "1" smd rect
			(at 0 -1.397 90)
			(size 1.651 1.27)
			(layers "F.Cu" "F.Mask" "F.Paste")
			(net "P5V_HDD3")
		)
		(pad "2" smd rect
			(at 0 1.397 90)
			(size 1.651 1.27)
			(layers "F.Cu" "F.Mask" "F.Paste")
			(net "GND")
		)
	)
	(footprint ""
		(layer "F.Cu")
		(at 458.299058 -245.269004 -90)
		(property "Reference" "R500"
			(at 0 0 270)
			(layer "F.SilkS")
			(hide yes)
			(effects
				(font
					(size 1.27 1.27)
				)
			)
		)
		(property "Value" "4K7R2J-2-GP"
			(at 0.064008 -3.993896 270)
			(unlocked yes)
			(layer "F.Fab")
			(hide yes)
			(effects
				(font
					(size 1.016 1.016)
					(thickness 0.1524)
				)
			)
		)
		(property "Device Type" "R402H16"
			(at 0.064008 -5.517896 270)
			(unlocked yes)
			(layer "F.Fab")
			(hide yes)
			(effects
				(font
					(size 1.016 1.016)
					(thickness 0.1524)
				)
			)
		)
		(duplicate_pad_numbers_are_jumpers no)
		(fp_line
			(start -0.508 -0.9398)
			(end -0.508 0.9398)
			(stroke
				(width 0.1524)
				(type default)
			)
			(layer "F.SilkS")
		)
		(fp_line
			(start 0.508 -0.9398)
			(end -0.508 -0.9398)
			(stroke
				(width 0.1524)
				(type default)
			)
			(layer "F.SilkS")
		)
		(fp_rect
			(start -0.508 0.9398)
			(end 0.508 -0.9398)
			(stroke
				(width 0)
				(type default)
			)
			(fill no)
			(layer "F.CrtYd")
		)
		(fp_rect
			(start -0.508 0.9398)
			(end 0.508 -0.9398)
			(stroke
				(width 0)
				(type default)
			)
			(fill no)
			(layer "F.Fab")
		)
		(pad "1" smd custom
			(at 0 -0.4445 270)
			(size 0.1397 0.1397)
			(layers "F.Cu" "F.Mask" "F.Paste")
			(net "DRIVE_A_11_FLT_LED")
			(options
				(clearance outline)
				(anchor circle)
			)
			(primitives
				(gr_poly
					(pts
						(arc
							(start -0.1778 -0.2794)
							(mid -0.249642 -0.249642)
							(end -0.2794 -0.1778)
						)
						(arc
							(start -0.2794 0.1778)
							(mid -0.249642 0.249642)
							(end -0.1778 0.2794)
						)
						(arc
							(start 0.1778 0.2794)
							(mid 0.249642 0.249642)
							(end 0.2794 0.1778)
						)
						(arc
							(start 0.2794 -0.1778)
							(mid 0.249642 -0.249642)
							(end 0.1778 -0.2794)
						)
					)
					(width 0)
					(fill yes)
				)
			)
		)
		(pad "2" smd custom
			(at 0 0.4445 270)
			(size 0.1397 0.1397)
			(layers "F.Cu" "F.Mask" "F.Paste")
			(net "GND")
			(options
				(clearance outline)
				(anchor circle)
			)
			(primitives
				(gr_poly
					(pts
						(arc
							(start -0.1778 -0.2794)
							(mid -0.249642 -0.249642)
							(end -0.2794 -0.1778)
						)
						(arc
							(start -0.2794 0.1778)
							(mid -0.249642 0.249642)
							(end -0.1778 0.2794)
						)
						(arc
							(start 0.1778 0.2794)
							(mid 0.249642 0.249642)
							(end 0.2794 0.1778)
						)
						(arc
							(start 0.2794 -0.1778)
							(mid 0.249642 -0.249642)
							(end 0.1778 -0.2794)
						)
					)
					(width 0)
					(fill yes)
				)
			)
		)
	)
	(footprint ""
		(layer "F.Cu")
		(at 115.080796 -163.554918 180)
		(property "Reference" "Q91"
			(at 0 0 180)
			(layer "F.SilkS")
			(hide yes)
			(effects
				(font
					(size 1.27 1.27)
				)
			)
		)
		(property "Value" "2N7002KDW-GP"
			(at -2.3622 -8.2042 180)
			(unlocked yes)
			(layer "F.Fab")
			(hide yes)
			(effects
				(font
					(size 1.016 1.016)
					(thickness 0.1524)
				)
			)
		)
		(property "Device Type" "SOT-363H44"
			(at -2.3622 -10.1092 180)
			(unlocked yes)
			(layer "F.Fab")
			(hide yes)
			(effects
				(font
					(size 1.016 1.016)
					(thickness 0.1524)
				)
			)
		)
		(duplicate_pad_numbers_are_jumpers no)
		(fp_line
			(start 1.4478 1.7018)
			(end 1.4478 -1.7018)
			(stroke
				(width 0.1524)
				(type default)
			)
			(layer "F.SilkS")
		)
		(fp_line
			(start 1.4478 -1.7018)
			(end -1.4478 -1.7018)
			(stroke
				(width 0.1524)
				(type default)
			)
			(layer "F.SilkS")
		)
		(fp_line
			(start -1.27 1.524)
			(end -1.27 0.6604)
			(stroke
				(width 0.4826)
				(type default)
			)
			(layer "F.SilkS")
		)
		(fp_line
			(start -1.4478 1.7018)
			(end 1.4478 1.7018)
			(stroke
				(width 0.1524)
				(type default)
			)
			(layer "F.SilkS")
		)
		(fp_line
			(start -1.4478 -1.7018)
			(end -1.4478 1.7018)
			(stroke
				(width 0.1524)
				(type default)
			)
			(layer "F.SilkS")
		)
		(fp_poly
			(pts
				(xy -1.524 -1.778) (xy 1.524 -1.778) (xy 1.524 1.778) (xy -1.524 1.778)
			)
			(stroke
				(width 0)
				(type default)
			)
			(fill no)
			(layer "F.CrtYd")
		)
		(fp_poly
			(pts
				(xy -1.524 -1.778) (xy 1.524 -1.778) (xy 1.524 1.778) (xy -1.524 1.778)
			)
			(stroke
				(width 0)
				(type default)
			)
			(fill no)
			(layer "F.Fab")
		)
		(pad "1" smd rect
			(at -0.65024 0.9398 180)
			(size 0.4064 1.016)
			(layers "F.Cu" "F.Mask" "F.Paste")
			(net "GND")
		)
		(pad "2" smd rect
			(at 0 0.9398 180)
			(size 0.4064 1.016)
			(layers "F.Cu" "F.Mask" "F.Paste")
			(net "SW_PWR_R_HDD15")
		)
		(pad "3" smd rect
			(at 0.65024 0.9398 180)
			(size 0.4064 1.016)
			(layers "F.Cu" "F.Mask" "F.Paste")
			(net "SW_HDD_P15")
		)
		(pad "4" smd rect
			(at 0.65024 -0.9398 180)
			(size 0.4064 1.016)
			(layers "F.Cu" "F.Mask" "F.Paste")
			(net "GND")
		)
		(pad "5" smd rect
			(at 0 -0.9398 180)
			(size 0.4064 1.016)
			(layers "F.Cu" "F.Mask" "F.Paste")
			(net "SW_HDD_G15")
		)
		(pad "6" smd rect
			(at -0.65024 -0.9398 180)
			(size 0.4064 1.016)
			(layers "F.Cu" "F.Mask" "F.Paste")
			(net "SW_HDD_R15")
		)
	)
	(footprint ""
		(layer "F.Cu")
		(at 346.005912 -137.746994 90)
		(property "Reference" "R1102"
			(at 0 0 90)
			(layer "F.SilkS")
			(hide yes)
			(effects
				(font
					(size 1.27 1.27)
				)
			)
		)
		(property "Value" "1KR2F-3-GP"
			(at 0.064008 -3.993896 90)
			(unlocked yes)
			(layer "F.Fab")
			(hide yes)
			(effects
				(font
					(size 1.016 1.016)
					(thickness 0.1524)
				)
			)
		)
		(property "Device Type" "R402H16"
			(at 0.064008 -5.517896 90)
			(unlocked yes)
			(layer "F.Fab")
			(hide yes)
			(effects
				(font
					(size 1.016 1.016)
					(thickness 0.1524)
				)
			)
		)
		(duplicate_pad_numbers_are_jumpers no)
		(fp_line
			(start 0.508 -0.9398)
			(end -0.508 -0.9398)
			(stroke
				(width 0.1524)
				(type default)
			)
			(layer "F.SilkS")
		)
		(fp_line
			(start -0.508 -0.9398)
			(end -0.508 0.9398)
			(stroke
				(width 0.1524)
				(type default)
			)
			(layer "F.SilkS")
		)
		(fp_rect
			(start -0.508 0.9398)
			(end 0.508 -0.9398)
			(stroke
				(width 0)
				(type default)
			)
			(fill no)
			(layer "F.CrtYd")
		)
		(fp_rect
			(start -0.508 0.9398)
			(end 0.508 -0.9398)
			(stroke
				(width 0)
				(type default)
			)
			(fill no)
			(layer "F.Fab")
		)
		(pad "1" smd custom
			(at 0 -0.4445 90)
			(size 0.1397 0.1397)
			(layers "F.Cu" "F.Mask" "F.Paste")
			(net "MB1_CM_VOUT_R")
			(options
				(clearance outline)
				(anchor circle)
			)
			(primitives
				(gr_poly
					(pts
						(arc
							(start -0.1778 -0.2794)
							(mid -0.249642 -0.249642)
							(end -0.2794 -0.1778)
						)
						(arc
							(start -0.2794 0.1778)
							(mid -0.249642 0.249642)
							(end -0.1778 0.2794)
						)
						(arc
							(start 0.1778 0.2794)
							(mid 0.249642 0.249642)
							(end 0.2794 0.1778)
						)
						(arc
							(start 0.2794 -0.1778)
							(mid 0.249642 -0.249642)
							(end 0.1778 -0.2794)
						)
					)
					(width 0)
					(fill yes)
				)
			)
		)
		(pad "2" smd custom
			(at 0 0.4445 90)
			(size 0.1397 0.1397)
			(layers "F.Cu" "F.Mask" "F.Paste")
			(net "P12V_B_COMP")
			(options
				(clearance outline)
				(anchor circle)
			)
			(primitives
				(gr_poly
					(pts
						(arc
							(start -0.1778 -0.2794)
							(mid -0.249642 -0.249642)
							(end -0.2794 -0.1778)
						)
						(arc
							(start -0.2794 0.1778)
							(mid -0.249642 0.249642)
							(end -0.1778 0.2794)
						)
						(arc
							(start 0.1778 0.2794)
							(mid 0.249642 0.249642)
							(end 0.2794 0.1778)
						)
						(arc
							(start 0.2794 -0.1778)
							(mid 0.249642 -0.249642)
							(end 0.1778 -0.2794)
						)
					)
					(width 0)
					(fill yes)
				)
			)
		)
	)
	(footprint ""
		(layer "F.Cu")
		(at 224.028 -365.125 180)
		(property "Reference" "R171"
			(at 0 0 180)
			(layer "F.SilkS")
			(hide yes)
			(effects
				(font
					(size 1.27 1.27)
				)
			)
		)
		(property "Value" "4K7R2F-GP"
			(at 0.064008 -3.993896 180)
			(unlocked yes)
			(layer "F.Fab")
			(hide yes)
			(effects
				(font
					(size 1.016 1.016)
					(thickness 0.1524)
				)
			)
		)
		(property "Device Type" "R402H16"
			(at 0.064008 -5.517896 180)
			(unlocked yes)
			(layer "F.Fab")
			(hide yes)
			(effects
				(font
					(size 1.016 1.016)
					(thickness 0.1524)
				)
			)
		)
		(duplicate_pad_numbers_are_jumpers no)
		(fp_line
			(start 0.508 -0.9398)
			(end -0.508 -0.9398)
			(stroke
				(width 0.1524)
				(type default)
			)
			(layer "F.SilkS")
		)
		(fp_line
			(start -0.508 -0.9398)
			(end -0.508 0.9398)
			(stroke
				(width 0.1524)
				(type default)
			)
			(layer "F.SilkS")
		)
		(fp_rect
			(start -0.508 0.9398)
			(end 0.508 -0.9398)
			(stroke
				(width 0)
				(type default)
			)
			(fill no)
			(layer "F.CrtYd")
		)
		(fp_rect
			(start -0.508 0.9398)
			(end 0.508 -0.9398)
			(stroke
				(width 0)
				(type default)
			)
			(fill no)
			(layer "F.Fab")
		)
		(pad "1" smd custom
			(at 0 -0.4445 180)
			(size 0.1397 0.1397)
			(layers "F.Cu" "F.Mask" "F.Paste")
			(net "P3V3_STBY_B")
			(options
				(clearance outline)
				(anchor circle)
			)
			(primitives
				(gr_poly
					(pts
						(arc
							(start -0.1778 -0.2794)
							(mid -0.249642 -0.249642)
							(end -0.2794 -0.1778)
						)
						(arc
							(start -0.2794 0.1778)
							(mid -0.249642 0.249642)
							(end -0.1778 0.2794)
						)
						(arc
							(start 0.1778 0.2794)
							(mid 0.249642 0.249642)
							(end 0.2794 0.1778)
						)
						(arc
							(start 0.2794 -0.1778)
							(mid 0.249642 -0.249642)
							(end 0.1778 -0.2794)
						)
					)
					(width 0)
					(fill yes)
				)
			)
		)
		(pad "2" smd custom
			(at 0 0.4445 180)
			(size 0.1397 0.1397)
			(layers "F.Cu" "F.Mask" "F.Paste")
			(net "IO_EXP3_HDD_FAULT_A2")
			(options
				(clearance outline)
				(anchor circle)
			)
			(primitives
				(gr_poly
					(pts
						(arc
							(start -0.1778 -0.2794)
							(mid -0.249642 -0.249642)
							(end -0.2794 -0.1778)
						)
						(arc
							(start -0.2794 0.1778)
							(mid -0.249642 0.249642)
							(end -0.1778 0.2794)
						)
						(arc
							(start 0.1778 0.2794)
							(mid 0.249642 0.249642)
							(end 0.2794 0.1778)
						)
						(arc
							(start 0.2794 -0.1778)
							(mid 0.249642 -0.249642)
							(end 0.1778 -0.2794)
						)
					)
					(width 0)
					(fill yes)
				)
			)
		)
	)
	(footprint ""
		(layer "F.Cu")
		(at 132.675884 -185.106564)
		(property "Reference" "Q267"
			(at 0 0 0)
			(layer "F.SilkS")
			(hide yes)
			(effects
				(font
					(size 1.27 1.27)
				)
			)
		)
		(property "Value" "SSM3K324R-GP"
			(at 0.127 -8.9662 0)
			(unlocked yes)
			(layer "F.Fab")
			(hide yes)
			(effects
				(font
					(size 1.016 1.016)
					(thickness 0.1524)
				)
			)
		)
		(property "Device Type" "SOT23DGS2D4H35"
			(at 0.127 -10.4902 0)
			(unlocked yes)
			(layer "F.Fab")
			(hide yes)
			(effects
				(font
					(size 1.016 1.016)
					(thickness 0.1524)
				)
			)
		)
		(duplicate_pad_numbers_are_jumpers no)
		(fp_line
			(start -1.651 -1.778)
			(end -1.651 1.778)
			(stroke
				(width 0.1524)
				(type default)
			)
			(layer "F.SilkS")
		)
		(fp_line
			(start -1.651 1.778)
			(end 1.651 1.778)
			(stroke
				(width 0.1524)
				(type default)
			)
			(layer "F.SilkS")
		)
		(fp_line
			(start 1.651 -1.778)
			(end -1.651 -1.778)
			(stroke
				(width 0.1524)
				(type default)
			)
			(layer "F.SilkS")
		)
		(fp_line
			(start 1.651 1.778)
			(end 1.651 -1.778)
			(stroke
				(width 0.1524)
				(type default)
			)
			(layer "F.SilkS")
		)
		(fp_poly
			(pts
				(xy -1.778 1.8796) (xy -1.778 -1.8796) (xy 1.778 -1.8796) (xy 1.778 1.8796)
			)
			(stroke
				(width 0)
				(type default)
			)
			(fill no)
			(layer "F.CrtYd")
		)
		(fp_poly
			(pts
				(xy -1.778 1.8796) (xy -1.778 -1.8796) (xy 1.778 -1.8796) (xy 1.778 1.8796)
			)
			(stroke
				(width 0)
				(type default)
			)
			(fill no)
			(layer "F.Fab")
		)
		(pad "D" smd custom
			(at 0 -0.9525)
			(size 0.1905 0.1905)
			(layers "F.Cu" "F.Mask" "F.Paste")
			(net "DRV_ACT_4_N")
			(options
				(clearance outline)
				(anchor circle)
			)
			(primitives
				(gr_poly
					(pts
						(arc
							(start -0.1778 0.5715)
							(mid -0.321484 0.511984)
							(end -0.381 0.3683)
						)
						(arc
							(start -0.381 -0.3683)
							(mid -0.321484 -0.511984)
							(end -0.1778 -0.5715)
						)
						(arc
							(start 0.1778 -0.5715)
							(mid 0.321484 -0.511984)
							(end 0.381 -0.3683)
						)
						(arc
							(start 0.381 0.3683)
							(mid 0.321484 0.511984)
							(end 0.1778 0.5715)
						)
					)
					(width 0)
					(fill yes)
				)
			)
		)
		(pad "G" smd custom
			(at -0.98425 0.9525)
			(size 0.1905 0.1905)
			(layers "F.Cu" "F.Mask" "F.Paste")
			(net "DRIVE_A_4_ACT")
			(options
				(clearance outline)
				(anchor circle)
			)
			(primitives
				(gr_poly
					(pts
						(arc
							(start -0.1778 0.5715)
							(mid -0.321484 0.511984)
							(end -0.381 0.3683)
						)
						(arc
							(start -0.381 -0.3683)
							(mid -0.321484 -0.511984)
							(end -0.1778 -0.5715)
						)
						(arc
							(start 0.1778 -0.5715)
							(mid 0.321484 -0.511984)
							(end 0.381 -0.3683)
						)
						(arc
							(start 0.381 0.3683)
							(mid 0.321484 0.511984)
							(end 0.1778 0.5715)
						)
					)
					(width 0)
					(fill yes)
				)
			)
		)
		(pad "S" smd custom
			(at 0.98425 0.9525)
			(size 0.1905 0.1905)
			(layers "F.Cu" "F.Mask" "F.Paste")
			(net "GND")
			(options
				(clearance outline)
				(anchor circle)
			)
			(primitives
				(gr_poly
					(pts
						(arc
							(start -0.1778 0.5715)
							(mid -0.321484 0.511984)
							(end -0.381 0.3683)
						)
						(arc
							(start -0.381 -0.3683)
							(mid -0.321484 -0.511984)
							(end -0.1778 -0.5715)
						)
						(arc
							(start 0.1778 -0.5715)
							(mid 0.321484 -0.511984)
							(end 0.381 -0.3683)
						)
						(arc
							(start 0.381 0.3683)
							(mid 0.321484 0.511984)
							(end 0.1778 0.5715)
						)
					)
					(width 0)
					(fill yes)
				)
			)
		)
	)
	(footprint ""
		(layer "F.Cu")
		(at 457.6699 -61.127894 -90)
		(property "Reference" "R911"
			(at 0 0 270)
			(layer "F.SilkS")
			(hide yes)
			(effects
				(font
					(size 1.27 1.27)
				)
			)
		)
		(property "Value" "2R6F-GP"
			(at -0.0508 -4.8514 270)
			(unlocked yes)
			(layer "F.Fab")
			(hide yes)
			(effects
				(font
					(size 1.016 1.016)
					(thickness 0.1524)
				)
			)
		)
		(property "Device Type" "R1206H26"
			(at 0 -6.3754 270)
			(unlocked yes)
			(layer "F.Fab")
			(hide yes)
			(effects
				(font
					(size 1.016 1.016)
					(thickness 0.1524)
				)
			)
		)
		(duplicate_pad_numbers_are_jumpers no)
		(fp_line
			(start -1.016 2.2352)
			(end -1.016 -2.2352)
			(stroke
				(width 0.1524)
				(type default)
			)
			(layer "F.SilkS")
		)
		(fp_line
			(start 1.016 2.2352)
			(end -1.016 2.2352)
			(stroke
				(width 0.1524)
				(type default)
			)
			(layer "F.SilkS")
		)
		(fp_line
			(start -1.016 -2.2352)
			(end 1.016 -2.2352)
			(stroke
				(width 0.1524)
				(type default)
			)
			(layer "F.SilkS")
		)
		(fp_line
			(start 1.016 -2.2352)
			(end 1.016 2.2352)
			(stroke
				(width 0.1524)
				(type default)
			)
			(layer "F.SilkS")
		)
		(fp_rect
			(start -1.0922 2.3114)
			(end 1.0922 -2.3114)
			(stroke
				(width 0)
				(type default)
			)
			(fill no)
			(layer "F.CrtYd")
		)
		(fp_poly
			(pts
				(xy -1.0922 -2.3114) (xy 1.0922 -2.3114) (xy 1.0922 2.3114) (xy -1.0922 2.3114)
			)
			(stroke
				(width 0)
				(type default)
			)
			(fill no)
			(layer "F.Fab")
		)
		(pad "1" smd rect
			(at 0 -1.397 270)
			(size 1.651 1.27)
			(layers "F.Cu" "F.Mask" "F.Paste")
			(net "P5V_HDD34")
		)
		(pad "2" smd rect
			(at 0 1.397 270)
			(size 1.651 1.27)
			(layers "F.Cu" "F.Mask" "F.Paste")
			(net "5V_PRE_34")
		)
	)
	(footprint ""
		(layer "F.Cu")
		(at 235.331 -382.1938)
		(property "Reference" "R1159"
			(at 0 0 0)
			(layer "F.SilkS")
			(hide yes)
			(effects
				(font
					(size 1.27 1.27)
				)
			)
		)
		(property "Value" "3K83R2F-GP"
			(at 0.064008 -3.993896 0)
			(unlocked yes)
			(layer "F.Fab")
			(hide yes)
			(effects
				(font
					(size 1.016 1.016)
					(thickness 0.1524)
				)
			)
		)
		(property "Device Type" "R402H16"
			(at 0.064008 -5.517896 0)
			(unlocked yes)
			(layer "F.Fab")
			(hide yes)
			(effects
				(font
					(size 1.016 1.016)
					(thickness 0.1524)
				)
			)
		)
		(duplicate_pad_numbers_are_jumpers no)
		(fp_line
			(start -0.508 -0.9398)
			(end -0.508 0.9398)
			(stroke
				(width 0.1524)
				(type default)
			)
			(layer "F.SilkS")
		)
		(fp_line
			(start 0.508 -0.9398)
			(end -0.508 -0.9398)
			(stroke
				(width 0.1524)
				(type default)
			)
			(layer "F.SilkS")
		)
		(fp_rect
			(start -0.508 0.9398)
			(end 0.508 -0.9398)
			(stroke
				(width 0)
				(type default)
			)
			(fill no)
			(layer "F.CrtYd")
		)
		(fp_rect
			(start -0.508 0.9398)
			(end 0.508 -0.9398)
			(stroke
				(width 0)
				(type default)
			)
			(fill no)
			(layer "F.Fab")
		)
		(pad "1" smd custom
			(at 0 -0.4445)
			(size 0.1397 0.1397)
			(layers "F.Cu" "F.Mask" "F.Paste")
			(net "P12V_A_PGOOD")
			(options
				(clearance outline)
				(anchor circle)
			)
			(primitives
				(gr_poly
					(pts
						(arc
							(start -0.1778 -0.2794)
							(mid -0.249642 -0.249642)
							(end -0.2794 -0.1778)
						)
						(arc
							(start -0.2794 0.1778)
							(mid -0.249642 0.249642)
							(end -0.1778 0.2794)
						)
						(arc
							(start 0.1778 0.2794)
							(mid 0.249642 0.249642)
							(end 0.2794 0.1778)
						)
						(arc
							(start 0.2794 -0.1778)
							(mid 0.249642 -0.249642)
							(end 0.1778 -0.2794)
						)
					)
					(width 0)
					(fill yes)
				)
			)
		)
		(pad "2" smd custom
			(at 0 0.4445)
			(size 0.1397 0.1397)
			(layers "F.Cu" "F.Mask" "F.Paste")
			(net "GND")
			(options
				(clearance outline)
				(anchor circle)
			)
			(primitives
				(gr_poly
					(pts
						(arc
							(start -0.1778 -0.2794)
							(mid -0.249642 -0.249642)
							(end -0.2794 -0.1778)
						)
						(arc
							(start -0.2794 0.1778)
							(mid -0.249642 0.249642)
							(end -0.1778 0.2794)
						)
						(arc
							(start 0.1778 0.2794)
							(mid 0.249642 0.249642)
							(end 0.2794 0.1778)
						)
						(arc
							(start 0.2794 -0.1778)
							(mid 0.249642 -0.249642)
							(end 0.1778 -0.2794)
						)
					)
					(width 0)
					(fill yes)
				)
			)
		)
	)
	(footprint ""
		(layer "F.Cu")
		(at 224.546922 -153.79827 -90)
		(property "Reference" "TP209"
			(at 0 0 270)
			(layer "F.SilkS")
			(hide yes)
			(effects
				(font
					(size 1.27 1.27)
				)
			)
		)
		(property "Value" "TPAD32-GP"
			(at -0.0508 -1.6764 270)
			(unlocked yes)
			(layer "F.Fab")
			(hide yes)
			(effects
				(font
					(size 1.016 1.016)
					(thickness 0.1524)
				)
			)
		)
		(property "Device Type" "TPAD32"
			(at -0.0508 -3.2004 270)
			(unlocked yes)
			(layer "F.Fab")
			(hide yes)
			(effects
				(font
					(size 1.016 1.016)
					(thickness 0.1524)
				)
			)
		)
		(duplicate_pad_numbers_are_jumpers no)
		(fp_poly
			(pts
				(arc
					(start 0 -0.4064)
					(mid 0 0.4064)
					(end 0 -0.4064)
				)
			)
			(stroke
				(width 0)
				(type default)
			)
			(fill no)
			(layer "F.CrtYd")
		)
		(fp_poly
			(pts
				(arc
					(start 0 -0.7112)
					(mid 0 0.7112)
					(end 0 -0.7112)
				)
			)
			(stroke
				(width 0)
				(type default)
			)
			(fill no)
			(layer "F.Fab")
		)
		(pad "1" smd circle
			(at 0 0 270)
			(size 0.8128 0.8128)
			(layers "F.Cu" "F.Mask" "F.Paste")
			(net "TP_COMP_A_KR_P0_TX_DP")
		)
	)
	(footprint ""
		(layer "F.Cu")
		(at 32.020002 -248.11355)
		(property "Reference" "R1209"
			(at 0 0 0)
			(layer "F.SilkS")
			(hide yes)
			(effects
				(font
					(size 1.27 1.27)
				)
			)
		)
		(property "Value" "0R3J-0-U-GP"
			(at -0.0254 -2.5146 0)
			(unlocked yes)
			(layer "F.Fab")
			(hide yes)
			(effects
				(font
					(size 1.016 1.016)
					(thickness 0.1524)
				)
			)
		)
		(property "Device Type" "R603H22"
			(at -0.0254 -4.0386 0)
			(unlocked yes)
			(layer "F.Fab")
			(hide yes)
			(effects
				(font
					(size 1.016 1.016)
					(thickness 0.1524)
				)
			)
		)
		(duplicate_pad_numbers_are_jumpers no)
		(fp_line
			(start -0.4826 0)
			(end -0.2032 0)
			(stroke
				(width 0.2032)
				(type default)
			)
			(layer "F.SilkS")
		)
		(fp_line
			(start 0.2032 0)
			(end 0.4826 0)
			(stroke
				(width 0.2032)
				(type default)
			)
			(layer "F.SilkS")
		)
		(fp_rect
			(start -0.5842 1.3335)
			(end 0.5842 -1.3335)
			(stroke
				(width 0)
				(type default)
			)
			(fill no)
			(layer "F.CrtYd")
		)
		(fp_rect
			(start -0.5842 1.3335)
			(end 0.5842 -1.3335)
			(stroke
				(width 0)
				(type default)
			)
			(fill no)
			(layer "F.Fab")
		)
		(pad "1" smd custom
			(at 0 -0.762)
			(size 0.2159 0.2159)
			(layers "F.Cu" "F.Mask" "F.Paste")
			(net "P5V_A_VBST")
			(options
				(clearance outline)
				(anchor circle)
			)
			(primitives
				(gr_poly
					(pts
						(arc
							(start -0.3302 -0.4318)
							(mid -0.402042 -0.402042)
							(end -0.4318 -0.3302)
						)
						(arc
							(start -0.4318 0.3302)
							(mid -0.402042 0.402042)
							(end -0.3302 0.4318)
						)
						(arc
							(start 0.3302 0.4318)
							(mid 0.402042 0.402042)
							(end 0.4318 0.3302)
						)
						(arc
							(start 0.4318 -0.3302)
							(mid 0.402042 -0.402042)
							(end 0.3302 -0.4318)
						)
					)
					(width 0)
					(fill yes)
				)
			)
		)
		(pad "2" smd custom
			(at 0 0.762)
			(size 0.2159 0.2159)
			(layers "F.Cu" "F.Mask" "F.Paste")
			(net "P5V_A_VBST_RC")
			(options
				(clearance outline)
				(anchor circle)
			)
			(primitives
				(gr_poly
					(pts
						(arc
							(start -0.3302 -0.4318)
							(mid -0.402042 -0.402042)
							(end -0.4318 -0.3302)
						)
						(arc
							(start -0.4318 0.3302)
							(mid -0.402042 0.402042)
							(end -0.3302 0.4318)
						)
						(arc
							(start 0.3302 0.4318)
							(mid 0.402042 0.402042)
							(end 0.4318 0.3302)
						)
						(arc
							(start 0.4318 -0.3302)
							(mid 0.402042 -0.402042)
							(end 0.3302 -0.4318)
						)
					)
					(width 0)
					(fill yes)
				)
			)
		)
	)
	(footprint ""
		(layer "F.Cu")
		(at 155.42514 -143.325596 180)
		(property "Reference" "R1065"
			(at 0 0 180)
			(layer "F.SilkS")
			(hide yes)
			(effects
				(font
					(size 1.27 1.27)
				)
			)
		)
		(property "Value" "3K92R2F-GP"
			(at 0.064008 -3.993896 180)
			(unlocked yes)
			(layer "F.Fab")
			(hide yes)
			(effects
				(font
					(size 1.016 1.016)
					(thickness 0.1524)
				)
			)
		)
		(property "Device Type" "R402H16"
			(at 0.064008 -5.517896 180)
			(unlocked yes)
			(layer "F.Fab")
			(hide yes)
			(effects
				(font
					(size 1.016 1.016)
					(thickness 0.1524)
				)
			)
		)
		(duplicate_pad_numbers_are_jumpers no)
		(fp_line
			(start 0.508 -0.9398)
			(end -0.508 -0.9398)
			(stroke
				(width 0.1524)
				(type default)
			)
			(layer "F.SilkS")
		)
		(fp_line
			(start -0.508 -0.9398)
			(end -0.508 0.9398)
			(stroke
				(width 0.1524)
				(type default)
			)
			(layer "F.SilkS")
		)
		(fp_rect
			(start -0.508 0.9398)
			(end 0.508 -0.9398)
			(stroke
				(width 0)
				(type default)
			)
			(fill no)
			(layer "F.CrtYd")
		)
		(fp_rect
			(start -0.508 0.9398)
			(end 0.508 -0.9398)
			(stroke
				(width 0)
				(type default)
			)
			(fill no)
			(layer "F.Fab")
		)
		(pad "1" smd custom
			(at 0 -0.4445 180)
			(size 0.1397 0.1397)
			(layers "F.Cu" "F.Mask" "F.Paste")
			(net "MB0_CM_OV_R")
			(options
				(clearance outline)
				(anchor circle)
			)
			(primitives
				(gr_poly
					(pts
						(arc
							(start -0.1778 -0.2794)
							(mid -0.249642 -0.249642)
							(end -0.2794 -0.1778)
						)
						(arc
							(start -0.2794 0.1778)
							(mid -0.249642 0.249642)
							(end -0.1778 0.2794)
						)
						(arc
							(start 0.1778 0.2794)
							(mid 0.249642 0.249642)
							(end 0.2794 0.1778)
						)
						(arc
							(start 0.2794 -0.1778)
							(mid 0.249642 -0.249642)
							(end 0.1778 -0.2794)
						)
					)
					(width 0)
					(fill yes)
				)
			)
		)
		(pad "2" smd custom
			(at 0 0.4445 180)
			(size 0.1397 0.1397)
			(layers "F.Cu" "F.Mask" "F.Paste")
			(net "AGND_CURRENT_MONOA")
			(options
				(clearance outline)
				(anchor circle)
			)
			(primitives
				(gr_poly
					(pts
						(arc
							(start -0.1778 -0.2794)
							(mid -0.249642 -0.249642)
							(end -0.2794 -0.1778)
						)
						(arc
							(start -0.2794 0.1778)
							(mid -0.249642 0.249642)
							(end -0.1778 0.2794)
						)
						(arc
							(start 0.1778 0.2794)
							(mid 0.249642 0.249642)
							(end 0.2794 0.1778)
						)
						(arc
							(start 0.2794 -0.1778)
							(mid 0.249642 -0.249642)
							(end 0.1778 -0.2794)
						)
					)
					(width 0)
					(fill yes)
				)
			)
		)
	)
	(footprint ""
		(layer "F.Cu")
		(at 439.8391 -158.939992 90)
		(property "Reference" "VIA12"
			(at 0 0 90)
			(layer "F.SilkS")
			(hide yes)
			(effects
				(font
					(size 1.27 1.27)
				)
			)
		)
		(property "Value" "100OHM-8L-1D6MM-L18L16-GP"
			(at -3.7211 -4.5085 90)
			(unlocked yes)
			(layer "F.Fab")
			(hide yes)
			(effects
				(font
					(size 1.016 1.016)
					(thickness 0.1524)
				)
			)
		)
		(property "Device Type" "VIA-PCIE-4P-394076"
			(at -3.7211 -6.0325 90)
			(unlocked yes)
			(layer "F.Fab")
			(hide yes)
			(effects
				(font
					(size 1.016 1.016)
					(thickness 0.1524)
				)
			)
		)
		(duplicate_pad_numbers_are_jumpers no)
		(fp_rect
			(start -1.9685 0.381)
			(end 1.9685 -0.381)
			(stroke
				(width 0)
				(type default)
			)
			(fill no)
			(layer "F.CrtYd")
		)
		(fp_rect
			(start -1.9685 0.381)
			(end 1.9685 -0.381)
			(stroke
				(width 0)
				(type default)
			)
			(fill no)
			(layer "F.Fab")
		)
		(pad "1" thru_hole circle
			(at -1.5875 0 90)
			(size 0.508 0.508)
			(drill 0.254)
			(layers "*.Cu" "*.Mask")
			(remove_unused_layers no)
			(net "GND")
			(clearance 0.127)
			(thermal_gap 0.127)
		)
		(pad "2" thru_hole circle
			(at -0.5715 0 90)
			(size 0.508 0.508)
			(drill 0.254)
			(layers "*.Cu" "*.Mask")
			(remove_unused_layers no)
			(net "PHY_SCC_A_TO_DRV_A_22_DP")
			(clearance 0.127)
			(thermal_gap 0.127)
		)
		(pad "3" thru_hole circle
			(at 0.5715 0 90)
			(size 0.508 0.508)
			(drill 0.254)
			(layers "*.Cu" "*.Mask")
			(remove_unused_layers no)
			(net "PHY_SCC_A_TO_DRV_A_22_DN")
			(clearance 0.127)
			(thermal_gap 0.127)
		)
		(pad "4" thru_hole circle
			(at 1.5875 0 90)
			(size 0.508 0.508)
			(drill 0.254)
			(layers "*.Cu" "*.Mask")
			(remove_unused_layers no)
			(net "GND")
			(clearance 0.127)
			(thermal_gap 0.127)
		)
	)
	(footprint ""
		(layer "F.Cu")
		(at 302.039528 -63.4492 90)
		(property "Reference" "R642"
			(at 0 0 90)
			(layer "F.SilkS")
			(hide yes)
			(effects
				(font
					(size 1.27 1.27)
				)
			)
		)
		(property "Value" "0R2J-2-GP"
			(at 0.064008 -3.993896 90)
			(unlocked yes)
			(layer "F.Fab")
			(hide yes)
			(effects
				(font
					(size 1.016 1.016)
					(thickness 0.1524)
				)
			)
		)
		(property "Device Type" "R402H16"
			(at 0.064008 -5.517896 90)
			(unlocked yes)
			(layer "F.Fab")
			(hide yes)
			(effects
				(font
					(size 1.016 1.016)
					(thickness 0.1524)
				)
			)
		)
		(duplicate_pad_numbers_are_jumpers no)
		(fp_line
			(start 0.508 -0.9398)
			(end -0.508 -0.9398)
			(stroke
				(width 0.1524)
				(type default)
			)
			(layer "F.SilkS")
		)
		(fp_line
			(start -0.508 -0.9398)
			(end -0.508 0.9398)
			(stroke
				(width 0.1524)
				(type default)
			)
			(layer "F.SilkS")
		)
		(fp_rect
			(start -0.508 0.9398)
			(end 0.508 -0.9398)
			(stroke
				(width 0)
				(type default)
			)
			(fill no)
			(layer "F.CrtYd")
		)
		(fp_rect
			(start -0.508 0.9398)
			(end 0.508 -0.9398)
			(stroke
				(width 0)
				(type default)
			)
			(fill no)
			(layer "F.Fab")
		)
		(pad "1" smd custom
			(at 0 -0.4445 90)
			(size 0.1397 0.1397)
			(layers "F.Cu" "F.Mask" "F.Paste")
			(net "I2C_BMC_B_COMP_B_SDA_R")
			(options
				(clearance outline)
				(anchor circle)
			)
			(primitives
				(gr_poly
					(pts
						(arc
							(start -0.1778 -0.2794)
							(mid -0.249642 -0.249642)
							(end -0.2794 -0.1778)
						)
						(arc
							(start -0.2794 0.1778)
							(mid -0.249642 0.249642)
							(end -0.1778 0.2794)
						)
						(arc
							(start 0.1778 0.2794)
							(mid 0.249642 0.249642)
							(end 0.2794 0.1778)
						)
						(arc
							(start 0.2794 -0.1778)
							(mid 0.249642 -0.249642)
							(end 0.1778 -0.2794)
						)
					)
					(width 0)
					(fill yes)
				)
			)
		)
		(pad "2" smd custom
			(at 0 0.4445 90)
			(size 0.1397 0.1397)
			(layers "F.Cu" "F.Mask" "F.Paste")
			(net "I2C_BMC_B_COMP_B_SDA_BUF")
			(options
				(clearance outline)
				(anchor circle)
			)
			(primitives
				(gr_poly
					(pts
						(arc
							(start -0.1778 -0.2794)
							(mid -0.249642 -0.249642)
							(end -0.2794 -0.1778)
						)
						(arc
							(start -0.2794 0.1778)
							(mid -0.249642 0.249642)
							(end -0.1778 0.2794)
						)
						(arc
							(start 0.1778 0.2794)
							(mid 0.249642 0.249642)
							(end 0.2794 0.1778)
						)
						(arc
							(start 0.2794 -0.1778)
							(mid 0.249642 -0.249642)
							(end 0.1778 -0.2794)
						)
					)
					(width 0)
					(fill yes)
				)
			)
		)
	)
	(footprint ""
		(layer "F.Cu")
		(at 373.5578 -133.8834)
		(property "Reference" "R1074"
			(at 0 0 0)
			(layer "F.SilkS")
			(hide yes)
			(effects
				(font
					(size 1.27 1.27)
				)
			)
		)
		(property "Value" "0R2J-2-GP"
			(at 0.064008 -3.993896 0)
			(unlocked yes)
			(layer "F.Fab")
			(hide yes)
			(effects
				(font
					(size 1.016 1.016)
					(thickness 0.1524)
				)
			)
		)
		(property "Device Type" "R402H16"
			(at 0.064008 -5.517896 0)
			(unlocked yes)
			(layer "F.Fab")
			(hide yes)
			(effects
				(font
					(size 1.016 1.016)
					(thickness 0.1524)
				)
			)
		)
		(duplicate_pad_numbers_are_jumpers no)
		(fp_line
			(start -0.508 -0.9398)
			(end -0.508 0.9398)
			(stroke
				(width 0.1524)
				(type default)
			)
			(layer "F.SilkS")
		)
		(fp_line
			(start 0.508 -0.9398)
			(end -0.508 -0.9398)
			(stroke
				(width 0.1524)
				(type default)
			)
			(layer "F.SilkS")
		)
		(fp_rect
			(start -0.508 0.9398)
			(end 0.508 -0.9398)
			(stroke
				(width 0)
				(type default)
			)
			(fill no)
			(layer "F.CrtYd")
		)
		(fp_rect
			(start -0.508 0.9398)
			(end 0.508 -0.9398)
			(stroke
				(width 0)
				(type default)
			)
			(fill no)
			(layer "F.Fab")
		)
		(pad "1" smd custom
			(at 0 -0.4445)
			(size 0.1397 0.1397)
			(layers "F.Cu" "F.Mask" "F.Paste")
			(net "MB1_CM_ADR1_R")
			(options
				(clearance outline)
				(anchor circle)
			)
			(primitives
				(gr_poly
					(pts
						(arc
							(start -0.1778 -0.2794)
							(mid -0.249642 -0.249642)
							(end -0.2794 -0.1778)
						)
						(arc
							(start -0.2794 0.1778)
							(mid -0.249642 0.249642)
							(end -0.1778 0.2794)
						)
						(arc
							(start 0.1778 0.2794)
							(mid 0.249642 0.249642)
							(end 0.2794 0.1778)
						)
						(arc
							(start 0.2794 -0.1778)
							(mid 0.249642 -0.249642)
							(end 0.1778 -0.2794)
						)
					)
					(width 0)
					(fill yes)
				)
			)
		)
		(pad "2" smd custom
			(at 0 0.4445)
			(size 0.1397 0.1397)
			(layers "F.Cu" "F.Mask" "F.Paste")
			(net "AGND_CURRENT_MONOB")
			(options
				(clearance outline)
				(anchor circle)
			)
			(primitives
				(gr_poly
					(pts
						(arc
							(start -0.1778 -0.2794)
							(mid -0.249642 -0.249642)
							(end -0.2794 -0.1778)
						)
						(arc
							(start -0.2794 0.1778)
							(mid -0.249642 0.249642)
							(end -0.1778 0.2794)
						)
						(arc
							(start 0.1778 0.2794)
							(mid 0.249642 0.249642)
							(end 0.2794 0.1778)
						)
						(arc
							(start 0.2794 -0.1778)
							(mid 0.249642 -0.249642)
							(end 0.1778 -0.2794)
						)
					)
					(width 0)
					(fill yes)
				)
			)
		)
	)
	(footprint ""
		(layer "F.Cu")
		(at 91.300046 -287.910016 -90)
		(property "Reference" "HDDSAS2"
			(at 0 0 270)
			(layer "F.SilkS")
			(hide yes)
			(effects
				(font
					(size 1.27 1.27)
				)
			)
		)
		(property "Value" "SKT-SAS15P-14P-45-GP"
			(at -20.7645 -8.9789 270)
			(unlocked yes)
			(layer "F.Fab")
			(hide yes)
			(effects
				(font
					(size 1.016 1.016)
					(thickness 0.1524)
				)
			)
		)
		(property "Device Type" "10120818-001C-TRLF"
			(at -20.7645 -10.5029 270)
			(unlocked yes)
			(layer "F.Fab")
			(hide yes)
			(effects
				(font
					(size 1.016 1.016)
					(thickness 0.1524)
				)
			)
		)
		(duplicate_pad_numbers_are_jumpers no)
		(fp_line
			(start 1.651 4.2926)
			(end 1.651 3.0099)
			(stroke
				(width 0.1524)
				(type default)
			)
			(layer "F.SilkS")
		)
		(fp_line
			(start 8.509 4.2926)
			(end 1.651 4.2926)
			(stroke
				(width 0.1524)
				(type default)
			)
			(layer "F.SilkS")
		)
		(fp_line
			(start -23.4188 3.0099)
			(end -23.4188 -3.2512)
			(stroke
				(width 0.1524)
				(type default)
			)
			(layer "F.SilkS")
		)
		(fp_line
			(start 1.651 3.0099)
			(end -23.4188 3.0099)
			(stroke
				(width 0.1524)
				(type default)
			)
			(layer "F.SilkS")
		)
		(fp_line
			(start 8.509 3.0099)
			(end 8.509 4.2926)
			(stroke
				(width 0.1524)
				(type default)
			)
			(layer "F.SilkS")
		)
		(fp_line
			(start 23.4188 3.0099)
			(end 8.509 3.0099)
			(stroke
				(width 0.1524)
				(type default)
			)
			(layer "F.SilkS")
		)
		(fp_line
			(start -23.4188 -3.2512)
			(end 23.4188 -3.2512)
			(stroke
				(width 0.1524)
				(type default)
			)
			(layer "F.SilkS")
		)
		(fp_line
			(start 23.4188 -3.2512)
			(end 23.4188 3.0099)
			(stroke
				(width 0.1524)
				(type default)
			)
			(layer "F.SilkS")
		)
		(fp_line
			(start 15.5067 -3.3401)
			(end 16.2687 -3.3401)
			(stroke
				(width 0.3302)
				(type default)
			)
			(layer "F.SilkS")
		)
		(fp_poly
			(pts
				(xy 15.868904 -3.230372) (xy 16.503904 -3.865372) (xy 15.233904 -3.865372)
			)
			(stroke
				(width 0)
				(type default)
			)
			(fill yes)
			(layer "F.SilkS")
		)
		(fp_poly
			(pts
				(xy -22.8727 -2.7559) (xy 22.8727 -2.7559) (xy 22.8727 2.7559) (xy 8.255 2.7559) (xy 8.255 3.5179)
				(xy 1.905 3.5179) (xy 1.905 2.7559) (xy -22.8727 2.7559)
			)
			(stroke
				(width 0)
				(type default)
			)
			(fill no)
			(layer "F.CrtYd")
		)
		(fp_poly
			(pts
				(xy 1.397 4.5466) (xy 1.397 3.2639) (xy -23.6728 3.2639) (xy -23.6728 -3.5052) (xy 23.6728 -3.5052)
				(xy 23.6728 -0.00635) (xy 22.8727 -0.00635) (xy 22.8727 -2.7559) (xy -22.8727 -2.7559) (xy -22.8727 2.7559)
				(xy 1.905 2.7559) (xy 1.905 3.5179) (xy 8.255 3.5179) (xy 8.255 2.7559) (xy 22.8727 2.7559) (xy 22.8727 0.00635)
				(xy 23.6728 0.00635) (xy 23.6728 3.2639) (xy 8.763 3.2639) (xy 8.763 4.5466)
			)
			(stroke
				(width 0)
				(type default)
			)
			(fill no)
			(layer "F.CrtYd")
		)
		(fp_poly
			(pts
				(xy 1.397 4.5466) (xy 1.397 3.2639) (xy -23.6728 3.2639) (xy -23.6728 -3.5052) (xy 23.6728 -3.5052)
				(xy 23.6728 3.2639) (xy 8.763 3.2639) (xy 8.763 4.5466)
			)
			(stroke
				(width 0)
				(type default)
			)
			(fill no)
			(layer "F.Fab")
		)
		(pad "" np_thru_hole circle
			(at -18.874994 0 270)
			(size 0.254 0.254)
			(drill 1.3462)
			(layers "*.Cu" "*.Mask")
			(clearance 0.9017)
			(thermal_gap 0.9017)
		)
		(pad "" np_thru_hole circle
			(at 18.874994 0 270)
			(size 0.254 0.254)
			(drill 0.9398)
			(layers "*.Cu" "*.Mask")
			(clearance 0.6985)
			(thermal_gap 0.6985)
		)
		(pad "G1" smd rect
			(at 21.874988 0 270)
			(size 2.5908 2.5908)
			(layers "F.Cu" "F.Mask" "F.Paste")
			(net "GND")
		)
		(pad "G2" smd rect
			(at -21.874988 0 270)
			(size 2.5908 2.5908)
			(layers "F.Cu" "F.Mask" "F.Paste")
			(net "GND")
		)
		(pad "P1" smd rect
			(at 1.905 -1.82499 270)
			(size 0.6096 2.3622)
			(layers "F.Cu" "F.Mask" "F.Paste")
			(net "Net_2066")
		)
		(pad "P2" smd rect
			(at 0.635 -1.82499 270)
			(size 0.6096 2.3622)
			(layers "F.Cu" "F.Mask" "F.Paste")
			(net "Net_2067")
		)
		(pad "P3" smd rect
			(at -0.635 -1.82499 270)
			(size 0.6096 2.3622)
			(layers "F.Cu" "F.Mask" "F.Paste")
			(net "Net_2068")
		)
		(pad "P4" smd rect
			(at -1.905 -1.82499 270)
			(size 0.6096 2.3622)
			(layers "F.Cu" "F.Mask" "F.Paste")
			(net "GND")
		)
		(pad "P5" smd rect
			(at -3.175 -1.82499 270)
			(size 0.6096 2.3622)
			(layers "F.Cu" "F.Mask" "F.Paste")
			(net "HDD_PRSNT_2")
		)
		(pad "P6" smd rect
			(at -4.445 -1.82499 270)
			(size 0.6096 2.3622)
			(layers "F.Cu" "F.Mask" "F.Paste")
			(net "GND")
		)
		(pad "P7" smd rect
			(at -5.715 -1.82499 270)
			(size 0.6096 2.3622)
			(layers "F.Cu" "F.Mask" "F.Paste")
			(net "5V_PRE_2")
		)
		(pad "P8" smd rect
			(at -6.985 -1.82499 270)
			(size 0.6096 2.3622)
			(layers "F.Cu" "F.Mask" "F.Paste")
			(net "P5V_HDD2")
		)
		(pad "P9" smd rect
			(at -8.255 -1.82499 270)
			(size 0.6096 2.3622)
			(layers "F.Cu" "F.Mask" "F.Paste")
			(net "P5V_HDD2")
		)
		(pad "P10" smd rect
			(at -9.525 -1.82499 270)
			(size 0.6096 2.3622)
			(layers "F.Cu" "F.Mask" "F.Paste")
			(net "GND")
		)
		(pad "P11" smd rect
			(at -10.795 -1.82499 270)
			(size 0.6096 2.3622)
			(layers "F.Cu" "F.Mask" "F.Paste")
			(net "ACT_HDD_2")
		)
		(pad "P12" smd rect
			(at -12.065 -1.82499 270)
			(size 0.6096 2.3622)
			(layers "F.Cu" "F.Mask" "F.Paste")
			(net "GND")
		)
		(pad "P13" smd rect
			(at -13.335 -1.82499 270)
			(size 0.6096 2.3622)
			(layers "F.Cu" "F.Mask" "F.Paste")
			(net "12V_PRE_2")
		)
		(pad "P14" smd rect
			(at -14.605 -1.82499 270)
			(size 0.6096 2.3622)
			(layers "F.Cu" "F.Mask" "F.Paste")
			(net "P12V_HDD2")
		)
		(pad "P15" smd rect
			(at -15.875 -1.82499 270)
			(size 0.6096 2.3622)
			(layers "F.Cu" "F.Mask" "F.Paste")
			(net "P12V_HDD2")
		)
		(pad "S1" smd rect
			(at 15.875 -1.82499 270)
			(size 0.6096 2.3622)
			(layers "F.Cu" "F.Mask" "F.Paste")
			(net "GND")
		)
		(pad "S2" smd rect
			(at 14.605 -1.82499 270)
			(size 0.6096 2.3622)
			(layers "F.Cu" "F.Mask" "F.Paste")
			(net "SAS_HDD_RX_P2")
		)
		(pad "S3" smd rect
			(at 13.335 -1.82499 270)
			(size 0.6096 2.3622)
			(layers "F.Cu" "F.Mask" "F.Paste")
			(net "SAS_HDD_RX_N2")
		)
		(pad "S4" smd rect
			(at 12.065 -1.82499 270)
			(size 0.6096 2.3622)
			(layers "F.Cu" "F.Mask" "F.Paste")
			(net "GND")
		)
		(pad "S5" smd rect
			(at 10.795 -1.82499 270)
			(size 0.6096 2.3622)
			(layers "F.Cu" "F.Mask" "F.Paste")
			(net "PHY_DRV_A_TO_SCC_A_2_DN")
		)
		(pad "S6" smd rect
			(at 9.525 -1.82499 270)
			(size 0.6096 2.3622)
			(layers "F.Cu" "F.Mask" "F.Paste")
			(net "PHY_DRV_A_TO_SCC_A_2_DP")
		)
		(pad "S7" smd rect
			(at 8.255 -1.82499 270)
			(size 0.6096 2.3622)
			(layers "F.Cu" "F.Mask" "F.Paste")
			(net "GND")
		)
		(pad "S8" smd rect
			(at 7.480046 2.845054 270)
			(size 0.508 2.3622)
			(layers "F.Cu" "F.Mask" "F.Paste")
			(net "GND")
		)
		(pad "S9" smd rect
			(at 6.679946 2.845054 270)
			(size 0.508 2.3622)
			(layers "F.Cu" "F.Mask" "F.Paste")
			(net "Net_467")
		)
		(pad "S10" smd rect
			(at 5.8801 2.845054 270)
			(size 0.508 2.3622)
			(layers "F.Cu" "F.Mask" "F.Paste")
			(net "Net_359")
		)
		(pad "S11" smd rect
			(at 5.08 2.845054 270)
			(size 0.508 2.3622)
			(layers "F.Cu" "F.Mask" "F.Paste")
			(net "GND")
		)
		(pad "S12" smd rect
			(at 4.2799 2.845054 270)
			(size 0.508 2.3622)
			(layers "F.Cu" "F.Mask" "F.Paste")
			(net "Net_395")
		)
		(pad "S13" smd rect
			(at 3.480054 2.845054 270)
			(size 0.508 2.3622)
			(layers "F.Cu" "F.Mask" "F.Paste")
			(net "Net_431")
		)
		(pad "S14" smd rect
			(at 2.679954 2.845054 270)
			(size 0.508 2.3622)
			(layers "F.Cu" "F.Mask" "F.Paste")
			(net "GND")
		)
		(zone
			(layer "F.Cu")
			(hatch none 0.5)
			(connect_pads
				(clearance 0)
			)
			(min_thickness 0.25)
			(keepout
				(tracks allowed)
				(vias not_allowed)
				(pads allowed)
				(copperpour not_allowed)
				(footprints allowed)
			)
			(placement
				(enabled no)
				(sheetname "")
			)
			(fill
				(thermal_gap 0.5)
				(thermal_bridge_width 0.5)
				(island_removal_mode 0)
			)
			(polygon
				(pts
					(xy 94.957646 -304.648616) (xy 87.883746 -304.648616) (xy 87.883746 -311.582816) (xy 88.988646 -311.582816)
					(xy 88.988646 -307.468016) (xy 93.611446 -307.468016) (xy 93.611446 -311.582816) (xy 94.957646 -311.582816)
				)
			)
		)
		(zone
			(layer "F.Cu")
			(hatch none 0.5)
			(connect_pads
				(clearance 0)
			)
			(min_thickness 0.25)
			(keepout
				(tracks not_allowed)
				(vias allowed)
				(pads allowed)
				(copperpour not_allowed)
				(footprints allowed)
			)
			(placement
				(enabled no)
				(sheetname "")
			)
			(fill
				(thermal_gap 0.5)
				(thermal_bridge_width 0.5)
				(island_removal_mode 0)
			)
			(polygon
				(pts
					(xy 94.957646 -304.648616) (xy 87.883746 -304.648616) (xy 87.883746 -311.582816) (xy 88.988646 -311.582816)
					(xy 88.988646 -307.468016) (xy 93.611446 -307.468016) (xy 93.611446 -311.582816) (xy 94.957646 -311.582816)
				)
			)
		)
		(zone
			(layer "F.Cu")
			(hatch none 0.5)
			(connect_pads
				(clearance 0)
			)
			(min_thickness 0.25)
			(keepout
				(tracks allowed)
				(vias not_allowed)
				(pads allowed)
				(copperpour not_allowed)
				(footprints allowed)
			)
			(placement
				(enabled no)
				(sheetname "")
			)
			(fill
				(thermal_gap 0.5)
				(thermal_bridge_width 0.5)
				(island_removal_mode 0)
			)
			(polygon
				(pts
					(xy 94.957646 -271.171416) (xy 87.883746 -271.171416) (xy 87.883746 -264.237216) (xy 88.988646 -264.237216)
					(xy 88.988646 -268.352016) (xy 93.611446 -268.352016) (xy 93.611446 -264.237216) (xy 94.957646 -264.237216)
				)
			)
		)
		(zone
			(layer "F.Cu")
			(hatch none 0.5)
			(connect_pads
				(clearance 0)
			)
			(min_thickness 0.25)
			(keepout
				(tracks not_allowed)
				(vias allowed)
				(pads allowed)
				(copperpour not_allowed)
				(footprints allowed)
			)
			(placement
				(enabled no)
				(sheetname "")
			)
			(fill
				(thermal_gap 0.5)
				(thermal_bridge_width 0.5)
				(island_removal_mode 0)
			)
			(polygon
				(pts
					(xy 94.957646 -271.171416) (xy 87.883746 -271.171416) (xy 87.883746 -264.237216) (xy 88.988646 -264.237216)
					(xy 88.988646 -268.352016) (xy 93.611446 -268.352016) (xy 93.611446 -264.237216) (xy 94.957646 -264.237216)
				)
			)
		)
		(zone
			(layers "F.Cu" "B.Cu" "In1.Cu" "In2.Cu" "In3.Cu" "In4.Cu" "In5.Cu" "In6.Cu"
				"In7.Cu" "In8.Cu" "In9.Cu" "In10.Cu"
			)
			(hatch none 0.5)
			(connect_pads
				(clearance 0)
			)
			(min_thickness 0.25)
			(keepout
				(tracks not_allowed)
				(vias allowed)
				(pads allowed)
				(copperpour not_allowed)
				(footprints allowed)
			)
			(placement
				(enabled no)
				(sheetname "")
			)
			(fill
				(thermal_gap 0.5)
				(thermal_bridge_width 0.5)
				(island_removal_mode 0)
			)
			(polygon
				(pts
					(arc
						(start 92.074746 -269.035022)
						(mid 90.525346 -269.035022)
						(end 92.074746 -269.035022)
					)
				)
			)
		)
		(zone
			(layers "F.Cu" "B.Cu" "In1.Cu" "In2.Cu" "In3.Cu" "In4.Cu" "In5.Cu" "In6.Cu"
				"In7.Cu" "In8.Cu" "In9.Cu" "In10.Cu"
			)
			(hatch none 0.5)
			(connect_pads
				(clearance 0)
			)
			(min_thickness 0.25)
			(keepout
				(tracks not_allowed)
				(vias allowed)
				(pads allowed)
				(copperpour not_allowed)
				(footprints allowed)
			)
			(placement
				(enabled no)
				(sheetname "")
			)
			(fill
				(thermal_gap 0.5)
				(thermal_bridge_width 0.5)
				(island_removal_mode 0)
			)
			(polygon
				(pts
					(arc
						(start 92.277946 -306.78501)
						(mid 90.322146 -306.78501)
						(end 92.277946 -306.78501)
					)
				)
			)
		)
	)
	(footprint ""
		(layer "F.Cu")
		(at 270.489172 -238.924846 180)
		(property "Reference" "R440"
			(at 0 0 180)
			(layer "F.SilkS")
			(hide yes)
			(effects
				(font
					(size 1.27 1.27)
				)
			)
		)
		(property "Value" "1KR2F-3-GP"
			(at 0.064008 -3.993896 180)
			(unlocked yes)
			(layer "F.Fab")
			(hide yes)
			(effects
				(font
					(size 1.016 1.016)
					(thickness 0.1524)
				)
			)
		)
		(property "Device Type" "R402H16"
			(at 0.064008 -5.517896 180)
			(unlocked yes)
			(layer "F.Fab")
			(hide yes)
			(effects
				(font
					(size 1.016 1.016)
					(thickness 0.1524)
				)
			)
		)
		(duplicate_pad_numbers_are_jumpers no)
		(fp_line
			(start 0.508 -0.9398)
			(end -0.508 -0.9398)
			(stroke
				(width 0.1524)
				(type default)
			)
			(layer "F.SilkS")
		)
		(fp_line
			(start -0.508 -0.9398)
			(end -0.508 0.9398)
			(stroke
				(width 0.1524)
				(type default)
			)
			(layer "F.SilkS")
		)
		(fp_rect
			(start -0.508 0.9398)
			(end 0.508 -0.9398)
			(stroke
				(width 0)
				(type default)
			)
			(fill no)
			(layer "F.CrtYd")
		)
		(fp_rect
			(start -0.508 0.9398)
			(end 0.508 -0.9398)
			(stroke
				(width 0)
				(type default)
			)
			(fill no)
			(layer "F.Fab")
		)
		(pad "1" smd custom
			(at 0 -0.4445 180)
			(size 0.1397 0.1397)
			(layers "F.Cu" "F.Mask" "F.Paste")
			(net "P3V3_STBY_A")
			(options
				(clearance outline)
				(anchor circle)
			)
			(primitives
				(gr_poly
					(pts
						(arc
							(start -0.1778 -0.2794)
							(mid -0.249642 -0.249642)
							(end -0.2794 -0.1778)
						)
						(arc
							(start -0.2794 0.1778)
							(mid -0.249642 0.249642)
							(end -0.1778 0.2794)
						)
						(arc
							(start 0.1778 0.2794)
							(mid 0.249642 0.249642)
							(end 0.2794 0.1778)
						)
						(arc
							(start 0.2794 -0.1778)
							(mid 0.249642 -0.249642)
							(end 0.1778 -0.2794)
						)
					)
					(width 0)
					(fill yes)
				)
			)
		)
		(pad "2" smd custom
			(at 0 0.4445 180)
			(size 0.1397 0.1397)
			(layers "F.Cu" "F.Mask" "F.Paste")
			(net "I2C_BMC_A_EXP_A_SDA")
			(options
				(clearance outline)
				(anchor circle)
			)
			(primitives
				(gr_poly
					(pts
						(arc
							(start -0.1778 -0.2794)
							(mid -0.249642 -0.249642)
							(end -0.2794 -0.1778)
						)
						(arc
							(start -0.2794 0.1778)
							(mid -0.249642 0.249642)
							(end -0.1778 0.2794)
						)
						(arc
							(start 0.1778 0.2794)
							(mid 0.249642 0.249642)
							(end 0.2794 0.1778)
						)
						(arc
							(start 0.2794 -0.1778)
							(mid 0.249642 -0.249642)
							(end 0.1778 -0.2794)
						)
					)
					(width 0)
					(fill yes)
				)
			)
		)
	)
	(footprint ""
		(layer "F.Cu")
		(at 178.2318 -163.935918 180)
		(property "Reference" "Q103"
			(at 0 0 180)
			(layer "F.SilkS")
			(hide yes)
			(effects
				(font
					(size 1.27 1.27)
				)
			)
		)
		(property "Value" "2N7002KDW-GP"
			(at -2.3622 -8.2042 180)
			(unlocked yes)
			(layer "F.Fab")
			(hide yes)
			(effects
				(font
					(size 1.016 1.016)
					(thickness 0.1524)
				)
			)
		)
		(property "Device Type" "SOT-363H44"
			(at -2.3622 -10.1092 180)
			(unlocked yes)
			(layer "F.Fab")
			(hide yes)
			(effects
				(font
					(size 1.016 1.016)
					(thickness 0.1524)
				)
			)
		)
		(duplicate_pad_numbers_are_jumpers no)
		(fp_line
			(start 1.4478 1.7018)
			(end 1.4478 -1.7018)
			(stroke
				(width 0.1524)
				(type default)
			)
			(layer "F.SilkS")
		)
		(fp_line
			(start 1.4478 -1.7018)
			(end -1.4478 -1.7018)
			(stroke
				(width 0.1524)
				(type default)
			)
			(layer "F.SilkS")
		)
		(fp_line
			(start -1.27 1.524)
			(end -1.27 0.6604)
			(stroke
				(width 0.4826)
				(type default)
			)
			(layer "F.SilkS")
		)
		(fp_line
			(start -1.4478 1.7018)
			(end 1.4478 1.7018)
			(stroke
				(width 0.1524)
				(type default)
			)
			(layer "F.SilkS")
		)
		(fp_line
			(start -1.4478 -1.7018)
			(end -1.4478 1.7018)
			(stroke
				(width 0.1524)
				(type default)
			)
			(layer "F.SilkS")
		)
		(fp_poly
			(pts
				(xy -1.524 -1.778) (xy 1.524 -1.778) (xy 1.524 1.778) (xy -1.524 1.778)
			)
			(stroke
				(width 0)
				(type default)
			)
			(fill no)
			(layer "F.CrtYd")
		)
		(fp_poly
			(pts
				(xy -1.524 -1.778) (xy 1.524 -1.778) (xy 1.524 1.778) (xy -1.524 1.778)
			)
			(stroke
				(width 0)
				(type default)
			)
			(fill no)
			(layer "F.Fab")
		)
		(pad "1" smd rect
			(at -0.65024 0.9398 180)
			(size 0.4064 1.016)
			(layers "F.Cu" "F.Mask" "F.Paste")
			(net "GND")
		)
		(pad "2" smd rect
			(at 0 0.9398 180)
			(size 0.4064 1.016)
			(layers "F.Cu" "F.Mask" "F.Paste")
			(net "SW_PWR_R_HDD17")
		)
		(pad "3" smd rect
			(at 0.65024 0.9398 180)
			(size 0.4064 1.016)
			(layers "F.Cu" "F.Mask" "F.Paste")
			(net "SW_HDD_P17")
		)
		(pad "4" smd rect
			(at 0.65024 -0.9398 180)
			(size 0.4064 1.016)
			(layers "F.Cu" "F.Mask" "F.Paste")
			(net "GND")
		)
		(pad "5" smd rect
			(at 0 -0.9398 180)
			(size 0.4064 1.016)
			(layers "F.Cu" "F.Mask" "F.Paste")
			(net "SW_HDD_G17")
		)
		(pad "6" smd rect
			(at -0.65024 -0.9398 180)
			(size 0.4064 1.016)
			(layers "F.Cu" "F.Mask" "F.Paste")
			(net "SW_HDD_R17")
		)
	)
	(footprint ""
		(layer "F.Cu")
		(at 258.402328 16.8148 -90)
		(property "Reference" "R611"
			(at 0 0 270)
			(layer "F.SilkS")
			(hide yes)
			(effects
				(font
					(size 1.27 1.27)
				)
			)
		)
		(property "Value" "10KR2F-2-GP"
			(at 0.064008 -3.993896 270)
			(unlocked yes)
			(layer "F.Fab")
			(hide yes)
			(effects
				(font
					(size 1.016 1.016)
					(thickness 0.1524)
				)
			)
		)
		(property "Device Type" "R402H16"
			(at 0.064008 -5.517896 270)
			(unlocked yes)
			(layer "F.Fab")
			(hide yes)
			(effects
				(font
					(size 1.016 1.016)
					(thickness 0.1524)
				)
			)
		)
		(duplicate_pad_numbers_are_jumpers no)
		(fp_line
			(start -0.508 -0.9398)
			(end -0.508 0.9398)
			(stroke
				(width 0.1524)
				(type default)
			)
			(layer "F.SilkS")
		)
		(fp_line
			(start 0.508 -0.9398)
			(end -0.508 -0.9398)
			(stroke
				(width 0.1524)
				(type default)
			)
			(layer "F.SilkS")
		)
		(fp_rect
			(start -0.508 0.9398)
			(end 0.508 -0.9398)
			(stroke
				(width 0)
				(type default)
			)
			(fill no)
			(layer "F.CrtYd")
		)
		(fp_rect
			(start -0.508 0.9398)
			(end 0.508 -0.9398)
			(stroke
				(width 0)
				(type default)
			)
			(fill no)
			(layer "F.Fab")
		)
		(pad "1" smd custom
			(at 0 -0.4445 270)
			(size 0.1397 0.1397)
			(layers "F.Cu" "F.Mask" "F.Paste")
			(net "SCC_A_FAULT_LED")
			(options
				(clearance outline)
				(anchor circle)
			)
			(primitives
				(gr_poly
					(pts
						(arc
							(start -0.1778 -0.2794)
							(mid -0.249642 -0.249642)
							(end -0.2794 -0.1778)
						)
						(arc
							(start -0.2794 0.1778)
							(mid -0.249642 0.249642)
							(end -0.1778 0.2794)
						)
						(arc
							(start 0.1778 0.2794)
							(mid 0.249642 0.249642)
							(end 0.2794 0.1778)
						)
						(arc
							(start 0.2794 -0.1778)
							(mid 0.249642 -0.249642)
							(end 0.1778 -0.2794)
						)
					)
					(width 0)
					(fill yes)
				)
			)
		)
		(pad "2" smd custom
			(at 0 0.4445 270)
			(size 0.1397 0.1397)
			(layers "F.Cu" "F.Mask" "F.Paste")
			(net "GND")
			(options
				(clearance outline)
				(anchor circle)
			)
			(primitives
				(gr_poly
					(pts
						(arc
							(start -0.1778 -0.2794)
							(mid -0.249642 -0.249642)
							(end -0.2794 -0.1778)
						)
						(arc
							(start -0.2794 0.1778)
							(mid -0.249642 0.249642)
							(end -0.1778 0.2794)
						)
						(arc
							(start 0.1778 0.2794)
							(mid 0.249642 0.249642)
							(end 0.2794 0.1778)
						)
						(arc
							(start 0.2794 -0.1778)
							(mid 0.249642 -0.249642)
							(end 0.1778 -0.2794)
						)
					)
					(width 0)
					(fill yes)
				)
			)
		)
	)
	(footprint ""
		(layer "F.Cu")
		(at 235.2294 -248.9708)
		(property "Reference" "R29"
			(at 0 0 0)
			(layer "F.SilkS")
			(hide yes)
			(effects
				(font
					(size 1.27 1.27)
				)
			)
		)
		(property "Value" "0R2J-2-GP"
			(at 0.064008 -3.993896 0)
			(unlocked yes)
			(layer "F.Fab")
			(hide yes)
			(effects
				(font
					(size 1.016 1.016)
					(thickness 0.1524)
				)
			)
		)
		(property "Device Type" "R402H16"
			(at 0.064008 -5.517896 0)
			(unlocked yes)
			(layer "F.Fab")
			(hide yes)
			(effects
				(font
					(size 1.016 1.016)
					(thickness 0.1524)
				)
			)
		)
		(duplicate_pad_numbers_are_jumpers no)
		(fp_line
			(start -0.508 -0.9398)
			(end -0.508 0.9398)
			(stroke
				(width 0.1524)
				(type default)
			)
			(layer "F.SilkS")
		)
		(fp_line
			(start 0.508 -0.9398)
			(end -0.508 -0.9398)
			(stroke
				(width 0.1524)
				(type default)
			)
			(layer "F.SilkS")
		)
		(fp_rect
			(start -0.508 0.9398)
			(end 0.508 -0.9398)
			(stroke
				(width 0)
				(type default)
			)
			(fill no)
			(layer "F.CrtYd")
		)
		(fp_rect
			(start -0.508 0.9398)
			(end 0.508 -0.9398)
			(stroke
				(width 0)
				(type default)
			)
			(fill no)
			(layer "F.Fab")
		)
		(pad "1" smd custom
			(at 0 -0.4445)
			(size 0.1397 0.1397)
			(layers "F.Cu" "F.Mask" "F.Paste")
			(net "IO_EXP4_SCL")
			(options
				(clearance outline)
				(anchor circle)
			)
			(primitives
				(gr_poly
					(pts
						(arc
							(start -0.1778 -0.2794)
							(mid -0.249642 -0.249642)
							(end -0.2794 -0.1778)
						)
						(arc
							(start -0.2794 0.1778)
							(mid -0.249642 0.249642)
							(end -0.1778 0.2794)
						)
						(arc
							(start 0.1778 0.2794)
							(mid 0.249642 0.249642)
							(end 0.2794 0.1778)
						)
						(arc
							(start 0.2794 -0.1778)
							(mid 0.249642 -0.249642)
							(end 0.1778 -0.2794)
						)
					)
					(width 0)
					(fill yes)
				)
			)
		)
		(pad "2" smd custom
			(at 0 0.4445)
			(size 0.1397 0.1397)
			(layers "F.Cu" "F.Mask" "F.Paste")
			(net "I2C_DRIVE_A_INS_SCL")
			(options
				(clearance outline)
				(anchor circle)
			)
			(primitives
				(gr_poly
					(pts
						(arc
							(start -0.1778 -0.2794)
							(mid -0.249642 -0.249642)
							(end -0.2794 -0.1778)
						)
						(arc
							(start -0.2794 0.1778)
							(mid -0.249642 0.249642)
							(end -0.1778 0.2794)
						)
						(arc
							(start 0.1778 0.2794)
							(mid 0.249642 0.249642)
							(end 0.2794 0.1778)
						)
						(arc
							(start 0.2794 -0.1778)
							(mid 0.249642 -0.249642)
							(end 0.1778 -0.2794)
						)
					)
					(width 0)
					(fill yes)
				)
			)
		)
	)
	(footprint ""
		(layer "F.Cu")
		(at 47.472346 -157.839918 90)
		(property "Reference" "R444"
			(at 0 0 90)
			(layer "F.SilkS")
			(hide yes)
			(effects
				(font
					(size 1.27 1.27)
				)
			)
		)
		(property "Value" "4K7R2J-2-GP"
			(at 0.064008 -3.993896 90)
			(unlocked yes)
			(layer "F.Fab")
			(hide yes)
			(effects
				(font
					(size 1.016 1.016)
					(thickness 0.1524)
				)
			)
		)
		(property "Device Type" "R402H16"
			(at 0.064008 -5.517896 90)
			(unlocked yes)
			(layer "F.Fab")
			(hide yes)
			(effects
				(font
					(size 1.016 1.016)
					(thickness 0.1524)
				)
			)
		)
		(duplicate_pad_numbers_are_jumpers no)
		(fp_line
			(start 0.508 -0.9398)
			(end -0.508 -0.9398)
			(stroke
				(width 0.1524)
				(type default)
			)
			(layer "F.SilkS")
		)
		(fp_line
			(start -0.508 -0.9398)
			(end -0.508 0.9398)
			(stroke
				(width 0.1524)
				(type default)
			)
			(layer "F.SilkS")
		)
		(fp_rect
			(start -0.508 0.9398)
			(end 0.508 -0.9398)
			(stroke
				(width 0)
				(type default)
			)
			(fill no)
			(layer "F.CrtYd")
		)
		(fp_rect
			(start -0.508 0.9398)
			(end 0.508 -0.9398)
			(stroke
				(width 0)
				(type default)
			)
			(fill no)
			(layer "F.Fab")
		)
		(pad "1" smd custom
			(at 0 -0.4445 90)
			(size 0.1397 0.1397)
			(layers "F.Cu" "F.Mask" "F.Paste")
			(net "P12V_A")
			(options
				(clearance outline)
				(anchor circle)
			)
			(primitives
				(gr_poly
					(pts
						(arc
							(start -0.1778 -0.2794)
							(mid -0.249642 -0.249642)
							(end -0.2794 -0.1778)
						)
						(arc
							(start -0.2794 0.1778)
							(mid -0.249642 0.249642)
							(end -0.1778 0.2794)
						)
						(arc
							(start 0.1778 0.2794)
							(mid 0.249642 0.249642)
							(end 0.2794 0.1778)
						)
						(arc
							(start 0.2794 -0.1778)
							(mid 0.249642 -0.249642)
							(end 0.1778 -0.2794)
						)
					)
					(width 0)
					(fill yes)
				)
			)
		)
		(pad "2" smd custom
			(at 0 0.4445 90)
			(size 0.1397 0.1397)
			(layers "F.Cu" "F.Mask" "F.Paste")
			(net "SW_HDD_R13")
			(options
				(clearance outline)
				(anchor circle)
			)
			(primitives
				(gr_poly
					(pts
						(arc
							(start -0.1778 -0.2794)
							(mid -0.249642 -0.249642)
							(end -0.2794 -0.1778)
						)
						(arc
							(start -0.2794 0.1778)
							(mid -0.249642 0.249642)
							(end -0.1778 0.2794)
						)
						(arc
							(start 0.1778 0.2794)
							(mid 0.249642 0.249642)
							(end 0.2794 0.1778)
						)
						(arc
							(start 0.2794 -0.1778)
							(mid 0.249642 -0.249642)
							(end 0.1778 -0.2794)
						)
					)
					(width 0)
					(fill yes)
				)
			)
		)
	)
	(footprint ""
		(layer "F.Cu")
		(at 254.811276 -261.32536 180)
		(property "Reference" "R57"
			(at 0 0 180)
			(layer "F.SilkS")
			(hide yes)
			(effects
				(font
					(size 1.27 1.27)
				)
			)
		)
		(property "Value" "0R2J-2-GP"
			(at 0.064008 -3.993896 180)
			(unlocked yes)
			(layer "F.Fab")
			(hide yes)
			(effects
				(font
					(size 1.016 1.016)
					(thickness 0.1524)
				)
			)
		)
		(property "Device Type" "R402H16"
			(at 0.064008 -5.517896 180)
			(unlocked yes)
			(layer "F.Fab")
			(hide yes)
			(effects
				(font
					(size 1.016 1.016)
					(thickness 0.1524)
				)
			)
		)
		(duplicate_pad_numbers_are_jumpers no)
		(fp_line
			(start 0.508 -0.9398)
			(end -0.508 -0.9398)
			(stroke
				(width 0.1524)
				(type default)
			)
			(layer "F.SilkS")
		)
		(fp_line
			(start -0.508 -0.9398)
			(end -0.508 0.9398)
			(stroke
				(width 0.1524)
				(type default)
			)
			(layer "F.SilkS")
		)
		(fp_rect
			(start -0.508 0.9398)
			(end 0.508 -0.9398)
			(stroke
				(width 0)
				(type default)
			)
			(fill no)
			(layer "F.CrtYd")
		)
		(fp_rect
			(start -0.508 0.9398)
			(end 0.508 -0.9398)
			(stroke
				(width 0)
				(type default)
			)
			(fill no)
			(layer "F.Fab")
		)
		(pad "1" smd custom
			(at 0 -0.4445 180)
			(size 0.1397 0.1397)
			(layers "F.Cu" "F.Mask" "F.Paste")
			(net "IO_EXP6_SCL")
			(options
				(clearance outline)
				(anchor circle)
			)
			(primitives
				(gr_poly
					(pts
						(arc
							(start -0.1778 -0.2794)
							(mid -0.249642 -0.249642)
							(end -0.2794 -0.1778)
						)
						(arc
							(start -0.2794 0.1778)
							(mid -0.249642 0.249642)
							(end -0.1778 0.2794)
						)
						(arc
							(start 0.1778 0.2794)
							(mid 0.249642 0.249642)
							(end 0.2794 0.1778)
						)
						(arc
							(start 0.2794 -0.1778)
							(mid 0.249642 -0.249642)
							(end 0.1778 -0.2794)
						)
					)
					(width 0)
					(fill yes)
				)
			)
		)
		(pad "2" smd custom
			(at 0 0.4445 180)
			(size 0.1397 0.1397)
			(layers "F.Cu" "F.Mask" "F.Paste")
			(net "I2C_DRIVE_A_INS_SCL")
			(options
				(clearance outline)
				(anchor circle)
			)
			(primitives
				(gr_poly
					(pts
						(arc
							(start -0.1778 -0.2794)
							(mid -0.249642 -0.249642)
							(end -0.2794 -0.1778)
						)
						(arc
							(start -0.2794 0.1778)
							(mid -0.249642 0.249642)
							(end -0.1778 0.2794)
						)
						(arc
							(start 0.1778 0.2794)
							(mid 0.249642 0.249642)
							(end 0.2794 0.1778)
						)
						(arc
							(start 0.2794 -0.1778)
							(mid 0.249642 -0.249642)
							(end 0.1778 -0.2794)
						)
					)
					(width 0)
					(fill yes)
				)
			)
		)
	)
	(footprint ""
		(layer "F.Cu")
		(at 141.042898 -54.523894 90)
		(property "Reference" "C413"
			(at 0 0 90)
			(layer "F.SilkS")
			(hide yes)
			(effects
				(font
					(size 1.27 1.27)
				)
			)
		)
		(property "Value" "SCD033U25V2KX-GP"
			(at 1.1811 -2.7051 90)
			(unlocked yes)
			(layer "F.Fab")
			(hide yes)
			(effects
				(font
					(size 1.016 1.016)
					(thickness 0.1524)
				)
			)
		)
		(property "Device Type" "C402H22"
			(at 1.1811 -4.2291 90)
			(unlocked yes)
			(layer "F.Fab")
			(hide yes)
			(effects
				(font
					(size 1.016 1.016)
					(thickness 0.1524)
				)
			)
		)
		(duplicate_pad_numbers_are_jumpers no)
		(fp_rect
			(start -0.4318 0.9525)
			(end 0.4318 -0.9525)
			(stroke
				(width 0)
				(type default)
			)
			(fill no)
			(layer "F.CrtYd")
		)
		(fp_rect
			(start -0.4318 0.9525)
			(end 0.4318 -0.9525)
			(stroke
				(width 0)
				(type default)
			)
			(fill no)
			(layer "F.Fab")
		)
		(pad "1" smd custom
			(at 0 -0.4445 90)
			(size 0.1524 0.1524)
			(layers "F.Cu" "F.Mask" "F.Paste")
			(net "P12V_A")
			(options
				(clearance outline)
				(anchor circle)
			)
			(primitives
				(gr_poly
					(pts
						(arc
							(start 0.3048 -0.2032)
							(mid 0.275042 -0.275042)
							(end 0.2032 -0.3048)
						)
						(arc
							(start -0.2032 -0.3048)
							(mid -0.275042 -0.275042)
							(end -0.3048 -0.2032)
						)
						(arc
							(start -0.3048 0.2032)
							(mid -0.275042 0.275042)
							(end -0.2032 0.3048)
						)
						(arc
							(start 0.2032 0.3048)
							(mid 0.275042 0.275042)
							(end 0.3048 0.2032)
						)
					)
					(width 0)
					(fill yes)
				)
			)
		)
		(pad "2" smd custom
			(at 0 0.4445 90)
			(size 0.1524 0.1524)
			(layers "F.Cu" "F.Mask" "F.Paste")
			(net "SW_HDD_N28")
			(options
				(clearance outline)
				(anchor circle)
			)
			(primitives
				(gr_poly
					(pts
						(arc
							(start 0.3048 -0.2032)
							(mid 0.275042 -0.275042)
							(end 0.2032 -0.3048)
						)
						(arc
							(start -0.2032 -0.3048)
							(mid -0.275042 -0.275042)
							(end -0.3048 -0.2032)
						)
						(arc
							(start -0.3048 0.2032)
							(mid -0.275042 0.275042)
							(end -0.2032 0.3048)
						)
						(arc
							(start 0.2032 0.3048)
							(mid 0.275042 0.275042)
							(end 0.3048 0.2032)
						)
					)
					(width 0)
					(fill yes)
				)
			)
		)
	)
	(footprint ""
		(layer "F.Cu")
		(at 180.7464 -44.821094 -90)
		(property "Reference" "R808"
			(at 0 0 270)
			(layer "F.SilkS")
			(hide yes)
			(effects
				(font
					(size 1.27 1.27)
				)
			)
		)
		(property "Value" "0R2J-2-GP"
			(at 0.064008 -3.993896 270)
			(unlocked yes)
			(layer "F.Fab")
			(hide yes)
			(effects
				(font
					(size 1.016 1.016)
					(thickness 0.1524)
				)
			)
		)
		(property "Device Type" "R402H16"
			(at 0.064008 -5.517896 270)
			(unlocked yes)
			(layer "F.Fab")
			(hide yes)
			(effects
				(font
					(size 1.016 1.016)
					(thickness 0.1524)
				)
			)
		)
		(duplicate_pad_numbers_are_jumpers no)
		(fp_line
			(start -0.508 -0.9398)
			(end -0.508 0.9398)
			(stroke
				(width 0.1524)
				(type default)
			)
			(layer "F.SilkS")
		)
		(fp_line
			(start 0.508 -0.9398)
			(end -0.508 -0.9398)
			(stroke
				(width 0.1524)
				(type default)
			)
			(layer "F.SilkS")
		)
		(fp_rect
			(start -0.508 0.9398)
			(end 0.508 -0.9398)
			(stroke
				(width 0)
				(type default)
			)
			(fill no)
			(layer "F.CrtYd")
		)
		(fp_rect
			(start -0.508 0.9398)
			(end 0.508 -0.9398)
			(stroke
				(width 0)
				(type default)
			)
			(fill no)
			(layer "F.Fab")
		)
		(pad "1" smd custom
			(at 0 -0.4445 270)
			(size 0.1397 0.1397)
			(layers "F.Cu" "F.Mask" "F.Paste")
			(net "DRIVE_A_29_PWR")
			(options
				(clearance outline)
				(anchor circle)
			)
			(primitives
				(gr_poly
					(pts
						(arc
							(start -0.1778 -0.2794)
							(mid -0.249642 -0.249642)
							(end -0.2794 -0.1778)
						)
						(arc
							(start -0.2794 0.1778)
							(mid -0.249642 0.249642)
							(end -0.1778 0.2794)
						)
						(arc
							(start 0.1778 0.2794)
							(mid 0.249642 0.249642)
							(end 0.2794 0.1778)
						)
						(arc
							(start 0.2794 -0.1778)
							(mid 0.249642 -0.249642)
							(end 0.1778 -0.2794)
						)
					)
					(width 0)
					(fill yes)
				)
			)
		)
		(pad "2" smd custom
			(at 0 0.4445 270)
			(size 0.1397 0.1397)
			(layers "F.Cu" "F.Mask" "F.Paste")
			(net "SW_PWR_R_HDD29")
			(options
				(clearance outline)
				(anchor circle)
			)
			(primitives
				(gr_poly
					(pts
						(arc
							(start -0.1778 -0.2794)
							(mid -0.249642 -0.249642)
							(end -0.2794 -0.1778)
						)
						(arc
							(start -0.2794 0.1778)
							(mid -0.249642 0.249642)
							(end -0.1778 0.2794)
						)
						(arc
							(start 0.1778 0.2794)
							(mid 0.249642 0.249642)
							(end 0.2794 0.1778)
						)
						(arc
							(start 0.2794 -0.1778)
							(mid 0.249642 -0.249642)
							(end 0.1778 -0.2794)
						)
					)
					(width 0)
					(fill yes)
				)
			)
		)
	)
	(footprint ""
		(layer "F.Cu")
		(at 245.499128 -390.723628 -90)
		(property "Reference" "R1141"
			(at 0 0 270)
			(layer "F.SilkS")
			(hide yes)
			(effects
				(font
					(size 1.27 1.27)
				)
			)
		)
		(property "Value" "10R2F-L-GP"
			(at 0.064008 -3.993896 270)
			(unlocked yes)
			(layer "F.Fab")
			(hide yes)
			(effects
				(font
					(size 1.016 1.016)
					(thickness 0.1524)
				)
			)
		)
		(property "Device Type" "R402H14"
			(at 0.064008 -5.517896 270)
			(unlocked yes)
			(layer "F.Fab")
			(hide yes)
			(effects
				(font
					(size 1.016 1.016)
					(thickness 0.1524)
				)
			)
		)
		(duplicate_pad_numbers_are_jumpers no)
		(fp_line
			(start -0.508 -0.9398)
			(end -0.508 0.9398)
			(stroke
				(width 0.1524)
				(type default)
			)
			(layer "F.SilkS")
		)
		(fp_line
			(start 0.508 -0.9398)
			(end -0.508 -0.9398)
			(stroke
				(width 0.1524)
				(type default)
			)
			(layer "F.SilkS")
		)
		(fp_rect
			(start -0.508 0.9398)
			(end 0.508 -0.9398)
			(stroke
				(width 0)
				(type default)
			)
			(fill no)
			(layer "F.CrtYd")
		)
		(fp_rect
			(start -0.508 0.9398)
			(end 0.508 -0.9398)
			(stroke
				(width 0)
				(type default)
			)
			(fill no)
			(layer "F.Fab")
		)
		(pad "1" smd custom
			(at 0 -0.4445 270)
			(size 0.1397 0.1397)
			(layers "F.Cu" "F.Mask" "F.Paste")
			(net "P12V_IN")
			(options
				(clearance outline)
				(anchor circle)
			)
			(primitives
				(gr_poly
					(pts
						(arc
							(start -0.1778 -0.2794)
							(mid -0.249642 -0.249642)
							(end -0.2794 -0.1778)
						)
						(arc
							(start -0.2794 0.1778)
							(mid -0.249642 0.249642)
							(end -0.1778 0.2794)
						)
						(arc
							(start 0.1778 0.2794)
							(mid 0.249642 0.249642)
							(end 0.2794 0.1778)
						)
						(arc
							(start 0.2794 -0.1778)
							(mid 0.249642 -0.249642)
							(end 0.1778 -0.2794)
						)
					)
					(width 0)
					(fill yes)
				)
			)
		)
		(pad "2" smd custom
			(at 0 0.4445 270)
			(size 0.1397 0.1397)
			(layers "F.Cu" "F.Mask" "F.Paste")
			(net "MB3_P12V_HS")
			(options
				(clearance outline)
				(anchor circle)
			)
			(primitives
				(gr_poly
					(pts
						(arc
							(start -0.1778 -0.2794)
							(mid -0.249642 -0.249642)
							(end -0.2794 -0.1778)
						)
						(arc
							(start -0.2794 0.1778)
							(mid -0.249642 0.249642)
							(end -0.1778 0.2794)
						)
						(arc
							(start 0.1778 0.2794)
							(mid 0.249642 0.249642)
							(end 0.2794 0.1778)
						)
						(arc
							(start 0.2794 -0.1778)
							(mid 0.249642 -0.249642)
							(end 0.1778 -0.2794)
						)
					)
					(width 0)
					(fill yes)
				)
			)
		)
	)
	(footprint ""
		(layer "F.Cu")
		(at 227.66909 -387.783832)
		(property "Reference" "R1107"
			(at 0 0 0)
			(layer "F.SilkS")
			(hide yes)
			(effects
				(font
					(size 1.27 1.27)
				)
			)
		)
		(property "Value" "10KR2F-2-GP"
			(at 0.064008 -3.993896 0)
			(unlocked yes)
			(layer "F.Fab")
			(hide yes)
			(effects
				(font
					(size 1.016 1.016)
					(thickness 0.1524)
				)
			)
		)
		(property "Device Type" "R402H16"
			(at 0.064008 -5.517896 0)
			(unlocked yes)
			(layer "F.Fab")
			(hide yes)
			(effects
				(font
					(size 1.016 1.016)
					(thickness 0.1524)
				)
			)
		)
		(duplicate_pad_numbers_are_jumpers no)
		(fp_line
			(start -0.508 -0.9398)
			(end -0.508 0.9398)
			(stroke
				(width 0.1524)
				(type default)
			)
			(layer "F.SilkS")
		)
		(fp_line
			(start 0.508 -0.9398)
			(end -0.508 -0.9398)
			(stroke
				(width 0.1524)
				(type default)
			)
			(layer "F.SilkS")
		)
		(fp_rect
			(start -0.508 0.9398)
			(end 0.508 -0.9398)
			(stroke
				(width 0)
				(type default)
			)
			(fill no)
			(layer "F.CrtYd")
		)
		(fp_rect
			(start -0.508 0.9398)
			(end 0.508 -0.9398)
			(stroke
				(width 0)
				(type default)
			)
			(fill no)
			(layer "F.Fab")
		)
		(pad "1" smd custom
			(at 0 -0.4445)
			(size 0.1397 0.1397)
			(layers "F.Cu" "F.Mask" "F.Paste")
			(net "P12V_IN")
			(options
				(clearance outline)
				(anchor circle)
			)
			(primitives
				(gr_poly
					(pts
						(arc
							(start -0.1778 -0.2794)
							(mid -0.249642 -0.249642)
							(end -0.2794 -0.1778)
						)
						(arc
							(start -0.2794 0.1778)
							(mid -0.249642 0.249642)
							(end -0.1778 0.2794)
						)
						(arc
							(start 0.1778 0.2794)
							(mid 0.249642 0.249642)
							(end 0.2794 0.1778)
						)
						(arc
							(start 0.2794 -0.1778)
							(mid 0.249642 -0.249642)
							(end 0.1778 -0.2794)
						)
					)
					(width 0)
					(fill yes)
				)
			)
		)
		(pad "2" smd custom
			(at 0 0.4445)
			(size 0.1397 0.1397)
			(layers "F.Cu" "F.Mask" "F.Paste")
			(net "DPB_PWR_BTN_BUF_A")
			(options
				(clearance outline)
				(anchor circle)
			)
			(primitives
				(gr_poly
					(pts
						(arc
							(start -0.1778 -0.2794)
							(mid -0.249642 -0.249642)
							(end -0.2794 -0.1778)
						)
						(arc
							(start -0.2794 0.1778)
							(mid -0.249642 0.249642)
							(end -0.1778 0.2794)
						)
						(arc
							(start 0.1778 0.2794)
							(mid 0.249642 0.249642)
							(end 0.2794 0.1778)
						)
						(arc
							(start 0.2794 -0.1778)
							(mid 0.249642 -0.249642)
							(end 0.1778 -0.2794)
						)
					)
					(width 0)
					(fill yes)
				)
			)
		)
	)
	(footprint ""
		(layer "F.Cu")
		(at 16.824198 -283.152342 -90)
		(property "Reference" "C516"
			(at 0 0 270)
			(layer "F.SilkS")
			(hide yes)
			(effects
				(font
					(size 1.27 1.27)
				)
			)
		)
		(property "Value" "SCD033U25V2KX-GP"
			(at 1.1811 -2.7051 270)
			(unlocked yes)
			(layer "F.Fab")
			(hide yes)
			(effects
				(font
					(size 1.016 1.016)
					(thickness 0.1524)
				)
			)
		)
		(property "Device Type" "C402H22"
			(at 1.1811 -4.2291 270)
			(unlocked yes)
			(layer "F.Fab")
			(hide yes)
			(effects
				(font
					(size 1.016 1.016)
					(thickness 0.1524)
				)
			)
		)
		(duplicate_pad_numbers_are_jumpers no)
		(fp_rect
			(start -0.4318 0.9525)
			(end 0.4318 -0.9525)
			(stroke
				(width 0)
				(type default)
			)
			(fill no)
			(layer "F.CrtYd")
		)
		(fp_rect
			(start -0.4318 0.9525)
			(end 0.4318 -0.9525)
			(stroke
				(width 0)
				(type default)
			)
			(fill no)
			(layer "F.Fab")
		)
		(pad "1" smd custom
			(at 0 -0.4445 270)
			(size 0.1524 0.1524)
			(layers "F.Cu" "F.Mask" "F.Paste")
			(net "SW_HDD_P0")
			(options
				(clearance outline)
				(anchor circle)
			)
			(primitives
				(gr_poly
					(pts
						(arc
							(start 0.3048 -0.2032)
							(mid 0.275042 -0.275042)
							(end 0.2032 -0.3048)
						)
						(arc
							(start -0.2032 -0.3048)
							(mid -0.275042 -0.275042)
							(end -0.3048 -0.2032)
						)
						(arc
							(start -0.3048 0.2032)
							(mid -0.275042 0.275042)
							(end -0.2032 0.3048)
						)
						(arc
							(start 0.2032 0.3048)
							(mid 0.275042 0.275042)
							(end 0.3048 0.2032)
						)
					)
					(width 0)
					(fill yes)
				)
			)
		)
		(pad "2" smd custom
			(at 0 0.4445 270)
			(size 0.1524 0.1524)
			(layers "F.Cu" "F.Mask" "F.Paste")
			(net "GND")
			(options
				(clearance outline)
				(anchor circle)
			)
			(primitives
				(gr_poly
					(pts
						(arc
							(start 0.3048 -0.2032)
							(mid 0.275042 -0.275042)
							(end 0.2032 -0.3048)
						)
						(arc
							(start -0.2032 -0.3048)
							(mid -0.275042 -0.275042)
							(end -0.3048 -0.2032)
						)
						(arc
							(start -0.3048 0.2032)
							(mid -0.275042 0.275042)
							(end -0.2032 0.3048)
						)
						(arc
							(start 0.2032 0.3048)
							(mid 0.275042 0.275042)
							(end 0.3048 0.2032)
						)
					)
					(width 0)
					(fill yes)
				)
			)
		)
	)
	(footprint ""
		(layer "F.Cu")
		(at 402.782278 -32.513016)
		(property "Reference" "R12"
			(at 0 0 0)
			(layer "F.SilkS")
			(hide yes)
			(effects
				(font
					(size 1.27 1.27)
				)
			)
		)
		(property "Value" "0R2J-2-GP"
			(at 0.064008 -3.993896 0)
			(unlocked yes)
			(layer "F.Fab")
			(hide yes)
			(effects
				(font
					(size 1.016 1.016)
					(thickness 0.1524)
				)
			)
		)
		(property "Device Type" "R402H16"
			(at 0.064008 -5.517896 0)
			(unlocked yes)
			(layer "F.Fab")
			(hide yes)
			(effects
				(font
					(size 1.016 1.016)
					(thickness 0.1524)
				)
			)
		)
		(duplicate_pad_numbers_are_jumpers no)
		(fp_line
			(start -0.508 -0.9398)
			(end -0.508 0.9398)
			(stroke
				(width 0.1524)
				(type default)
			)
			(layer "F.SilkS")
		)
		(fp_line
			(start 0.508 -0.9398)
			(end -0.508 -0.9398)
			(stroke
				(width 0.1524)
				(type default)
			)
			(layer "F.SilkS")
		)
		(fp_rect
			(start -0.508 0.9398)
			(end 0.508 -0.9398)
			(stroke
				(width 0)
				(type default)
			)
			(fill no)
			(layer "F.CrtYd")
		)
		(fp_rect
			(start -0.508 0.9398)
			(end 0.508 -0.9398)
			(stroke
				(width 0)
				(type default)
			)
			(fill no)
			(layer "F.Fab")
		)
		(pad "1" smd custom
			(at 0 -0.4445)
			(size 0.1397 0.1397)
			(layers "F.Cu" "F.Mask" "F.Paste")
			(net "GND")
			(options
				(clearance outline)
				(anchor circle)
			)
			(primitives
				(gr_poly
					(pts
						(arc
							(start -0.1778 -0.2794)
							(mid -0.249642 -0.249642)
							(end -0.2794 -0.1778)
						)
						(arc
							(start -0.2794 0.1778)
							(mid -0.249642 0.249642)
							(end -0.1778 0.2794)
						)
						(arc
							(start 0.1778 0.2794)
							(mid 0.249642 0.249642)
							(end 0.2794 0.1778)
						)
						(arc
							(start 0.2794 -0.1778)
							(mid 0.249642 -0.249642)
							(end 0.1778 -0.2794)
						)
					)
					(width 0)
					(fill yes)
				)
			)
		)
		(pad "2" smd custom
			(at 0 0.4445)
			(size 0.1397 0.1397)
			(layers "F.Cu" "F.Mask" "F.Paste")
			(net "IOM_B_MATED_N")
			(options
				(clearance outline)
				(anchor circle)
			)
			(primitives
				(gr_poly
					(pts
						(arc
							(start -0.1778 -0.2794)
							(mid -0.249642 -0.249642)
							(end -0.2794 -0.1778)
						)
						(arc
							(start -0.2794 0.1778)
							(mid -0.249642 0.249642)
							(end -0.1778 0.2794)
						)
						(arc
							(start 0.1778 0.2794)
							(mid 0.249642 0.249642)
							(end 0.2794 0.1778)
						)
						(arc
							(start 0.2794 -0.1778)
							(mid 0.249642 -0.249642)
							(end 0.1778 -0.2794)
						)
					)
					(width 0)
					(fill yes)
				)
			)
		)
	)
	(footprint ""
		(layer "F.Cu")
		(at 77.892148 -275.633942 90)
		(property "Reference" "R190"
			(at 0 0 90)
			(layer "F.SilkS")
			(hide yes)
			(effects
				(font
					(size 1.27 1.27)
				)
			)
		)
		(property "Value" "4K7R2J-2-GP"
			(at 0.064008 -3.993896 90)
			(unlocked yes)
			(layer "F.Fab")
			(hide yes)
			(effects
				(font
					(size 1.016 1.016)
					(thickness 0.1524)
				)
			)
		)
		(property "Device Type" "R402H16"
			(at 0.064008 -5.517896 90)
			(unlocked yes)
			(layer "F.Fab")
			(hide yes)
			(effects
				(font
					(size 1.016 1.016)
					(thickness 0.1524)
				)
			)
		)
		(duplicate_pad_numbers_are_jumpers no)
		(fp_line
			(start 0.508 -0.9398)
			(end -0.508 -0.9398)
			(stroke
				(width 0.1524)
				(type default)
			)
			(layer "F.SilkS")
		)
		(fp_line
			(start -0.508 -0.9398)
			(end -0.508 0.9398)
			(stroke
				(width 0.1524)
				(type default)
			)
			(layer "F.SilkS")
		)
		(fp_rect
			(start -0.508 0.9398)
			(end 0.508 -0.9398)
			(stroke
				(width 0)
				(type default)
			)
			(fill no)
			(layer "F.CrtYd")
		)
		(fp_rect
			(start -0.508 0.9398)
			(end 0.508 -0.9398)
			(stroke
				(width 0)
				(type default)
			)
			(fill no)
			(layer "F.Fab")
		)
		(pad "1" smd custom
			(at 0 -0.4445 90)
			(size 0.1397 0.1397)
			(layers "F.Cu" "F.Mask" "F.Paste")
			(net "P12V_A")
			(options
				(clearance outline)
				(anchor circle)
			)
			(primitives
				(gr_poly
					(pts
						(arc
							(start -0.1778 -0.2794)
							(mid -0.249642 -0.249642)
							(end -0.2794 -0.1778)
						)
						(arc
							(start -0.2794 0.1778)
							(mid -0.249642 0.249642)
							(end -0.1778 0.2794)
						)
						(arc
							(start 0.1778 0.2794)
							(mid 0.249642 0.249642)
							(end 0.2794 0.1778)
						)
						(arc
							(start 0.2794 -0.1778)
							(mid 0.249642 -0.249642)
							(end 0.1778 -0.2794)
						)
					)
					(width 0)
					(fill yes)
				)
			)
		)
		(pad "2" smd custom
			(at 0 0.4445 90)
			(size 0.1397 0.1397)
			(layers "F.Cu" "F.Mask" "F.Paste")
			(net "SW_HDD_R2")
			(options
				(clearance outline)
				(anchor circle)
			)
			(primitives
				(gr_poly
					(pts
						(arc
							(start -0.1778 -0.2794)
							(mid -0.249642 -0.249642)
							(end -0.2794 -0.1778)
						)
						(arc
							(start -0.2794 0.1778)
							(mid -0.249642 0.249642)
							(end -0.1778 0.2794)
						)
						(arc
							(start 0.1778 0.2794)
							(mid 0.249642 0.249642)
							(end 0.2794 0.1778)
						)
						(arc
							(start 0.2794 -0.1778)
							(mid 0.249642 -0.249642)
							(end 0.1778 -0.2794)
						)
					)
					(width 0)
					(fill yes)
				)
			)
		)
	)
	(footprint ""
		(layer "F.Cu")
		(at 6.906006 -178.824636)
		(property "Reference" "Q223"
			(at 0 0 0)
			(layer "F.SilkS")
			(hide yes)
			(effects
				(font
					(size 1.27 1.27)
				)
			)
		)
		(property "Value" "2N7002K-2-GP"
			(at 0.127 -8.9662 0)
			(unlocked yes)
			(layer "F.Fab")
			(hide yes)
			(effects
				(font
					(size 1.016 1.016)
					(thickness 0.1524)
				)
			)
		)
		(property "Device Type" "SOT23DGS2D4H44"
			(at 0.127 -10.4902 0)
			(unlocked yes)
			(layer "F.Fab")
			(hide yes)
			(effects
				(font
					(size 1.016 1.016)
					(thickness 0.1524)
				)
			)
		)
		(duplicate_pad_numbers_are_jumpers no)
		(fp_line
			(start -1.651 -1.778)
			(end -1.651 1.778)
			(stroke
				(width 0.1524)
				(type default)
			)
			(layer "F.SilkS")
		)
		(fp_line
			(start -1.651 1.778)
			(end 1.651 1.778)
			(stroke
				(width 0.1524)
				(type default)
			)
			(layer "F.SilkS")
		)
		(fp_line
			(start 1.651 -1.778)
			(end -1.651 -1.778)
			(stroke
				(width 0.1524)
				(type default)
			)
			(layer "F.SilkS")
		)
		(fp_line
			(start 1.651 1.778)
			(end 1.651 -1.778)
			(stroke
				(width 0.1524)
				(type default)
			)
			(layer "F.SilkS")
		)
		(fp_poly
			(pts
				(xy -1.778 1.8796) (xy -1.778 -1.8796) (xy 1.778 -1.8796) (xy 1.778 1.8796)
			)
			(stroke
				(width 0)
				(type default)
			)
			(fill no)
			(layer "F.CrtYd")
		)
		(fp_poly
			(pts
				(xy -1.778 1.8796) (xy -1.778 -1.8796) (xy 1.778 -1.8796) (xy 1.778 1.8796)
			)
			(stroke
				(width 0)
				(type default)
			)
			(fill no)
			(layer "F.Fab")
		)
		(pad "D" smd custom
			(at 0 -0.9525)
			(size 0.1905 0.1905)
			(layers "F.Cu" "F.Mask" "F.Paste")
			(net "FLT_HDD0_N")
			(options
				(clearance outline)
				(anchor circle)
			)
			(primitives
				(gr_poly
					(pts
						(arc
							(start -0.1778 0.5715)
							(mid -0.321484 0.511984)
							(end -0.381 0.3683)
						)
						(arc
							(start -0.381 -0.3683)
							(mid -0.321484 -0.511984)
							(end -0.1778 -0.5715)
						)
						(arc
							(start 0.1778 -0.5715)
							(mid 0.321484 -0.511984)
							(end 0.381 -0.3683)
						)
						(arc
							(start 0.381 0.3683)
							(mid 0.321484 0.511984)
							(end 0.1778 0.5715)
						)
					)
					(width 0)
					(fill yes)
				)
			)
		)
		(pad "G" smd custom
			(at -0.98425 0.9525)
			(size 0.1905 0.1905)
			(layers "F.Cu" "F.Mask" "F.Paste")
			(net "DRIVE_A_0_FLT_LED")
			(options
				(clearance outline)
				(anchor circle)
			)
			(primitives
				(gr_poly
					(pts
						(arc
							(start -0.1778 0.5715)
							(mid -0.321484 0.511984)
							(end -0.381 0.3683)
						)
						(arc
							(start -0.381 -0.3683)
							(mid -0.321484 -0.511984)
							(end -0.1778 -0.5715)
						)
						(arc
							(start 0.1778 -0.5715)
							(mid 0.321484 -0.511984)
							(end 0.381 -0.3683)
						)
						(arc
							(start 0.381 0.3683)
							(mid 0.321484 0.511984)
							(end 0.1778 0.5715)
						)
					)
					(width 0)
					(fill yes)
				)
			)
		)
		(pad "S" smd custom
			(at 0.98425 0.9525)
			(size 0.1905 0.1905)
			(layers "F.Cu" "F.Mask" "F.Paste")
			(net "GND")
			(options
				(clearance outline)
				(anchor circle)
			)
			(primitives
				(gr_poly
					(pts
						(arc
							(start -0.1778 0.5715)
							(mid -0.321484 0.511984)
							(end -0.381 0.3683)
						)
						(arc
							(start -0.381 -0.3683)
							(mid -0.321484 -0.511984)
							(end -0.1778 -0.5715)
						)
						(arc
							(start 0.1778 -0.5715)
							(mid 0.321484 -0.511984)
							(end 0.381 -0.3683)
						)
						(arc
							(start 0.381 0.3683)
							(mid 0.321484 0.511984)
							(end 0.1778 0.5715)
						)
					)
					(width 0)
					(fill yes)
				)
			)
		)
	)
	(footprint ""
		(layer "F.Cu")
		(at 20.430998 -163.554918 180)
		(property "Reference" "Q73"
			(at 0 0 180)
			(layer "F.SilkS")
			(hide yes)
			(effects
				(font
					(size 1.27 1.27)
				)
			)
		)
		(property "Value" "2N7002KDW-GP"
			(at -2.3622 -8.2042 180)
			(unlocked yes)
			(layer "F.Fab")
			(hide yes)
			(effects
				(font
					(size 1.016 1.016)
					(thickness 0.1524)
				)
			)
		)
		(property "Device Type" "SOT-363H44"
			(at -2.3622 -10.1092 180)
			(unlocked yes)
			(layer "F.Fab")
			(hide yes)
			(effects
				(font
					(size 1.016 1.016)
					(thickness 0.1524)
				)
			)
		)
		(duplicate_pad_numbers_are_jumpers no)
		(fp_line
			(start 1.4478 1.7018)
			(end 1.4478 -1.7018)
			(stroke
				(width 0.1524)
				(type default)
			)
			(layer "F.SilkS")
		)
		(fp_line
			(start 1.4478 -1.7018)
			(end -1.4478 -1.7018)
			(stroke
				(width 0.1524)
				(type default)
			)
			(layer "F.SilkS")
		)
		(fp_line
			(start -1.27 1.524)
			(end -1.27 0.6604)
			(stroke
				(width 0.4826)
				(type default)
			)
			(layer "F.SilkS")
		)
		(fp_line
			(start -1.4478 1.7018)
			(end 1.4478 1.7018)
			(stroke
				(width 0.1524)
				(type default)
			)
			(layer "F.SilkS")
		)
		(fp_line
			(start -1.4478 -1.7018)
			(end -1.4478 1.7018)
			(stroke
				(width 0.1524)
				(type default)
			)
			(layer "F.SilkS")
		)
		(fp_poly
			(pts
				(xy -1.524 -1.778) (xy 1.524 -1.778) (xy 1.524 1.778) (xy -1.524 1.778)
			)
			(stroke
				(width 0)
				(type default)
			)
			(fill no)
			(layer "F.CrtYd")
		)
		(fp_poly
			(pts
				(xy -1.524 -1.778) (xy 1.524 -1.778) (xy 1.524 1.778) (xy -1.524 1.778)
			)
			(stroke
				(width 0)
				(type default)
			)
			(fill no)
			(layer "F.Fab")
		)
		(pad "1" smd rect
			(at -0.65024 0.9398 180)
			(size 0.4064 1.016)
			(layers "F.Cu" "F.Mask" "F.Paste")
			(net "GND")
		)
		(pad "2" smd rect
			(at 0 0.9398 180)
			(size 0.4064 1.016)
			(layers "F.Cu" "F.Mask" "F.Paste")
			(net "SW_PWR_R_HDD12")
		)
		(pad "3" smd rect
			(at 0.65024 0.9398 180)
			(size 0.4064 1.016)
			(layers "F.Cu" "F.Mask" "F.Paste")
			(net "SW_HDD_P12")
		)
		(pad "4" smd rect
			(at 0.65024 -0.9398 180)
			(size 0.4064 1.016)
			(layers "F.Cu" "F.Mask" "F.Paste")
			(net "GND")
		)
		(pad "5" smd rect
			(at 0 -0.9398 180)
			(size 0.4064 1.016)
			(layers "F.Cu" "F.Mask" "F.Paste")
			(net "SW_HDD_G12")
		)
		(pad "6" smd rect
			(at -0.65024 -0.9398 180)
			(size 0.4064 1.016)
			(layers "F.Cu" "F.Mask" "F.Paste")
			(net "SW_HDD_R12")
		)
	)
	(footprint ""
		(layer "F.Cu")
		(at 361.6198 -139.5984 90)
		(property "Reference" "R1105"
			(at 0 0 90)
			(layer "F.SilkS")
			(hide yes)
			(effects
				(font
					(size 1.27 1.27)
				)
			)
		)
		(property "Value" "10R2F-L-GP"
			(at 0.064008 -3.993896 90)
			(unlocked yes)
			(layer "F.Fab")
			(hide yes)
			(effects
				(font
					(size 1.016 1.016)
					(thickness 0.1524)
				)
			)
		)
		(property "Device Type" "R402H14"
			(at 0.064008 -5.517896 90)
			(unlocked yes)
			(layer "F.Fab")
			(hide yes)
			(effects
				(font
					(size 1.016 1.016)
					(thickness 0.1524)
				)
			)
		)
		(duplicate_pad_numbers_are_jumpers no)
		(fp_line
			(start 0.508 -0.9398)
			(end -0.508 -0.9398)
			(stroke
				(width 0.1524)
				(type default)
			)
			(layer "F.SilkS")
		)
		(fp_line
			(start -0.508 -0.9398)
			(end -0.508 0.9398)
			(stroke
				(width 0.1524)
				(type default)
			)
			(layer "F.SilkS")
		)
		(fp_rect
			(start -0.508 0.9398)
			(end 0.508 -0.9398)
			(stroke
				(width 0)
				(type default)
			)
			(fill no)
			(layer "F.CrtYd")
		)
		(fp_rect
			(start -0.508 0.9398)
			(end 0.508 -0.9398)
			(stroke
				(width 0)
				(type default)
			)
			(fill no)
			(layer "F.Fab")
		)
		(pad "1" smd custom
			(at 0 -0.4445 90)
			(size 0.1397 0.1397)
			(layers "F.Cu" "F.Mask" "F.Paste")
			(net "MB1_CM_SENSE_R1_P")
			(options
				(clearance outline)
				(anchor circle)
			)
			(primitives
				(gr_poly
					(pts
						(arc
							(start -0.1778 -0.2794)
							(mid -0.249642 -0.249642)
							(end -0.2794 -0.1778)
						)
						(arc
							(start -0.2794 0.1778)
							(mid -0.249642 0.249642)
							(end -0.1778 0.2794)
						)
						(arc
							(start 0.1778 0.2794)
							(mid 0.249642 0.249642)
							(end 0.2794 0.1778)
						)
						(arc
							(start 0.2794 -0.1778)
							(mid 0.249642 -0.249642)
							(end 0.1778 -0.2794)
						)
					)
					(width 0)
					(fill yes)
				)
			)
		)
		(pad "2" smd custom
			(at 0 0.4445 90)
			(size 0.1397 0.1397)
			(layers "F.Cu" "F.Mask" "F.Paste")
			(net "MB1_HS_SENSE_P")
			(options
				(clearance outline)
				(anchor circle)
			)
			(primitives
				(gr_poly
					(pts
						(arc
							(start -0.1778 -0.2794)
							(mid -0.249642 -0.249642)
							(end -0.2794 -0.1778)
						)
						(arc
							(start -0.2794 0.1778)
							(mid -0.249642 0.249642)
							(end -0.1778 0.2794)
						)
						(arc
							(start 0.1778 0.2794)
							(mid 0.249642 0.249642)
							(end 0.2794 0.1778)
						)
						(arc
							(start 0.2794 -0.1778)
							(mid 0.249642 -0.249642)
							(end 0.1778 -0.2794)
						)
					)
					(width 0)
					(fill yes)
				)
			)
		)
	)
	(footprint ""
		(layer "F.Cu")
		(at 224.553526 -136.293098 -90)
		(property "Reference" "TP211"
			(at 0 0 270)
			(layer "F.SilkS")
			(hide yes)
			(effects
				(font
					(size 1.27 1.27)
				)
			)
		)
		(property "Value" "TPAD32-GP"
			(at -0.0508 -1.6764 270)
			(unlocked yes)
			(layer "F.Fab")
			(hide yes)
			(effects
				(font
					(size 1.016 1.016)
					(thickness 0.1524)
				)
			)
		)
		(property "Device Type" "TPAD32"
			(at -0.0508 -3.2004 270)
			(unlocked yes)
			(layer "F.Fab")
			(hide yes)
			(effects
				(font
					(size 1.016 1.016)
					(thickness 0.1524)
				)
			)
		)
		(duplicate_pad_numbers_are_jumpers no)
		(fp_poly
			(pts
				(arc
					(start 0 -0.4064)
					(mid 0 0.4064)
					(end 0 -0.4064)
				)
			)
			(stroke
				(width 0)
				(type default)
			)
			(fill no)
			(layer "F.CrtYd")
		)
		(fp_poly
			(pts
				(arc
					(start 0 -0.7112)
					(mid 0 0.7112)
					(end 0 -0.7112)
				)
			)
			(stroke
				(width 0)
				(type default)
			)
			(fill no)
			(layer "F.Fab")
		)
		(pad "1" smd circle
			(at 0 0 270)
			(size 0.8128 0.8128)
			(layers "F.Cu" "F.Mask" "F.Paste")
			(net "TP_PCIE_COMP_A_CLK_1_DP")
		)
	)
	(footprint ""
		(layer "F.Cu")
		(at 161.880804 -187.468764)
		(property "Reference" "R473"
			(at 0 0 0)
			(layer "F.SilkS")
			(hide yes)
			(effects
				(font
					(size 1.27 1.27)
				)
			)
		)
		(property "Value" "4K7R2J-2-GP"
			(at 0.064008 -3.993896 0)
			(unlocked yes)
			(layer "F.Fab")
			(hide yes)
			(effects
				(font
					(size 1.016 1.016)
					(thickness 0.1524)
				)
			)
		)
		(property "Device Type" "R402H16"
			(at 0.064008 -5.517896 0)
			(unlocked yes)
			(layer "F.Fab")
			(hide yes)
			(effects
				(font
					(size 1.016 1.016)
					(thickness 0.1524)
				)
			)
		)
		(duplicate_pad_numbers_are_jumpers no)
		(fp_line
			(start -0.508 -0.9398)
			(end -0.508 0.9398)
			(stroke
				(width 0.1524)
				(type default)
			)
			(layer "F.SilkS")
		)
		(fp_line
			(start 0.508 -0.9398)
			(end -0.508 -0.9398)
			(stroke
				(width 0.1524)
				(type default)
			)
			(layer "F.SilkS")
		)
		(fp_rect
			(start -0.508 0.9398)
			(end 0.508 -0.9398)
			(stroke
				(width 0)
				(type default)
			)
			(fill no)
			(layer "F.CrtYd")
		)
		(fp_rect
			(start -0.508 0.9398)
			(end 0.508 -0.9398)
			(stroke
				(width 0)
				(type default)
			)
			(fill no)
			(layer "F.Fab")
		)
		(pad "1" smd custom
			(at 0 -0.4445)
			(size 0.1397 0.1397)
			(layers "F.Cu" "F.Mask" "F.Paste")
			(net "DRIVE_A_5_FLT_LED")
			(options
				(clearance outline)
				(anchor circle)
			)
			(primitives
				(gr_poly
					(pts
						(arc
							(start -0.1778 -0.2794)
							(mid -0.249642 -0.249642)
							(end -0.2794 -0.1778)
						)
						(arc
							(start -0.2794 0.1778)
							(mid -0.249642 0.249642)
							(end -0.1778 0.2794)
						)
						(arc
							(start 0.1778 0.2794)
							(mid 0.249642 0.249642)
							(end 0.2794 0.1778)
						)
						(arc
							(start 0.2794 -0.1778)
							(mid 0.249642 -0.249642)
							(end 0.1778 -0.2794)
						)
					)
					(width 0)
					(fill yes)
				)
			)
		)
		(pad "2" smd custom
			(at 0 0.4445)
			(size 0.1397 0.1397)
			(layers "F.Cu" "F.Mask" "F.Paste")
			(net "GND")
			(options
				(clearance outline)
				(anchor circle)
			)
			(primitives
				(gr_poly
					(pts
						(arc
							(start -0.1778 -0.2794)
							(mid -0.249642 -0.249642)
							(end -0.2794 -0.1778)
						)
						(arc
							(start -0.2794 0.1778)
							(mid -0.249642 0.249642)
							(end -0.1778 0.2794)
						)
						(arc
							(start 0.1778 0.2794)
							(mid 0.249642 0.249642)
							(end 0.2794 0.1778)
						)
						(arc
							(start 0.2794 -0.1778)
							(mid 0.249642 -0.249642)
							(end 0.1778 -0.2794)
						)
					)
					(width 0)
					(fill yes)
				)
			)
		)
	)
	(footprint ""
		(layer "F.Cu")
		(at 47.877476 -140.73505 -90)
		(property "Reference" "R1231"
			(at 0 0 270)
			(layer "F.SilkS")
			(hide yes)
			(effects
				(font
					(size 1.27 1.27)
				)
			)
		)
		(property "Value" "3D01R5F-GP"
			(at 0 -8.9535 270)
			(unlocked yes)
			(layer "F.Fab")
			(hide yes)
			(effects
				(font
					(size 1.27 1.016)
					(thickness 0.1524)
				)
			)
		)
		(property "Device Type" "R805H24"
			(at 0 -10.6299 270)
			(unlocked yes)
			(layer "F.Fab")
			(hide yes)
			(effects
				(font
					(size 1.27 1.016)
					(thickness 0.1524)
				)
			)
		)
		(duplicate_pad_numbers_are_jumpers no)
		(fp_line
			(start -0.889 1.7018)
			(end 0.889 1.7018)
			(stroke
				(width 0.1524)
				(type default)
			)
			(layer "F.SilkS")
		)
		(fp_line
			(start 0.889 1.7018)
			(end 0.889 -0.508)
			(stroke
				(width 0.1524)
				(type default)
			)
			(layer "F.SilkS")
		)
		(fp_line
			(start -0.889 0.0762)
			(end -0.889 1.7018)
			(stroke
				(width 0.1524)
				(type default)
			)
			(layer "F.SilkS")
		)
		(fp_line
			(start -0.889 -1.7018)
			(end -0.889 0.2794)
			(stroke
				(width 0.1524)
				(type default)
			)
			(layer "F.SilkS")
		)
		(fp_line
			(start 0.889 -1.7018)
			(end 0.889 -0.381)
			(stroke
				(width 0.1524)
				(type default)
			)
			(layer "F.SilkS")
		)
		(fp_line
			(start 0.889 -1.7018)
			(end -0.889 -1.7018)
			(stroke
				(width 0.1524)
				(type default)
			)
			(layer "F.SilkS")
		)
		(fp_poly
			(pts
				(xy 0.9652 -1.778) (xy 0.9652 1.778) (xy -0.9652 1.778) (xy -0.9652 -1.778)
			)
			(stroke
				(width 0)
				(type default)
			)
			(fill no)
			(layer "F.CrtYd")
		)
		(fp_rect
			(start -0.9652 1.778)
			(end 0.9652 -1.778)
			(stroke
				(width 0)
				(type default)
			)
			(fill no)
			(layer "F.Fab")
		)
		(pad "1" smd rect
			(at 0 -0.9652 270)
			(size 1.397 1.143)
			(layers "F.Cu" "F.Mask" "F.Paste")
			(net "P5V_B_SNB")
		)
		(pad "2" smd rect
			(at 0 0.9652 270)
			(size 1.397 1.143)
			(layers "F.Cu" "F.Mask" "F.Paste")
			(net "GND")
		)
	)
	(footprint ""
		(layer "F.Cu")
		(at 321.634612 -158.660592 -90)
		(property "Reference" "C273"
			(at 0 0 270)
			(layer "F.SilkS")
			(hide yes)
			(effects
				(font
					(size 1.27 1.27)
				)
			)
		)
		(property "Value" "SCD01U16V1KX-GP"
			(at -2.8321 -1.7399 270)
			(unlocked yes)
			(layer "F.Fab")
			(hide yes)
			(effects
				(font
					(size 1.016 1.016)
					(thickness 0.1524)
				)
			)
		)
		(property "Device Type" "C0201H13"
			(at -2.8321 -3.2639 270)
			(unlocked yes)
			(layer "F.Fab")
			(hide yes)
			(effects
				(font
					(size 1.016 1.016)
					(thickness 0.1524)
				)
			)
		)
		(duplicate_pad_numbers_are_jumpers no)
		(fp_rect
			(start -0.2794 0.6477)
			(end 0.2794 -0.6477)
			(stroke
				(width 0)
				(type default)
			)
			(fill no)
			(layer "F.CrtYd")
		)
		(fp_rect
			(start -0.2794 0.6477)
			(end 0.2794 -0.6477)
			(stroke
				(width 0)
				(type default)
			)
			(fill no)
			(layer "F.Fab")
		)
		(pad "1" smd custom
			(at 0 -0.2794 270)
			(size 0.0762 0.0762)
			(layers "F.Cu" "F.Mask" "F.Paste")
			(net "SAS_HDD_RX_P18")
			(options
				(clearance outline)
				(anchor circle)
			)
			(primitives
				(gr_poly
					(pts
						(arc
							(start 0.1524 -0.127)
							(mid 0.137521 -0.162921)
							(end 0.1016 -0.1778)
						)
						(arc
							(start -0.1016 -0.1778)
							(mid -0.137521 -0.162921)
							(end -0.1524 -0.127)
						)
						(arc
							(start -0.1524 0.127)
							(mid -0.137521 0.162921)
							(end -0.1016 0.1778)
						)
						(arc
							(start 0.1016 0.1778)
							(mid 0.137521 0.162921)
							(end 0.1524 0.127)
						)
					)
					(width 0)
					(fill yes)
				)
			)
		)
		(pad "2" smd custom
			(at 0 0.2794 270)
			(size 0.0762 0.0762)
			(layers "F.Cu" "F.Mask" "F.Paste")
			(net "PHY_SCC_A_TO_DRV_A_18_DP")
			(options
				(clearance outline)
				(anchor circle)
			)
			(primitives
				(gr_poly
					(pts
						(arc
							(start 0.1524 -0.127)
							(mid 0.137521 -0.162921)
							(end 0.1016 -0.1778)
						)
						(arc
							(start -0.1016 -0.1778)
							(mid -0.137521 -0.162921)
							(end -0.1524 -0.127)
						)
						(arc
							(start -0.1524 0.127)
							(mid -0.137521 0.162921)
							(end -0.1016 0.1778)
						)
						(arc
							(start 0.1016 0.1778)
							(mid 0.137521 0.162921)
							(end 0.1524 0.127)
						)
					)
					(width 0)
					(fill yes)
				)
			)
		)
	)
	(footprint ""
		(layer "F.Cu")
		(at 395.20495 -272.585942)
		(property "Reference" "R327"
			(at 0 0 0)
			(layer "F.SilkS")
			(hide yes)
			(effects
				(font
					(size 1.27 1.27)
				)
			)
		)
		(property "Value" "4K7R2J-2-GP"
			(at 0.064008 -3.993896 0)
			(unlocked yes)
			(layer "F.Fab")
			(hide yes)
			(effects
				(font
					(size 1.016 1.016)
					(thickness 0.1524)
				)
			)
		)
		(property "Device Type" "R402H16"
			(at 0.064008 -5.517896 0)
			(unlocked yes)
			(layer "F.Fab")
			(hide yes)
			(effects
				(font
					(size 1.016 1.016)
					(thickness 0.1524)
				)
			)
		)
		(duplicate_pad_numbers_are_jumpers no)
		(fp_line
			(start -0.508 -0.9398)
			(end -0.508 0.9398)
			(stroke
				(width 0.1524)
				(type default)
			)
			(layer "F.SilkS")
		)
		(fp_line
			(start 0.508 -0.9398)
			(end -0.508 -0.9398)
			(stroke
				(width 0.1524)
				(type default)
			)
			(layer "F.SilkS")
		)
		(fp_rect
			(start -0.508 0.9398)
			(end 0.508 -0.9398)
			(stroke
				(width 0)
				(type default)
			)
			(fill no)
			(layer "F.CrtYd")
		)
		(fp_rect
			(start -0.508 0.9398)
			(end 0.508 -0.9398)
			(stroke
				(width 0)
				(type default)
			)
			(fill no)
			(layer "F.Fab")
		)
		(pad "1" smd custom
			(at 0 -0.4445)
			(size 0.1397 0.1397)
			(layers "F.Cu" "F.Mask" "F.Paste")
			(net "SW_PWR_R_HDD8")
			(options
				(clearance outline)
				(anchor circle)
			)
			(primitives
				(gr_poly
					(pts
						(arc
							(start -0.1778 -0.2794)
							(mid -0.249642 -0.249642)
							(end -0.2794 -0.1778)
						)
						(arc
							(start -0.2794 0.1778)
							(mid -0.249642 0.249642)
							(end -0.1778 0.2794)
						)
						(arc
							(start 0.1778 0.2794)
							(mid 0.249642 0.249642)
							(end 0.2794 0.1778)
						)
						(arc
							(start 0.2794 -0.1778)
							(mid 0.249642 -0.249642)
							(end 0.1778 -0.2794)
						)
					)
					(width 0)
					(fill yes)
				)
			)
		)
		(pad "2" smd custom
			(at 0 0.4445)
			(size 0.1397 0.1397)
			(layers "F.Cu" "F.Mask" "F.Paste")
			(net "GND")
			(options
				(clearance outline)
				(anchor circle)
			)
			(primitives
				(gr_poly
					(pts
						(arc
							(start -0.1778 -0.2794)
							(mid -0.249642 -0.249642)
							(end -0.2794 -0.1778)
						)
						(arc
							(start -0.2794 0.1778)
							(mid -0.249642 0.249642)
							(end -0.1778 0.2794)
						)
						(arc
							(start 0.1778 0.2794)
							(mid 0.249642 0.249642)
							(end 0.2794 0.1778)
						)
						(arc
							(start 0.2794 -0.1778)
							(mid 0.249642 -0.249642)
							(end 0.1778 -0.2794)
						)
					)
					(width 0)
					(fill yes)
				)
			)
		)
	)
	(footprint ""
		(layer "F.Cu")
		(at 67.347846 -291.127942 90)
		(property "Reference" "C55"
			(at 0 0 90)
			(layer "F.SilkS")
			(hide yes)
			(effects
				(font
					(size 1.27 1.27)
				)
			)
		)
		(property "Value" "SCD01U50V2KX-1GP"
			(at 1.1811 -2.7051 90)
			(unlocked yes)
			(layer "F.Fab")
			(hide yes)
			(effects
				(font
					(size 1.016 1.016)
					(thickness 0.1524)
				)
			)
		)
		(property "Device Type" "C402H22"
			(at 1.1811 -4.2291 90)
			(unlocked yes)
			(layer "F.Fab")
			(hide yes)
			(effects
				(font
					(size 1.016 1.016)
					(thickness 0.1524)
				)
			)
		)
		(duplicate_pad_numbers_are_jumpers no)
		(fp_rect
			(start -0.4318 0.9525)
			(end 0.4318 -0.9525)
			(stroke
				(width 0)
				(type default)
			)
			(fill no)
			(layer "F.CrtYd")
		)
		(fp_rect
			(start -0.4318 0.9525)
			(end 0.4318 -0.9525)
			(stroke
				(width 0)
				(type default)
			)
			(fill no)
			(layer "F.Fab")
		)
		(pad "1" smd custom
			(at 0 -0.4445 90)
			(size 0.1524 0.1524)
			(layers "F.Cu" "F.Mask" "F.Paste")
			(net "HDD_PRSNT_1")
			(options
				(clearance outline)
				(anchor circle)
			)
			(primitives
				(gr_poly
					(pts
						(arc
							(start 0.3048 -0.2032)
							(mid 0.275042 -0.275042)
							(end 0.2032 -0.3048)
						)
						(arc
							(start -0.2032 -0.3048)
							(mid -0.275042 -0.275042)
							(end -0.3048 -0.2032)
						)
						(arc
							(start -0.3048 0.2032)
							(mid -0.275042 0.275042)
							(end -0.2032 0.3048)
						)
						(arc
							(start 0.2032 0.3048)
							(mid 0.275042 0.275042)
							(end 0.3048 0.2032)
						)
					)
					(width 0)
					(fill yes)
				)
			)
		)
		(pad "2" smd custom
			(at 0 0.4445 90)
			(size 0.1524 0.1524)
			(layers "F.Cu" "F.Mask" "F.Paste")
			(net "GND")
			(options
				(clearance outline)
				(anchor circle)
			)
			(primitives
				(gr_poly
					(pts
						(arc
							(start 0.3048 -0.2032)
							(mid 0.275042 -0.275042)
							(end 0.2032 -0.3048)
						)
						(arc
							(start -0.2032 -0.3048)
							(mid -0.275042 -0.275042)
							(end -0.3048 -0.2032)
						)
						(arc
							(start -0.3048 0.2032)
							(mid -0.275042 0.275042)
							(end -0.2032 0.3048)
						)
						(arc
							(start 0.2032 0.3048)
							(mid 0.275042 0.275042)
							(end 0.3048 0.2032)
						)
					)
					(width 0)
					(fill yes)
				)
			)
		)
	)
	(footprint ""
		(layer "F.Cu")
		(at 387.83895 -162.749992 -90)
		(property "Reference" "VIA26"
			(at 0 0 270)
			(layer "F.SilkS")
			(hide yes)
			(effects
				(font
					(size 1.27 1.27)
				)
			)
		)
		(property "Value" "100OHM-8L-1D6MM-L18L16-GP"
			(at -3.7211 -4.5085 270)
			(unlocked yes)
			(layer "F.Fab")
			(hide yes)
			(effects
				(font
					(size 1.016 1.016)
					(thickness 0.1524)
				)
			)
		)
		(property "Device Type" "VIA-PCIE-4P-394076"
			(at -3.7211 -6.0325 270)
			(unlocked yes)
			(layer "F.Fab")
			(hide yes)
			(effects
				(font
					(size 1.016 1.016)
					(thickness 0.1524)
				)
			)
		)
		(duplicate_pad_numbers_are_jumpers no)
		(fp_rect
			(start -1.9685 0.381)
			(end 1.9685 -0.381)
			(stroke
				(width 0)
				(type default)
			)
			(fill no)
			(layer "F.CrtYd")
		)
		(fp_rect
			(start -1.9685 0.381)
			(end 1.9685 -0.381)
			(stroke
				(width 0)
				(type default)
			)
			(fill no)
			(layer "F.Fab")
		)
		(pad "1" thru_hole circle
			(at -1.5875 0 270)
			(size 0.508 0.508)
			(drill 0.254)
			(layers "*.Cu" "*.Mask")
			(remove_unused_layers no)
			(net "GND")
			(clearance 0.127)
			(thermal_gap 0.127)
		)
		(pad "2" thru_hole circle
			(at -0.5715 0 270)
			(size 0.508 0.508)
			(drill 0.254)
			(layers "*.Cu" "*.Mask")
			(remove_unused_layers no)
			(net "PHY_DRV_A_TO_SCC_A_20_DP")
			(clearance 0.127)
			(thermal_gap 0.127)
		)
		(pad "3" thru_hole circle
			(at 0.5715 0 270)
			(size 0.508 0.508)
			(drill 0.254)
			(layers "*.Cu" "*.Mask")
			(remove_unused_layers no)
			(net "PHY_DRV_A_TO_SCC_A_20_DN")
			(clearance 0.127)
			(thermal_gap 0.127)
		)
		(pad "4" thru_hole circle
			(at 1.5875 0 270)
			(size 0.508 0.508)
			(drill 0.254)
			(layers "*.Cu" "*.Mask")
			(remove_unused_layers no)
			(net "GND")
			(clearance 0.127)
			(thermal_gap 0.127)
		)
	)
	(footprint ""
		(layer "F.Cu")
		(at 138.018266 -134.246874 -90)
		(property "Reference" "R1042"
			(at 0 0 270)
			(layer "F.SilkS")
			(hide yes)
			(effects
				(font
					(size 1.27 1.27)
				)
			)
		)
		(property "Value" "0R2J-2-GP"
			(at 0.064008 -3.993896 270)
			(unlocked yes)
			(layer "F.Fab")
			(hide yes)
			(effects
				(font
					(size 1.016 1.016)
					(thickness 0.1524)
				)
			)
		)
		(property "Device Type" "R402H16"
			(at 0.064008 -5.517896 270)
			(unlocked yes)
			(layer "F.Fab")
			(hide yes)
			(effects
				(font
					(size 1.016 1.016)
					(thickness 0.1524)
				)
			)
		)
		(duplicate_pad_numbers_are_jumpers no)
		(fp_line
			(start -0.508 -0.9398)
			(end -0.508 0.9398)
			(stroke
				(width 0.1524)
				(type default)
			)
			(layer "F.SilkS")
		)
		(fp_line
			(start 0.508 -0.9398)
			(end -0.508 -0.9398)
			(stroke
				(width 0.1524)
				(type default)
			)
			(layer "F.SilkS")
		)
		(fp_rect
			(start -0.508 0.9398)
			(end 0.508 -0.9398)
			(stroke
				(width 0)
				(type default)
			)
			(fill no)
			(layer "F.CrtYd")
		)
		(fp_rect
			(start -0.508 0.9398)
			(end 0.508 -0.9398)
			(stroke
				(width 0)
				(type default)
			)
			(fill no)
			(layer "F.Fab")
		)
		(pad "1" smd custom
			(at 0 -0.4445 270)
			(size 0.1397 0.1397)
			(layers "F.Cu" "F.Mask" "F.Paste")
			(net "MB0_SCL_R")
			(options
				(clearance outline)
				(anchor circle)
			)
			(primitives
				(gr_poly
					(pts
						(arc
							(start -0.1778 -0.2794)
							(mid -0.249642 -0.249642)
							(end -0.2794 -0.1778)
						)
						(arc
							(start -0.2794 0.1778)
							(mid -0.249642 0.249642)
							(end -0.1778 0.2794)
						)
						(arc
							(start 0.1778 0.2794)
							(mid 0.249642 0.249642)
							(end 0.2794 0.1778)
						)
						(arc
							(start 0.2794 -0.1778)
							(mid 0.249642 -0.249642)
							(end 0.1778 -0.2794)
						)
					)
					(width 0)
					(fill yes)
				)
			)
		)
		(pad "2" smd custom
			(at 0 0.4445 270)
			(size 0.1397 0.1397)
			(layers "F.Cu" "F.Mask" "F.Paste")
			(net "I2C_BMC_A_MISC_SCL")
			(options
				(clearance outline)
				(anchor circle)
			)
			(primitives
				(gr_poly
					(pts
						(arc
							(start -0.1778 -0.2794)
							(mid -0.249642 -0.249642)
							(end -0.2794 -0.1778)
						)
						(arc
							(start -0.2794 0.1778)
							(mid -0.249642 0.249642)
							(end -0.1778 0.2794)
						)
						(arc
							(start 0.1778 0.2794)
							(mid 0.249642 0.249642)
							(end 0.2794 0.1778)
						)
						(arc
							(start 0.2794 -0.1778)
							(mid 0.249642 -0.249642)
							(end 0.1778 -0.2794)
						)
					)
					(width 0)
					(fill yes)
				)
			)
		)
	)
	(footprint ""
		(layer "F.Cu")
		(at 257.4036 -290.195)
		(property "Reference" "R8"
			(at 0 0 0)
			(layer "F.SilkS")
			(hide yes)
			(effects
				(font
					(size 1.27 1.27)
				)
			)
		)
		(property "Value" "4K7R2F-GP"
			(at 0.064008 -3.993896 0)
			(unlocked yes)
			(layer "F.Fab")
			(hide yes)
			(effects
				(font
					(size 1.016 1.016)
					(thickness 0.1524)
				)
			)
		)
		(property "Device Type" "R402H16"
			(at 0.064008 -5.517896 0)
			(unlocked yes)
			(layer "F.Fab")
			(hide yes)
			(effects
				(font
					(size 1.016 1.016)
					(thickness 0.1524)
				)
			)
		)
		(duplicate_pad_numbers_are_jumpers no)
		(fp_line
			(start -0.508 -0.9398)
			(end -0.508 0.9398)
			(stroke
				(width 0.1524)
				(type default)
			)
			(layer "F.SilkS")
		)
		(fp_line
			(start 0.508 -0.9398)
			(end -0.508 -0.9398)
			(stroke
				(width 0.1524)
				(type default)
			)
			(layer "F.SilkS")
		)
		(fp_rect
			(start -0.508 0.9398)
			(end 0.508 -0.9398)
			(stroke
				(width 0)
				(type default)
			)
			(fill no)
			(layer "F.CrtYd")
		)
		(fp_rect
			(start -0.508 0.9398)
			(end 0.508 -0.9398)
			(stroke
				(width 0)
				(type default)
			)
			(fill no)
			(layer "F.Fab")
		)
		(pad "1" smd custom
			(at 0 -0.4445)
			(size 0.1397 0.1397)
			(layers "F.Cu" "F.Mask" "F.Paste")
			(net "EEPROM_A2")
			(options
				(clearance outline)
				(anchor circle)
			)
			(primitives
				(gr_poly
					(pts
						(arc
							(start -0.1778 -0.2794)
							(mid -0.249642 -0.249642)
							(end -0.2794 -0.1778)
						)
						(arc
							(start -0.2794 0.1778)
							(mid -0.249642 0.249642)
							(end -0.1778 0.2794)
						)
						(arc
							(start 0.1778 0.2794)
							(mid 0.249642 0.249642)
							(end 0.2794 0.1778)
						)
						(arc
							(start 0.2794 -0.1778)
							(mid 0.249642 -0.249642)
							(end 0.1778 -0.2794)
						)
					)
					(width 0)
					(fill yes)
				)
			)
		)
		(pad "2" smd custom
			(at 0 0.4445)
			(size 0.1397 0.1397)
			(layers "F.Cu" "F.Mask" "F.Paste")
			(net "GND")
			(options
				(clearance outline)
				(anchor circle)
			)
			(primitives
				(gr_poly
					(pts
						(arc
							(start -0.1778 -0.2794)
							(mid -0.249642 -0.249642)
							(end -0.2794 -0.1778)
						)
						(arc
							(start -0.2794 0.1778)
							(mid -0.249642 0.249642)
							(end -0.1778 0.2794)
						)
						(arc
							(start 0.1778 0.2794)
							(mid 0.249642 0.249642)
							(end 0.2794 0.1778)
						)
						(arc
							(start 0.2794 -0.1778)
							(mid 0.249642 -0.249642)
							(end 0.1778 -0.2794)
						)
					)
					(width 0)
					(fill yes)
				)
			)
		)
	)
	(footprint ""
		(layer "F.Cu")
		(at 333.248 -157.585918 180)
		(property "Reference" "R552"
			(at 0 0 180)
			(layer "F.SilkS")
			(hide yes)
			(effects
				(font
					(size 1.27 1.27)
				)
			)
		)
		(property "Value" "1KR2F-3-GP"
			(at 0.064008 -3.993896 180)
			(unlocked yes)
			(layer "F.Fab")
			(hide yes)
			(effects
				(font
					(size 1.016 1.016)
					(thickness 0.1524)
				)
			)
		)
		(property "Device Type" "R402H16"
			(at 0.064008 -5.517896 180)
			(unlocked yes)
			(layer "F.Fab")
			(hide yes)
			(effects
				(font
					(size 1.016 1.016)
					(thickness 0.1524)
				)
			)
		)
		(duplicate_pad_numbers_are_jumpers no)
		(fp_line
			(start 0.508 -0.9398)
			(end -0.508 -0.9398)
			(stroke
				(width 0.1524)
				(type default)
			)
			(layer "F.SilkS")
		)
		(fp_line
			(start -0.508 -0.9398)
			(end -0.508 0.9398)
			(stroke
				(width 0.1524)
				(type default)
			)
			(layer "F.SilkS")
		)
		(fp_rect
			(start -0.508 0.9398)
			(end 0.508 -0.9398)
			(stroke
				(width 0)
				(type default)
			)
			(fill no)
			(layer "F.CrtYd")
		)
		(fp_rect
			(start -0.508 0.9398)
			(end 0.508 -0.9398)
			(stroke
				(width 0)
				(type default)
			)
			(fill no)
			(layer "F.Fab")
		)
		(pad "1" smd custom
			(at 0 -0.4445 180)
			(size 0.1397 0.1397)
			(layers "F.Cu" "F.Mask" "F.Paste")
			(net "P3V3_STBY_A")
			(options
				(clearance outline)
				(anchor circle)
			)
			(primitives
				(gr_poly
					(pts
						(arc
							(start -0.1778 -0.2794)
							(mid -0.249642 -0.249642)
							(end -0.2794 -0.1778)
						)
						(arc
							(start -0.2794 0.1778)
							(mid -0.249642 0.249642)
							(end -0.1778 0.2794)
						)
						(arc
							(start 0.1778 0.2794)
							(mid 0.249642 0.249642)
							(end 0.2794 0.1778)
						)
						(arc
							(start 0.2794 -0.1778)
							(mid 0.249642 -0.249642)
							(end 0.1778 -0.2794)
						)
					)
					(width 0)
					(fill yes)
				)
			)
		)
		(pad "2" smd custom
			(at 0 0.4445 180)
			(size 0.1397 0.1397)
			(layers "F.Cu" "F.Mask" "F.Paste")
			(net "SW_PWR_R_HDD18")
			(options
				(clearance outline)
				(anchor circle)
			)
			(primitives
				(gr_poly
					(pts
						(arc
							(start -0.1778 -0.2794)
							(mid -0.249642 -0.249642)
							(end -0.2794 -0.1778)
						)
						(arc
							(start -0.2794 0.1778)
							(mid -0.249642 0.249642)
							(end -0.1778 0.2794)
						)
						(arc
							(start 0.1778 0.2794)
							(mid 0.249642 0.249642)
							(end 0.2794 0.1778)
						)
						(arc
							(start 0.2794 -0.1778)
							(mid 0.249642 -0.249642)
							(end 0.1778 -0.2794)
						)
					)
					(width 0)
					(fill yes)
				)
			)
		)
	)
	(footprint ""
		(layer "F.Cu")
		(at 220.599 -365.125)
		(property "Reference" "R173"
			(at 0 0 0)
			(layer "F.SilkS")
			(hide yes)
			(effects
				(font
					(size 1.27 1.27)
				)
			)
		)
		(property "Value" "4K7R2F-GP"
			(at 0.064008 -3.993896 0)
			(unlocked yes)
			(layer "F.Fab")
			(hide yes)
			(effects
				(font
					(size 1.016 1.016)
					(thickness 0.1524)
				)
			)
		)
		(property "Device Type" "R402H16"
			(at 0.064008 -5.517896 0)
			(unlocked yes)
			(layer "F.Fab")
			(hide yes)
			(effects
				(font
					(size 1.016 1.016)
					(thickness 0.1524)
				)
			)
		)
		(duplicate_pad_numbers_are_jumpers no)
		(fp_line
			(start -0.508 -0.9398)
			(end -0.508 0.9398)
			(stroke
				(width 0.1524)
				(type default)
			)
			(layer "F.SilkS")
		)
		(fp_line
			(start 0.508 -0.9398)
			(end -0.508 -0.9398)
			(stroke
				(width 0.1524)
				(type default)
			)
			(layer "F.SilkS")
		)
		(fp_rect
			(start -0.508 0.9398)
			(end 0.508 -0.9398)
			(stroke
				(width 0)
				(type default)
			)
			(fill no)
			(layer "F.CrtYd")
		)
		(fp_rect
			(start -0.508 0.9398)
			(end 0.508 -0.9398)
			(stroke
				(width 0)
				(type default)
			)
			(fill no)
			(layer "F.Fab")
		)
		(pad "1" smd custom
			(at 0 -0.4445)
			(size 0.1397 0.1397)
			(layers "F.Cu" "F.Mask" "F.Paste")
			(net "IO_EXP3_HDD_FAULT_INT_N")
			(options
				(clearance outline)
				(anchor circle)
			)
			(primitives
				(gr_poly
					(pts
						(arc
							(start -0.1778 -0.2794)
							(mid -0.249642 -0.249642)
							(end -0.2794 -0.1778)
						)
						(arc
							(start -0.2794 0.1778)
							(mid -0.249642 0.249642)
							(end -0.1778 0.2794)
						)
						(arc
							(start 0.1778 0.2794)
							(mid 0.249642 0.249642)
							(end 0.2794 0.1778)
						)
						(arc
							(start 0.2794 -0.1778)
							(mid 0.249642 -0.249642)
							(end 0.1778 -0.2794)
						)
					)
					(width 0)
					(fill yes)
				)
			)
		)
		(pad "2" smd custom
			(at 0 0.4445)
			(size 0.1397 0.1397)
			(layers "F.Cu" "F.Mask" "F.Paste")
			(net "P3V3_STBY_B")
			(options
				(clearance outline)
				(anchor circle)
			)
			(primitives
				(gr_poly
					(pts
						(arc
							(start -0.1778 -0.2794)
							(mid -0.249642 -0.249642)
							(end -0.2794 -0.1778)
						)
						(arc
							(start -0.2794 0.1778)
							(mid -0.249642 0.249642)
							(end -0.1778 0.2794)
						)
						(arc
							(start 0.1778 0.2794)
							(mid 0.249642 0.249642)
							(end 0.2794 0.1778)
						)
						(arc
							(start 0.2794 -0.1778)
							(mid 0.249642 -0.249642)
							(end 0.1778 -0.2794)
						)
					)
					(width 0)
					(fill yes)
				)
			)
		)
	)
	(footprint ""
		(layer "F.Cu")
		(at 143.999966 -209.399886)
		(property "Reference" "FLED5"
			(at 0 0 0)
			(layer "F.SilkS")
			(hide yes)
			(effects
				(font
					(size 1.27 1.27)
				)
			)
		)
		(property "Value" "LED-BY-19-GP"
			(at -2.132076 1.414018 0)
			(unlocked yes)
			(layer "F.Fab")
			(hide yes)
			(effects
				(font
					(size 1.016 1.016)
					(thickness 0.1524)
				)
			)
		)
		(property "Device Type" "LED-1615-4PH26"
			(at -2.132076 -0.109982 0)
			(unlocked yes)
			(layer "F.Fab")
			(hide yes)
			(effects
				(font
					(size 1.016 1.016)
					(thickness 0.1524)
				)
			)
		)
		(duplicate_pad_numbers_are_jumpers no)
		(fp_line
			(start -1.2954 0.254)
			(end -1.2954 1.6002)
			(stroke
				(width 0.508)
				(type default)
			)
			(layer "F.SilkS")
		)
		(fp_line
			(start -1.2954 1.6002)
			(end 1.2954 1.6002)
			(stroke
				(width 0.508)
				(type default)
			)
			(layer "F.SilkS")
		)
		(fp_line
			(start -1.1176 -1.4224)
			(end 1.1176 -1.4224)
			(stroke
				(width 0.1524)
				(type default)
			)
			(layer "F.SilkS")
		)
		(fp_line
			(start -1.1176 1.4224)
			(end -1.1176 -1.4224)
			(stroke
				(width 0.1524)
				(type default)
			)
			(layer "F.SilkS")
		)
		(fp_line
			(start 1.1176 -1.4224)
			(end 1.1176 1.4224)
			(stroke
				(width 0.1524)
				(type default)
			)
			(layer "F.SilkS")
		)
		(fp_line
			(start 1.1176 1.4224)
			(end -1.1176 1.4224)
			(stroke
				(width 0.1524)
				(type default)
			)
			(layer "F.SilkS")
		)
		(fp_line
			(start 1.2954 1.6002)
			(end 1.2954 0.254)
			(stroke
				(width 0.508)
				(type default)
			)
			(layer "F.SilkS")
		)
		(fp_rect
			(start -0.7493 0.8001)
			(end 0.7493 -0.8001)
			(stroke
				(width 0)
				(type default)
			)
			(fill no)
			(layer "F.CrtYd")
		)
		(fp_poly
			(pts
				(xy -1.3716 1.6764) (xy -1.3716 -1.6764) (xy 1.3716 -1.6764) (xy 1.3716 0.0635) (xy 0.7493 0.0635)
				(xy 0.7493 -0.8001) (xy -0.7493 -0.8001) (xy -0.7493 0.8001) (xy 0.7493 0.8001) (xy 0.7493 0.0762)
				(xy 1.3716 0.0762) (xy 1.3716 1.6764)
			)
			(stroke
				(width 0)
				(type default)
			)
			(fill no)
			(layer "F.CrtYd")
		)
		(fp_rect
			(start -1.3716 1.6764)
			(end 1.3716 -1.6764)
			(stroke
				(width 0)
				(type default)
			)
			(fill no)
			(layer "F.Fab")
		)
		(pad "1" smd rect
			(at 0.50038 -0.73025)
			(size 0.7112 0.8636)
			(layers "F.Cu" "F.Mask" "F.Paste")
			(net "DRV_ACT_4")
		)
		(pad "2" smd rect
			(at -0.50038 -0.73025)
			(size 0.7112 0.8636)
			(layers "F.Cu" "F.Mask" "F.Paste")
			(net "FLT_HDD4")
		)
		(pad "3" smd rect
			(at 0.50038 0.73025)
			(size 0.7112 0.8636)
			(layers "F.Cu" "F.Mask" "F.Paste")
			(net "DRV_ACT_4_N")
		)
		(pad "4" smd rect
			(at -0.50038 0.73025)
			(size 0.7112 0.8636)
			(layers "F.Cu" "F.Mask" "F.Paste")
			(net "FLT_HDD4_N")
		)
	)
	(footprint ""
		(layer "F.Cu")
		(at 237.492286 -251.907802 90)
		(property "Reference" "C9"
			(at 0 0 90)
			(layer "F.SilkS")
			(hide yes)
			(effects
				(font
					(size 1.27 1.27)
				)
			)
		)
		(property "Value" "SC1U16V3KX-5GP"
			(at 0 -2.8194 90)
			(unlocked yes)
			(layer "F.Fab")
			(hide yes)
			(effects
				(font
					(size 1.016 1.016)
					(thickness 0.1524)
				)
			)
		)
		(property "Device Type" "C603H36"
			(at 0 -4.3434 90)
			(unlocked yes)
			(layer "F.Fab")
			(hide yes)
			(effects
				(font
					(size 1.016 1.016)
					(thickness 0.1524)
				)
			)
		)
		(duplicate_pad_numbers_are_jumpers no)
		(fp_line
			(start 0.508 0)
			(end -0.508 0)
			(stroke
				(width 0.2032)
				(type default)
			)
			(layer "F.SilkS")
		)
		(fp_rect
			(start -0.5842 1.3335)
			(end 0.5842 -1.3335)
			(stroke
				(width 0)
				(type default)
			)
			(fill no)
			(layer "F.CrtYd")
		)
		(fp_rect
			(start -0.5842 1.3335)
			(end 0.5842 -1.3335)
			(stroke
				(width 0)
				(type default)
			)
			(fill no)
			(layer "F.Fab")
		)
		(pad "1" smd custom
			(at 0 -0.762 90)
			(size 0.2159 0.2159)
			(layers "F.Cu" "F.Mask" "F.Paste")
			(net "P3V3_STBY_A")
			(options
				(clearance outline)
				(anchor circle)
			)
			(primitives
				(gr_poly
					(pts
						(arc
							(start -0.3302 -0.4318)
							(mid -0.402042 -0.402042)
							(end -0.4318 -0.3302)
						)
						(arc
							(start -0.4318 0.3302)
							(mid -0.402042 0.402042)
							(end -0.3302 0.4318)
						)
						(arc
							(start 0.3302 0.4318)
							(mid 0.402042 0.402042)
							(end 0.4318 0.3302)
						)
						(arc
							(start 0.4318 -0.3302)
							(mid 0.402042 -0.402042)
							(end 0.3302 -0.4318)
						)
					)
					(width 0)
					(fill yes)
				)
			)
		)
		(pad "2" smd custom
			(at 0 0.762 90)
			(size 0.2159 0.2159)
			(layers "F.Cu" "F.Mask" "F.Paste")
			(net "GND")
			(options
				(clearance outline)
				(anchor circle)
			)
			(primitives
				(gr_poly
					(pts
						(arc
							(start -0.3302 -0.4318)
							(mid -0.402042 -0.402042)
							(end -0.4318 -0.3302)
						)
						(arc
							(start -0.4318 0.3302)
							(mid -0.402042 0.402042)
							(end -0.3302 0.4318)
						)
						(arc
							(start 0.3302 0.4318)
							(mid 0.402042 0.402042)
							(end 0.4318 0.3302)
						)
						(arc
							(start 0.4318 -0.3302)
							(mid 0.402042 -0.402042)
							(end 0.3302 -0.4318)
						)
					)
					(width 0)
					(fill yes)
				)
			)
		)
	)
	(footprint ""
		(layer "F.Cu")
		(at 122.849894 -287.910016 -90)
		(property "Reference" "HDDSAS3"
			(at 0 0 270)
			(layer "F.SilkS")
			(hide yes)
			(effects
				(font
					(size 1.27 1.27)
				)
			)
		)
		(property "Value" "SKT-SAS15P-14P-45-GP"
			(at -20.7645 -8.9789 270)
			(unlocked yes)
			(layer "F.Fab")
			(hide yes)
			(effects
				(font
					(size 1.016 1.016)
					(thickness 0.1524)
				)
			)
		)
		(property "Device Type" "10120818-001C-TRLF"
			(at -20.7645 -10.5029 270)
			(unlocked yes)
			(layer "F.Fab")
			(hide yes)
			(effects
				(font
					(size 1.016 1.016)
					(thickness 0.1524)
				)
			)
		)
		(duplicate_pad_numbers_are_jumpers no)
		(fp_line
			(start 1.651 4.2926)
			(end 1.651 3.0099)
			(stroke
				(width 0.1524)
				(type default)
			)
			(layer "F.SilkS")
		)
		(fp_line
			(start 8.509 4.2926)
			(end 1.651 4.2926)
			(stroke
				(width 0.1524)
				(type default)
			)
			(layer "F.SilkS")
		)
		(fp_line
			(start -23.4188 3.0099)
			(end -23.4188 -3.2512)
			(stroke
				(width 0.1524)
				(type default)
			)
			(layer "F.SilkS")
		)
		(fp_line
			(start 1.651 3.0099)
			(end -23.4188 3.0099)
			(stroke
				(width 0.1524)
				(type default)
			)
			(layer "F.SilkS")
		)
		(fp_line
			(start 8.509 3.0099)
			(end 8.509 4.2926)
			(stroke
				(width 0.1524)
				(type default)
			)
			(layer "F.SilkS")
		)
		(fp_line
			(start 23.4188 3.0099)
			(end 8.509 3.0099)
			(stroke
				(width 0.1524)
				(type default)
			)
			(layer "F.SilkS")
		)
		(fp_line
			(start -23.4188 -3.2512)
			(end 23.4188 -3.2512)
			(stroke
				(width 0.1524)
				(type default)
			)
			(layer "F.SilkS")
		)
		(fp_line
			(start 23.4188 -3.2512)
			(end 23.4188 3.0099)
			(stroke
				(width 0.1524)
				(type default)
			)
			(layer "F.SilkS")
		)
		(fp_line
			(start 15.5067 -3.3401)
			(end 16.2687 -3.3401)
			(stroke
				(width 0.3302)
				(type default)
			)
			(layer "F.SilkS")
		)
		(fp_poly
			(pts
				(xy 15.868904 -3.230372) (xy 16.503904 -3.865372) (xy 15.233904 -3.865372)
			)
			(stroke
				(width 0)
				(type default)
			)
			(fill yes)
			(layer "F.SilkS")
		)
		(fp_poly
			(pts
				(xy -22.8727 -2.7559) (xy 22.8727 -2.7559) (xy 22.8727 2.7559) (xy 8.255 2.7559) (xy 8.255 3.5179)
				(xy 1.905 3.5179) (xy 1.905 2.7559) (xy -22.8727 2.7559)
			)
			(stroke
				(width 0)
				(type default)
			)
			(fill no)
			(layer "F.CrtYd")
		)
		(fp_poly
			(pts
				(xy 1.397 4.5466) (xy 1.397 3.2639) (xy -23.6728 3.2639) (xy -23.6728 -3.5052) (xy 23.6728 -3.5052)
				(xy 23.6728 -0.00635) (xy 22.8727 -0.00635) (xy 22.8727 -2.7559) (xy -22.8727 -2.7559) (xy -22.8727 2.7559)
				(xy 1.905 2.7559) (xy 1.905 3.5179) (xy 8.255 3.5179) (xy 8.255 2.7559) (xy 22.8727 2.7559) (xy 22.8727 0.00635)
				(xy 23.6728 0.00635) (xy 23.6728 3.2639) (xy 8.763 3.2639) (xy 8.763 4.5466)
			)
			(stroke
				(width 0)
				(type default)
			)
			(fill no)
			(layer "F.CrtYd")
		)
		(fp_poly
			(pts
				(xy 1.397 4.5466) (xy 1.397 3.2639) (xy -23.6728 3.2639) (xy -23.6728 -3.5052) (xy 23.6728 -3.5052)
				(xy 23.6728 3.2639) (xy 8.763 3.2639) (xy 8.763 4.5466)
			)
			(stroke
				(width 0)
				(type default)
			)
			(fill no)
			(layer "F.Fab")
		)
		(pad "" np_thru_hole circle
			(at -18.874994 0 270)
			(size 0.254 0.254)
			(drill 1.3462)
			(layers "*.Cu" "*.Mask")
			(clearance 0.9017)
			(thermal_gap 0.9017)
		)
		(pad "" np_thru_hole circle
			(at 18.874994 0 270)
			(size 0.254 0.254)
			(drill 0.9398)
			(layers "*.Cu" "*.Mask")
			(clearance 0.6985)
			(thermal_gap 0.6985)
		)
		(pad "G1" smd rect
			(at 21.874988 0 270)
			(size 2.5908 2.5908)
			(layers "F.Cu" "F.Mask" "F.Paste")
			(net "GND")
		)
		(pad "G2" smd rect
			(at -21.874988 0 270)
			(size 2.5908 2.5908)
			(layers "F.Cu" "F.Mask" "F.Paste")
			(net "GND")
		)
		(pad "P1" smd rect
			(at 1.905 -1.82499 270)
			(size 0.6096 2.3622)
			(layers "F.Cu" "F.Mask" "F.Paste")
			(net "Net_2026")
		)
		(pad "P2" smd rect
			(at 0.635 -1.82499 270)
			(size 0.6096 2.3622)
			(layers "F.Cu" "F.Mask" "F.Paste")
			(net "Net_2027")
		)
		(pad "P3" smd rect
			(at -0.635 -1.82499 270)
			(size 0.6096 2.3622)
			(layers "F.Cu" "F.Mask" "F.Paste")
			(net "Net_2028")
		)
		(pad "P4" smd rect
			(at -1.905 -1.82499 270)
			(size 0.6096 2.3622)
			(layers "F.Cu" "F.Mask" "F.Paste")
			(net "GND")
		)
		(pad "P5" smd rect
			(at -3.175 -1.82499 270)
			(size 0.6096 2.3622)
			(layers "F.Cu" "F.Mask" "F.Paste")
			(net "HDD_PRSNT_3")
		)
		(pad "P6" smd rect
			(at -4.445 -1.82499 270)
			(size 0.6096 2.3622)
			(layers "F.Cu" "F.Mask" "F.Paste")
			(net "GND")
		)
		(pad "P7" smd rect
			(at -5.715 -1.82499 270)
			(size 0.6096 2.3622)
			(layers "F.Cu" "F.Mask" "F.Paste")
			(net "5V_PRE_3")
		)
		(pad "P8" smd rect
			(at -6.985 -1.82499 270)
			(size 0.6096 2.3622)
			(layers "F.Cu" "F.Mask" "F.Paste")
			(net "P5V_HDD3")
		)
		(pad "P9" smd rect
			(at -8.255 -1.82499 270)
			(size 0.6096 2.3622)
			(layers "F.Cu" "F.Mask" "F.Paste")
			(net "P5V_HDD3")
		)
		(pad "P10" smd rect
			(at -9.525 -1.82499 270)
			(size 0.6096 2.3622)
			(layers "F.Cu" "F.Mask" "F.Paste")
			(net "GND")
		)
		(pad "P11" smd rect
			(at -10.795 -1.82499 270)
			(size 0.6096 2.3622)
			(layers "F.Cu" "F.Mask" "F.Paste")
			(net "ACT_HDD_3")
		)
		(pad "P12" smd rect
			(at -12.065 -1.82499 270)
			(size 0.6096 2.3622)
			(layers "F.Cu" "F.Mask" "F.Paste")
			(net "GND")
		)
		(pad "P13" smd rect
			(at -13.335 -1.82499 270)
			(size 0.6096 2.3622)
			(layers "F.Cu" "F.Mask" "F.Paste")
			(net "12V_PRE_3")
		)
		(pad "P14" smd rect
			(at -14.605 -1.82499 270)
			(size 0.6096 2.3622)
			(layers "F.Cu" "F.Mask" "F.Paste")
			(net "P12V_HDD3")
		)
		(pad "P15" smd rect
			(at -15.875 -1.82499 270)
			(size 0.6096 2.3622)
			(layers "F.Cu" "F.Mask" "F.Paste")
			(net "P12V_HDD3")
		)
		(pad "S1" smd rect
			(at 15.875 -1.82499 270)
			(size 0.6096 2.3622)
			(layers "F.Cu" "F.Mask" "F.Paste")
			(net "GND")
		)
		(pad "S2" smd rect
			(at 14.605 -1.82499 270)
			(size 0.6096 2.3622)
			(layers "F.Cu" "F.Mask" "F.Paste")
			(net "SAS_HDD_RX_P3")
		)
		(pad "S3" smd rect
			(at 13.335 -1.82499 270)
			(size 0.6096 2.3622)
			(layers "F.Cu" "F.Mask" "F.Paste")
			(net "SAS_HDD_RX_N3")
		)
		(pad "S4" smd rect
			(at 12.065 -1.82499 270)
			(size 0.6096 2.3622)
			(layers "F.Cu" "F.Mask" "F.Paste")
			(net "GND")
		)
		(pad "S5" smd rect
			(at 10.795 -1.82499 270)
			(size 0.6096 2.3622)
			(layers "F.Cu" "F.Mask" "F.Paste")
			(net "PHY_DRV_A_TO_SCC_A_3_DN")
		)
		(pad "S6" smd rect
			(at 9.525 -1.82499 270)
			(size 0.6096 2.3622)
			(layers "F.Cu" "F.Mask" "F.Paste")
			(net "PHY_DRV_A_TO_SCC_A_3_DP")
		)
		(pad "S7" smd rect
			(at 8.255 -1.82499 270)
			(size 0.6096 2.3622)
			(layers "F.Cu" "F.Mask" "F.Paste")
			(net "GND")
		)
		(pad "S8" smd rect
			(at 7.480046 2.845054 270)
			(size 0.508 2.3622)
			(layers "F.Cu" "F.Mask" "F.Paste")
			(net "GND")
		)
		(pad "S9" smd rect
			(at 6.679946 2.845054 270)
			(size 0.508 2.3622)
			(layers "F.Cu" "F.Mask" "F.Paste")
			(net "Net_475")
		)
		(pad "S10" smd rect
			(at 5.8801 2.845054 270)
			(size 0.508 2.3622)
			(layers "F.Cu" "F.Mask" "F.Paste")
			(net "Net_367")
		)
		(pad "S11" smd rect
			(at 5.08 2.845054 270)
			(size 0.508 2.3622)
			(layers "F.Cu" "F.Mask" "F.Paste")
			(net "GND")
		)
		(pad "S12" smd rect
			(at 4.2799 2.845054 270)
			(size 0.508 2.3622)
			(layers "F.Cu" "F.Mask" "F.Paste")
			(net "Net_403")
		)
		(pad "S13" smd rect
			(at 3.480054 2.845054 270)
			(size 0.508 2.3622)
			(layers "F.Cu" "F.Mask" "F.Paste")
			(net "Net_439")
		)
		(pad "S14" smd rect
			(at 2.679954 2.845054 270)
			(size 0.508 2.3622)
			(layers "F.Cu" "F.Mask" "F.Paste")
			(net "GND")
		)
		(zone
			(layer "F.Cu")
			(hatch none 0.5)
			(connect_pads
				(clearance 0)
			)
			(min_thickness 0.25)
			(keepout
				(tracks not_allowed)
				(vias allowed)
				(pads allowed)
				(copperpour not_allowed)
				(footprints allowed)
			)
			(placement
				(enabled no)
				(sheetname "")
			)
			(fill
				(thermal_gap 0.5)
				(thermal_bridge_width 0.5)
				(island_removal_mode 0)
			)
			(polygon
				(pts
					(xy 126.507494 -304.648616) (xy 119.433594 -304.648616) (xy 119.433594 -311.582816) (xy 120.538494 -311.582816)
					(xy 120.538494 -307.468016) (xy 125.161294 -307.468016) (xy 125.161294 -311.582816) (xy 126.507494 -311.582816)
				)
			)
		)
		(zone
			(layer "F.Cu")
			(hatch none 0.5)
			(connect_pads
				(clearance 0)
			)
			(min_thickness 0.25)
			(keepout
				(tracks allowed)
				(vias not_allowed)
				(pads allowed)
				(copperpour not_allowed)
				(footprints allowed)
			)
			(placement
				(enabled no)
				(sheetname "")
			)
			(fill
				(thermal_gap 0.5)
				(thermal_bridge_width 0.5)
				(island_removal_mode 0)
			)
			(polygon
				(pts
					(xy 126.507494 -304.648616) (xy 119.433594 -304.648616) (xy 119.433594 -311.582816) (xy 120.538494 -311.582816)
					(xy 120.538494 -307.468016) (xy 125.161294 -307.468016) (xy 125.161294 -311.582816) (xy 126.507494 -311.582816)
				)
			)
		)
		(zone
			(layer "F.Cu")
			(hatch none 0.5)
			(connect_pads
				(clearance 0)
			)
			(min_thickness 0.25)
			(keepout
				(tracks not_allowed)
				(vias allowed)
				(pads allowed)
				(copperpour not_allowed)
				(footprints allowed)
			)
			(placement
				(enabled no)
				(sheetname "")
			)
			(fill
				(thermal_gap 0.5)
				(thermal_bridge_width 0.5)
				(island_removal_mode 0)
			)
			(polygon
				(pts
					(xy 126.507494 -271.171416) (xy 119.433594 -271.171416) (xy 119.433594 -264.237216) (xy 120.538494 -264.237216)
					(xy 120.538494 -268.352016) (xy 125.161294 -268.352016) (xy 125.161294 -264.237216) (xy 126.507494 -264.237216)
				)
			)
		)
		(zone
			(layer "F.Cu")
			(hatch none 0.5)
			(connect_pads
				(clearance 0)
			)
			(min_thickness 0.25)
			(keepout
				(tracks allowed)
				(vias not_allowed)
				(pads allowed)
				(copperpour not_allowed)
				(footprints allowed)
			)
			(placement
				(enabled no)
				(sheetname "")
			)
			(fill
				(thermal_gap 0.5)
				(thermal_bridge_width 0.5)
				(island_removal_mode 0)
			)
			(polygon
				(pts
					(xy 126.507494 -271.171416) (xy 119.433594 -271.171416) (xy 119.433594 -264.237216) (xy 120.538494 -264.237216)
					(xy 120.538494 -268.352016) (xy 125.161294 -268.352016) (xy 125.161294 -264.237216) (xy 126.507494 -264.237216)
				)
			)
		)
		(zone
			(layers "F.Cu" "B.Cu" "In1.Cu" "In2.Cu" "In3.Cu" "In4.Cu" "In5.Cu" "In6.Cu"
				"In7.Cu" "In8.Cu" "In9.Cu" "In10.Cu"
			)
			(hatch none 0.5)
			(connect_pads
				(clearance 0)
			)
			(min_thickness 0.25)
			(keepout
				(tracks not_allowed)
				(vias allowed)
				(pads allowed)
				(copperpour not_allowed)
				(footprints allowed)
			)
			(placement
				(enabled no)
				(sheetname "")
			)
			(fill
				(thermal_gap 0.5)
				(thermal_bridge_width 0.5)
				(island_removal_mode 0)
			)
			(polygon
				(pts
					(arc
						(start 123.624594 -269.035022)
						(mid 122.075194 -269.035022)
						(end 123.624594 -269.035022)
					)
				)
			)
		)
		(zone
			(layers "F.Cu" "B.Cu" "In1.Cu" "In2.Cu" "In3.Cu" "In4.Cu" "In5.Cu" "In6.Cu"
				"In7.Cu" "In8.Cu" "In9.Cu" "In10.Cu"
			)
			(hatch none 0.5)
			(connect_pads
				(clearance 0)
			)
			(min_thickness 0.25)
			(keepout
				(tracks not_allowed)
				(vias allowed)
				(pads allowed)
				(copperpour not_allowed)
				(footprints allowed)
			)
			(placement
				(enabled no)
				(sheetname "")
			)
			(fill
				(thermal_gap 0.5)
				(thermal_bridge_width 0.5)
				(island_removal_mode 0)
			)
			(polygon
				(pts
					(arc
						(start 123.827794 -306.78501)
						(mid 121.871994 -306.78501)
						(end 123.827794 -306.78501)
					)
				)
			)
		)
	)
	(footprint ""
		(layer "F.Cu")
		(at 436.401718 -294.424862 180)
		(property "Reference" "R324"
			(at 0 0 180)
			(layer "F.SilkS")
			(hide yes)
			(effects
				(font
					(size 1.27 1.27)
				)
			)
		)
		(property "Value" "91R3F-1-GP"
			(at -0.0254 -2.5146 180)
			(unlocked yes)
			(layer "F.Fab")
			(hide yes)
			(effects
				(font
					(size 1.016 1.016)
					(thickness 0.1524)
				)
			)
		)
		(property "Device Type" "R603H22"
			(at -0.0254 -4.0386 180)
			(unlocked yes)
			(layer "F.Fab")
			(hide yes)
			(effects
				(font
					(size 1.016 1.016)
					(thickness 0.1524)
				)
			)
		)
		(duplicate_pad_numbers_are_jumpers no)
		(fp_line
			(start 0.2032 0)
			(end 0.4826 0)
			(stroke
				(width 0.2032)
				(type default)
			)
			(layer "F.SilkS")
		)
		(fp_line
			(start -0.4826 0)
			(end -0.2032 0)
			(stroke
				(width 0.2032)
				(type default)
			)
			(layer "F.SilkS")
		)
		(fp_rect
			(start -0.5842 1.3335)
			(end 0.5842 -1.3335)
			(stroke
				(width 0)
				(type default)
			)
			(fill no)
			(layer "F.CrtYd")
		)
		(fp_rect
			(start -0.5842 1.3335)
			(end 0.5842 -1.3335)
			(stroke
				(width 0)
				(type default)
			)
			(fill no)
			(layer "F.Fab")
		)
		(pad "1" smd custom
			(at 0 -0.762 180)
			(size 0.2159 0.2159)
			(layers "F.Cu" "F.Mask" "F.Paste")
			(net "P5V_B")
			(options
				(clearance outline)
				(anchor circle)
			)
			(primitives
				(gr_poly
					(pts
						(arc
							(start -0.3302 -0.4318)
							(mid -0.402042 -0.402042)
							(end -0.4318 -0.3302)
						)
						(arc
							(start -0.4318 0.3302)
							(mid -0.402042 0.402042)
							(end -0.3302 0.4318)
						)
						(arc
							(start 0.3302 0.4318)
							(mid 0.402042 0.402042)
							(end 0.4318 0.3302)
						)
						(arc
							(start 0.4318 -0.3302)
							(mid 0.402042 -0.402042)
							(end 0.3302 -0.4318)
						)
					)
					(width 0)
					(fill yes)
				)
			)
		)
		(pad "2" smd custom
			(at 0 0.762 180)
			(size 0.2159 0.2159)
			(layers "F.Cu" "F.Mask" "F.Paste")
			(net "DRV_ACT_34")
			(options
				(clearance outline)
				(anchor circle)
			)
			(primitives
				(gr_poly
					(pts
						(arc
							(start -0.3302 -0.4318)
							(mid -0.402042 -0.402042)
							(end -0.4318 -0.3302)
						)
						(arc
							(start -0.4318 0.3302)
							(mid -0.402042 0.402042)
							(end -0.3302 0.4318)
						)
						(arc
							(start 0.3302 0.4318)
							(mid 0.402042 0.402042)
							(end 0.4318 0.3302)
						)
						(arc
							(start 0.4318 -0.3302)
							(mid 0.402042 -0.402042)
							(end 0.3302 -0.4318)
						)
					)
					(width 0)
					(fill yes)
				)
			)
		)
	)
	(footprint ""
		(layer "F.Cu")
		(at 458.9399 -164.596318 90)
		(property "Reference" "C334"
			(at 0 0 90)
			(layer "F.SilkS")
			(hide yes)
			(effects
				(font
					(size 1.27 1.27)
				)
			)
		)
		(property "Value" "SCD033U25V2KX-GP"
			(at 1.1811 -2.7051 90)
			(unlocked yes)
			(layer "F.Fab")
			(hide yes)
			(effects
				(font
					(size 1.016 1.016)
					(thickness 0.1524)
				)
			)
		)
		(property "Device Type" "C402H22"
			(at 1.1811 -4.2291 90)
			(unlocked yes)
			(layer "F.Fab")
			(hide yes)
			(effects
				(font
					(size 1.016 1.016)
					(thickness 0.1524)
				)
			)
		)
		(duplicate_pad_numbers_are_jumpers no)
		(fp_rect
			(start -0.4318 0.9525)
			(end 0.4318 -0.9525)
			(stroke
				(width 0)
				(type default)
			)
			(fill no)
			(layer "F.CrtYd")
		)
		(fp_rect
			(start -0.4318 0.9525)
			(end 0.4318 -0.9525)
			(stroke
				(width 0)
				(type default)
			)
			(fill no)
			(layer "F.Fab")
		)
		(pad "1" smd custom
			(at 0 -0.4445 90)
			(size 0.1524 0.1524)
			(layers "F.Cu" "F.Mask" "F.Paste")
			(net "SW_HDD_P22")
			(options
				(clearance outline)
				(anchor circle)
			)
			(primitives
				(gr_poly
					(pts
						(arc
							(start 0.3048 -0.2032)
							(mid 0.275042 -0.275042)
							(end 0.2032 -0.3048)
						)
						(arc
							(start -0.2032 -0.3048)
							(mid -0.275042 -0.275042)
							(end -0.3048 -0.2032)
						)
						(arc
							(start -0.3048 0.2032)
							(mid -0.275042 0.275042)
							(end -0.2032 0.3048)
						)
						(arc
							(start 0.2032 0.3048)
							(mid 0.275042 0.275042)
							(end 0.3048 0.2032)
						)
					)
					(width 0)
					(fill yes)
				)
			)
		)
		(pad "2" smd custom
			(at 0 0.4445 90)
			(size 0.1524 0.1524)
			(layers "F.Cu" "F.Mask" "F.Paste")
			(net "GND")
			(options
				(clearance outline)
				(anchor circle)
			)
			(primitives
				(gr_poly
					(pts
						(arc
							(start 0.3048 -0.2032)
							(mid 0.275042 -0.275042)
							(end 0.2032 -0.3048)
						)
						(arc
							(start -0.2032 -0.3048)
							(mid -0.275042 -0.275042)
							(end -0.3048 -0.2032)
						)
						(arc
							(start -0.3048 0.2032)
							(mid -0.275042 0.275042)
							(end -0.2032 0.3048)
						)
						(arc
							(start 0.2032 0.3048)
							(mid 0.275042 0.275042)
							(end 0.3048 0.2032)
						)
					)
					(width 0)
					(fill yes)
				)
			)
		)
	)
	(footprint ""
		(layer "F.Cu")
		(at 81.51495 -242.25377)
		(property "Reference" "R218"
			(at 0 0 0)
			(layer "F.SilkS")
			(hide yes)
			(effects
				(font
					(size 1.27 1.27)
				)
			)
		)
		(property "Value" "91R3F-1-GP"
			(at -0.0254 -2.5146 0)
			(unlocked yes)
			(layer "F.Fab")
			(hide yes)
			(effects
				(font
					(size 1.016 1.016)
					(thickness 0.1524)
				)
			)
		)
		(property "Device Type" "R603H22"
			(at -0.0254 -4.0386 0)
			(unlocked yes)
			(layer "F.Fab")
			(hide yes)
			(effects
				(font
					(size 1.016 1.016)
					(thickness 0.1524)
				)
			)
		)
		(duplicate_pad_numbers_are_jumpers no)
		(fp_line
			(start -0.4826 0)
			(end -0.2032 0)
			(stroke
				(width 0.2032)
				(type default)
			)
			(layer "F.SilkS")
		)
		(fp_line
			(start 0.2032 0)
			(end 0.4826 0)
			(stroke
				(width 0.2032)
				(type default)
			)
			(layer "F.SilkS")
		)
		(fp_rect
			(start -0.5842 1.3335)
			(end 0.5842 -1.3335)
			(stroke
				(width 0)
				(type default)
			)
			(fill no)
			(layer "F.CrtYd")
		)
		(fp_rect
			(start -0.5842 1.3335)
			(end 0.5842 -1.3335)
			(stroke
				(width 0)
				(type default)
			)
			(fill no)
			(layer "F.Fab")
		)
		(pad "1" smd custom
			(at 0 -0.762)
			(size 0.2159 0.2159)
			(layers "F.Cu" "F.Mask" "F.Paste")
			(net "P5V_A_1")
			(options
				(clearance outline)
				(anchor circle)
			)
			(primitives
				(gr_poly
					(pts
						(arc
							(start -0.3302 -0.4318)
							(mid -0.402042 -0.402042)
							(end -0.4318 -0.3302)
						)
						(arc
							(start -0.4318 0.3302)
							(mid -0.402042 0.402042)
							(end -0.3302 0.4318)
						)
						(arc
							(start 0.3302 0.4318)
							(mid 0.402042 0.402042)
							(end 0.4318 0.3302)
						)
						(arc
							(start 0.4318 -0.3302)
							(mid 0.402042 -0.402042)
							(end 0.3302 -0.4318)
						)
					)
					(width 0)
					(fill yes)
				)
			)
		)
		(pad "2" smd custom
			(at 0 0.762)
			(size 0.2159 0.2159)
			(layers "F.Cu" "F.Mask" "F.Paste")
			(net "DRV_ACT_2")
			(options
				(clearance outline)
				(anchor circle)
			)
			(primitives
				(gr_poly
					(pts
						(arc
							(start -0.3302 -0.4318)
							(mid -0.402042 -0.402042)
							(end -0.4318 -0.3302)
						)
						(arc
							(start -0.4318 0.3302)
							(mid -0.402042 0.402042)
							(end -0.3302 0.4318)
						)
						(arc
							(start 0.3302 0.4318)
							(mid 0.402042 0.402042)
							(end 0.4318 0.3302)
						)
						(arc
							(start 0.4318 -0.3302)
							(mid 0.402042 -0.402042)
							(end 0.3302 -0.4318)
						)
					)
					(width 0)
					(fill yes)
				)
			)
		)
	)
	(footprint ""
		(layer "F.Cu")
		(at 420.200074 -57.909968 -90)
		(property "Reference" "HDDSAS33"
			(at 0 0 270)
			(layer "F.SilkS")
			(hide yes)
			(effects
				(font
					(size 1.27 1.27)
				)
			)
		)
		(property "Value" "SKT-SAS15P-14P-45-GP"
			(at -20.7645 -8.9789 270)
			(unlocked yes)
			(layer "F.Fab")
			(hide yes)
			(effects
				(font
					(size 1.016 1.016)
					(thickness 0.1524)
				)
			)
		)
		(property "Device Type" "10120818-001C-TRLF"
			(at -20.7645 -10.5029 270)
			(unlocked yes)
			(layer "F.Fab")
			(hide yes)
			(effects
				(font
					(size 1.016 1.016)
					(thickness 0.1524)
				)
			)
		)
		(duplicate_pad_numbers_are_jumpers no)
		(fp_line
			(start 1.651 4.2926)
			(end 1.651 3.0099)
			(stroke
				(width 0.1524)
				(type default)
			)
			(layer "F.SilkS")
		)
		(fp_line
			(start 8.509 4.2926)
			(end 1.651 4.2926)
			(stroke
				(width 0.1524)
				(type default)
			)
			(layer "F.SilkS")
		)
		(fp_line
			(start -23.4188 3.0099)
			(end -23.4188 -3.2512)
			(stroke
				(width 0.1524)
				(type default)
			)
			(layer "F.SilkS")
		)
		(fp_line
			(start 1.651 3.0099)
			(end -23.4188 3.0099)
			(stroke
				(width 0.1524)
				(type default)
			)
			(layer "F.SilkS")
		)
		(fp_line
			(start 8.509 3.0099)
			(end 8.509 4.2926)
			(stroke
				(width 0.1524)
				(type default)
			)
			(layer "F.SilkS")
		)
		(fp_line
			(start 23.4188 3.0099)
			(end 8.509 3.0099)
			(stroke
				(width 0.1524)
				(type default)
			)
			(layer "F.SilkS")
		)
		(fp_line
			(start -23.4188 -3.2512)
			(end 23.4188 -3.2512)
			(stroke
				(width 0.1524)
				(type default)
			)
			(layer "F.SilkS")
		)
		(fp_line
			(start 23.4188 -3.2512)
			(end 23.4188 3.0099)
			(stroke
				(width 0.1524)
				(type default)
			)
			(layer "F.SilkS")
		)
		(fp_line
			(start 15.5067 -3.3401)
			(end 16.2687 -3.3401)
			(stroke
				(width 0.3302)
				(type default)
			)
			(layer "F.SilkS")
		)
		(fp_poly
			(pts
				(xy 15.868904 -3.230372) (xy 16.503904 -3.865372) (xy 15.233904 -3.865372)
			)
			(stroke
				(width 0)
				(type default)
			)
			(fill yes)
			(layer "F.SilkS")
		)
		(fp_poly
			(pts
				(xy -22.8727 -2.7559) (xy 22.8727 -2.7559) (xy 22.8727 2.7559) (xy 8.255 2.7559) (xy 8.255 3.5179)
				(xy 1.905 3.5179) (xy 1.905 2.7559) (xy -22.8727 2.7559)
			)
			(stroke
				(width 0)
				(type default)
			)
			(fill no)
			(layer "F.CrtYd")
		)
		(fp_poly
			(pts
				(xy 1.397 4.5466) (xy 1.397 3.2639) (xy -23.6728 3.2639) (xy -23.6728 -3.5052) (xy 23.6728 -3.5052)
				(xy 23.6728 -0.00635) (xy 22.8727 -0.00635) (xy 22.8727 -2.7559) (xy -22.8727 -2.7559) (xy -22.8727 2.7559)
				(xy 1.905 2.7559) (xy 1.905 3.5179) (xy 8.255 3.5179) (xy 8.255 2.7559) (xy 22.8727 2.7559) (xy 22.8727 0.00635)
				(xy 23.6728 0.00635) (xy 23.6728 3.2639) (xy 8.763 3.2639) (xy 8.763 4.5466)
			)
			(stroke
				(width 0)
				(type default)
			)
			(fill no)
			(layer "F.CrtYd")
		)
		(fp_poly
			(pts
				(xy 1.397 4.5466) (xy 1.397 3.2639) (xy -23.6728 3.2639) (xy -23.6728 -3.5052) (xy 23.6728 -3.5052)
				(xy 23.6728 3.2639) (xy 8.763 3.2639) (xy 8.763 4.5466)
			)
			(stroke
				(width 0)
				(type default)
			)
			(fill no)
			(layer "F.Fab")
		)
		(pad "" np_thru_hole circle
			(at -18.874994 0 270)
			(size 0.254 0.254)
			(drill 1.3462)
			(layers "*.Cu" "*.Mask")
			(clearance 0.9017)
			(thermal_gap 0.9017)
		)
		(pad "" np_thru_hole circle
			(at 18.874994 0 270)
			(size 0.254 0.254)
			(drill 0.9398)
			(layers "*.Cu" "*.Mask")
			(clearance 0.6985)
			(thermal_gap 0.6985)
		)
		(pad "G1" smd rect
			(at 21.874988 0 270)
			(size 2.5908 2.5908)
			(layers "F.Cu" "F.Mask" "F.Paste")
			(net "GND")
		)
		(pad "G2" smd rect
			(at -21.874988 0 270)
			(size 2.5908 2.5908)
			(layers "F.Cu" "F.Mask" "F.Paste")
			(net "GND")
		)
		(pad "P1" smd rect
			(at 1.905 -1.82499 270)
			(size 0.6096 2.3622)
			(layers "F.Cu" "F.Mask" "F.Paste")
			(net "Net_2041")
		)
		(pad "P2" smd rect
			(at 0.635 -1.82499 270)
			(size 0.6096 2.3622)
			(layers "F.Cu" "F.Mask" "F.Paste")
			(net "Net_2042")
		)
		(pad "P3" smd rect
			(at -0.635 -1.82499 270)
			(size 0.6096 2.3622)
			(layers "F.Cu" "F.Mask" "F.Paste")
			(net "Net_2043")
		)
		(pad "P4" smd rect
			(at -1.905 -1.82499 270)
			(size 0.6096 2.3622)
			(layers "F.Cu" "F.Mask" "F.Paste")
			(net "GND")
		)
		(pad "P5" smd rect
			(at -3.175 -1.82499 270)
			(size 0.6096 2.3622)
			(layers "F.Cu" "F.Mask" "F.Paste")
			(net "HDD_PRSNT_33")
		)
		(pad "P6" smd rect
			(at -4.445 -1.82499 270)
			(size 0.6096 2.3622)
			(layers "F.Cu" "F.Mask" "F.Paste")
			(net "GND")
		)
		(pad "P7" smd rect
			(at -5.715 -1.82499 270)
			(size 0.6096 2.3622)
			(layers "F.Cu" "F.Mask" "F.Paste")
			(net "5V_PRE_33")
		)
		(pad "P8" smd rect
			(at -6.985 -1.82499 270)
			(size 0.6096 2.3622)
			(layers "F.Cu" "F.Mask" "F.Paste")
			(net "P5V_HDD33")
		)
		(pad "P9" smd rect
			(at -8.255 -1.82499 270)
			(size 0.6096 2.3622)
			(layers "F.Cu" "F.Mask" "F.Paste")
			(net "P5V_HDD33")
		)
		(pad "P10" smd rect
			(at -9.525 -1.82499 270)
			(size 0.6096 2.3622)
			(layers "F.Cu" "F.Mask" "F.Paste")
			(net "GND")
		)
		(pad "P11" smd rect
			(at -10.795 -1.82499 270)
			(size 0.6096 2.3622)
			(layers "F.Cu" "F.Mask" "F.Paste")
			(net "ACT_HDD_33")
		)
		(pad "P12" smd rect
			(at -12.065 -1.82499 270)
			(size 0.6096 2.3622)
			(layers "F.Cu" "F.Mask" "F.Paste")
			(net "GND")
		)
		(pad "P13" smd rect
			(at -13.335 -1.82499 270)
			(size 0.6096 2.3622)
			(layers "F.Cu" "F.Mask" "F.Paste")
			(net "12V_PRE_33")
		)
		(pad "P14" smd rect
			(at -14.605 -1.82499 270)
			(size 0.6096 2.3622)
			(layers "F.Cu" "F.Mask" "F.Paste")
			(net "P12V_HDD33")
		)
		(pad "P15" smd rect
			(at -15.875 -1.82499 270)
			(size 0.6096 2.3622)
			(layers "F.Cu" "F.Mask" "F.Paste")
			(net "P12V_HDD33")
		)
		(pad "S1" smd rect
			(at 15.875 -1.82499 270)
			(size 0.6096 2.3622)
			(layers "F.Cu" "F.Mask" "F.Paste")
			(net "GND")
		)
		(pad "S2" smd rect
			(at 14.605 -1.82499 270)
			(size 0.6096 2.3622)
			(layers "F.Cu" "F.Mask" "F.Paste")
			(net "SAS_HDD_RX_P33")
		)
		(pad "S3" smd rect
			(at 13.335 -1.82499 270)
			(size 0.6096 2.3622)
			(layers "F.Cu" "F.Mask" "F.Paste")
			(net "SAS_HDD_RX_N33")
		)
		(pad "S4" smd rect
			(at 12.065 -1.82499 270)
			(size 0.6096 2.3622)
			(layers "F.Cu" "F.Mask" "F.Paste")
			(net "GND")
		)
		(pad "S5" smd rect
			(at 10.795 -1.82499 270)
			(size 0.6096 2.3622)
			(layers "F.Cu" "F.Mask" "F.Paste")
			(net "PHY_DRV_A_TO_SCC_A_33_DN")
		)
		(pad "S6" smd rect
			(at 9.525 -1.82499 270)
			(size 0.6096 2.3622)
			(layers "F.Cu" "F.Mask" "F.Paste")
			(net "PHY_DRV_A_TO_SCC_A_33_DP")
		)
		(pad "S7" smd rect
			(at 8.255 -1.82499 270)
			(size 0.6096 2.3622)
			(layers "F.Cu" "F.Mask" "F.Paste")
			(net "GND")
		)
		(pad "S8" smd rect
			(at 7.480046 2.845054 270)
			(size 0.508 2.3622)
			(layers "F.Cu" "F.Mask" "F.Paste")
			(net "GND")
		)
		(pad "S9" smd rect
			(at 6.679946 2.845054 270)
			(size 0.508 2.3622)
			(layers "F.Cu" "F.Mask" "F.Paste")
			(net "Net_472")
		)
		(pad "S10" smd rect
			(at 5.8801 2.845054 270)
			(size 0.508 2.3622)
			(layers "F.Cu" "F.Mask" "F.Paste")
			(net "Net_364")
		)
		(pad "S11" smd rect
			(at 5.08 2.845054 270)
			(size 0.508 2.3622)
			(layers "F.Cu" "F.Mask" "F.Paste")
			(net "GND")
		)
		(pad "S12" smd rect
			(at 4.2799 2.845054 270)
			(size 0.508 2.3622)
			(layers "F.Cu" "F.Mask" "F.Paste")
			(net "Net_400")
		)
		(pad "S13" smd rect
			(at 3.480054 2.845054 270)
			(size 0.508 2.3622)
			(layers "F.Cu" "F.Mask" "F.Paste")
			(net "Net_436")
		)
		(pad "S14" smd rect
			(at 2.679954 2.845054 270)
			(size 0.508 2.3622)
			(layers "F.Cu" "F.Mask" "F.Paste")
			(net "GND")
		)
		(zone
			(layer "F.Cu")
			(hatch none 0.5)
			(connect_pads
				(clearance 0)
			)
			(min_thickness 0.25)
			(keepout
				(tracks not_allowed)
				(vias allowed)
				(pads allowed)
				(copperpour not_allowed)
				(footprints allowed)
			)
			(placement
				(enabled no)
				(sheetname "")
			)
			(fill
				(thermal_gap 0.5)
				(thermal_bridge_width 0.5)
				(island_removal_mode 0)
			)
			(polygon
				(pts
					(xy 423.857674 -74.648568) (xy 416.783774 -74.648568) (xy 416.783774 -81.582768) (xy 417.888674 -81.582768)
					(xy 417.888674 -77.467968) (xy 422.511474 -77.467968) (xy 422.511474 -81.582768) (xy 423.857674 -81.582768)
				)
			)
		)
		(zone
			(layer "F.Cu")
			(hatch none 0.5)
			(connect_pads
				(clearance 0)
			)
			(min_thickness 0.25)
			(keepout
				(tracks allowed)
				(vias not_allowed)
				(pads allowed)
				(copperpour not_allowed)
				(footprints allowed)
			)
			(placement
				(enabled no)
				(sheetname "")
			)
			(fill
				(thermal_gap 0.5)
				(thermal_bridge_width 0.5)
				(island_removal_mode 0)
			)
			(polygon
				(pts
					(xy 423.857674 -74.648568) (xy 416.783774 -74.648568) (xy 416.783774 -81.582768) (xy 417.888674 -81.582768)
					(xy 417.888674 -77.467968) (xy 422.511474 -77.467968) (xy 422.511474 -81.582768) (xy 423.857674 -81.582768)
				)
			)
		)
		(zone
			(layer "F.Cu")
			(hatch none 0.5)
			(connect_pads
				(clearance 0)
			)
			(min_thickness 0.25)
			(keepout
				(tracks not_allowed)
				(vias allowed)
				(pads allowed)
				(copperpour not_allowed)
				(footprints allowed)
			)
			(placement
				(enabled no)
				(sheetname "")
			)
			(fill
				(thermal_gap 0.5)
				(thermal_bridge_width 0.5)
				(island_removal_mode 0)
			)
			(polygon
				(pts
					(xy 423.857674 -41.171368) (xy 416.783774 -41.171368) (xy 416.783774 -34.237168) (xy 417.888674 -34.237168)
					(xy 417.888674 -38.351968) (xy 422.511474 -38.351968) (xy 422.511474 -34.237168) (xy 423.857674 -34.237168)
				)
			)
		)
		(zone
			(layer "F.Cu")
			(hatch none 0.5)
			(connect_pads
				(clearance 0)
			)
			(min_thickness 0.25)
			(keepout
				(tracks allowed)
				(vias not_allowed)
				(pads allowed)
				(copperpour not_allowed)
				(footprints allowed)
			)
			(placement
				(enabled no)
				(sheetname "")
			)
			(fill
				(thermal_gap 0.5)
				(thermal_bridge_width 0.5)
				(island_removal_mode 0)
			)
			(polygon
				(pts
					(xy 423.857674 -41.171368) (xy 416.783774 -41.171368) (xy 416.783774 -34.237168) (xy 417.888674 -34.237168)
					(xy 417.888674 -38.351968) (xy 422.511474 -38.351968) (xy 422.511474 -34.237168) (xy 423.857674 -34.237168)
				)
			)
		)
		(zone
			(layers "F.Cu" "B.Cu" "In1.Cu" "In2.Cu" "In3.Cu" "In4.Cu" "In5.Cu" "In6.Cu"
				"In7.Cu" "In8.Cu" "In9.Cu" "In10.Cu"
			)
			(hatch none 0.5)
			(connect_pads
				(clearance 0)
			)
			(min_thickness 0.25)
			(keepout
				(tracks not_allowed)
				(vias allowed)
				(pads allowed)
				(copperpour not_allowed)
				(footprints allowed)
			)
			(placement
				(enabled no)
				(sheetname "")
			)
			(fill
				(thermal_gap 0.5)
				(thermal_bridge_width 0.5)
				(island_removal_mode 0)
			)
			(polygon
				(pts
					(arc
						(start 420.974774 -39.034974)
						(mid 419.425374 -39.034974)
						(end 420.974774 -39.034974)
					)
				)
			)
		)
		(zone
			(layers "F.Cu" "B.Cu" "In1.Cu" "In2.Cu" "In3.Cu" "In4.Cu" "In5.Cu" "In6.Cu"
				"In7.Cu" "In8.Cu" "In9.Cu" "In10.Cu"
			)
			(hatch none 0.5)
			(connect_pads
				(clearance 0)
			)
			(min_thickness 0.25)
			(keepout
				(tracks not_allowed)
				(vias allowed)
				(pads allowed)
				(copperpour not_allowed)
				(footprints allowed)
			)
			(placement
				(enabled no)
				(sheetname "")
			)
			(fill
				(thermal_gap 0.5)
				(thermal_bridge_width 0.5)
				(island_removal_mode 0)
			)
			(polygon
				(pts
					(arc
						(start 421.177974 -76.784962)
						(mid 419.222174 -76.784962)
						(end 421.177974 -76.784962)
					)
				)
			)
		)
	)
	(footprint ""
		(layer "F.Cu")
		(at 240.578386 -346.351098 180)
		(property "Reference" "R168"
			(at 0 0 180)
			(layer "F.SilkS")
			(hide yes)
			(effects
				(font
					(size 1.27 1.27)
				)
			)
		)
		(property "Value" "10KR2F-2-GP"
			(at 0.064008 -3.993896 180)
			(unlocked yes)
			(layer "F.Fab")
			(hide yes)
			(effects
				(font
					(size 1.016 1.016)
					(thickness 0.1524)
				)
			)
		)
		(property "Device Type" "R402H16"
			(at 0.064008 -5.517896 180)
			(unlocked yes)
			(layer "F.Fab")
			(hide yes)
			(effects
				(font
					(size 1.016 1.016)
					(thickness 0.1524)
				)
			)
		)
		(duplicate_pad_numbers_are_jumpers no)
		(fp_line
			(start 0.508 -0.9398)
			(end -0.508 -0.9398)
			(stroke
				(width 0.1524)
				(type default)
			)
			(layer "F.SilkS")
		)
		(fp_line
			(start -0.508 -0.9398)
			(end -0.508 0.9398)
			(stroke
				(width 0.1524)
				(type default)
			)
			(layer "F.SilkS")
		)
		(fp_rect
			(start -0.508 0.9398)
			(end 0.508 -0.9398)
			(stroke
				(width 0)
				(type default)
			)
			(fill no)
			(layer "F.CrtYd")
		)
		(fp_rect
			(start -0.508 0.9398)
			(end 0.508 -0.9398)
			(stroke
				(width 0)
				(type default)
			)
			(fill no)
			(layer "F.Fab")
		)
		(pad "1" smd custom
			(at 0 -0.4445 180)
			(size 0.1397 0.1397)
			(layers "F.Cu" "F.Mask" "F.Paste")
			(net "P5V_A_3_SENSE")
			(options
				(clearance outline)
				(anchor circle)
			)
			(primitives
				(gr_poly
					(pts
						(arc
							(start -0.1778 -0.2794)
							(mid -0.249642 -0.249642)
							(end -0.2794 -0.1778)
						)
						(arc
							(start -0.2794 0.1778)
							(mid -0.249642 0.249642)
							(end -0.1778 0.2794)
						)
						(arc
							(start 0.1778 0.2794)
							(mid 0.249642 0.249642)
							(end 0.2794 0.1778)
						)
						(arc
							(start 0.2794 -0.1778)
							(mid 0.249642 -0.249642)
							(end 0.1778 -0.2794)
						)
					)
					(width 0)
					(fill yes)
				)
			)
		)
		(pad "2" smd custom
			(at 0 0.4445 180)
			(size 0.1397 0.1397)
			(layers "F.Cu" "F.Mask" "F.Paste")
			(net "GND")
			(options
				(clearance outline)
				(anchor circle)
			)
			(primitives
				(gr_poly
					(pts
						(arc
							(start -0.1778 -0.2794)
							(mid -0.249642 -0.249642)
							(end -0.2794 -0.1778)
						)
						(arc
							(start -0.2794 0.1778)
							(mid -0.249642 0.249642)
							(end -0.1778 0.2794)
						)
						(arc
							(start 0.1778 0.2794)
							(mid 0.249642 0.249642)
							(end 0.2794 0.1778)
						)
						(arc
							(start 0.2794 -0.1778)
							(mid 0.249642 -0.249642)
							(end 0.1778 -0.2794)
						)
					)
					(width 0)
					(fill yes)
				)
			)
		)
	)
	(footprint ""
		(layer "F.Cu")
		(at 377.915932 -139.13485 -90)
		(property "Reference" "U31"
			(at 0 0 270)
			(layer "F.SilkS")
			(hide yes)
			(effects
				(font
					(size 1.27 1.27)
				)
			)
		)
		(property "Value" "SN74LVC1G08DCKR-GP"
			(at -2.3368 -8.6868 270)
			(unlocked yes)
			(layer "F.Fab")
			(hide yes)
			(effects
				(font
					(size 1.016 1.016)
					(thickness 0.1524)
				)
			)
		)
		(property "Device Type" "SC70-5H44"
			(at -2.3114 -10.414 270)
			(unlocked yes)
			(layer "F.Fab")
			(hide yes)
			(effects
				(font
					(size 1.016 1.016)
					(thickness 0.1524)
				)
			)
		)
		(duplicate_pad_numbers_are_jumpers no)
		(fp_line
			(start -1.27 1.7018)
			(end -1.27 -1.7018)
			(stroke
				(width 0.1524)
				(type default)
			)
			(layer "F.SilkS")
		)
		(fp_line
			(start 1.27 1.7018)
			(end -1.27 1.7018)
			(stroke
				(width 0.1524)
				(type default)
			)
			(layer "F.SilkS")
		)
		(fp_line
			(start -1.27 -1.7018)
			(end 1.27 -1.7018)
			(stroke
				(width 0.1524)
				(type default)
			)
			(layer "F.SilkS")
		)
		(fp_line
			(start 1.27 -1.7018)
			(end 1.27 1.7018)
			(stroke
				(width 0.1524)
				(type default)
			)
			(layer "F.SilkS")
		)
		(fp_line
			(start 0.6604 -1.8034)
			(end 1.3843 -1.8034)
			(stroke
				(width 0.3302)
				(type default)
			)
			(layer "F.SilkS")
		)
		(fp_line
			(start 1.3843 -1.8034)
			(end 1.3843 -1.1176)
			(stroke
				(width 0.3302)
				(type default)
			)
			(layer "F.SilkS")
		)
		(fp_rect
			(start -1.524 1.9558)
			(end 1.524 -1.9558)
			(stroke
				(width 0)
				(type default)
			)
			(fill no)
			(layer "F.CrtYd")
		)
		(fp_poly
			(pts
				(xy -1.524 -1.9558) (xy 1.524 -1.9558) (xy 1.524 1.9558) (xy -1.524 1.9558)
			)
			(stroke
				(width 0)
				(type default)
			)
			(fill no)
			(layer "F.Fab")
		)
		(pad "1" smd rect
			(at 0.65024 -0.8255 270)
			(size 0.4064 1.2192)
			(layers "F.Cu" "F.Mask" "F.Paste")
			(net "P12V_B_PGOOD")
		)
		(pad "2" smd rect
			(at 0 -0.8255 270)
			(size 0.4064 1.2192)
			(layers "F.Cu" "F.Mask" "F.Paste")
			(net "COMP_B_PWR_EN")
		)
		(pad "3" smd rect
			(at -0.65024 -0.8255 270)
			(size 0.4064 1.2192)
			(layers "F.Cu" "F.Mask" "F.Paste")
			(net "GND")
		)
		(pad "4" smd rect
			(at -0.65024 0.8255 270)
			(size 0.4064 1.2192)
			(layers "F.Cu" "F.Mask" "F.Paste")
			(net "MB1_HS_ENABLE")
		)
		(pad "5" smd rect
			(at 0.65024 0.8255 270)
			(size 0.4064 1.2192)
			(layers "F.Cu" "F.Mask" "F.Paste")
			(net "P3V3_B_BIAS")
		)
	)
	(footprint ""
		(layer "F.Cu")
		(at 427.009052 -295.826942 180)
		(property "Reference" "C158"
			(at 0 0 180)
			(layer "F.SilkS")
			(hide yes)
			(effects
				(font
					(size 1.27 1.27)
				)
			)
		)
		(property "Value" "SC10U16V6KX-2GP"
			(at -0.0762 -5.1308 180)
			(unlocked yes)
			(layer "F.Fab")
			(hide yes)
			(effects
				(font
					(size 1.016 1.016)
					(thickness 0.1524)
				)
			)
		)
		(property "Device Type" "C1206H71"
			(at -0.127 -6.6548 180)
			(unlocked yes)
			(layer "F.Fab")
			(hide yes)
			(effects
				(font
					(size 1.016 1.016)
					(thickness 0.1524)
				)
			)
		)
		(duplicate_pad_numbers_are_jumpers no)
		(fp_line
			(start 1.016 2.2352)
			(end -1.016 2.2352)
			(stroke
				(width 0.1524)
				(type default)
			)
			(layer "F.SilkS")
		)
		(fp_line
			(start 1.016 0.8382)
			(end 1.016 2.2352)
			(stroke
				(width 0.1524)
				(type default)
			)
			(layer "F.SilkS")
		)
		(fp_line
			(start 1.016 -2.2352)
			(end 1.016 -0.8382)
			(stroke
				(width 0.1524)
				(type default)
			)
			(layer "F.SilkS")
		)
		(fp_line
			(start -1.016 2.2352)
			(end -1.016 0.8382)
			(stroke
				(width 0.1524)
				(type default)
			)
			(layer "F.SilkS")
		)
		(fp_line
			(start -1.016 -0.8382)
			(end -1.016 -2.2352)
			(stroke
				(width 0.1524)
				(type default)
			)
			(layer "F.SilkS")
		)
		(fp_line
			(start -1.016 -2.2352)
			(end 1.016 -2.2352)
			(stroke
				(width 0.1524)
				(type default)
			)
			(layer "F.SilkS")
		)
		(fp_rect
			(start -1.0922 2.3114)
			(end 1.0922 -2.3114)
			(stroke
				(width 0)
				(type default)
			)
			(fill no)
			(layer "F.CrtYd")
		)
		(fp_poly
			(pts
				(xy 1.0922 -2.3114) (xy 1.0922 2.3114) (xy -1.0922 2.3114) (xy -1.0922 -2.3114)
			)
			(stroke
				(width 0)
				(type default)
			)
			(fill no)
			(layer "F.Fab")
		)
		(pad "1" smd rect
			(at 0 -1.397 180)
			(size 1.651 1.27)
			(layers "F.Cu" "F.Mask" "F.Paste")
			(net "P5V_HDD9")
		)
		(pad "2" smd rect
			(at 0 1.397 180)
			(size 1.651 1.27)
			(layers "F.Cu" "F.Mask" "F.Paste")
			(net "GND")
		)
	)
	(footprint ""
		(layer "F.Cu")
		(at 444.7286 -68.707)
		(property "Reference" "TP172"
			(at 0 0 0)
			(layer "F.SilkS")
			(hide yes)
			(effects
				(font
					(size 1.27 1.27)
				)
			)
		)
		(property "Value" "TPAD32-GP"
			(at -0.0508 -1.6764 0)
			(unlocked yes)
			(layer "F.Fab")
			(hide yes)
			(effects
				(font
					(size 1.016 1.016)
					(thickness 0.1524)
				)
			)
		)
		(property "Device Type" "TPAD32"
			(at -0.0508 -3.2004 0)
			(unlocked yes)
			(layer "F.Fab")
			(hide yes)
			(effects
				(font
					(size 1.016 1.016)
					(thickness 0.1524)
				)
			)
		)
		(duplicate_pad_numbers_are_jumpers no)
		(fp_poly
			(pts
				(arc
					(start 0.4064 0)
					(mid -0.4064 0)
					(end 0.4064 0)
				)
			)
			(stroke
				(width 0)
				(type default)
			)
			(fill no)
			(layer "F.CrtYd")
		)
		(fp_poly
			(pts
				(arc
					(start 0.7112 0)
					(mid -0.7112 0)
					(end 0.7112 0)
				)
			)
			(stroke
				(width 0)
				(type default)
			)
			(fill no)
			(layer "F.Fab")
		)
		(pad "1" smd circle
			(at 0 0)
			(size 0.8128 0.8128)
			(layers "F.Cu" "F.Mask" "F.Paste")
			(net "ACT_HDD_34")
		)
	)
	(footprint ""
		(layer "F.Cu")
		(at 247.79097 -296.901362 180)
		(property "Reference" "U47"
			(at 0 0 180)
			(layer "F.SilkS")
			(hide yes)
			(effects
				(font
					(size 1.27 1.27)
				)
			)
		)
		(property "Value" "SN74LVC1G08DCKR-GP"
			(at -2.3368 -8.6868 180)
			(unlocked yes)
			(layer "F.Fab")
			(hide yes)
			(effects
				(font
					(size 1.016 1.016)
					(thickness 0.1524)
				)
			)
		)
		(property "Device Type" "SC70-5H44"
			(at -2.3114 -10.414 180)
			(unlocked yes)
			(layer "F.Fab")
			(hide yes)
			(effects
				(font
					(size 1.016 1.016)
					(thickness 0.1524)
				)
			)
		)
		(duplicate_pad_numbers_are_jumpers no)
		(fp_line
			(start 1.3843 -1.8034)
			(end 1.3843 -1.1176)
			(stroke
				(width 0.3302)
				(type default)
			)
			(layer "F.SilkS")
		)
		(fp_line
			(start 1.27 1.7018)
			(end -1.27 1.7018)
			(stroke
				(width 0.1524)
				(type default)
			)
			(layer "F.SilkS")
		)
		(fp_line
			(start 1.27 -1.7018)
			(end 1.27 1.7018)
			(stroke
				(width 0.1524)
				(type default)
			)
			(layer "F.SilkS")
		)
		(fp_line
			(start 0.6604 -1.8034)
			(end 1.3843 -1.8034)
			(stroke
				(width 0.3302)
				(type default)
			)
			(layer "F.SilkS")
		)
		(fp_line
			(start -1.27 1.7018)
			(end -1.27 -1.7018)
			(stroke
				(width 0.1524)
				(type default)
			)
			(layer "F.SilkS")
		)
		(fp_line
			(start -1.27 -1.7018)
			(end 1.27 -1.7018)
			(stroke
				(width 0.1524)
				(type default)
			)
			(layer "F.SilkS")
		)
		(fp_rect
			(start -1.524 1.9558)
			(end 1.524 -1.9558)
			(stroke
				(width 0)
				(type default)
			)
			(fill no)
			(layer "F.CrtYd")
		)
		(fp_poly
			(pts
				(xy -1.524 -1.9558) (xy 1.524 -1.9558) (xy 1.524 1.9558) (xy -1.524 1.9558)
			)
			(stroke
				(width 0)
				(type default)
			)
			(fill no)
			(layer "F.Fab")
		)
		(pad "1" smd rect
			(at 0.65024 -0.8255 180)
			(size 0.4064 1.2192)
			(layers "F.Cu" "F.Mask" "F.Paste")
			(net "BMC_A_TO_EXP_A_RESET_N")
		)
		(pad "2" smd rect
			(at 0 -0.8255 180)
			(size 0.4064 1.2192)
			(layers "F.Cu" "F.Mask" "F.Paste")
			(net "RST_BTN_A_N")
		)
		(pad "3" smd rect
			(at -0.65024 -0.8255 180)
			(size 0.4064 1.2192)
			(layers "F.Cu" "F.Mask" "F.Paste")
			(net "GND")
		)
		(pad "4" smd rect
			(at -0.65024 0.8255 180)
			(size 0.4064 1.2192)
			(layers "F.Cu" "F.Mask" "F.Paste")
			(net "SCC_A_RESET_N")
		)
		(pad "5" smd rect
			(at 0.65024 0.8255 180)
			(size 0.4064 1.2192)
			(layers "F.Cu" "F.Mask" "F.Paste")
			(net "P3V3_STBY_A")
		)
	)
	(footprint ""
		(layer "F.Cu")
		(at 441.484512 -159.219392 -90)
		(property "Reference" "C324"
			(at 0 0 270)
			(layer "F.SilkS")
			(hide yes)
			(effects
				(font
					(size 1.27 1.27)
				)
			)
		)
		(property "Value" "SCD01U16V1KX-GP"
			(at -2.8321 -1.7399 270)
			(unlocked yes)
			(layer "F.Fab")
			(hide yes)
			(effects
				(font
					(size 1.016 1.016)
					(thickness 0.1524)
				)
			)
		)
		(property "Device Type" "C0201H13"
			(at -2.8321 -3.2639 270)
			(unlocked yes)
			(layer "F.Fab")
			(hide yes)
			(effects
				(font
					(size 1.016 1.016)
					(thickness 0.1524)
				)
			)
		)
		(duplicate_pad_numbers_are_jumpers no)
		(fp_rect
			(start -0.2794 0.6477)
			(end 0.2794 -0.6477)
			(stroke
				(width 0)
				(type default)
			)
			(fill no)
			(layer "F.CrtYd")
		)
		(fp_rect
			(start -0.2794 0.6477)
			(end 0.2794 -0.6477)
			(stroke
				(width 0)
				(type default)
			)
			(fill no)
			(layer "F.Fab")
		)
		(pad "1" smd custom
			(at 0 -0.2794 270)
			(size 0.0762 0.0762)
			(layers "F.Cu" "F.Mask" "F.Paste")
			(net "SAS_HDD_RX_N22")
			(options
				(clearance outline)
				(anchor circle)
			)
			(primitives
				(gr_poly
					(pts
						(arc
							(start 0.1524 -0.127)
							(mid 0.137521 -0.162921)
							(end 0.1016 -0.1778)
						)
						(arc
							(start -0.1016 -0.1778)
							(mid -0.137521 -0.162921)
							(end -0.1524 -0.127)
						)
						(arc
							(start -0.1524 0.127)
							(mid -0.137521 0.162921)
							(end -0.1016 0.1778)
						)
						(arc
							(start 0.1016 0.1778)
							(mid 0.137521 0.162921)
							(end 0.1524 0.127)
						)
					)
					(width 0)
					(fill yes)
				)
			)
		)
		(pad "2" smd custom
			(at 0 0.2794 270)
			(size 0.0762 0.0762)
			(layers "F.Cu" "F.Mask" "F.Paste")
			(net "PHY_SCC_A_TO_DRV_A_22_DN")
			(options
				(clearance outline)
				(anchor circle)
			)
			(primitives
				(gr_poly
					(pts
						(arc
							(start 0.1524 -0.127)
							(mid 0.137521 -0.162921)
							(end 0.1016 -0.1778)
						)
						(arc
							(start -0.1016 -0.1778)
							(mid -0.137521 -0.162921)
							(end -0.1524 -0.127)
						)
						(arc
							(start -0.1524 0.127)
							(mid -0.137521 0.162921)
							(end -0.1016 0.1778)
						)
						(arc
							(start 0.1016 0.1778)
							(mid 0.137521 0.162921)
							(end 0.1524 0.127)
						)
					)
					(width 0)
					(fill yes)
				)
			)
		)
	)
	(footprint ""
		(layer "F.Cu")
		(at 332.105 -42.585894)
		(property "Reference" "R833"
			(at 0 0 0)
			(layer "F.SilkS")
			(hide yes)
			(effects
				(font
					(size 1.27 1.27)
				)
			)
		)
		(property "Value" "4K7R2J-2-GP"
			(at 0.064008 -3.993896 0)
			(unlocked yes)
			(layer "F.Fab")
			(hide yes)
			(effects
				(font
					(size 1.016 1.016)
					(thickness 0.1524)
				)
			)
		)
		(property "Device Type" "R402H16"
			(at 0.064008 -5.517896 0)
			(unlocked yes)
			(layer "F.Fab")
			(hide yes)
			(effects
				(font
					(size 1.016 1.016)
					(thickness 0.1524)
				)
			)
		)
		(duplicate_pad_numbers_are_jumpers no)
		(fp_line
			(start -0.508 -0.9398)
			(end -0.508 0.9398)
			(stroke
				(width 0.1524)
				(type default)
			)
			(layer "F.SilkS")
		)
		(fp_line
			(start 0.508 -0.9398)
			(end -0.508 -0.9398)
			(stroke
				(width 0.1524)
				(type default)
			)
			(layer "F.SilkS")
		)
		(fp_rect
			(start -0.508 0.9398)
			(end 0.508 -0.9398)
			(stroke
				(width 0)
				(type default)
			)
			(fill no)
			(layer "F.CrtYd")
		)
		(fp_rect
			(start -0.508 0.9398)
			(end 0.508 -0.9398)
			(stroke
				(width 0)
				(type default)
			)
			(fill no)
			(layer "F.Fab")
		)
		(pad "1" smd custom
			(at 0 -0.4445)
			(size 0.1397 0.1397)
			(layers "F.Cu" "F.Mask" "F.Paste")
			(net "SW_PWR_R_HDD30")
			(options
				(clearance outline)
				(anchor circle)
			)
			(primitives
				(gr_poly
					(pts
						(arc
							(start -0.1778 -0.2794)
							(mid -0.249642 -0.249642)
							(end -0.2794 -0.1778)
						)
						(arc
							(start -0.2794 0.1778)
							(mid -0.249642 0.249642)
							(end -0.1778 0.2794)
						)
						(arc
							(start 0.1778 0.2794)
							(mid 0.249642 0.249642)
							(end 0.2794 0.1778)
						)
						(arc
							(start 0.2794 -0.1778)
							(mid 0.249642 -0.249642)
							(end 0.1778 -0.2794)
						)
					)
					(width 0)
					(fill yes)
				)
			)
		)
		(pad "2" smd custom
			(at 0 0.4445)
			(size 0.1397 0.1397)
			(layers "F.Cu" "F.Mask" "F.Paste")
			(net "GND")
			(options
				(clearance outline)
				(anchor circle)
			)
			(primitives
				(gr_poly
					(pts
						(arc
							(start -0.1778 -0.2794)
							(mid -0.249642 -0.249642)
							(end -0.2794 -0.1778)
						)
						(arc
							(start -0.2794 0.1778)
							(mid -0.249642 0.249642)
							(end -0.1778 0.2794)
						)
						(arc
							(start 0.1778 0.2794)
							(mid 0.249642 0.249642)
							(end 0.2794 0.1778)
						)
						(arc
							(start 0.2794 -0.1778)
							(mid 0.249642 -0.249642)
							(end 0.1778 -0.2794)
						)
					)
					(width 0)
					(fill yes)
				)
			)
		)
	)
	(footprint ""
		(layer "F.Cu")
		(at 262.69442 -212.046566 -90)
		(property "Reference" "C115"
			(at 0 0 270)
			(layer "F.SilkS")
			(hide yes)
			(effects
				(font
					(size 1.27 1.27)
				)
			)
		)
		(property "Value" "SCD1U16V2KX-3GP"
			(at 1.1811 -2.7051 270)
			(unlocked yes)
			(layer "F.Fab")
			(hide yes)
			(effects
				(font
					(size 1.016 1.016)
					(thickness 0.1524)
				)
			)
		)
		(property "Device Type" "C402H22"
			(at 1.1811 -4.2291 270)
			(unlocked yes)
			(layer "F.Fab")
			(hide yes)
			(effects
				(font
					(size 1.016 1.016)
					(thickness 0.1524)
				)
			)
		)
		(duplicate_pad_numbers_are_jumpers no)
		(fp_rect
			(start -0.4318 0.9525)
			(end 0.4318 -0.9525)
			(stroke
				(width 0)
				(type default)
			)
			(fill no)
			(layer "F.CrtYd")
		)
		(fp_rect
			(start -0.4318 0.9525)
			(end 0.4318 -0.9525)
			(stroke
				(width 0)
				(type default)
			)
			(fill no)
			(layer "F.Fab")
		)
		(pad "1" smd custom
			(at 0 -0.4445 270)
			(size 0.1524 0.1524)
			(layers "F.Cu" "F.Mask" "F.Paste")
			(net "I2C_DPB_BUFF_EN")
			(options
				(clearance outline)
				(anchor circle)
			)
			(primitives
				(gr_poly
					(pts
						(arc
							(start 0.3048 -0.2032)
							(mid 0.275042 -0.275042)
							(end 0.2032 -0.3048)
						)
						(arc
							(start -0.2032 -0.3048)
							(mid -0.275042 -0.275042)
							(end -0.3048 -0.2032)
						)
						(arc
							(start -0.3048 0.2032)
							(mid -0.275042 0.275042)
							(end -0.2032 0.3048)
						)
						(arc
							(start 0.2032 0.3048)
							(mid 0.275042 0.275042)
							(end 0.3048 0.2032)
						)
					)
					(width 0)
					(fill yes)
				)
			)
		)
		(pad "2" smd custom
			(at 0 0.4445 270)
			(size 0.1524 0.1524)
			(layers "F.Cu" "F.Mask" "F.Paste")
			(net "GND")
			(options
				(clearance outline)
				(anchor circle)
			)
			(primitives
				(gr_poly
					(pts
						(arc
							(start 0.3048 -0.2032)
							(mid 0.275042 -0.275042)
							(end 0.2032 -0.3048)
						)
						(arc
							(start -0.2032 -0.3048)
							(mid -0.275042 -0.275042)
							(end -0.3048 -0.2032)
						)
						(arc
							(start -0.3048 0.2032)
							(mid -0.275042 0.275042)
							(end -0.2032 0.3048)
						)
						(arc
							(start 0.2032 0.3048)
							(mid 0.275042 0.275042)
							(end 0.3048 0.2032)
						)
					)
					(width 0)
					(fill yes)
				)
			)
		)
	)
	(footprint ""
		(layer "F.Cu")
		(at 20.430998 -177.778918 -90)
		(property "Reference" "C196"
			(at 0 0 270)
			(layer "F.SilkS")
			(hide yes)
			(effects
				(font
					(size 1.27 1.27)
				)
			)
		)
		(property "Value" "SC1U16V3KX-5GP"
			(at 0 -2.8194 270)
			(unlocked yes)
			(layer "F.Fab")
			(hide yes)
			(effects
				(font
					(size 1.016 1.016)
					(thickness 0.1524)
				)
			)
		)
		(property "Device Type" "C603H36"
			(at 0 -4.3434 270)
			(unlocked yes)
			(layer "F.Fab")
			(hide yes)
			(effects
				(font
					(size 1.016 1.016)
					(thickness 0.1524)
				)
			)
		)
		(duplicate_pad_numbers_are_jumpers no)
		(fp_line
			(start 0.508 0)
			(end -0.508 0)
			(stroke
				(width 0.2032)
				(type default)
			)
			(layer "F.SilkS")
		)
		(fp_rect
			(start -0.5842 1.3335)
			(end 0.5842 -1.3335)
			(stroke
				(width 0)
				(type default)
			)
			(fill no)
			(layer "F.CrtYd")
		)
		(fp_rect
			(start -0.5842 1.3335)
			(end 0.5842 -1.3335)
			(stroke
				(width 0)
				(type default)
			)
			(fill no)
			(layer "F.Fab")
		)
		(pad "1" smd custom
			(at 0 -0.762 270)
			(size 0.2159 0.2159)
			(layers "F.Cu" "F.Mask" "F.Paste")
			(net "P5V_HDD12")
			(options
				(clearance outline)
				(anchor circle)
			)
			(primitives
				(gr_poly
					(pts
						(arc
							(start -0.3302 -0.4318)
							(mid -0.402042 -0.402042)
							(end -0.4318 -0.3302)
						)
						(arc
							(start -0.4318 0.3302)
							(mid -0.402042 0.402042)
							(end -0.3302 0.4318)
						)
						(arc
							(start 0.3302 0.4318)
							(mid 0.402042 0.402042)
							(end 0.4318 0.3302)
						)
						(arc
							(start 0.4318 -0.3302)
							(mid 0.402042 -0.402042)
							(end 0.3302 -0.4318)
						)
					)
					(width 0)
					(fill yes)
				)
			)
		)
		(pad "2" smd custom
			(at 0 0.762 270)
			(size 0.2159 0.2159)
			(layers "F.Cu" "F.Mask" "F.Paste")
			(net "GND")
			(options
				(clearance outline)
				(anchor circle)
			)
			(primitives
				(gr_poly
					(pts
						(arc
							(start -0.3302 -0.4318)
							(mid -0.402042 -0.402042)
							(end -0.4318 -0.3302)
						)
						(arc
							(start -0.4318 0.3302)
							(mid -0.402042 0.402042)
							(end -0.3302 0.4318)
						)
						(arc
							(start 0.3302 0.4318)
							(mid 0.402042 0.402042)
							(end 0.4318 0.3302)
						)
						(arc
							(start 0.4318 -0.3302)
							(mid 0.402042 -0.402042)
							(end 0.3302 -0.4318)
						)
					)
					(width 0)
					(fill yes)
				)
			)
		)
	)
	(footprint ""
		(layer "F.Cu")
		(at 235.99267 -261.68604)
		(property "Reference" "R32"
			(at 0 0 0)
			(layer "F.SilkS")
			(hide yes)
			(effects
				(font
					(size 1.27 1.27)
				)
			)
		)
		(property "Value" "4K7R2F-GP"
			(at 0.064008 -3.993896 0)
			(unlocked yes)
			(layer "F.Fab")
			(hide yes)
			(effects
				(font
					(size 1.016 1.016)
					(thickness 0.1524)
				)
			)
		)
		(property "Device Type" "R402H16"
			(at 0.064008 -5.517896 0)
			(unlocked yes)
			(layer "F.Fab")
			(hide yes)
			(effects
				(font
					(size 1.016 1.016)
					(thickness 0.1524)
				)
			)
		)
		(duplicate_pad_numbers_are_jumpers no)
		(fp_line
			(start -0.508 -0.9398)
			(end -0.508 0.9398)
			(stroke
				(width 0.1524)
				(type default)
			)
			(layer "F.SilkS")
		)
		(fp_line
			(start 0.508 -0.9398)
			(end -0.508 -0.9398)
			(stroke
				(width 0.1524)
				(type default)
			)
			(layer "F.SilkS")
		)
		(fp_rect
			(start -0.508 0.9398)
			(end 0.508 -0.9398)
			(stroke
				(width 0)
				(type default)
			)
			(fill no)
			(layer "F.CrtYd")
		)
		(fp_rect
			(start -0.508 0.9398)
			(end 0.508 -0.9398)
			(stroke
				(width 0)
				(type default)
			)
			(fill no)
			(layer "F.Fab")
		)
		(pad "1" smd custom
			(at 0 -0.4445)
			(size 0.1397 0.1397)
			(layers "F.Cu" "F.Mask" "F.Paste")
			(net "P3V3_STBY_A")
			(options
				(clearance outline)
				(anchor circle)
			)
			(primitives
				(gr_poly
					(pts
						(arc
							(start -0.1778 -0.2794)
							(mid -0.249642 -0.249642)
							(end -0.2794 -0.1778)
						)
						(arc
							(start -0.2794 0.1778)
							(mid -0.249642 0.249642)
							(end -0.1778 0.2794)
						)
						(arc
							(start 0.1778 0.2794)
							(mid 0.249642 0.249642)
							(end 0.2794 0.1778)
						)
						(arc
							(start 0.2794 -0.1778)
							(mid 0.249642 -0.249642)
							(end 0.1778 -0.2794)
						)
					)
					(width 0)
					(fill yes)
				)
			)
		)
		(pad "2" smd custom
			(at 0 0.4445)
			(size 0.1397 0.1397)
			(layers "F.Cu" "F.Mask" "F.Paste")
			(net "IO_EXP4_A1")
			(options
				(clearance outline)
				(anchor circle)
			)
			(primitives
				(gr_poly
					(pts
						(arc
							(start -0.1778 -0.2794)
							(mid -0.249642 -0.249642)
							(end -0.2794 -0.1778)
						)
						(arc
							(start -0.2794 0.1778)
							(mid -0.249642 0.249642)
							(end -0.1778 0.2794)
						)
						(arc
							(start 0.1778 0.2794)
							(mid 0.249642 0.249642)
							(end 0.2794 0.1778)
						)
						(arc
							(start 0.2794 -0.1778)
							(mid 0.249642 -0.249642)
							(end 0.1778 -0.2794)
						)
					)
					(width 0)
					(fill yes)
				)
			)
		)
	)
	(footprint ""
		(layer "F.Cu")
		(at 237.115096 -234.9246 180)
		(property "Reference" "C21"
			(at 0 0 180)
			(layer "F.SilkS")
			(hide yes)
			(effects
				(font
					(size 1.27 1.27)
				)
			)
		)
		(property "Value" "SC1U16V3KX-5GP"
			(at 0 -2.8194 180)
			(unlocked yes)
			(layer "F.Fab")
			(hide yes)
			(effects
				(font
					(size 1.016 1.016)
					(thickness 0.1524)
				)
			)
		)
		(property "Device Type" "C603H36"
			(at 0 -4.3434 180)
			(unlocked yes)
			(layer "F.Fab")
			(hide yes)
			(effects
				(font
					(size 1.016 1.016)
					(thickness 0.1524)
				)
			)
		)
		(duplicate_pad_numbers_are_jumpers no)
		(fp_line
			(start 0.508 0)
			(end -0.508 0)
			(stroke
				(width 0.2032)
				(type default)
			)
			(layer "F.SilkS")
		)
		(fp_rect
			(start -0.5842 1.3335)
			(end 0.5842 -1.3335)
			(stroke
				(width 0)
				(type default)
			)
			(fill no)
			(layer "F.CrtYd")
		)
		(fp_rect
			(start -0.5842 1.3335)
			(end 0.5842 -1.3335)
			(stroke
				(width 0)
				(type default)
			)
			(fill no)
			(layer "F.Fab")
		)
		(pad "1" smd custom
			(at 0 -0.762 180)
			(size 0.2159 0.2159)
			(layers "F.Cu" "F.Mask" "F.Paste")
			(net "GPIO_VCC_U7")
			(options
				(clearance outline)
				(anchor circle)
			)
			(primitives
				(gr_poly
					(pts
						(arc
							(start -0.3302 -0.4318)
							(mid -0.402042 -0.402042)
							(end -0.4318 -0.3302)
						)
						(arc
							(start -0.4318 0.3302)
							(mid -0.402042 0.402042)
							(end -0.3302 0.4318)
						)
						(arc
							(start 0.3302 0.4318)
							(mid 0.402042 0.402042)
							(end 0.4318 0.3302)
						)
						(arc
							(start 0.4318 -0.3302)
							(mid 0.402042 -0.402042)
							(end 0.3302 -0.4318)
						)
					)
					(width 0)
					(fill yes)
				)
			)
		)
		(pad "2" smd custom
			(at 0 0.762 180)
			(size 0.2159 0.2159)
			(layers "F.Cu" "F.Mask" "F.Paste")
			(net "GND")
			(options
				(clearance outline)
				(anchor circle)
			)
			(primitives
				(gr_poly
					(pts
						(arc
							(start -0.3302 -0.4318)
							(mid -0.402042 -0.402042)
							(end -0.4318 -0.3302)
						)
						(arc
							(start -0.4318 0.3302)
							(mid -0.402042 0.402042)
							(end -0.3302 0.4318)
						)
						(arc
							(start 0.3302 0.4318)
							(mid 0.402042 0.402042)
							(end 0.4318 0.3302)
						)
						(arc
							(start 0.4318 -0.3302)
							(mid 0.402042 -0.402042)
							(end 0.3302 -0.4318)
						)
					)
					(width 0)
					(fill yes)
				)
			)
		)
	)
	(footprint ""
		(layer "F.Cu")
		(at 370.259102 -56.809894 -90)
		(property "Reference" "R857"
			(at 0 0 270)
			(layer "F.SilkS")
			(hide yes)
			(effects
				(font
					(size 1.27 1.27)
				)
			)
		)
		(property "Value" "300KR2F-GP"
			(at 0.064008 -3.993896 270)
			(unlocked yes)
			(layer "F.Fab")
			(hide yes)
			(effects
				(font
					(size 1.016 1.016)
					(thickness 0.1524)
				)
			)
		)
		(property "Device Type" "R402H16"
			(at 0.064008 -5.517896 270)
			(unlocked yes)
			(layer "F.Fab")
			(hide yes)
			(effects
				(font
					(size 1.016 1.016)
					(thickness 0.1524)
				)
			)
		)
		(duplicate_pad_numbers_are_jumpers no)
		(fp_line
			(start -0.508 -0.9398)
			(end -0.508 0.9398)
			(stroke
				(width 0.1524)
				(type default)
			)
			(layer "F.SilkS")
		)
		(fp_line
			(start 0.508 -0.9398)
			(end -0.508 -0.9398)
			(stroke
				(width 0.1524)
				(type default)
			)
			(layer "F.SilkS")
		)
		(fp_rect
			(start -0.508 0.9398)
			(end 0.508 -0.9398)
			(stroke
				(width 0)
				(type default)
			)
			(fill no)
			(layer "F.CrtYd")
		)
		(fp_rect
			(start -0.508 0.9398)
			(end 0.508 -0.9398)
			(stroke
				(width 0)
				(type default)
			)
			(fill no)
			(layer "F.Fab")
		)
		(pad "1" smd custom
			(at 0 -0.4445 270)
			(size 0.1397 0.1397)
			(layers "F.Cu" "F.Mask" "F.Paste")
			(net "SW_HDD_N31")
			(options
				(clearance outline)
				(anchor circle)
			)
			(primitives
				(gr_poly
					(pts
						(arc
							(start -0.1778 -0.2794)
							(mid -0.249642 -0.249642)
							(end -0.2794 -0.1778)
						)
						(arc
							(start -0.2794 0.1778)
							(mid -0.249642 0.249642)
							(end -0.1778 0.2794)
						)
						(arc
							(start 0.1778 0.2794)
							(mid 0.249642 0.249642)
							(end 0.2794 0.1778)
						)
						(arc
							(start 0.2794 -0.1778)
							(mid 0.249642 -0.249642)
							(end 0.1778 -0.2794)
						)
					)
					(width 0)
					(fill yes)
				)
			)
		)
		(pad "2" smd custom
			(at 0 0.4445 270)
			(size 0.1397 0.1397)
			(layers "F.Cu" "F.Mask" "F.Paste")
			(net "P12V_A")
			(options
				(clearance outline)
				(anchor circle)
			)
			(primitives
				(gr_poly
					(pts
						(arc
							(start -0.1778 -0.2794)
							(mid -0.249642 -0.249642)
							(end -0.2794 -0.1778)
						)
						(arc
							(start -0.2794 0.1778)
							(mid -0.249642 0.249642)
							(end -0.1778 0.2794)
						)
						(arc
							(start 0.1778 0.2794)
							(mid 0.249642 0.249642)
							(end 0.2794 0.1778)
						)
						(arc
							(start 0.2794 -0.1778)
							(mid 0.249642 -0.249642)
							(end 0.1778 -0.2794)
						)
					)
					(width 0)
					(fill yes)
				)
			)
		)
	)
	(footprint ""
		(layer "F.Cu")
		(at 395.20495 -160.252918 -90)
		(property "Reference" "Q121"
			(at 0 0 270)
			(layer "F.SilkS")
			(hide yes)
			(effects
				(font
					(size 1.27 1.27)
				)
			)
		)
		(property "Value" "2N7002KDW-GP"
			(at -2.3622 -8.2042 270)
			(unlocked yes)
			(layer "F.Fab")
			(hide yes)
			(effects
				(font
					(size 1.016 1.016)
					(thickness 0.1524)
				)
			)
		)
		(property "Device Type" "SOT-363H44"
			(at -2.3622 -10.1092 270)
			(unlocked yes)
			(layer "F.Fab")
			(hide yes)
			(effects
				(font
					(size 1.016 1.016)
					(thickness 0.1524)
				)
			)
		)
		(duplicate_pad_numbers_are_jumpers no)
		(fp_line
			(start -1.4478 1.7018)
			(end 1.4478 1.7018)
			(stroke
				(width 0.1524)
				(type default)
			)
			(layer "F.SilkS")
		)
		(fp_line
			(start 1.4478 1.7018)
			(end 1.4478 -1.7018)
			(stroke
				(width 0.1524)
				(type default)
			)
			(layer "F.SilkS")
		)
		(fp_line
			(start -1.27 1.524)
			(end -1.27 0.6604)
			(stroke
				(width 0.4826)
				(type default)
			)
			(layer "F.SilkS")
		)
		(fp_line
			(start -1.4478 -1.7018)
			(end -1.4478 1.7018)
			(stroke
				(width 0.1524)
				(type default)
			)
			(layer "F.SilkS")
		)
		(fp_line
			(start 1.4478 -1.7018)
			(end -1.4478 -1.7018)
			(stroke
				(width 0.1524)
				(type default)
			)
			(layer "F.SilkS")
		)
		(fp_poly
			(pts
				(xy -1.524 -1.778) (xy 1.524 -1.778) (xy 1.524 1.778) (xy -1.524 1.778)
			)
			(stroke
				(width 0)
				(type default)
			)
			(fill no)
			(layer "F.CrtYd")
		)
		(fp_poly
			(pts
				(xy -1.524 -1.778) (xy 1.524 -1.778) (xy 1.524 1.778) (xy -1.524 1.778)
			)
			(stroke
				(width 0)
				(type default)
			)
			(fill no)
			(layer "F.Fab")
		)
		(pad "1" smd rect
			(at -0.65024 0.9398 270)
			(size 0.4064 1.016)
			(layers "F.Cu" "F.Mask" "F.Paste")
			(net "GND")
		)
		(pad "2" smd rect
			(at 0 0.9398 270)
			(size 0.4064 1.016)
			(layers "F.Cu" "F.Mask" "F.Paste")
			(net "SW_PWR_R_HDD20")
		)
		(pad "3" smd rect
			(at 0.65024 0.9398 270)
			(size 0.4064 1.016)
			(layers "F.Cu" "F.Mask" "F.Paste")
			(net "SW_HDD_P20")
		)
		(pad "4" smd rect
			(at 0.65024 -0.9398 270)
			(size 0.4064 1.016)
			(layers "F.Cu" "F.Mask" "F.Paste")
			(net "GND")
		)
		(pad "5" smd rect
			(at 0 -0.9398 270)
			(size 0.4064 1.016)
			(layers "F.Cu" "F.Mask" "F.Paste")
			(net "SW_HDD_G20")
		)
		(pad "6" smd rect
			(at -0.65024 -0.9398 270)
			(size 0.4064 1.016)
			(layers "F.Cu" "F.Mask" "F.Paste")
			(net "SW_HDD_R20")
		)
	)
	(footprint ""
		(layer "F.Cu")
		(at 129.058162 -304.331878 180)
		(property "Reference" "R254"
			(at 0 0 180)
			(layer "F.SilkS")
			(hide yes)
			(effects
				(font
					(size 1.27 1.27)
				)
			)
		)
		(property "Value" "91R3F-1-GP"
			(at -0.0254 -2.5146 180)
			(unlocked yes)
			(layer "F.Fab")
			(hide yes)
			(effects
				(font
					(size 1.016 1.016)
					(thickness 0.1524)
				)
			)
		)
		(property "Device Type" "R603H22"
			(at -0.0254 -4.0386 180)
			(unlocked yes)
			(layer "F.Fab")
			(hide yes)
			(effects
				(font
					(size 1.016 1.016)
					(thickness 0.1524)
				)
			)
		)
		(duplicate_pad_numbers_are_jumpers no)
		(fp_line
			(start 0.2032 0)
			(end 0.4826 0)
			(stroke
				(width 0.2032)
				(type default)
			)
			(layer "F.SilkS")
		)
		(fp_line
			(start -0.4826 0)
			(end -0.2032 0)
			(stroke
				(width 0.2032)
				(type default)
			)
			(layer "F.SilkS")
		)
		(fp_rect
			(start -0.5842 1.3335)
			(end 0.5842 -1.3335)
			(stroke
				(width 0)
				(type default)
			)
			(fill no)
			(layer "F.CrtYd")
		)
		(fp_rect
			(start -0.5842 1.3335)
			(end 0.5842 -1.3335)
			(stroke
				(width 0)
				(type default)
			)
			(fill no)
			(layer "F.Fab")
		)
		(pad "1" smd custom
			(at 0 -0.762 180)
			(size 0.2159 0.2159)
			(layers "F.Cu" "F.Mask" "F.Paste")
			(net "P5V_B")
			(options
				(clearance outline)
				(anchor circle)
			)
			(primitives
				(gr_poly
					(pts
						(arc
							(start -0.3302 -0.4318)
							(mid -0.402042 -0.402042)
							(end -0.4318 -0.3302)
						)
						(arc
							(start -0.4318 0.3302)
							(mid -0.402042 0.402042)
							(end -0.3302 0.4318)
						)
						(arc
							(start 0.3302 0.4318)
							(mid 0.402042 0.402042)
							(end 0.4318 0.3302)
						)
						(arc
							(start 0.4318 -0.3302)
							(mid 0.402042 -0.402042)
							(end 0.3302 -0.4318)
						)
					)
					(width 0)
					(fill yes)
				)
			)
		)
		(pad "2" smd custom
			(at 0 0.762 180)
			(size 0.2159 0.2159)
			(layers "F.Cu" "F.Mask" "F.Paste")
			(net "DRV_ACT_28")
			(options
				(clearance outline)
				(anchor circle)
			)
			(primitives
				(gr_poly
					(pts
						(arc
							(start -0.3302 -0.4318)
							(mid -0.402042 -0.402042)
							(end -0.4318 -0.3302)
						)
						(arc
							(start -0.4318 0.3302)
							(mid -0.402042 0.402042)
							(end -0.3302 0.4318)
						)
						(arc
							(start 0.3302 0.4318)
							(mid 0.402042 0.402042)
							(end 0.4318 0.3302)
						)
						(arc
							(start 0.4318 -0.3302)
							(mid 0.402042 -0.402042)
							(end 0.3302 -0.4318)
						)
					)
					(width 0)
					(fill yes)
				)
			)
		)
	)
	(footprint ""
		(layer "F.Cu")
		(at 178.181 -62.778894 -90)
		(property "Reference" "C417"
			(at 0 0 270)
			(layer "F.SilkS")
			(hide yes)
			(effects
				(font
					(size 1.27 1.27)
				)
			)
		)
		(property "Value" "SC1U16V3KX-5GP"
			(at 0 -2.8194 270)
			(unlocked yes)
			(layer "F.Fab")
			(hide yes)
			(effects
				(font
					(size 1.016 1.016)
					(thickness 0.1524)
				)
			)
		)
		(property "Device Type" "C603H36"
			(at 0 -4.3434 270)
			(unlocked yes)
			(layer "F.Fab")
			(hide yes)
			(effects
				(font
					(size 1.016 1.016)
					(thickness 0.1524)
				)
			)
		)
		(duplicate_pad_numbers_are_jumpers no)
		(fp_line
			(start 0.508 0)
			(end -0.508 0)
			(stroke
				(width 0.2032)
				(type default)
			)
			(layer "F.SilkS")
		)
		(fp_rect
			(start -0.5842 1.3335)
			(end 0.5842 -1.3335)
			(stroke
				(width 0)
				(type default)
			)
			(fill no)
			(layer "F.CrtYd")
		)
		(fp_rect
			(start -0.5842 1.3335)
			(end 0.5842 -1.3335)
			(stroke
				(width 0)
				(type default)
			)
			(fill no)
			(layer "F.Fab")
		)
		(pad "1" smd custom
			(at 0 -0.762 270)
			(size 0.2159 0.2159)
			(layers "F.Cu" "F.Mask" "F.Paste")
			(net "P5V_HDD29")
			(options
				(clearance outline)
				(anchor circle)
			)
			(primitives
				(gr_poly
					(pts
						(arc
							(start -0.3302 -0.4318)
							(mid -0.402042 -0.402042)
							(end -0.4318 -0.3302)
						)
						(arc
							(start -0.4318 0.3302)
							(mid -0.402042 0.402042)
							(end -0.3302 0.4318)
						)
						(arc
							(start 0.3302 0.4318)
							(mid 0.402042 0.402042)
							(end 0.4318 0.3302)
						)
						(arc
							(start 0.4318 -0.3302)
							(mid 0.402042 -0.402042)
							(end 0.3302 -0.4318)
						)
					)
					(width 0)
					(fill yes)
				)
			)
		)
		(pad "2" smd custom
			(at 0 0.762 270)
			(size 0.2159 0.2159)
			(layers "F.Cu" "F.Mask" "F.Paste")
			(net "GND")
			(options
				(clearance outline)
				(anchor circle)
			)
			(primitives
				(gr_poly
					(pts
						(arc
							(start -0.3302 -0.4318)
							(mid -0.402042 -0.402042)
							(end -0.4318 -0.3302)
						)
						(arc
							(start -0.4318 0.3302)
							(mid -0.402042 0.402042)
							(end -0.3302 0.4318)
						)
						(arc
							(start 0.3302 0.4318)
							(mid 0.402042 0.402042)
							(end 0.4318 0.3302)
						)
						(arc
							(start 0.4318 -0.3302)
							(mid 0.402042 -0.402042)
							(end 0.3302 -0.4318)
						)
					)
					(width 0)
					(fill yes)
				)
			)
		)
	)
	(footprint ""
		(layer "F.Cu")
		(at 258.318 -279.908)
		(property "Reference" "C34"
			(at 0 0 0)
			(layer "F.SilkS")
			(hide yes)
			(effects
				(font
					(size 1.27 1.27)
				)
			)
		)
		(property "Value" "SC1U16V3KX-5GP"
			(at 0 -2.8194 0)
			(unlocked yes)
			(layer "F.Fab")
			(hide yes)
			(effects
				(font
					(size 1.016 1.016)
					(thickness 0.1524)
				)
			)
		)
		(property "Device Type" "C603H36"
			(at 0 -4.3434 0)
			(unlocked yes)
			(layer "F.Fab")
			(hide yes)
			(effects
				(font
					(size 1.016 1.016)
					(thickness 0.1524)
				)
			)
		)
		(duplicate_pad_numbers_are_jumpers no)
		(fp_line
			(start 0.508 0)
			(end -0.508 0)
			(stroke
				(width 0.2032)
				(type default)
			)
			(layer "F.SilkS")
		)
		(fp_rect
			(start -0.5842 1.3335)
			(end 0.5842 -1.3335)
			(stroke
				(width 0)
				(type default)
			)
			(fill no)
			(layer "F.CrtYd")
		)
		(fp_rect
			(start -0.5842 1.3335)
			(end 0.5842 -1.3335)
			(stroke
				(width 0)
				(type default)
			)
			(fill no)
			(layer "F.Fab")
		)
		(pad "1" smd custom
			(at 0 -0.762)
			(size 0.2159 0.2159)
			(layers "F.Cu" "F.Mask" "F.Paste")
			(net "P3V3_STBY_A")
			(options
				(clearance outline)
				(anchor circle)
			)
			(primitives
				(gr_poly
					(pts
						(arc
							(start -0.3302 -0.4318)
							(mid -0.402042 -0.402042)
							(end -0.4318 -0.3302)
						)
						(arc
							(start -0.4318 0.3302)
							(mid -0.402042 0.402042)
							(end -0.3302 0.4318)
						)
						(arc
							(start 0.3302 0.4318)
							(mid 0.402042 0.402042)
							(end 0.4318 0.3302)
						)
						(arc
							(start 0.4318 -0.3302)
							(mid 0.402042 -0.402042)
							(end 0.3302 -0.4318)
						)
					)
					(width 0)
					(fill yes)
				)
			)
		)
		(pad "2" smd custom
			(at 0 0.762)
			(size 0.2159 0.2159)
			(layers "F.Cu" "F.Mask" "F.Paste")
			(net "GND")
			(options
				(clearance outline)
				(anchor circle)
			)
			(primitives
				(gr_poly
					(pts
						(arc
							(start -0.3302 -0.4318)
							(mid -0.402042 -0.402042)
							(end -0.4318 -0.3302)
						)
						(arc
							(start -0.4318 0.3302)
							(mid -0.402042 0.402042)
							(end -0.3302 0.4318)
						)
						(arc
							(start 0.3302 0.4318)
							(mid 0.402042 0.402042)
							(end 0.4318 0.3302)
						)
						(arc
							(start 0.4318 -0.3302)
							(mid 0.402042 -0.402042)
							(end 0.3302 -0.4318)
						)
					)
					(width 0)
					(fill yes)
				)
			)
		)
	)
	(footprint ""
		(layer "F.Cu")
		(at 395.83995 -48.554894 -90)
		(property "Reference" "R873"
			(at 0 0 270)
			(layer "F.SilkS")
			(hide yes)
			(effects
				(font
					(size 1.27 1.27)
				)
			)
		)
		(property "Value" "4K7R2J-2-GP"
			(at 0.064008 -3.993896 270)
			(unlocked yes)
			(layer "F.Fab")
			(hide yes)
			(effects
				(font
					(size 1.016 1.016)
					(thickness 0.1524)
				)
			)
		)
		(property "Device Type" "R402H16"
			(at 0.064008 -5.517896 270)
			(unlocked yes)
			(layer "F.Fab")
			(hide yes)
			(effects
				(font
					(size 1.016 1.016)
					(thickness 0.1524)
				)
			)
		)
		(duplicate_pad_numbers_are_jumpers no)
		(fp_line
			(start -0.508 -0.9398)
			(end -0.508 0.9398)
			(stroke
				(width 0.1524)
				(type default)
			)
			(layer "F.SilkS")
		)
		(fp_line
			(start 0.508 -0.9398)
			(end -0.508 -0.9398)
			(stroke
				(width 0.1524)
				(type default)
			)
			(layer "F.SilkS")
		)
		(fp_rect
			(start -0.508 0.9398)
			(end 0.508 -0.9398)
			(stroke
				(width 0)
				(type default)
			)
			(fill no)
			(layer "F.CrtYd")
		)
		(fp_rect
			(start -0.508 0.9398)
			(end 0.508 -0.9398)
			(stroke
				(width 0)
				(type default)
			)
			(fill no)
			(layer "F.Fab")
		)
		(pad "1" smd custom
			(at 0 -0.4445 270)
			(size 0.1397 0.1397)
			(layers "F.Cu" "F.Mask" "F.Paste")
			(net "P12V_A")
			(options
				(clearance outline)
				(anchor circle)
			)
			(primitives
				(gr_poly
					(pts
						(arc
							(start -0.1778 -0.2794)
							(mid -0.249642 -0.249642)
							(end -0.2794 -0.1778)
						)
						(arc
							(start -0.2794 0.1778)
							(mid -0.249642 0.249642)
							(end -0.1778 0.2794)
						)
						(arc
							(start 0.1778 0.2794)
							(mid 0.249642 0.249642)
							(end 0.2794 0.1778)
						)
						(arc
							(start 0.2794 -0.1778)
							(mid 0.249642 -0.249642)
							(end 0.1778 -0.2794)
						)
					)
					(width 0)
					(fill yes)
				)
			)
		)
		(pad "2" smd custom
			(at 0 0.4445 270)
			(size 0.1397 0.1397)
			(layers "F.Cu" "F.Mask" "F.Paste")
			(net "SW_HDD_P32")
			(options
				(clearance outline)
				(anchor circle)
			)
			(primitives
				(gr_poly
					(pts
						(arc
							(start -0.1778 -0.2794)
							(mid -0.249642 -0.249642)
							(end -0.2794 -0.1778)
						)
						(arc
							(start -0.2794 0.1778)
							(mid -0.249642 0.249642)
							(end -0.1778 0.2794)
						)
						(arc
							(start 0.1778 0.2794)
							(mid 0.249642 0.249642)
							(end 0.2794 0.1778)
						)
						(arc
							(start 0.2794 -0.1778)
							(mid 0.249642 -0.249642)
							(end 0.1778 -0.2794)
						)
					)
					(width 0)
					(fill yes)
				)
			)
		)
	)
	(footprint ""
		(layer "F.Cu")
		(at 482.489002 -277.750016 -90)
		(property "Reference" "VIA20"
			(at 0 0 270)
			(layer "F.SilkS")
			(hide yes)
			(effects
				(font
					(size 1.27 1.27)
				)
			)
		)
		(property "Value" "100OHM-8L-1D6MM-L18L16-GP"
			(at -3.7211 -4.5085 270)
			(unlocked yes)
			(layer "F.Fab")
			(hide yes)
			(effects
				(font
					(size 1.016 1.016)
					(thickness 0.1524)
				)
			)
		)
		(property "Device Type" "VIA-PCIE-4P-394076"
			(at -3.7211 -6.0325 270)
			(unlocked yes)
			(layer "F.Fab")
			(hide yes)
			(effects
				(font
					(size 1.016 1.016)
					(thickness 0.1524)
				)
			)
		)
		(duplicate_pad_numbers_are_jumpers no)
		(fp_rect
			(start -1.9685 0.381)
			(end 1.9685 -0.381)
			(stroke
				(width 0)
				(type default)
			)
			(fill no)
			(layer "F.CrtYd")
		)
		(fp_rect
			(start -1.9685 0.381)
			(end 1.9685 -0.381)
			(stroke
				(width 0)
				(type default)
			)
			(fill no)
			(layer "F.Fab")
		)
		(pad "1" thru_hole circle
			(at -1.5875 0 270)
			(size 0.508 0.508)
			(drill 0.254)
			(layers "*.Cu" "*.Mask")
			(remove_unused_layers no)
			(net "GND")
			(clearance 0.127)
			(thermal_gap 0.127)
		)
		(pad "2" thru_hole circle
			(at -0.5715 0 270)
			(size 0.508 0.508)
			(drill 0.254)
			(layers "*.Cu" "*.Mask")
			(remove_unused_layers no)
			(net "PHY_DRV_A_TO_SCC_A_11_DP")
			(clearance 0.127)
			(thermal_gap 0.127)
		)
		(pad "3" thru_hole circle
			(at 0.5715 0 270)
			(size 0.508 0.508)
			(drill 0.254)
			(layers "*.Cu" "*.Mask")
			(remove_unused_layers no)
			(net "PHY_DRV_A_TO_SCC_A_11_DN")
			(clearance 0.127)
			(thermal_gap 0.127)
		)
		(pad "4" thru_hole circle
			(at 1.5875 0 270)
			(size 0.508 0.508)
			(drill 0.254)
			(layers "*.Cu" "*.Mask")
			(remove_unused_layers no)
			(net "GND")
			(clearance 0.127)
			(thermal_gap 0.127)
		)
	)
	(footprint ""
		(layer "F.Cu")
		(at 475.906592 -287.818322 -90)
		(property "Reference" "C183"
			(at 0 0 270)
			(layer "F.SilkS")
			(hide yes)
			(effects
				(font
					(size 1.27 1.27)
				)
			)
		)
		(property "Value" "SC1U16V3KX-5GP"
			(at 0 -2.8194 270)
			(unlocked yes)
			(layer "F.Fab")
			(hide yes)
			(effects
				(font
					(size 1.016 1.016)
					(thickness 0.1524)
				)
			)
		)
		(property "Device Type" "C603H36"
			(at 0 -4.3434 270)
			(unlocked yes)
			(layer "F.Fab")
			(hide yes)
			(effects
				(font
					(size 1.016 1.016)
					(thickness 0.1524)
				)
			)
		)
		(duplicate_pad_numbers_are_jumpers no)
		(fp_line
			(start 0.508 0)
			(end -0.508 0)
			(stroke
				(width 0.2032)
				(type default)
			)
			(layer "F.SilkS")
		)
		(fp_rect
			(start -0.5842 1.3335)
			(end 0.5842 -1.3335)
			(stroke
				(width 0)
				(type default)
			)
			(fill no)
			(layer "F.CrtYd")
		)
		(fp_rect
			(start -0.5842 1.3335)
			(end 0.5842 -1.3335)
			(stroke
				(width 0)
				(type default)
			)
			(fill no)
			(layer "F.Fab")
		)
		(pad "1" smd custom
			(at 0 -0.762 270)
			(size 0.2159 0.2159)
			(layers "F.Cu" "F.Mask" "F.Paste")
			(net "P5V_HDD11")
			(options
				(clearance outline)
				(anchor circle)
			)
			(primitives
				(gr_poly
					(pts
						(arc
							(start -0.3302 -0.4318)
							(mid -0.402042 -0.402042)
							(end -0.4318 -0.3302)
						)
						(arc
							(start -0.4318 0.3302)
							(mid -0.402042 0.402042)
							(end -0.3302 0.4318)
						)
						(arc
							(start 0.3302 0.4318)
							(mid 0.402042 0.402042)
							(end 0.4318 0.3302)
						)
						(arc
							(start 0.4318 -0.3302)
							(mid 0.402042 -0.402042)
							(end 0.3302 -0.4318)
						)
					)
					(width 0)
					(fill yes)
				)
			)
		)
		(pad "2" smd custom
			(at 0 0.762 270)
			(size 0.2159 0.2159)
			(layers "F.Cu" "F.Mask" "F.Paste")
			(net "GND")
			(options
				(clearance outline)
				(anchor circle)
			)
			(primitives
				(gr_poly
					(pts
						(arc
							(start -0.3302 -0.4318)
							(mid -0.402042 -0.402042)
							(end -0.4318 -0.3302)
						)
						(arc
							(start -0.4318 0.3302)
							(mid -0.402042 0.402042)
							(end -0.3302 0.4318)
						)
						(arc
							(start 0.3302 0.4318)
							(mid 0.402042 0.402042)
							(end 0.4318 0.3302)
						)
						(arc
							(start 0.4318 -0.3302)
							(mid 0.402042 -0.402042)
							(end 0.3302 -0.4318)
						)
					)
					(width 0)
					(fill yes)
				)
			)
		)
	)
	(footprint ""
		(layer "F.Cu")
		(at 43.323002 -150.12035 -90)
		(property "Reference" "R1237"
			(at 0 0 270)
			(layer "F.SilkS")
			(hide yes)
			(effects
				(font
					(size 1.27 1.27)
				)
			)
		)
		(property "Value" "143KR2F-L-1-GP"
			(at 0.064008 -3.993896 270)
			(unlocked yes)
			(layer "F.Fab")
			(hide yes)
			(effects
				(font
					(size 1.016 1.016)
					(thickness 0.1524)
				)
			)
		)
		(property "Device Type" "R402H16"
			(at 0.064008 -5.517896 270)
			(unlocked yes)
			(layer "F.Fab")
			(hide yes)
			(effects
				(font
					(size 1.016 1.016)
					(thickness 0.1524)
				)
			)
		)
		(duplicate_pad_numbers_are_jumpers no)
		(fp_line
			(start -0.508 -0.9398)
			(end -0.508 0.9398)
			(stroke
				(width 0.1524)
				(type default)
			)
			(layer "F.SilkS")
		)
		(fp_line
			(start 0.508 -0.9398)
			(end -0.508 -0.9398)
			(stroke
				(width 0.1524)
				(type default)
			)
			(layer "F.SilkS")
		)
		(fp_rect
			(start -0.508 0.9398)
			(end 0.508 -0.9398)
			(stroke
				(width 0)
				(type default)
			)
			(fill no)
			(layer "F.CrtYd")
		)
		(fp_rect
			(start -0.508 0.9398)
			(end 0.508 -0.9398)
			(stroke
				(width 0)
				(type default)
			)
			(fill no)
			(layer "F.Fab")
		)
		(pad "1" smd custom
			(at 0 -0.4445 270)
			(size 0.1397 0.1397)
			(layers "F.Cu" "F.Mask" "F.Paste")
			(net "AGND_P5V_B")
			(options
				(clearance outline)
				(anchor circle)
			)
			(primitives
				(gr_poly
					(pts
						(arc
							(start -0.1778 -0.2794)
							(mid -0.249642 -0.249642)
							(end -0.2794 -0.1778)
						)
						(arc
							(start -0.2794 0.1778)
							(mid -0.249642 0.249642)
							(end -0.1778 0.2794)
						)
						(arc
							(start 0.1778 0.2794)
							(mid 0.249642 0.249642)
							(end 0.2794 0.1778)
						)
						(arc
							(start 0.2794 -0.1778)
							(mid 0.249642 -0.249642)
							(end 0.1778 -0.2794)
						)
					)
					(width 0)
					(fill yes)
				)
			)
		)
		(pad "2" smd custom
			(at 0 0.4445 270)
			(size 0.1397 0.1397)
			(layers "F.Cu" "F.Mask" "F.Paste")
			(net "P5V_B_TRIP")
			(options
				(clearance outline)
				(anchor circle)
			)
			(primitives
				(gr_poly
					(pts
						(arc
							(start -0.1778 -0.2794)
							(mid -0.249642 -0.249642)
							(end -0.2794 -0.1778)
						)
						(arc
							(start -0.2794 0.1778)
							(mid -0.249642 0.249642)
							(end -0.1778 0.2794)
						)
						(arc
							(start 0.1778 0.2794)
							(mid 0.249642 0.249642)
							(end 0.2794 0.1778)
						)
						(arc
							(start 0.2794 -0.1778)
							(mid 0.249642 -0.249642)
							(end 0.1778 -0.2794)
						)
					)
					(width 0)
					(fill yes)
				)
			)
		)
	)
	(footprint ""
		(layer "F.Cu")
		(at 351.336102 -42.627042 180)
		(property "Reference" "VIA71"
			(at 0 0 180)
			(layer "F.SilkS")
			(hide yes)
			(effects
				(font
					(size 1.27 1.27)
				)
			)
		)
		(property "Value" "100OHM-8L-1D6MM-L18L16-GP"
			(at -3.7211 -4.5085 180)
			(unlocked yes)
			(layer "F.Fab")
			(hide yes)
			(effects
				(font
					(size 1.016 1.016)
					(thickness 0.1524)
				)
			)
		)
		(property "Device Type" "VIA-PCIE-4P-394076"
			(at -3.7211 -6.0325 180)
			(unlocked yes)
			(layer "F.Fab")
			(hide yes)
			(effects
				(font
					(size 1.016 1.016)
					(thickness 0.1524)
				)
			)
		)
		(duplicate_pad_numbers_are_jumpers no)
		(fp_rect
			(start -1.9685 0.381)
			(end 1.9685 -0.381)
			(stroke
				(width 0)
				(type default)
			)
			(fill no)
			(layer "F.CrtYd")
		)
		(fp_rect
			(start -1.9685 0.381)
			(end 1.9685 -0.381)
			(stroke
				(width 0)
				(type default)
			)
			(fill no)
			(layer "F.Fab")
		)
		(pad "1" thru_hole circle
			(at -1.5875 0 180)
			(size 0.508 0.508)
			(drill 0.254)
			(layers "*.Cu" "*.Mask")
			(remove_unused_layers no)
			(net "GND")
			(clearance 0.127)
			(thermal_gap 0.127)
		)
		(pad "2" thru_hole circle
			(at -0.5715 0 180)
			(size 0.508 0.508)
			(drill 0.254)
			(layers "*.Cu" "*.Mask")
			(remove_unused_layers no)
			(net "PHY_SCC_A_TO_DRV_A_31_DP")
			(clearance 0.127)
			(thermal_gap 0.127)
		)
		(pad "3" thru_hole circle
			(at 0.5715 0 180)
			(size 0.508 0.508)
			(drill 0.254)
			(layers "*.Cu" "*.Mask")
			(remove_unused_layers no)
			(net "PHY_SCC_A_TO_DRV_A_31_DN")
			(clearance 0.127)
			(thermal_gap 0.127)
		)
		(pad "4" thru_hole circle
			(at 1.5875 0 180)
			(size 0.508 0.508)
			(drill 0.254)
			(layers "*.Cu" "*.Mask")
			(remove_unused_layers no)
			(net "GND")
			(clearance 0.127)
			(thermal_gap 0.127)
		)
	)
	(footprint ""
		(layer "F.Cu")
		(at 324.739 -277.750016 -90)
		(property "Reference" "VIA17"
			(at 0 0 270)
			(layer "F.SilkS")
			(hide yes)
			(effects
				(font
					(size 1.27 1.27)
				)
			)
		)
		(property "Value" "100OHM-8L-1D6MM-L18L16-GP"
			(at -3.7211 -4.5085 270)
			(unlocked yes)
			(layer "F.Fab")
			(hide yes)
			(effects
				(font
					(size 1.016 1.016)
					(thickness 0.1524)
				)
			)
		)
		(property "Device Type" "VIA-PCIE-4P-394076"
			(at -3.7211 -6.0325 270)
			(unlocked yes)
			(layer "F.Fab")
			(hide yes)
			(effects
				(font
					(size 1.016 1.016)
					(thickness 0.1524)
				)
			)
		)
		(duplicate_pad_numbers_are_jumpers no)
		(fp_rect
			(start -1.9685 0.381)
			(end 1.9685 -0.381)
			(stroke
				(width 0)
				(type default)
			)
			(fill no)
			(layer "F.CrtYd")
		)
		(fp_rect
			(start -1.9685 0.381)
			(end 1.9685 -0.381)
			(stroke
				(width 0)
				(type default)
			)
			(fill no)
			(layer "F.Fab")
		)
		(pad "1" thru_hole circle
			(at -1.5875 0 270)
			(size 0.508 0.508)
			(drill 0.254)
			(layers "*.Cu" "*.Mask")
			(remove_unused_layers no)
			(net "GND")
			(clearance 0.127)
			(thermal_gap 0.127)
		)
		(pad "2" thru_hole circle
			(at -0.5715 0 270)
			(size 0.508 0.508)
			(drill 0.254)
			(layers "*.Cu" "*.Mask")
			(remove_unused_layers no)
			(net "PHY_DRV_A_TO_SCC_A_6_DP")
			(clearance 0.127)
			(thermal_gap 0.127)
		)
		(pad "3" thru_hole circle
			(at 0.5715 0 270)
			(size 0.508 0.508)
			(drill 0.254)
			(layers "*.Cu" "*.Mask")
			(remove_unused_layers no)
			(net "PHY_DRV_A_TO_SCC_A_6_DN")
			(clearance 0.127)
			(thermal_gap 0.127)
		)
		(pad "4" thru_hole circle
			(at 1.5875 0 270)
			(size 0.508 0.508)
			(drill 0.254)
			(layers "*.Cu" "*.Mask")
			(remove_unused_layers no)
			(net "GND")
			(clearance 0.127)
			(thermal_gap 0.127)
		)
	)
	(footprint ""
		(layer "F.Cu")
		(at 6.35 -304.292 180)
		(property "Reference" "R208"
			(at 0 0 180)
			(layer "F.SilkS")
			(hide yes)
			(effects
				(font
					(size 1.27 1.27)
				)
			)
		)
		(property "Value" "91R3F-1-GP"
			(at -0.0254 -2.5146 180)
			(unlocked yes)
			(layer "F.Fab")
			(hide yes)
			(effects
				(font
					(size 1.016 1.016)
					(thickness 0.1524)
				)
			)
		)
		(property "Device Type" "R603H22"
			(at -0.0254 -4.0386 180)
			(unlocked yes)
			(layer "F.Fab")
			(hide yes)
			(effects
				(font
					(size 1.016 1.016)
					(thickness 0.1524)
				)
			)
		)
		(duplicate_pad_numbers_are_jumpers no)
		(fp_line
			(start 0.2032 0)
			(end 0.4826 0)
			(stroke
				(width 0.2032)
				(type default)
			)
			(layer "F.SilkS")
		)
		(fp_line
			(start -0.4826 0)
			(end -0.2032 0)
			(stroke
				(width 0.2032)
				(type default)
			)
			(layer "F.SilkS")
		)
		(fp_rect
			(start -0.5842 1.3335)
			(end 0.5842 -1.3335)
			(stroke
				(width 0)
				(type default)
			)
			(fill no)
			(layer "F.CrtYd")
		)
		(fp_rect
			(start -0.5842 1.3335)
			(end 0.5842 -1.3335)
			(stroke
				(width 0)
				(type default)
			)
			(fill no)
			(layer "F.Fab")
		)
		(pad "1" smd custom
			(at 0 -0.762 180)
			(size 0.2159 0.2159)
			(layers "F.Cu" "F.Mask" "F.Paste")
			(net "P5V_B")
			(options
				(clearance outline)
				(anchor circle)
			)
			(primitives
				(gr_poly
					(pts
						(arc
							(start -0.3302 -0.4318)
							(mid -0.402042 -0.402042)
							(end -0.4318 -0.3302)
						)
						(arc
							(start -0.4318 0.3302)
							(mid -0.402042 0.402042)
							(end -0.3302 0.4318)
						)
						(arc
							(start 0.3302 0.4318)
							(mid 0.402042 0.402042)
							(end 0.4318 0.3302)
						)
						(arc
							(start 0.4318 -0.3302)
							(mid 0.402042 -0.402042)
							(end 0.3302 -0.4318)
						)
					)
					(width 0)
					(fill yes)
				)
			)
		)
		(pad "2" smd custom
			(at 0 0.762 180)
			(size 0.2159 0.2159)
			(layers "F.Cu" "F.Mask" "F.Paste")
			(net "DRV_ACT_24")
			(options
				(clearance outline)
				(anchor circle)
			)
			(primitives
				(gr_poly
					(pts
						(arc
							(start -0.3302 -0.4318)
							(mid -0.402042 -0.402042)
							(end -0.4318 -0.3302)
						)
						(arc
							(start -0.4318 0.3302)
							(mid -0.402042 0.402042)
							(end -0.3302 0.4318)
						)
						(arc
							(start 0.3302 0.4318)
							(mid 0.402042 0.402042)
							(end 0.4318 0.3302)
						)
						(arc
							(start 0.4318 -0.3302)
							(mid 0.402042 -0.402042)
							(end 0.3302 -0.4318)
						)
					)
					(width 0)
					(fill yes)
				)
			)
		)
	)
	(footprint ""
		(layer "F.Cu")
		(at 409.800044 -94.400116)
		(property "Reference" "FLED22"
			(at 0 0 0)
			(layer "F.SilkS")
			(hide yes)
			(effects
				(font
					(size 1.27 1.27)
				)
			)
		)
		(property "Value" "LED-BY-19-GP"
			(at -2.132076 1.414018 0)
			(unlocked yes)
			(layer "F.Fab")
			(hide yes)
			(effects
				(font
					(size 1.016 1.016)
					(thickness 0.1524)
				)
			)
		)
		(property "Device Type" "LED-1615-4PH26"
			(at -2.132076 -0.109982 0)
			(unlocked yes)
			(layer "F.Fab")
			(hide yes)
			(effects
				(font
					(size 1.016 1.016)
					(thickness 0.1524)
				)
			)
		)
		(duplicate_pad_numbers_are_jumpers no)
		(fp_line
			(start -1.2954 0.254)
			(end -1.2954 1.6002)
			(stroke
				(width 0.508)
				(type default)
			)
			(layer "F.SilkS")
		)
		(fp_line
			(start -1.2954 1.6002)
			(end 1.2954 1.6002)
			(stroke
				(width 0.508)
				(type default)
			)
			(layer "F.SilkS")
		)
		(fp_line
			(start -1.1176 -1.4224)
			(end 1.1176 -1.4224)
			(stroke
				(width 0.1524)
				(type default)
			)
			(layer "F.SilkS")
		)
		(fp_line
			(start -1.1176 1.4224)
			(end -1.1176 -1.4224)
			(stroke
				(width 0.1524)
				(type default)
			)
			(layer "F.SilkS")
		)
		(fp_line
			(start 1.1176 -1.4224)
			(end 1.1176 1.4224)
			(stroke
				(width 0.1524)
				(type default)
			)
			(layer "F.SilkS")
		)
		(fp_line
			(start 1.1176 1.4224)
			(end -1.1176 1.4224)
			(stroke
				(width 0.1524)
				(type default)
			)
			(layer "F.SilkS")
		)
		(fp_line
			(start 1.2954 1.6002)
			(end 1.2954 0.254)
			(stroke
				(width 0.508)
				(type default)
			)
			(layer "F.SilkS")
		)
		(fp_rect
			(start -0.7493 0.8001)
			(end 0.7493 -0.8001)
			(stroke
				(width 0)
				(type default)
			)
			(fill no)
			(layer "F.CrtYd")
		)
		(fp_poly
			(pts
				(xy -1.3716 1.6764) (xy -1.3716 -1.6764) (xy 1.3716 -1.6764) (xy 1.3716 0.0635) (xy 0.7493 0.0635)
				(xy 0.7493 -0.8001) (xy -0.7493 -0.8001) (xy -0.7493 0.8001) (xy 0.7493 0.8001) (xy 0.7493 0.0762)
				(xy 1.3716 0.0762) (xy 1.3716 1.6764)
			)
			(stroke
				(width 0)
				(type default)
			)
			(fill no)
			(layer "F.CrtYd")
		)
		(fp_rect
			(start -1.3716 1.6764)
			(end 1.3716 -1.6764)
			(stroke
				(width 0)
				(type default)
			)
			(fill no)
			(layer "F.Fab")
		)
		(pad "1" smd rect
			(at 0.50038 -0.73025)
			(size 0.7112 0.8636)
			(layers "F.Cu" "F.Mask" "F.Paste")
			(net "DRV_ACT_21")
		)
		(pad "2" smd rect
			(at -0.50038 -0.73025)
			(size 0.7112 0.8636)
			(layers "F.Cu" "F.Mask" "F.Paste")
			(net "FLT_HDD21")
		)
		(pad "3" smd rect
			(at 0.50038 0.73025)
			(size 0.7112 0.8636)
			(layers "F.Cu" "F.Mask" "F.Paste")
			(net "DRV_ACT_21_N")
		)
		(pad "4" smd rect
			(at -0.50038 0.73025)
			(size 0.7112 0.8636)
			(layers "F.Cu" "F.Mask" "F.Paste")
			(net "FLT_HDD21_N")
		)
	)
	(footprint ""
		(layer "F.Cu")
		(at 145.106898 -64.683894 90)
		(property "Reference" "R775"
			(at 0 0 90)
			(layer "F.SilkS")
			(hide yes)
			(effects
				(font
					(size 1.27 1.27)
				)
			)
		)
		(property "Value" "2R6F-GP"
			(at -0.0508 -4.8514 90)
			(unlocked yes)
			(layer "F.Fab")
			(hide yes)
			(effects
				(font
					(size 1.016 1.016)
					(thickness 0.1524)
				)
			)
		)
		(property "Device Type" "R1206H26"
			(at 0 -6.3754 90)
			(unlocked yes)
			(layer "F.Fab")
			(hide yes)
			(effects
				(font
					(size 1.016 1.016)
					(thickness 0.1524)
				)
			)
		)
		(duplicate_pad_numbers_are_jumpers no)
		(fp_line
			(start 1.016 -2.2352)
			(end 1.016 2.2352)
			(stroke
				(width 0.1524)
				(type default)
			)
			(layer "F.SilkS")
		)
		(fp_line
			(start -1.016 -2.2352)
			(end 1.016 -2.2352)
			(stroke
				(width 0.1524)
				(type default)
			)
			(layer "F.SilkS")
		)
		(fp_line
			(start 1.016 2.2352)
			(end -1.016 2.2352)
			(stroke
				(width 0.1524)
				(type default)
			)
			(layer "F.SilkS")
		)
		(fp_line
			(start -1.016 2.2352)
			(end -1.016 -2.2352)
			(stroke
				(width 0.1524)
				(type default)
			)
			(layer "F.SilkS")
		)
		(fp_rect
			(start -1.0922 2.3114)
			(end 1.0922 -2.3114)
			(stroke
				(width 0)
				(type default)
			)
			(fill no)
			(layer "F.CrtYd")
		)
		(fp_poly
			(pts
				(xy -1.0922 -2.3114) (xy 1.0922 -2.3114) (xy 1.0922 2.3114) (xy -1.0922 2.3114)
			)
			(stroke
				(width 0)
				(type default)
			)
			(fill no)
			(layer "F.Fab")
		)
		(pad "1" smd rect
			(at 0 -1.397 90)
			(size 1.651 1.27)
			(layers "F.Cu" "F.Mask" "F.Paste")
			(net "P12V_HDD28")
		)
		(pad "2" smd rect
			(at 0 1.397 90)
			(size 1.651 1.27)
			(layers "F.Cu" "F.Mask" "F.Paste")
			(net "12V_PRE_28")
		)
	)
	(footprint ""
		(layer "F.Cu")
		(at 466.164168 -127.75692 180)
		(property "Reference" "Q286"
			(at 0 0 180)
			(layer "F.SilkS")
			(hide yes)
			(effects
				(font
					(size 1.27 1.27)
				)
			)
		)
		(property "Value" "SSM3K324R-GP"
			(at 0.127 -8.9662 180)
			(unlocked yes)
			(layer "F.Fab")
			(hide yes)
			(effects
				(font
					(size 1.016 1.016)
					(thickness 0.1524)
				)
			)
		)
		(property "Device Type" "SOT23DGS2D4H35"
			(at 0.127 -10.4902 180)
			(unlocked yes)
			(layer "F.Fab")
			(hide yes)
			(effects
				(font
					(size 1.016 1.016)
					(thickness 0.1524)
				)
			)
		)
		(duplicate_pad_numbers_are_jumpers no)
		(fp_line
			(start 1.651 1.778)
			(end 1.651 -1.778)
			(stroke
				(width 0.1524)
				(type default)
			)
			(layer "F.SilkS")
		)
		(fp_line
			(start 1.651 -1.778)
			(end -1.651 -1.778)
			(stroke
				(width 0.1524)
				(type default)
			)
			(layer "F.SilkS")
		)
		(fp_line
			(start -1.651 1.778)
			(end 1.651 1.778)
			(stroke
				(width 0.1524)
				(type default)
			)
			(layer "F.SilkS")
		)
		(fp_line
			(start -1.651 -1.778)
			(end -1.651 1.778)
			(stroke
				(width 0.1524)
				(type default)
			)
			(layer "F.SilkS")
		)
		(fp_poly
			(pts
				(xy -1.778 1.8796) (xy -1.778 -1.8796) (xy 1.778 -1.8796) (xy 1.778 1.8796)
			)
			(stroke
				(width 0)
				(type default)
			)
			(fill no)
			(layer "F.CrtYd")
		)
		(fp_poly
			(pts
				(xy -1.778 1.8796) (xy -1.778 -1.8796) (xy 1.778 -1.8796) (xy 1.778 1.8796)
			)
			(stroke
				(width 0)
				(type default)
			)
			(fill no)
			(layer "F.Fab")
		)
		(pad "D" smd custom
			(at 0 -0.9525 180)
			(size 0.1905 0.1905)
			(layers "F.Cu" "F.Mask" "F.Paste")
			(net "DRV_ACT_23_N")
			(options
				(clearance outline)
				(anchor circle)
			)
			(primitives
				(gr_poly
					(pts
						(arc
							(start -0.1778 0.5715)
							(mid -0.321484 0.511984)
							(end -0.381 0.3683)
						)
						(arc
							(start -0.381 -0.3683)
							(mid -0.321484 -0.511984)
							(end -0.1778 -0.5715)
						)
						(arc
							(start 0.1778 -0.5715)
							(mid 0.321484 -0.511984)
							(end 0.381 -0.3683)
						)
						(arc
							(start 0.381 0.3683)
							(mid 0.321484 0.511984)
							(end 0.1778 0.5715)
						)
					)
					(width 0)
					(fill yes)
				)
			)
		)
		(pad "G" smd custom
			(at -0.98425 0.9525 180)
			(size 0.1905 0.1905)
			(layers "F.Cu" "F.Mask" "F.Paste")
			(net "DRIVE_A_23_ACT")
			(options
				(clearance outline)
				(anchor circle)
			)
			(primitives
				(gr_poly
					(pts
						(arc
							(start -0.1778 0.5715)
							(mid -0.321484 0.511984)
							(end -0.381 0.3683)
						)
						(arc
							(start -0.381 -0.3683)
							(mid -0.321484 -0.511984)
							(end -0.1778 -0.5715)
						)
						(arc
							(start 0.1778 -0.5715)
							(mid 0.321484 -0.511984)
							(end 0.381 -0.3683)
						)
						(arc
							(start 0.381 0.3683)
							(mid 0.321484 0.511984)
							(end 0.1778 0.5715)
						)
					)
					(width 0)
					(fill yes)
				)
			)
		)
		(pad "S" smd custom
			(at 0.98425 0.9525 180)
			(size 0.1905 0.1905)
			(layers "F.Cu" "F.Mask" "F.Paste")
			(net "GND")
			(options
				(clearance outline)
				(anchor circle)
			)
			(primitives
				(gr_poly
					(pts
						(arc
							(start -0.1778 0.5715)
							(mid -0.321484 0.511984)
							(end -0.381 0.3683)
						)
						(arc
							(start -0.381 -0.3683)
							(mid -0.321484 -0.511984)
							(end -0.1778 -0.5715)
						)
						(arc
							(start 0.1778 -0.5715)
							(mid 0.321484 -0.511984)
							(end 0.381 -0.3683)
						)
						(arc
							(start 0.381 0.3683)
							(mid 0.321484 0.511984)
							(end 0.1778 0.5715)
						)
					)
					(width 0)
					(fill yes)
				)
			)
		)
	)
	(footprint ""
		(layer "F.Cu")
		(at 225.245168 -357.991156)
		(property "Reference" "R380"
			(at 0 0 0)
			(layer "F.SilkS")
			(hide yes)
			(effects
				(font
					(size 1.27 1.27)
				)
			)
		)
		(property "Value" "100KR2F-L1-GP"
			(at 0.064008 -3.993896 0)
			(unlocked yes)
			(layer "F.Fab")
			(hide yes)
			(effects
				(font
					(size 1.016 1.016)
					(thickness 0.1524)
				)
			)
		)
		(property "Device Type" "R402H16"
			(at 0.064008 -5.517896 0)
			(unlocked yes)
			(layer "F.Fab")
			(hide yes)
			(effects
				(font
					(size 1.016 1.016)
					(thickness 0.1524)
				)
			)
		)
		(duplicate_pad_numbers_are_jumpers no)
		(fp_line
			(start -0.508 -0.9398)
			(end -0.508 0.9398)
			(stroke
				(width 0.1524)
				(type default)
			)
			(layer "F.SilkS")
		)
		(fp_line
			(start 0.508 -0.9398)
			(end -0.508 -0.9398)
			(stroke
				(width 0.1524)
				(type default)
			)
			(layer "F.SilkS")
		)
		(fp_rect
			(start -0.508 0.9398)
			(end 0.508 -0.9398)
			(stroke
				(width 0)
				(type default)
			)
			(fill no)
			(layer "F.CrtYd")
		)
		(fp_rect
			(start -0.508 0.9398)
			(end 0.508 -0.9398)
			(stroke
				(width 0)
				(type default)
			)
			(fill no)
			(layer "F.Fab")
		)
		(pad "1" smd custom
			(at 0 -0.4445)
			(size 0.1397 0.1397)
			(layers "F.Cu" "F.Mask" "F.Paste")
			(net "P3V3_STBY_A")
			(options
				(clearance outline)
				(anchor circle)
			)
			(primitives
				(gr_poly
					(pts
						(arc
							(start -0.1778 -0.2794)
							(mid -0.249642 -0.249642)
							(end -0.2794 -0.1778)
						)
						(arc
							(start -0.2794 0.1778)
							(mid -0.249642 0.249642)
							(end -0.1778 0.2794)
						)
						(arc
							(start 0.1778 0.2794)
							(mid 0.249642 0.249642)
							(end 0.2794 0.1778)
						)
						(arc
							(start 0.2794 -0.1778)
							(mid 0.249642 -0.249642)
							(end 0.1778 -0.2794)
						)
					)
					(width 0)
					(fill yes)
				)
			)
		)
		(pad "2" smd custom
			(at 0 0.4445)
			(size 0.1397 0.1397)
			(layers "F.Cu" "F.Mask" "F.Paste")
			(net "SCC_A_INS_N")
			(options
				(clearance outline)
				(anchor circle)
			)
			(primitives
				(gr_poly
					(pts
						(arc
							(start -0.1778 -0.2794)
							(mid -0.249642 -0.249642)
							(end -0.2794 -0.1778)
						)
						(arc
							(start -0.2794 0.1778)
							(mid -0.249642 0.249642)
							(end -0.1778 0.2794)
						)
						(arc
							(start 0.1778 0.2794)
							(mid 0.249642 0.249642)
							(end 0.2794 0.1778)
						)
						(arc
							(start 0.2794 -0.1778)
							(mid 0.249642 -0.249642)
							(end 0.1778 -0.2794)
						)
					)
					(width 0)
					(fill yes)
				)
			)
		)
	)
	(footprint ""
		(layer "F.Cu")
		(at 77.942948 -283.482542 -90)
		(property "Reference" "R191"
			(at 0 0 270)
			(layer "F.SilkS")
			(hide yes)
			(effects
				(font
					(size 1.27 1.27)
				)
			)
		)
		(property "Value" "300KR2F-GP"
			(at 0.064008 -3.993896 270)
			(unlocked yes)
			(layer "F.Fab")
			(hide yes)
			(effects
				(font
					(size 1.016 1.016)
					(thickness 0.1524)
				)
			)
		)
		(property "Device Type" "R402H16"
			(at 0.064008 -5.517896 270)
			(unlocked yes)
			(layer "F.Fab")
			(hide yes)
			(effects
				(font
					(size 1.016 1.016)
					(thickness 0.1524)
				)
			)
		)
		(duplicate_pad_numbers_are_jumpers no)
		(fp_line
			(start -0.508 -0.9398)
			(end -0.508 0.9398)
			(stroke
				(width 0.1524)
				(type default)
			)
			(layer "F.SilkS")
		)
		(fp_line
			(start 0.508 -0.9398)
			(end -0.508 -0.9398)
			(stroke
				(width 0.1524)
				(type default)
			)
			(layer "F.SilkS")
		)
		(fp_rect
			(start -0.508 0.9398)
			(end 0.508 -0.9398)
			(stroke
				(width 0)
				(type default)
			)
			(fill no)
			(layer "F.CrtYd")
		)
		(fp_rect
			(start -0.508 0.9398)
			(end 0.508 -0.9398)
			(stroke
				(width 0)
				(type default)
			)
			(fill no)
			(layer "F.Fab")
		)
		(pad "1" smd custom
			(at 0 -0.4445 270)
			(size 0.1397 0.1397)
			(layers "F.Cu" "F.Mask" "F.Paste")
			(net "SW_HDD_N2")
			(options
				(clearance outline)
				(anchor circle)
			)
			(primitives
				(gr_poly
					(pts
						(arc
							(start -0.1778 -0.2794)
							(mid -0.249642 -0.249642)
							(end -0.2794 -0.1778)
						)
						(arc
							(start -0.2794 0.1778)
							(mid -0.249642 0.249642)
							(end -0.1778 0.2794)
						)
						(arc
							(start 0.1778 0.2794)
							(mid 0.249642 0.249642)
							(end 0.2794 0.1778)
						)
						(arc
							(start 0.2794 -0.1778)
							(mid 0.249642 -0.249642)
							(end 0.1778 -0.2794)
						)
					)
					(width 0)
					(fill yes)
				)
			)
		)
		(pad "2" smd custom
			(at 0 0.4445 270)
			(size 0.1397 0.1397)
			(layers "F.Cu" "F.Mask" "F.Paste")
			(net "P12V_A")
			(options
				(clearance outline)
				(anchor circle)
			)
			(primitives
				(gr_poly
					(pts
						(arc
							(start -0.1778 -0.2794)
							(mid -0.249642 -0.249642)
							(end -0.2794 -0.1778)
						)
						(arc
							(start -0.2794 0.1778)
							(mid -0.249642 0.249642)
							(end -0.1778 0.2794)
						)
						(arc
							(start 0.1778 0.2794)
							(mid 0.249642 0.249642)
							(end 0.2794 0.1778)
						)
						(arc
							(start 0.2794 -0.1778)
							(mid 0.249642 -0.249642)
							(end 0.1778 -0.2794)
						)
					)
					(width 0)
					(fill yes)
				)
			)
		)
	)
	(footprint ""
		(layer "F.Cu")
		(at 450.9389 -47.749968 -90)
		(property "Reference" "VIA30"
			(at 0 0 270)
			(layer "F.SilkS")
			(hide yes)
			(effects
				(font
					(size 1.27 1.27)
				)
			)
		)
		(property "Value" "100OHM-8L-1D6MM-L18L16-GP"
			(at -3.7211 -4.5085 270)
			(unlocked yes)
			(layer "F.Fab")
			(hide yes)
			(effects
				(font
					(size 1.016 1.016)
					(thickness 0.1524)
				)
			)
		)
		(property "Device Type" "VIA-PCIE-4P-394076"
			(at -3.7211 -6.0325 270)
			(unlocked yes)
			(layer "F.Fab")
			(hide yes)
			(effects
				(font
					(size 1.016 1.016)
					(thickness 0.1524)
				)
			)
		)
		(duplicate_pad_numbers_are_jumpers no)
		(fp_rect
			(start -1.9685 0.381)
			(end 1.9685 -0.381)
			(stroke
				(width 0)
				(type default)
			)
			(fill no)
			(layer "F.CrtYd")
		)
		(fp_rect
			(start -1.9685 0.381)
			(end 1.9685 -0.381)
			(stroke
				(width 0)
				(type default)
			)
			(fill no)
			(layer "F.Fab")
		)
		(pad "1" thru_hole circle
			(at -1.5875 0 270)
			(size 0.508 0.508)
			(drill 0.254)
			(layers "*.Cu" "*.Mask")
			(remove_unused_layers no)
			(net "GND")
			(clearance 0.127)
			(thermal_gap 0.127)
		)
		(pad "2" thru_hole circle
			(at -0.5715 0 270)
			(size 0.508 0.508)
			(drill 0.254)
			(layers "*.Cu" "*.Mask")
			(remove_unused_layers no)
			(net "PHY_DRV_A_TO_SCC_A_34_DP")
			(clearance 0.127)
			(thermal_gap 0.127)
		)
		(pad "3" thru_hole circle
			(at 0.5715 0 270)
			(size 0.508 0.508)
			(drill 0.254)
			(layers "*.Cu" "*.Mask")
			(remove_unused_layers no)
			(net "PHY_DRV_A_TO_SCC_A_34_DN")
			(clearance 0.127)
			(thermal_gap 0.127)
		)
		(pad "4" thru_hole circle
			(at 1.5875 0 270)
			(size 0.508 0.508)
			(drill 0.254)
			(layers "*.Cu" "*.Mask")
			(remove_unused_layers no)
			(net "GND")
			(clearance 0.127)
			(thermal_gap 0.127)
		)
	)
	(footprint ""
		(layer "F.Cu")
		(at 426.755052 -275.252942 -90)
		(property "Reference" "Q55"
			(at 0 0 270)
			(layer "F.SilkS")
			(hide yes)
			(effects
				(font
					(size 1.27 1.27)
				)
			)
		)
		(property "Value" "2N7002KDW-GP"
			(at -2.3622 -8.2042 270)
			(unlocked yes)
			(layer "F.Fab")
			(hide yes)
			(effects
				(font
					(size 1.016 1.016)
					(thickness 0.1524)
				)
			)
		)
		(property "Device Type" "SOT-363H44"
			(at -2.3622 -10.1092 270)
			(unlocked yes)
			(layer "F.Fab")
			(hide yes)
			(effects
				(font
					(size 1.016 1.016)
					(thickness 0.1524)
				)
			)
		)
		(duplicate_pad_numbers_are_jumpers no)
		(fp_line
			(start -1.4478 1.7018)
			(end 1.4478 1.7018)
			(stroke
				(width 0.1524)
				(type default)
			)
			(layer "F.SilkS")
		)
		(fp_line
			(start 1.4478 1.7018)
			(end 1.4478 -1.7018)
			(stroke
				(width 0.1524)
				(type default)
			)
			(layer "F.SilkS")
		)
		(fp_line
			(start -1.27 1.524)
			(end -1.27 0.6604)
			(stroke
				(width 0.4826)
				(type default)
			)
			(layer "F.SilkS")
		)
		(fp_line
			(start -1.4478 -1.7018)
			(end -1.4478 1.7018)
			(stroke
				(width 0.1524)
				(type default)
			)
			(layer "F.SilkS")
		)
		(fp_line
			(start 1.4478 -1.7018)
			(end -1.4478 -1.7018)
			(stroke
				(width 0.1524)
				(type default)
			)
			(layer "F.SilkS")
		)
		(fp_poly
			(pts
				(xy -1.524 -1.778) (xy 1.524 -1.778) (xy 1.524 1.778) (xy -1.524 1.778)
			)
			(stroke
				(width 0)
				(type default)
			)
			(fill no)
			(layer "F.CrtYd")
		)
		(fp_poly
			(pts
				(xy -1.524 -1.778) (xy 1.524 -1.778) (xy 1.524 1.778) (xy -1.524 1.778)
			)
			(stroke
				(width 0)
				(type default)
			)
			(fill no)
			(layer "F.Fab")
		)
		(pad "1" smd rect
			(at -0.65024 0.9398 270)
			(size 0.4064 1.016)
			(layers "F.Cu" "F.Mask" "F.Paste")
			(net "GND")
		)
		(pad "2" smd rect
			(at 0 0.9398 270)
			(size 0.4064 1.016)
			(layers "F.Cu" "F.Mask" "F.Paste")
			(net "SW_PWR_R_HDD9")
		)
		(pad "3" smd rect
			(at 0.65024 0.9398 270)
			(size 0.4064 1.016)
			(layers "F.Cu" "F.Mask" "F.Paste")
			(net "SW_HDD_P9")
		)
		(pad "4" smd rect
			(at 0.65024 -0.9398 270)
			(size 0.4064 1.016)
			(layers "F.Cu" "F.Mask" "F.Paste")
			(net "GND")
		)
		(pad "5" smd rect
			(at 0 -0.9398 270)
			(size 0.4064 1.016)
			(layers "F.Cu" "F.Mask" "F.Paste")
			(net "SW_HDD_G9")
		)
		(pad "6" smd rect
			(at -0.65024 -0.9398 270)
			(size 0.4064 1.016)
			(layers "F.Cu" "F.Mask" "F.Paste")
			(net "SW_HDD_R9")
		)
	)
	(footprint ""
		(layer "F.Cu")
		(at 397.99895 -52.872894 -90)
		(property "Reference" "Q191"
			(at 0 0 270)
			(layer "F.SilkS")
			(hide yes)
			(effects
				(font
					(size 1.27 1.27)
				)
			)
		)
		(property "Value" "AO4406AL-GP"
			(at -3.707384 -1.5367 270)
			(unlocked yes)
			(layer "F.Fab")
			(hide yes)
			(effects
				(font
					(size 1.016 1.016)
					(thickness 0.1524)
				)
			)
		)
		(property "Device Type" "SOIC8H69"
			(at -3.707384 -3.0607 270)
			(unlocked yes)
			(layer "F.Fab")
			(hide yes)
			(effects
				(font
					(size 1.016 1.016)
					(thickness 0.1524)
				)
			)
		)
		(duplicate_pad_numbers_are_jumpers no)
		(fp_line
			(start -2.6289 3.4417)
			(end -2.6289 1.4732)
			(stroke
				(width 0.381)
				(type default)
			)
			(layer "F.SilkS")
		)
		(fp_line
			(start -2.7432 1.4224)
			(end -2.6416 1.4224)
			(stroke
				(width 0.1524)
				(type default)
			)
			(layer "F.SilkS")
		)
		(fp_line
			(start -2.7432 1.4224)
			(end 2.1336 1.4224)
			(stroke
				(width 0.1524)
				(type default)
			)
			(layer "F.SilkS")
		)
		(fp_line
			(start 2.1336 1.4224)
			(end 2.1336 -1.4224)
			(stroke
				(width 0.1524)
				(type default)
			)
			(layer "F.SilkS")
		)
		(fp_line
			(start -2.1844 -0.0508)
			(end -2.7178 0.508)
			(stroke
				(width 0.1524)
				(type default)
			)
			(layer "F.SilkS")
		)
		(fp_line
			(start -2.7178 -0.508)
			(end -2.1844 -0.0508)
			(stroke
				(width 0.1524)
				(type default)
			)
			(layer "F.SilkS")
		)
		(fp_line
			(start -2.7432 -1.4224)
			(end -2.7432 1.4224)
			(stroke
				(width 0.1524)
				(type default)
			)
			(layer "F.SilkS")
		)
		(fp_line
			(start 2.1336 -1.4224)
			(end -2.7432 -1.4224)
			(stroke
				(width 0.1524)
				(type default)
			)
			(layer "F.SilkS")
		)
		(fp_poly
			(pts
				(xy -2.2098 -1.4224) (xy -2.2098 1.4224) (xy 2.2098 1.4224) (xy 2.2098 -1.4224)
			)
			(stroke
				(width 0)
				(type default)
			)
			(fill yes)
			(layer "F.SilkS")
		)
		(fp_rect
			(start -2.450084 2.999994)
			(end 2.450084 -2.999994)
			(stroke
				(width 0)
				(type default)
			)
			(fill no)
			(layer "F.CrtYd")
		)
		(fp_poly
			(pts
				(xy -2.8194 3.6322) (xy -2.8194 -3.6322) (xy 2.8194 -3.6322) (xy 2.8194 1.18364) (xy 2.450084 1.18364)
				(xy 2.450084 -2.999994) (xy -2.450084 -2.999994) (xy -2.450084 2.999994) (xy 2.450084 2.999994)
				(xy 2.450084 1.18618) (xy 2.8194 1.18618) (xy 2.8194 3.6322)
			)
			(stroke
				(width 0)
				(type default)
			)
			(fill no)
			(layer "F.CrtYd")
		)
		(fp_rect
			(start -2.8194 3.6322)
			(end 2.8194 -3.6322)
			(stroke
				(width 0)
				(type default)
			)
			(fill no)
			(layer "F.Fab")
		)
		(pad "1" smd rect
			(at -1.905 2.54 270)
			(size 0.635 1.651)
			(layers "F.Cu" "F.Mask" "F.Paste")
			(net "P5V_HDD32")
		)
		(pad "2" smd rect
			(at -0.635 2.54 270)
			(size 0.635 1.651)
			(layers "F.Cu" "F.Mask" "F.Paste")
			(net "P5V_HDD32")
		)
		(pad "3" smd rect
			(at 0.635 2.54 270)
			(size 0.635 1.651)
			(layers "F.Cu" "F.Mask" "F.Paste")
			(net "P5V_HDD32")
		)
		(pad "4" smd rect
			(at 1.905 2.54 270)
			(size 0.635 1.651)
			(layers "F.Cu" "F.Mask" "F.Paste")
			(net "SW_HDD_P32")
		)
		(pad "5" smd rect
			(at 1.905 -2.54 270)
			(size 0.635 1.651)
			(layers "F.Cu" "F.Mask" "F.Paste")
			(net "P5V_A_4")
		)
		(pad "6" smd rect
			(at 0.635 -2.54 270)
			(size 0.635 1.651)
			(layers "F.Cu" "F.Mask" "F.Paste")
			(net "P5V_A_4")
		)
		(pad "7" smd rect
			(at -0.635 -2.54 270)
			(size 0.635 1.651)
			(layers "F.Cu" "F.Mask" "F.Paste")
			(net "P5V_A_4")
		)
		(pad "8" smd rect
			(at -1.905 -2.54 270)
			(size 0.635 1.651)
			(layers "F.Cu" "F.Mask" "F.Paste")
			(net "P5V_A_4")
		)
	)
	(footprint ""
		(layer "F.Cu")
		(at 74.747628 -130.269996 -90)
		(property "Reference" "R508"
			(at 0 0 270)
			(layer "F.SilkS")
			(hide yes)
			(effects
				(font
					(size 1.27 1.27)
				)
			)
		)
		(property "Value" "4K7R2J-2-GP"
			(at 0.064008 -3.993896 270)
			(unlocked yes)
			(layer "F.Fab")
			(hide yes)
			(effects
				(font
					(size 1.016 1.016)
					(thickness 0.1524)
				)
			)
		)
		(property "Device Type" "R402H16"
			(at 0.064008 -5.517896 270)
			(unlocked yes)
			(layer "F.Fab")
			(hide yes)
			(effects
				(font
					(size 1.016 1.016)
					(thickness 0.1524)
				)
			)
		)
		(duplicate_pad_numbers_are_jumpers no)
		(fp_line
			(start -0.508 -0.9398)
			(end -0.508 0.9398)
			(stroke
				(width 0.1524)
				(type default)
			)
			(layer "F.SilkS")
		)
		(fp_line
			(start 0.508 -0.9398)
			(end -0.508 -0.9398)
			(stroke
				(width 0.1524)
				(type default)
			)
			(layer "F.SilkS")
		)
		(fp_rect
			(start -0.508 0.9398)
			(end 0.508 -0.9398)
			(stroke
				(width 0)
				(type default)
			)
			(fill no)
			(layer "F.CrtYd")
		)
		(fp_rect
			(start -0.508 0.9398)
			(end 0.508 -0.9398)
			(stroke
				(width 0)
				(type default)
			)
			(fill no)
			(layer "F.Fab")
		)
		(pad "1" smd custom
			(at 0 -0.4445 270)
			(size 0.1397 0.1397)
			(layers "F.Cu" "F.Mask" "F.Paste")
			(net "DRIVE_A_14_ACT")
			(options
				(clearance outline)
				(anchor circle)
			)
			(primitives
				(gr_poly
					(pts
						(arc
							(start -0.1778 -0.2794)
							(mid -0.249642 -0.249642)
							(end -0.2794 -0.1778)
						)
						(arc
							(start -0.2794 0.1778)
							(mid -0.249642 0.249642)
							(end -0.1778 0.2794)
						)
						(arc
							(start 0.1778 0.2794)
							(mid 0.249642 0.249642)
							(end 0.2794 0.1778)
						)
						(arc
							(start 0.2794 -0.1778)
							(mid 0.249642 -0.249642)
							(end 0.1778 -0.2794)
						)
					)
					(width 0)
					(fill yes)
				)
			)
		)
		(pad "2" smd custom
			(at 0 0.4445 270)
			(size 0.1397 0.1397)
			(layers "F.Cu" "F.Mask" "F.Paste")
			(net "GND")
			(options
				(clearance outline)
				(anchor circle)
			)
			(primitives
				(gr_poly
					(pts
						(arc
							(start -0.1778 -0.2794)
							(mid -0.249642 -0.249642)
							(end -0.2794 -0.1778)
						)
						(arc
							(start -0.2794 0.1778)
							(mid -0.249642 0.249642)
							(end -0.1778 0.2794)
						)
						(arc
							(start 0.1778 0.2794)
							(mid 0.249642 0.249642)
							(end 0.2794 0.1778)
						)
						(arc
							(start 0.2794 -0.1778)
							(mid 0.249642 -0.249642)
							(end 0.1778 -0.2794)
						)
					)
					(width 0)
					(fill yes)
				)
			)
		)
	)
	(footprint ""
		(layer "F.Cu")
		(at 54.546246 -157.204918 -90)
		(property "Reference" "R439"
			(at 0 0 270)
			(layer "F.SilkS")
			(hide yes)
			(effects
				(font
					(size 1.27 1.27)
				)
			)
		)
		(property "Value" "0R2J-2-GP"
			(at 0.064008 -3.993896 270)
			(unlocked yes)
			(layer "F.Fab")
			(hide yes)
			(effects
				(font
					(size 1.016 1.016)
					(thickness 0.1524)
				)
			)
		)
		(property "Device Type" "R402H16"
			(at 0.064008 -5.517896 270)
			(unlocked yes)
			(layer "F.Fab")
			(hide yes)
			(effects
				(font
					(size 1.016 1.016)
					(thickness 0.1524)
				)
			)
		)
		(duplicate_pad_numbers_are_jumpers no)
		(fp_line
			(start -0.508 -0.9398)
			(end -0.508 0.9398)
			(stroke
				(width 0.1524)
				(type default)
			)
			(layer "F.SilkS")
		)
		(fp_line
			(start 0.508 -0.9398)
			(end -0.508 -0.9398)
			(stroke
				(width 0.1524)
				(type default)
			)
			(layer "F.SilkS")
		)
		(fp_rect
			(start -0.508 0.9398)
			(end 0.508 -0.9398)
			(stroke
				(width 0)
				(type default)
			)
			(fill no)
			(layer "F.CrtYd")
		)
		(fp_rect
			(start -0.508 0.9398)
			(end 0.508 -0.9398)
			(stroke
				(width 0)
				(type default)
			)
			(fill no)
			(layer "F.Fab")
		)
		(pad "1" smd custom
			(at 0 -0.4445 270)
			(size 0.1397 0.1397)
			(layers "F.Cu" "F.Mask" "F.Paste")
			(net "DRIVE_A_13_PWR")
			(options
				(clearance outline)
				(anchor circle)
			)
			(primitives
				(gr_poly
					(pts
						(arc
							(start -0.1778 -0.2794)
							(mid -0.249642 -0.249642)
							(end -0.2794 -0.1778)
						)
						(arc
							(start -0.2794 0.1778)
							(mid -0.249642 0.249642)
							(end -0.1778 0.2794)
						)
						(arc
							(start 0.1778 0.2794)
							(mid 0.249642 0.249642)
							(end 0.2794 0.1778)
						)
						(arc
							(start 0.2794 -0.1778)
							(mid 0.249642 -0.249642)
							(end 0.1778 -0.2794)
						)
					)
					(width 0)
					(fill yes)
				)
			)
		)
		(pad "2" smd custom
			(at 0 0.4445 270)
			(size 0.1397 0.1397)
			(layers "F.Cu" "F.Mask" "F.Paste")
			(net "SW_PWR_R_HDD13")
			(options
				(clearance outline)
				(anchor circle)
			)
			(primitives
				(gr_poly
					(pts
						(arc
							(start -0.1778 -0.2794)
							(mid -0.249642 -0.249642)
							(end -0.2794 -0.1778)
						)
						(arc
							(start -0.2794 0.1778)
							(mid -0.249642 0.249642)
							(end -0.1778 0.2794)
						)
						(arc
							(start 0.1778 0.2794)
							(mid 0.249642 0.249642)
							(end 0.2794 0.1778)
						)
						(arc
							(start 0.2794 -0.1778)
							(mid 0.249642 -0.249642)
							(end 0.1778 -0.2794)
						)
					)
					(width 0)
					(fill yes)
				)
			)
		)
	)
	(footprint ""
		(layer "F.Cu")
		(at 150.440898 -304.462942 180)
		(property "Reference" "C99"
			(at 0 0 180)
			(layer "F.SilkS")
			(hide yes)
			(effects
				(font
					(size 1.27 1.27)
				)
			)
		)
		(property "Value" "SC1U25V3KX-GP"
			(at 0 -2.8194 180)
			(unlocked yes)
			(layer "F.Fab")
			(hide yes)
			(effects
				(font
					(size 1.016 1.016)
					(thickness 0.1524)
				)
			)
		)
		(property "Device Type" "C603H36"
			(at 0 -4.3434 180)
			(unlocked yes)
			(layer "F.Fab")
			(hide yes)
			(effects
				(font
					(size 1.016 1.016)
					(thickness 0.1524)
				)
			)
		)
		(duplicate_pad_numbers_are_jumpers no)
		(fp_line
			(start 0.508 0)
			(end -0.508 0)
			(stroke
				(width 0.2032)
				(type default)
			)
			(layer "F.SilkS")
		)
		(fp_rect
			(start -0.5842 1.3335)
			(end 0.5842 -1.3335)
			(stroke
				(width 0)
				(type default)
			)
			(fill no)
			(layer "F.CrtYd")
		)
		(fp_rect
			(start -0.5842 1.3335)
			(end 0.5842 -1.3335)
			(stroke
				(width 0)
				(type default)
			)
			(fill no)
			(layer "F.Fab")
		)
		(pad "1" smd custom
			(at 0 -0.762 180)
			(size 0.2159 0.2159)
			(layers "F.Cu" "F.Mask" "F.Paste")
			(net "P12V_HDD4")
			(options
				(clearance outline)
				(anchor circle)
			)
			(primitives
				(gr_poly
					(pts
						(arc
							(start -0.3302 -0.4318)
							(mid -0.402042 -0.402042)
							(end -0.4318 -0.3302)
						)
						(arc
							(start -0.4318 0.3302)
							(mid -0.402042 0.402042)
							(end -0.3302 0.4318)
						)
						(arc
							(start 0.3302 0.4318)
							(mid 0.402042 0.402042)
							(end 0.4318 0.3302)
						)
						(arc
							(start 0.4318 -0.3302)
							(mid 0.402042 -0.402042)
							(end 0.3302 -0.4318)
						)
					)
					(width 0)
					(fill yes)
				)
			)
		)
		(pad "2" smd custom
			(at 0 0.762 180)
			(size 0.2159 0.2159)
			(layers "F.Cu" "F.Mask" "F.Paste")
			(net "GND")
			(options
				(clearance outline)
				(anchor circle)
			)
			(primitives
				(gr_poly
					(pts
						(arc
							(start -0.3302 -0.4318)
							(mid -0.402042 -0.402042)
							(end -0.4318 -0.3302)
						)
						(arc
							(start -0.4318 0.3302)
							(mid -0.402042 0.402042)
							(end -0.3302 0.4318)
						)
						(arc
							(start 0.3302 0.4318)
							(mid 0.402042 0.402042)
							(end 0.4318 0.3302)
						)
						(arc
							(start 0.4318 -0.3302)
							(mid 0.402042 -0.402042)
							(end 0.3302 -0.4318)
						)
					)
					(width 0)
					(fill yes)
				)
			)
		)
	)
	(footprint ""
		(layer "F.Cu")
		(at 281.269948 17.480534)
		(property "Reference" "U44"
			(at 0 0 0)
			(layer "F.SilkS")
			(hide yes)
			(effects
				(font
					(size 1.27 1.27)
				)
			)
		)
		(property "Value" "74LVC2G07GW-GP"
			(at -2.3622 -8.2042 0)
			(unlocked yes)
			(layer "F.Fab")
			(hide yes)
			(effects
				(font
					(size 1.016 1.016)
					(thickness 0.1524)
				)
			)
		)
		(property "Device Type" "SOT-363H44"
			(at -2.3622 -10.1092 0)
			(unlocked yes)
			(layer "F.Fab")
			(hide yes)
			(effects
				(font
					(size 1.016 1.016)
					(thickness 0.1524)
				)
			)
		)
		(duplicate_pad_numbers_are_jumpers no)
		(fp_line
			(start -1.4478 -1.7018)
			(end -1.4478 1.7018)
			(stroke
				(width 0.1524)
				(type default)
			)
			(layer "F.SilkS")
		)
		(fp_line
			(start -1.4478 1.7018)
			(end 1.4478 1.7018)
			(stroke
				(width 0.1524)
				(type default)
			)
			(layer "F.SilkS")
		)
		(fp_line
			(start -1.27 1.524)
			(end -1.27 0.6604)
			(stroke
				(width 0.4826)
				(type default)
			)
			(layer "F.SilkS")
		)
		(fp_line
			(start 1.4478 -1.7018)
			(end -1.4478 -1.7018)
			(stroke
				(width 0.1524)
				(type default)
			)
			(layer "F.SilkS")
		)
		(fp_line
			(start 1.4478 1.7018)
			(end 1.4478 -1.7018)
			(stroke
				(width 0.1524)
				(type default)
			)
			(layer "F.SilkS")
		)
		(fp_poly
			(pts
				(xy -1.524 -1.778) (xy 1.524 -1.778) (xy 1.524 1.778) (xy -1.524 1.778)
			)
			(stroke
				(width 0)
				(type default)
			)
			(fill no)
			(layer "F.CrtYd")
		)
		(fp_poly
			(pts
				(xy -1.524 -1.778) (xy 1.524 -1.778) (xy 1.524 1.778) (xy -1.524 1.778)
			)
			(stroke
				(width 0)
				(type default)
			)
			(fill no)
			(layer "F.Fab")
		)
		(pad "1" smd rect
			(at -0.65024 0.9398)
			(size 0.4064 1.016)
			(layers "F.Cu" "F.Mask" "F.Paste")
			(net "DPB_PWR_BTN_A")
		)
		(pad "2" smd rect
			(at 0 0.9398)
			(size 0.4064 1.016)
			(layers "F.Cu" "F.Mask" "F.Paste")
			(net "GND")
		)
		(pad "3" smd rect
			(at 0.65024 0.9398)
			(size 0.4064 1.016)
			(layers "F.Cu" "F.Mask" "F.Paste")
			(net "DPB_PWR_BTN_B")
		)
		(pad "4" smd rect
			(at 0.65024 -0.9398)
			(size 0.4064 1.016)
			(layers "F.Cu" "F.Mask" "F.Paste")
			(net "DPB_PWR_BTN_BUF_B")
		)
		(pad "5" smd rect
			(at 0 -0.9398)
			(size 0.4064 1.016)
			(layers "F.Cu" "F.Mask" "F.Paste")
			(net "P3V3_BIAS")
		)
		(pad "6" smd rect
			(at -0.65024 -0.9398)
			(size 0.4064 1.016)
			(layers "F.Cu" "F.Mask" "F.Paste")
			(net "DPB_PWR_BTN_BUF_A")
		)
	)
	(footprint ""
		(layer "F.Cu")
		(at 224.522538 -377.00458 180)
		(property "Reference" "R172"
			(at 0 0 180)
			(layer "F.SilkS")
			(hide yes)
			(effects
				(font
					(size 1.27 1.27)
				)
			)
		)
		(property "Value" "0R2J-2-GP"
			(at 0.064008 -3.993896 180)
			(unlocked yes)
			(layer "F.Fab")
			(hide yes)
			(effects
				(font
					(size 1.016 1.016)
					(thickness 0.1524)
				)
			)
		)
		(property "Device Type" "R402H16"
			(at 0.064008 -5.517896 180)
			(unlocked yes)
			(layer "F.Fab")
			(hide yes)
			(effects
				(font
					(size 1.016 1.016)
					(thickness 0.1524)
				)
			)
		)
		(duplicate_pad_numbers_are_jumpers no)
		(fp_line
			(start 0.508 -0.9398)
			(end -0.508 -0.9398)
			(stroke
				(width 0.1524)
				(type default)
			)
			(layer "F.SilkS")
		)
		(fp_line
			(start -0.508 -0.9398)
			(end -0.508 0.9398)
			(stroke
				(width 0.1524)
				(type default)
			)
			(layer "F.SilkS")
		)
		(fp_rect
			(start -0.508 0.9398)
			(end 0.508 -0.9398)
			(stroke
				(width 0)
				(type default)
			)
			(fill no)
			(layer "F.CrtYd")
		)
		(fp_rect
			(start -0.508 0.9398)
			(end 0.508 -0.9398)
			(stroke
				(width 0)
				(type default)
			)
			(fill no)
			(layer "F.Fab")
		)
		(pad "1" smd custom
			(at 0 -0.4445 180)
			(size 0.1397 0.1397)
			(layers "F.Cu" "F.Mask" "F.Paste")
			(net "IO_EXP3_LED_SCL")
			(options
				(clearance outline)
				(anchor circle)
			)
			(primitives
				(gr_poly
					(pts
						(arc
							(start -0.1778 -0.2794)
							(mid -0.249642 -0.249642)
							(end -0.2794 -0.1778)
						)
						(arc
							(start -0.2794 0.1778)
							(mid -0.249642 0.249642)
							(end -0.1778 0.2794)
						)
						(arc
							(start 0.1778 0.2794)
							(mid 0.249642 0.249642)
							(end 0.2794 0.1778)
						)
						(arc
							(start 0.2794 -0.1778)
							(mid 0.249642 -0.249642)
							(end 0.1778 -0.2794)
						)
					)
					(width 0)
					(fill yes)
				)
			)
		)
		(pad "2" smd custom
			(at 0 0.4445 180)
			(size 0.1397 0.1397)
			(layers "F.Cu" "F.Mask" "F.Paste")
			(net "I2C_DRIVE_B_FLT_LED_SCL")
			(options
				(clearance outline)
				(anchor circle)
			)
			(primitives
				(gr_poly
					(pts
						(arc
							(start -0.1778 -0.2794)
							(mid -0.249642 -0.249642)
							(end -0.2794 -0.1778)
						)
						(arc
							(start -0.2794 0.1778)
							(mid -0.249642 0.249642)
							(end -0.1778 0.2794)
						)
						(arc
							(start 0.1778 0.2794)
							(mid 0.249642 0.249642)
							(end 0.2794 0.1778)
						)
						(arc
							(start 0.2794 -0.1778)
							(mid 0.249642 -0.249642)
							(end 0.1778 -0.2794)
						)
					)
					(width 0)
					(fill yes)
				)
			)
		)
	)
	(footprint ""
		(layer "F.Cu")
		(at 16.824198 -52.136294 90)
		(property "Reference" "R689"
			(at 0 0 90)
			(layer "F.SilkS")
			(hide yes)
			(effects
				(font
					(size 1.27 1.27)
				)
			)
		)
		(property "Value" "4K7R2J-2-GP"
			(at 0.064008 -3.993896 90)
			(unlocked yes)
			(layer "F.Fab")
			(hide yes)
			(effects
				(font
					(size 1.016 1.016)
					(thickness 0.1524)
				)
			)
		)
		(property "Device Type" "R402H16"
			(at 0.064008 -5.517896 90)
			(unlocked yes)
			(layer "F.Fab")
			(hide yes)
			(effects
				(font
					(size 1.016 1.016)
					(thickness 0.1524)
				)
			)
		)
		(duplicate_pad_numbers_are_jumpers no)
		(fp_line
			(start 0.508 -0.9398)
			(end -0.508 -0.9398)
			(stroke
				(width 0.1524)
				(type default)
			)
			(layer "F.SilkS")
		)
		(fp_line
			(start -0.508 -0.9398)
			(end -0.508 0.9398)
			(stroke
				(width 0.1524)
				(type default)
			)
			(layer "F.SilkS")
		)
		(fp_rect
			(start -0.508 0.9398)
			(end 0.508 -0.9398)
			(stroke
				(width 0)
				(type default)
			)
			(fill no)
			(layer "F.CrtYd")
		)
		(fp_rect
			(start -0.508 0.9398)
			(end 0.508 -0.9398)
			(stroke
				(width 0)
				(type default)
			)
			(fill no)
			(layer "F.Fab")
		)
		(pad "1" smd custom
			(at 0 -0.4445 90)
			(size 0.1397 0.1397)
			(layers "F.Cu" "F.Mask" "F.Paste")
			(net "P12V_A")
			(options
				(clearance outline)
				(anchor circle)
			)
			(primitives
				(gr_poly
					(pts
						(arc
							(start -0.1778 -0.2794)
							(mid -0.249642 -0.249642)
							(end -0.2794 -0.1778)
						)
						(arc
							(start -0.2794 0.1778)
							(mid -0.249642 0.249642)
							(end -0.1778 0.2794)
						)
						(arc
							(start 0.1778 0.2794)
							(mid 0.249642 0.249642)
							(end 0.2794 0.1778)
						)
						(arc
							(start 0.2794 -0.1778)
							(mid 0.249642 -0.249642)
							(end 0.1778 -0.2794)
						)
					)
					(width 0)
					(fill yes)
				)
			)
		)
		(pad "2" smd custom
			(at 0 0.4445 90)
			(size 0.1397 0.1397)
			(layers "F.Cu" "F.Mask" "F.Paste")
			(net "SW_HDD_P24")
			(options
				(clearance outline)
				(anchor circle)
			)
			(primitives
				(gr_poly
					(pts
						(arc
							(start -0.1778 -0.2794)
							(mid -0.249642 -0.249642)
							(end -0.2794 -0.1778)
						)
						(arc
							(start -0.2794 0.1778)
							(mid -0.249642 0.249642)
							(end -0.1778 0.2794)
						)
						(arc
							(start 0.1778 0.2794)
							(mid 0.249642 0.249642)
							(end 0.2794 0.1778)
						)
						(arc
							(start 0.2794 -0.1778)
							(mid 0.249642 -0.249642)
							(end 0.1778 -0.2794)
						)
					)
					(width 0)
					(fill yes)
				)
			)
		)
	)
	(footprint ""
		(layer "F.Cu")
		(at 32.463486 -274.219416 90)
		(property "Reference" "C506"
			(at 0 0 90)
			(layer "F.SilkS")
			(hide yes)
			(effects
				(font
					(size 1.27 1.27)
				)
			)
		)
		(property "Value" "SCD01U16V1KX-GP"
			(at -2.8321 -1.7399 90)
			(unlocked yes)
			(layer "F.Fab")
			(hide yes)
			(effects
				(font
					(size 1.016 1.016)
					(thickness 0.1524)
				)
			)
		)
		(property "Device Type" "C0201H13"
			(at -2.8321 -3.2639 90)
			(unlocked yes)
			(layer "F.Fab")
			(hide yes)
			(effects
				(font
					(size 1.016 1.016)
					(thickness 0.1524)
				)
			)
		)
		(duplicate_pad_numbers_are_jumpers no)
		(fp_rect
			(start -0.2794 0.6477)
			(end 0.2794 -0.6477)
			(stroke
				(width 0)
				(type default)
			)
			(fill no)
			(layer "F.CrtYd")
		)
		(fp_rect
			(start -0.2794 0.6477)
			(end 0.2794 -0.6477)
			(stroke
				(width 0)
				(type default)
			)
			(fill no)
			(layer "F.Fab")
		)
		(pad "1" smd custom
			(at 0 -0.2794 90)
			(size 0.0762 0.0762)
			(layers "F.Cu" "F.Mask" "F.Paste")
			(net "SAS_HDD_RX_N0")
			(options
				(clearance outline)
				(anchor circle)
			)
			(primitives
				(gr_poly
					(pts
						(arc
							(start 0.1524 -0.127)
							(mid 0.137521 -0.162921)
							(end 0.1016 -0.1778)
						)
						(arc
							(start -0.1016 -0.1778)
							(mid -0.137521 -0.162921)
							(end -0.1524 -0.127)
						)
						(arc
							(start -0.1524 0.127)
							(mid -0.137521 0.162921)
							(end -0.1016 0.1778)
						)
						(arc
							(start 0.1016 0.1778)
							(mid 0.137521 0.162921)
							(end 0.1524 0.127)
						)
					)
					(width 0)
					(fill yes)
				)
			)
		)
		(pad "2" smd custom
			(at 0 0.2794 90)
			(size 0.0762 0.0762)
			(layers "F.Cu" "F.Mask" "F.Paste")
			(net "PHY_SCC_A_TO_DRV_A_0_DN")
			(options
				(clearance outline)
				(anchor circle)
			)
			(primitives
				(gr_poly
					(pts
						(arc
							(start 0.1524 -0.127)
							(mid 0.137521 -0.162921)
							(end 0.1016 -0.1778)
						)
						(arc
							(start -0.1016 -0.1778)
							(mid -0.137521 -0.162921)
							(end -0.1524 -0.127)
						)
						(arc
							(start -0.1524 0.127)
							(mid -0.137521 0.162921)
							(end -0.1016 0.1778)
						)
						(arc
							(start 0.1016 0.1778)
							(mid 0.137521 0.162921)
							(end 0.1524 0.127)
						)
					)
					(width 0)
					(fill yes)
				)
			)
		)
	)
	(footprint ""
		(layer "F.Cu")
		(at 80.24495 -242.25377)
		(property "Reference" "R217"
			(at 0 0 0)
			(layer "F.SilkS")
			(hide yes)
			(effects
				(font
					(size 1.27 1.27)
				)
			)
		)
		(property "Value" "130R3F-GP"
			(at -0.0254 -2.5146 0)
			(unlocked yes)
			(layer "F.Fab")
			(hide yes)
			(effects
				(font
					(size 1.016 1.016)
					(thickness 0.1524)
				)
			)
		)
		(property "Device Type" "R603H22"
			(at -0.0254 -4.0386 0)
			(unlocked yes)
			(layer "F.Fab")
			(hide yes)
			(effects
				(font
					(size 1.016 1.016)
					(thickness 0.1524)
				)
			)
		)
		(duplicate_pad_numbers_are_jumpers no)
		(fp_line
			(start -0.4826 0)
			(end -0.2032 0)
			(stroke
				(width 0.2032)
				(type default)
			)
			(layer "F.SilkS")
		)
		(fp_line
			(start 0.2032 0)
			(end 0.4826 0)
			(stroke
				(width 0.2032)
				(type default)
			)
			(layer "F.SilkS")
		)
		(fp_rect
			(start -0.5842 1.3335)
			(end 0.5842 -1.3335)
			(stroke
				(width 0)
				(type default)
			)
			(fill no)
			(layer "F.CrtYd")
		)
		(fp_rect
			(start -0.5842 1.3335)
			(end 0.5842 -1.3335)
			(stroke
				(width 0)
				(type default)
			)
			(fill no)
			(layer "F.Fab")
		)
		(pad "1" smd custom
			(at 0 -0.762)
			(size 0.2159 0.2159)
			(layers "F.Cu" "F.Mask" "F.Paste")
			(net "P5V_A_1")
			(options
				(clearance outline)
				(anchor circle)
			)
			(primitives
				(gr_poly
					(pts
						(arc
							(start -0.3302 -0.4318)
							(mid -0.402042 -0.402042)
							(end -0.4318 -0.3302)
						)
						(arc
							(start -0.4318 0.3302)
							(mid -0.402042 0.402042)
							(end -0.3302 0.4318)
						)
						(arc
							(start 0.3302 0.4318)
							(mid 0.402042 0.402042)
							(end 0.4318 0.3302)
						)
						(arc
							(start 0.4318 -0.3302)
							(mid 0.402042 -0.402042)
							(end 0.3302 -0.4318)
						)
					)
					(width 0)
					(fill yes)
				)
			)
		)
		(pad "2" smd custom
			(at 0 0.762)
			(size 0.2159 0.2159)
			(layers "F.Cu" "F.Mask" "F.Paste")
			(net "FLT_HDD2")
			(options
				(clearance outline)
				(anchor circle)
			)
			(primitives
				(gr_poly
					(pts
						(arc
							(start -0.3302 -0.4318)
							(mid -0.402042 -0.402042)
							(end -0.4318 -0.3302)
						)
						(arc
							(start -0.4318 0.3302)
							(mid -0.402042 0.402042)
							(end -0.3302 0.4318)
						)
						(arc
							(start 0.3302 0.4318)
							(mid 0.402042 0.402042)
							(end 0.4318 0.3302)
						)
						(arc
							(start 0.4318 -0.3302)
							(mid 0.402042 -0.402042)
							(end 0.3302 -0.4318)
						)
					)
					(width 0)
					(fill yes)
				)
			)
		)
	)
	(footprint ""
		(layer "F.Cu")
		(at 431.581052 -45.735494 180)
		(property "Reference" "R902"
			(at 0 0 180)
			(layer "F.SilkS")
			(hide yes)
			(effects
				(font
					(size 1.27 1.27)
				)
			)
		)
		(property "Value" "4K7R2J-2-GP"
			(at 0.064008 -3.993896 180)
			(unlocked yes)
			(layer "F.Fab")
			(hide yes)
			(effects
				(font
					(size 1.016 1.016)
					(thickness 0.1524)
				)
			)
		)
		(property "Device Type" "R402H16"
			(at 0.064008 -5.517896 180)
			(unlocked yes)
			(layer "F.Fab")
			(hide yes)
			(effects
				(font
					(size 1.016 1.016)
					(thickness 0.1524)
				)
			)
		)
		(duplicate_pad_numbers_are_jumpers no)
		(fp_line
			(start 0.508 -0.9398)
			(end -0.508 -0.9398)
			(stroke
				(width 0.1524)
				(type default)
			)
			(layer "F.SilkS")
		)
		(fp_line
			(start -0.508 -0.9398)
			(end -0.508 0.9398)
			(stroke
				(width 0.1524)
				(type default)
			)
			(layer "F.SilkS")
		)
		(fp_rect
			(start -0.508 0.9398)
			(end 0.508 -0.9398)
			(stroke
				(width 0)
				(type default)
			)
			(fill no)
			(layer "F.CrtYd")
		)
		(fp_rect
			(start -0.508 0.9398)
			(end 0.508 -0.9398)
			(stroke
				(width 0)
				(type default)
			)
			(fill no)
			(layer "F.Fab")
		)
		(pad "1" smd custom
			(at 0 -0.4445 180)
			(size 0.1397 0.1397)
			(layers "F.Cu" "F.Mask" "F.Paste")
			(net "P12V_A")
			(options
				(clearance outline)
				(anchor circle)
			)
			(primitives
				(gr_poly
					(pts
						(arc
							(start -0.1778 -0.2794)
							(mid -0.249642 -0.249642)
							(end -0.2794 -0.1778)
						)
						(arc
							(start -0.2794 0.1778)
							(mid -0.249642 0.249642)
							(end -0.1778 0.2794)
						)
						(arc
							(start 0.1778 0.2794)
							(mid 0.249642 0.249642)
							(end 0.2794 0.1778)
						)
						(arc
							(start 0.2794 -0.1778)
							(mid 0.249642 -0.249642)
							(end 0.1778 -0.2794)
						)
					)
					(width 0)
					(fill yes)
				)
			)
		)
		(pad "2" smd custom
			(at 0 0.4445 180)
			(size 0.1397 0.1397)
			(layers "F.Cu" "F.Mask" "F.Paste")
			(net "SW_HDD_R33")
			(options
				(clearance outline)
				(anchor circle)
			)
			(primitives
				(gr_poly
					(pts
						(arc
							(start -0.1778 -0.2794)
							(mid -0.249642 -0.249642)
							(end -0.2794 -0.1778)
						)
						(arc
							(start -0.2794 0.1778)
							(mid -0.249642 0.249642)
							(end -0.1778 0.2794)
						)
						(arc
							(start 0.1778 0.2794)
							(mid 0.249642 0.249642)
							(end 0.2794 0.1778)
						)
						(arc
							(start 0.2794 -0.1778)
							(mid 0.249642 -0.249642)
							(end 0.1778 -0.2794)
						)
					)
					(width 0)
					(fill yes)
				)
			)
		)
	)
	(footprint ""
		(layer "F.Cu")
		(at 452.797164 -242.250976)
		(property "Reference" "R269"
			(at 0 0 0)
			(layer "F.SilkS")
			(hide yes)
			(effects
				(font
					(size 1.27 1.27)
				)
			)
		)
		(property "Value" "91R3F-1-GP"
			(at -0.0254 -2.5146 0)
			(unlocked yes)
			(layer "F.Fab")
			(hide yes)
			(effects
				(font
					(size 1.016 1.016)
					(thickness 0.1524)
				)
			)
		)
		(property "Device Type" "R603H22"
			(at -0.0254 -4.0386 0)
			(unlocked yes)
			(layer "F.Fab")
			(hide yes)
			(effects
				(font
					(size 1.016 1.016)
					(thickness 0.1524)
				)
			)
		)
		(duplicate_pad_numbers_are_jumpers no)
		(fp_line
			(start -0.4826 0)
			(end -0.2032 0)
			(stroke
				(width 0.2032)
				(type default)
			)
			(layer "F.SilkS")
		)
		(fp_line
			(start 0.2032 0)
			(end 0.4826 0)
			(stroke
				(width 0.2032)
				(type default)
			)
			(layer "F.SilkS")
		)
		(fp_rect
			(start -0.5842 1.3335)
			(end 0.5842 -1.3335)
			(stroke
				(width 0)
				(type default)
			)
			(fill no)
			(layer "F.CrtYd")
		)
		(fp_rect
			(start -0.5842 1.3335)
			(end 0.5842 -1.3335)
			(stroke
				(width 0)
				(type default)
			)
			(fill no)
			(layer "F.Fab")
		)
		(pad "1" smd custom
			(at 0 -0.762)
			(size 0.2159 0.2159)
			(layers "F.Cu" "F.Mask" "F.Paste")
			(net "P5V_A_3")
			(options
				(clearance outline)
				(anchor circle)
			)
			(primitives
				(gr_poly
					(pts
						(arc
							(start -0.3302 -0.4318)
							(mid -0.402042 -0.402042)
							(end -0.4318 -0.3302)
						)
						(arc
							(start -0.4318 0.3302)
							(mid -0.402042 0.402042)
							(end -0.3302 0.4318)
						)
						(arc
							(start 0.3302 0.4318)
							(mid 0.402042 0.402042)
							(end 0.4318 0.3302)
						)
						(arc
							(start 0.4318 -0.3302)
							(mid 0.402042 -0.402042)
							(end 0.3302 -0.4318)
						)
					)
					(width 0)
					(fill yes)
				)
			)
		)
		(pad "2" smd custom
			(at 0 0.762)
			(size 0.2159 0.2159)
			(layers "F.Cu" "F.Mask" "F.Paste")
			(net "DRV_ACT_11")
			(options
				(clearance outline)
				(anchor circle)
			)
			(primitives
				(gr_poly
					(pts
						(arc
							(start -0.3302 -0.4318)
							(mid -0.402042 -0.402042)
							(end -0.4318 -0.3302)
						)
						(arc
							(start -0.4318 0.3302)
							(mid -0.402042 0.402042)
							(end -0.3302 0.4318)
						)
						(arc
							(start 0.3302 0.4318)
							(mid 0.402042 0.402042)
							(end 0.4318 0.3302)
						)
						(arc
							(start 0.4318 -0.3302)
							(mid 0.402042 -0.402042)
							(end 0.3302 -0.4318)
						)
					)
					(width 0)
					(fill yes)
				)
			)
		)
	)
	(footprint ""
		(layer "F.Cu")
		(at 432.724052 -279.443942 90)
		(property "Reference" "R353"
			(at 0 0 90)
			(layer "F.SilkS")
			(hide yes)
			(effects
				(font
					(size 1.27 1.27)
				)
			)
		)
		(property "Value" "200KR2F-L-GP"
			(at 0.064008 -3.993896 90)
			(unlocked yes)
			(layer "F.Fab")
			(hide yes)
			(effects
				(font
					(size 1.016 1.016)
					(thickness 0.1524)
				)
			)
		)
		(property "Device Type" "R402H16"
			(at 0.064008 -5.517896 90)
			(unlocked yes)
			(layer "F.Fab")
			(hide yes)
			(effects
				(font
					(size 1.016 1.016)
					(thickness 0.1524)
				)
			)
		)
		(duplicate_pad_numbers_are_jumpers no)
		(fp_line
			(start 0.508 -0.9398)
			(end -0.508 -0.9398)
			(stroke
				(width 0.1524)
				(type default)
			)
			(layer "F.SilkS")
		)
		(fp_line
			(start -0.508 -0.9398)
			(end -0.508 0.9398)
			(stroke
				(width 0.1524)
				(type default)
			)
			(layer "F.SilkS")
		)
		(fp_rect
			(start -0.508 0.9398)
			(end 0.508 -0.9398)
			(stroke
				(width 0)
				(type default)
			)
			(fill no)
			(layer "F.CrtYd")
		)
		(fp_rect
			(start -0.508 0.9398)
			(end 0.508 -0.9398)
			(stroke
				(width 0)
				(type default)
			)
			(fill no)
			(layer "F.Fab")
		)
		(pad "1" smd custom
			(at 0 -0.4445 90)
			(size 0.1397 0.1397)
			(layers "F.Cu" "F.Mask" "F.Paste")
			(net "SW_HDD_R9")
			(options
				(clearance outline)
				(anchor circle)
			)
			(primitives
				(gr_poly
					(pts
						(arc
							(start -0.1778 -0.2794)
							(mid -0.249642 -0.249642)
							(end -0.2794 -0.1778)
						)
						(arc
							(start -0.2794 0.1778)
							(mid -0.249642 0.249642)
							(end -0.1778 0.2794)
						)
						(arc
							(start 0.1778 0.2794)
							(mid 0.249642 0.249642)
							(end 0.2794 0.1778)
						)
						(arc
							(start 0.2794 -0.1778)
							(mid 0.249642 -0.249642)
							(end 0.1778 -0.2794)
						)
					)
					(width 0)
					(fill yes)
				)
			)
		)
		(pad "2" smd custom
			(at 0 0.4445 90)
			(size 0.1397 0.1397)
			(layers "F.Cu" "F.Mask" "F.Paste")
			(net "SW_HDD_N9")
			(options
				(clearance outline)
				(anchor circle)
			)
			(primitives
				(gr_poly
					(pts
						(arc
							(start -0.1778 -0.2794)
							(mid -0.249642 -0.249642)
							(end -0.2794 -0.1778)
						)
						(arc
							(start -0.2794 0.1778)
							(mid -0.249642 0.249642)
							(end -0.1778 0.2794)
						)
						(arc
							(start 0.1778 0.2794)
							(mid 0.249642 0.249642)
							(end 0.2794 0.1778)
						)
						(arc
							(start 0.2794 -0.1778)
							(mid 0.249642 -0.249642)
							(end 0.1778 -0.2794)
						)
					)
					(width 0)
					(fill yes)
				)
			)
		)
	)
	(footprint ""
		(layer "F.Cu")
		(at 394.56995 -61.127894 -90)
		(property "Reference" "R865"
			(at 0 0 270)
			(layer "F.SilkS")
			(hide yes)
			(effects
				(font
					(size 1.27 1.27)
				)
			)
		)
		(property "Value" "2R6F-GP"
			(at -0.0508 -4.8514 270)
			(unlocked yes)
			(layer "F.Fab")
			(hide yes)
			(effects
				(font
					(size 1.016 1.016)
					(thickness 0.1524)
				)
			)
		)
		(property "Device Type" "R1206H26"
			(at 0 -6.3754 270)
			(unlocked yes)
			(layer "F.Fab")
			(hide yes)
			(effects
				(font
					(size 1.016 1.016)
					(thickness 0.1524)
				)
			)
		)
		(duplicate_pad_numbers_are_jumpers no)
		(fp_line
			(start -1.016 2.2352)
			(end -1.016 -2.2352)
			(stroke
				(width 0.1524)
				(type default)
			)
			(layer "F.SilkS")
		)
		(fp_line
			(start 1.016 2.2352)
			(end -1.016 2.2352)
			(stroke
				(width 0.1524)
				(type default)
			)
			(layer "F.SilkS")
		)
		(fp_line
			(start -1.016 -2.2352)
			(end 1.016 -2.2352)
			(stroke
				(width 0.1524)
				(type default)
			)
			(layer "F.SilkS")
		)
		(fp_line
			(start 1.016 -2.2352)
			(end 1.016 2.2352)
			(stroke
				(width 0.1524)
				(type default)
			)
			(layer "F.SilkS")
		)
		(fp_rect
			(start -1.0922 2.3114)
			(end 1.0922 -2.3114)
			(stroke
				(width 0)
				(type default)
			)
			(fill no)
			(layer "F.CrtYd")
		)
		(fp_poly
			(pts
				(xy -1.0922 -2.3114) (xy 1.0922 -2.3114) (xy 1.0922 2.3114) (xy -1.0922 2.3114)
			)
			(stroke
				(width 0)
				(type default)
			)
			(fill no)
			(layer "F.Fab")
		)
		(pad "1" smd rect
			(at 0 -1.397 270)
			(size 1.651 1.27)
			(layers "F.Cu" "F.Mask" "F.Paste")
			(net "P5V_HDD32")
		)
		(pad "2" smd rect
			(at 0 1.397 270)
			(size 1.651 1.27)
			(layers "F.Cu" "F.Mask" "F.Paste")
			(net "5V_PRE_32")
		)
	)
	(footprint ""
		(layer "F.Cu")
		(at 221.3864 -376.62104 -90)
		(property "Reference" "C535"
			(at 0 0 270)
			(layer "F.SilkS")
			(hide yes)
			(effects
				(font
					(size 1.27 1.27)
				)
			)
		)
		(property "Value" "SC1U16V3KX-5GP"
			(at 0 -2.8194 270)
			(unlocked yes)
			(layer "F.Fab")
			(hide yes)
			(effects
				(font
					(size 1.016 1.016)
					(thickness 0.1524)
				)
			)
		)
		(property "Device Type" "C603H36"
			(at 0 -4.3434 270)
			(unlocked yes)
			(layer "F.Fab")
			(hide yes)
			(effects
				(font
					(size 1.016 1.016)
					(thickness 0.1524)
				)
			)
		)
		(duplicate_pad_numbers_are_jumpers no)
		(fp_line
			(start 0.508 0)
			(end -0.508 0)
			(stroke
				(width 0.2032)
				(type default)
			)
			(layer "F.SilkS")
		)
		(fp_rect
			(start -0.5842 1.3335)
			(end 0.5842 -1.3335)
			(stroke
				(width 0)
				(type default)
			)
			(fill no)
			(layer "F.CrtYd")
		)
		(fp_rect
			(start -0.5842 1.3335)
			(end 0.5842 -1.3335)
			(stroke
				(width 0)
				(type default)
			)
			(fill no)
			(layer "F.Fab")
		)
		(pad "1" smd custom
			(at 0 -0.762 270)
			(size 0.2159 0.2159)
			(layers "F.Cu" "F.Mask" "F.Paste")
			(net "P3V3_STBY_B")
			(options
				(clearance outline)
				(anchor circle)
			)
			(primitives
				(gr_poly
					(pts
						(arc
							(start -0.3302 -0.4318)
							(mid -0.402042 -0.402042)
							(end -0.4318 -0.3302)
						)
						(arc
							(start -0.4318 0.3302)
							(mid -0.402042 0.402042)
							(end -0.3302 0.4318)
						)
						(arc
							(start 0.3302 0.4318)
							(mid 0.402042 0.402042)
							(end 0.4318 0.3302)
						)
						(arc
							(start 0.4318 -0.3302)
							(mid 0.402042 -0.402042)
							(end 0.3302 -0.4318)
						)
					)
					(width 0)
					(fill yes)
				)
			)
		)
		(pad "2" smd custom
			(at 0 0.762 270)
			(size 0.2159 0.2159)
			(layers "F.Cu" "F.Mask" "F.Paste")
			(net "GND")
			(options
				(clearance outline)
				(anchor circle)
			)
			(primitives
				(gr_poly
					(pts
						(arc
							(start -0.3302 -0.4318)
							(mid -0.402042 -0.402042)
							(end -0.4318 -0.3302)
						)
						(arc
							(start -0.4318 0.3302)
							(mid -0.402042 0.402042)
							(end -0.3302 0.4318)
						)
						(arc
							(start 0.3302 0.4318)
							(mid 0.402042 0.402042)
							(end 0.4318 0.3302)
						)
						(arc
							(start 0.4318 -0.3302)
							(mid 0.402042 -0.402042)
							(end 0.3302 -0.4318)
						)
					)
					(width 0)
					(fill yes)
				)
			)
		)
	)
	(footprint ""
		(layer "F.Cu")
		(at 468.354918 -161.018474 -90)
		(property "Reference" "R676"
			(at 0 0 270)
			(layer "F.SilkS")
			(hide yes)
			(effects
				(font
					(size 1.27 1.27)
				)
			)
		)
		(property "Value" "0R2J-2-GP"
			(at 0.064008 -3.993896 270)
			(unlocked yes)
			(layer "F.Fab")
			(hide yes)
			(effects
				(font
					(size 1.016 1.016)
					(thickness 0.1524)
				)
			)
		)
		(property "Device Type" "R402H16"
			(at 0.064008 -5.517896 270)
			(unlocked yes)
			(layer "F.Fab")
			(hide yes)
			(effects
				(font
					(size 1.016 1.016)
					(thickness 0.1524)
				)
			)
		)
		(duplicate_pad_numbers_are_jumpers no)
		(fp_line
			(start -0.508 -0.9398)
			(end -0.508 0.9398)
			(stroke
				(width 0.1524)
				(type default)
			)
			(layer "F.SilkS")
		)
		(fp_line
			(start 0.508 -0.9398)
			(end -0.508 -0.9398)
			(stroke
				(width 0.1524)
				(type default)
			)
			(layer "F.SilkS")
		)
		(fp_rect
			(start -0.508 0.9398)
			(end 0.508 -0.9398)
			(stroke
				(width 0)
				(type default)
			)
			(fill no)
			(layer "F.CrtYd")
		)
		(fp_rect
			(start -0.508 0.9398)
			(end 0.508 -0.9398)
			(stroke
				(width 0)
				(type default)
			)
			(fill no)
			(layer "F.Fab")
		)
		(pad "1" smd custom
			(at 0 -0.4445 270)
			(size 0.1397 0.1397)
			(layers "F.Cu" "F.Mask" "F.Paste")
			(net "SW_HDD_G23")
			(options
				(clearance outline)
				(anchor circle)
			)
			(primitives
				(gr_poly
					(pts
						(arc
							(start -0.1778 -0.2794)
							(mid -0.249642 -0.249642)
							(end -0.2794 -0.1778)
						)
						(arc
							(start -0.2794 0.1778)
							(mid -0.249642 0.249642)
							(end -0.1778 0.2794)
						)
						(arc
							(start 0.1778 0.2794)
							(mid 0.249642 0.249642)
							(end 0.2794 0.1778)
						)
						(arc
							(start 0.2794 -0.1778)
							(mid 0.249642 -0.249642)
							(end 0.1778 -0.2794)
						)
					)
					(width 0)
					(fill yes)
				)
			)
		)
		(pad "2" smd custom
			(at 0 0.4445 270)
			(size 0.1397 0.1397)
			(layers "F.Cu" "F.Mask" "F.Paste")
			(net "SW_HDD_R23")
			(options
				(clearance outline)
				(anchor circle)
			)
			(primitives
				(gr_poly
					(pts
						(arc
							(start -0.1778 -0.2794)
							(mid -0.249642 -0.249642)
							(end -0.2794 -0.1778)
						)
						(arc
							(start -0.2794 0.1778)
							(mid -0.249642 0.249642)
							(end -0.1778 0.2794)
						)
						(arc
							(start 0.1778 0.2794)
							(mid 0.249642 0.249642)
							(end 0.2794 0.1778)
						)
						(arc
							(start 0.2794 -0.1778)
							(mid 0.249642 -0.249642)
							(end 0.1778 -0.2794)
						)
					)
					(width 0)
					(fill yes)
				)
			)
		)
	)
	(footprint ""
		(layer "F.Cu")
		(at 303.090072 -12.183872 90)
		(property "Reference" "C41"
			(at 0 0 90)
			(layer "F.SilkS")
			(hide yes)
			(effects
				(font
					(size 1.27 1.27)
				)
			)
		)
		(property "Value" "SC22U25V6KX-2-GP-U"
			(at -2.860802 -5.279644 90)
			(unlocked yes)
			(layer "F.Fab")
			(hide yes)
			(effects
				(font
					(size 1.016 1.016)
					(thickness 0.1524)
				)
			)
		)
		(property "Device Type" "C1206-TO0D3H75"
			(at -2.860802 -6.803644 90)
			(unlocked yes)
			(layer "F.Fab")
			(hide yes)
			(effects
				(font
					(size 1.016 1.016)
					(thickness 0.1524)
				)
			)
		)
		(duplicate_pad_numbers_are_jumpers no)
		(fp_line
			(start 1.3081 -2.3749)
			(end 1.3081 2.3749)
			(stroke
				(width 0.1524)
				(type default)
			)
			(layer "F.SilkS")
		)
		(fp_line
			(start -1.3081 -2.3749)
			(end 1.3081 -2.3749)
			(stroke
				(width 0.1524)
				(type default)
			)
			(layer "F.SilkS")
		)
		(fp_line
			(start 1.3081 2.3749)
			(end -1.3081 2.3749)
			(stroke
				(width 0.1524)
				(type default)
			)
			(layer "F.SilkS")
		)
		(fp_line
			(start -1.3081 2.3749)
			(end -1.3081 -2.3749)
			(stroke
				(width 0.1524)
				(type default)
			)
			(layer "F.SilkS")
		)
		(fp_rect
			(start -0.8001 1.6002)
			(end 0.8001 -1.6002)
			(stroke
				(width 0)
				(type default)
			)
			(fill no)
			(layer "F.CrtYd")
		)
		(fp_poly
			(pts
				(xy -1.5621 2.4511) (xy -1.5621 1.6002) (xy 0.8001 1.6002) (xy 0.8001 -1.6002) (xy -0.8001 -1.6002)
				(xy -0.8001 1.5875) (xy -1.5621 1.5875) (xy -1.5621 -2.4511) (xy 1.5621 -2.4511) (xy 1.5621 2.4511)
			)
			(stroke
				(width 0)
				(type default)
			)
			(fill no)
			(layer "F.CrtYd")
		)
		(fp_rect
			(start -1.5621 2.4511)
			(end 1.5621 -2.4511)
			(stroke
				(width 0)
				(type default)
			)
			(fill no)
			(layer "F.Fab")
		)
		(pad "1" smd rect
			(at 0 -1.392936 90)
			(size 2.1082 1.4478)
			(layers "F.Cu" "F.Mask" "F.Paste")
			(net "P12V_B_COMP")
		)
		(pad "2" smd rect
			(at 0 1.392936 90)
			(size 2.1082 1.4478)
			(layers "F.Cu" "F.Mask" "F.Paste")
			(net "GND")
		)
	)
	(footprint ""
		(layer "F.Cu")
		(at 456.0189 -181.842918 180)
		(property "Reference" "C326"
			(at 0 0 180)
			(layer "F.SilkS")
			(hide yes)
			(effects
				(font
					(size 1.27 1.27)
				)
			)
		)
		(property "Value" "SC1U16V3KX-5GP"
			(at 0 -2.8194 180)
			(unlocked yes)
			(layer "F.Fab")
			(hide yes)
			(effects
				(font
					(size 1.016 1.016)
					(thickness 0.1524)
				)
			)
		)
		(property "Device Type" "C603H36"
			(at 0 -4.3434 180)
			(unlocked yes)
			(layer "F.Fab")
			(hide yes)
			(effects
				(font
					(size 1.016 1.016)
					(thickness 0.1524)
				)
			)
		)
		(duplicate_pad_numbers_are_jumpers no)
		(fp_line
			(start 0.508 0)
			(end -0.508 0)
			(stroke
				(width 0.2032)
				(type default)
			)
			(layer "F.SilkS")
		)
		(fp_rect
			(start -0.5842 1.3335)
			(end 0.5842 -1.3335)
			(stroke
				(width 0)
				(type default)
			)
			(fill no)
			(layer "F.CrtYd")
		)
		(fp_rect
			(start -0.5842 1.3335)
			(end 0.5842 -1.3335)
			(stroke
				(width 0)
				(type default)
			)
			(fill no)
			(layer "F.Fab")
		)
		(pad "1" smd custom
			(at 0 -0.762 180)
			(size 0.2159 0.2159)
			(layers "F.Cu" "F.Mask" "F.Paste")
			(net "P5V_HDD22")
			(options
				(clearance outline)
				(anchor circle)
			)
			(primitives
				(gr_poly
					(pts
						(arc
							(start -0.3302 -0.4318)
							(mid -0.402042 -0.402042)
							(end -0.4318 -0.3302)
						)
						(arc
							(start -0.4318 0.3302)
							(mid -0.402042 0.402042)
							(end -0.3302 0.4318)
						)
						(arc
							(start 0.3302 0.4318)
							(mid 0.402042 0.402042)
							(end 0.4318 0.3302)
						)
						(arc
							(start 0.4318 -0.3302)
							(mid 0.402042 -0.402042)
							(end 0.3302 -0.4318)
						)
					)
					(width 0)
					(fill yes)
				)
			)
		)
		(pad "2" smd custom
			(at 0 0.762 180)
			(size 0.2159 0.2159)
			(layers "F.Cu" "F.Mask" "F.Paste")
			(net "GND")
			(options
				(clearance outline)
				(anchor circle)
			)
			(primitives
				(gr_poly
					(pts
						(arc
							(start -0.3302 -0.4318)
							(mid -0.402042 -0.402042)
							(end -0.4318 -0.3302)
						)
						(arc
							(start -0.4318 0.3302)
							(mid -0.402042 0.402042)
							(end -0.3302 0.4318)
						)
						(arc
							(start 0.3302 0.4318)
							(mid 0.402042 0.402042)
							(end 0.4318 0.3302)
						)
						(arc
							(start 0.4318 -0.3302)
							(mid 0.402042 -0.402042)
							(end 0.3302 -0.4318)
						)
					)
					(width 0)
					(fill yes)
				)
			)
		)
	)
	(footprint ""
		(layer "F.Cu")
		(at 130.274568 -187.489846)
		(property "Reference" "R471"
			(at 0 0 0)
			(layer "F.SilkS")
			(hide yes)
			(effects
				(font
					(size 1.27 1.27)
				)
			)
		)
		(property "Value" "4K7R2J-2-GP"
			(at 0.064008 -3.993896 0)
			(unlocked yes)
			(layer "F.Fab")
			(hide yes)
			(effects
				(font
					(size 1.016 1.016)
					(thickness 0.1524)
				)
			)
		)
		(property "Device Type" "R402H16"
			(at 0.064008 -5.517896 0)
			(unlocked yes)
			(layer "F.Fab")
			(hide yes)
			(effects
				(font
					(size 1.016 1.016)
					(thickness 0.1524)
				)
			)
		)
		(duplicate_pad_numbers_are_jumpers no)
		(fp_line
			(start -0.508 -0.9398)
			(end -0.508 0.9398)
			(stroke
				(width 0.1524)
				(type default)
			)
			(layer "F.SilkS")
		)
		(fp_line
			(start 0.508 -0.9398)
			(end -0.508 -0.9398)
			(stroke
				(width 0.1524)
				(type default)
			)
			(layer "F.SilkS")
		)
		(fp_rect
			(start -0.508 0.9398)
			(end 0.508 -0.9398)
			(stroke
				(width 0)
				(type default)
			)
			(fill no)
			(layer "F.CrtYd")
		)
		(fp_rect
			(start -0.508 0.9398)
			(end 0.508 -0.9398)
			(stroke
				(width 0)
				(type default)
			)
			(fill no)
			(layer "F.Fab")
		)
		(pad "1" smd custom
			(at 0 -0.4445)
			(size 0.1397 0.1397)
			(layers "F.Cu" "F.Mask" "F.Paste")
			(net "DRIVE_A_4_FLT_LED")
			(options
				(clearance outline)
				(anchor circle)
			)
			(primitives
				(gr_poly
					(pts
						(arc
							(start -0.1778 -0.2794)
							(mid -0.249642 -0.249642)
							(end -0.2794 -0.1778)
						)
						(arc
							(start -0.2794 0.1778)
							(mid -0.249642 0.249642)
							(end -0.1778 0.2794)
						)
						(arc
							(start 0.1778 0.2794)
							(mid 0.249642 0.249642)
							(end 0.2794 0.1778)
						)
						(arc
							(start 0.2794 -0.1778)
							(mid 0.249642 -0.249642)
							(end 0.1778 -0.2794)
						)
					)
					(width 0)
					(fill yes)
				)
			)
		)
		(pad "2" smd custom
			(at 0 0.4445)
			(size 0.1397 0.1397)
			(layers "F.Cu" "F.Mask" "F.Paste")
			(net "GND")
			(options
				(clearance outline)
				(anchor circle)
			)
			(primitives
				(gr_poly
					(pts
						(arc
							(start -0.1778 -0.2794)
							(mid -0.249642 -0.249642)
							(end -0.2794 -0.1778)
						)
						(arc
							(start -0.2794 0.1778)
							(mid -0.249642 0.249642)
							(end -0.1778 0.2794)
						)
						(arc
							(start 0.1778 0.2794)
							(mid 0.249642 0.249642)
							(end 0.2794 0.1778)
						)
						(arc
							(start 0.2794 -0.1778)
							(mid 0.249642 -0.249642)
							(end 0.1778 -0.2794)
						)
					)
					(width 0)
					(fill yes)
				)
			)
		)
	)
	(footprint ""
		(layer "F.Cu")
		(at 190.258954 -162.749992 -90)
		(property "Reference" "VIA56"
			(at 0 0 270)
			(layer "F.SilkS")
			(hide yes)
			(effects
				(font
					(size 1.27 1.27)
				)
			)
		)
		(property "Value" "100OHM-8L-1D6MM-L18L16-GP"
			(at -3.7211 -4.5085 270)
			(unlocked yes)
			(layer "F.Fab")
			(hide yes)
			(effects
				(font
					(size 1.016 1.016)
					(thickness 0.1524)
				)
			)
		)
		(property "Device Type" "VIA-PCIE-4P-394076"
			(at -3.7211 -6.0325 270)
			(unlocked yes)
			(layer "F.Fab")
			(hide yes)
			(effects
				(font
					(size 1.016 1.016)
					(thickness 0.1524)
				)
			)
		)
		(duplicate_pad_numbers_are_jumpers no)
		(fp_rect
			(start -1.9685 0.381)
			(end 1.9685 -0.381)
			(stroke
				(width 0)
				(type default)
			)
			(fill no)
			(layer "F.CrtYd")
		)
		(fp_rect
			(start -1.9685 0.381)
			(end 1.9685 -0.381)
			(stroke
				(width 0)
				(type default)
			)
			(fill no)
			(layer "F.Fab")
		)
		(pad "1" thru_hole circle
			(at -1.5875 0 270)
			(size 0.508 0.508)
			(drill 0.254)
			(layers "*.Cu" "*.Mask")
			(remove_unused_layers no)
			(net "GND")
			(clearance 0.127)
			(thermal_gap 0.127)
		)
		(pad "2" thru_hole circle
			(at -0.5715 0 270)
			(size 0.508 0.508)
			(drill 0.254)
			(layers "*.Cu" "*.Mask")
			(remove_unused_layers no)
			(net "PHY_DRV_A_TO_SCC_A_17_DP")
			(clearance 0.127)
			(thermal_gap 0.127)
		)
		(pad "3" thru_hole circle
			(at 0.5715 0 270)
			(size 0.508 0.508)
			(drill 0.254)
			(layers "*.Cu" "*.Mask")
			(remove_unused_layers no)
			(net "PHY_DRV_A_TO_SCC_A_17_DN")
			(clearance 0.127)
			(thermal_gap 0.127)
		)
		(pad "4" thru_hole circle
			(at 1.5875 0 270)
			(size 0.508 0.508)
			(drill 0.254)
			(layers "*.Cu" "*.Mask")
			(remove_unused_layers no)
			(net "GND")
			(clearance 0.127)
			(thermal_gap 0.127)
		)
	)
	(footprint ""
		(layer "F.Cu")
		(at 257.345688 -138.482578 90)
		(property "Reference" "R1003"
			(at 0 0 90)
			(layer "F.SilkS")
			(hide yes)
			(effects
				(font
					(size 1.27 1.27)
				)
			)
		)
		(property "Value" "100KR2F-L1-GP"
			(at 0.064008 -3.993896 90)
			(unlocked yes)
			(layer "F.Fab")
			(hide yes)
			(effects
				(font
					(size 1.016 1.016)
					(thickness 0.1524)
				)
			)
		)
		(property "Device Type" "R402H16"
			(at 0.064008 -5.517896 90)
			(unlocked yes)
			(layer "F.Fab")
			(hide yes)
			(effects
				(font
					(size 1.016 1.016)
					(thickness 0.1524)
				)
			)
		)
		(duplicate_pad_numbers_are_jumpers no)
		(fp_line
			(start 0.508 -0.9398)
			(end -0.508 -0.9398)
			(stroke
				(width 0.1524)
				(type default)
			)
			(layer "F.SilkS")
		)
		(fp_line
			(start -0.508 -0.9398)
			(end -0.508 0.9398)
			(stroke
				(width 0.1524)
				(type default)
			)
			(layer "F.SilkS")
		)
		(fp_rect
			(start -0.508 0.9398)
			(end 0.508 -0.9398)
			(stroke
				(width 0)
				(type default)
			)
			(fill no)
			(layer "F.CrtYd")
		)
		(fp_rect
			(start -0.508 0.9398)
			(end 0.508 -0.9398)
			(stroke
				(width 0)
				(type default)
			)
			(fill no)
			(layer "F.Fab")
		)
		(pad "1" smd custom
			(at 0 -0.4445 90)
			(size 0.1397 0.1397)
			(layers "F.Cu" "F.Mask" "F.Paste")
			(net "PCIE_COMP_A_TO_IOM_A_RST_2")
			(options
				(clearance outline)
				(anchor circle)
			)
			(primitives
				(gr_poly
					(pts
						(arc
							(start -0.1778 -0.2794)
							(mid -0.249642 -0.249642)
							(end -0.2794 -0.1778)
						)
						(arc
							(start -0.2794 0.1778)
							(mid -0.249642 0.249642)
							(end -0.1778 0.2794)
						)
						(arc
							(start 0.1778 0.2794)
							(mid 0.249642 0.249642)
							(end 0.2794 0.1778)
						)
						(arc
							(start 0.2794 -0.1778)
							(mid 0.249642 -0.249642)
							(end 0.1778 -0.2794)
						)
					)
					(width 0)
					(fill yes)
				)
			)
		)
		(pad "2" smd custom
			(at 0 0.4445 90)
			(size 0.1397 0.1397)
			(layers "F.Cu" "F.Mask" "F.Paste")
			(net "GND")
			(options
				(clearance outline)
				(anchor circle)
			)
			(primitives
				(gr_poly
					(pts
						(arc
							(start -0.1778 -0.2794)
							(mid -0.249642 -0.249642)
							(end -0.2794 -0.1778)
						)
						(arc
							(start -0.2794 0.1778)
							(mid -0.249642 0.249642)
							(end -0.1778 0.2794)
						)
						(arc
							(start 0.1778 0.2794)
							(mid 0.249642 0.249642)
							(end 0.2794 0.1778)
						)
						(arc
							(start 0.2794 -0.1778)
							(mid 0.249642 -0.249642)
							(end 0.1778 -0.2794)
						)
					)
					(width 0)
					(fill yes)
				)
			)
		)
	)
	(footprint ""
		(layer "F.Cu")
		(at 95.563436 -274.219416 90)
		(property "Reference" "C64"
			(at 0 0 90)
			(layer "F.SilkS")
			(hide yes)
			(effects
				(font
					(size 1.27 1.27)
				)
			)
		)
		(property "Value" "SCD01U16V1KX-GP"
			(at -2.8321 -1.7399 90)
			(unlocked yes)
			(layer "F.Fab")
			(hide yes)
			(effects
				(font
					(size 1.016 1.016)
					(thickness 0.1524)
				)
			)
		)
		(property "Device Type" "C0201H13"
			(at -2.8321 -3.2639 90)
			(unlocked yes)
			(layer "F.Fab")
			(hide yes)
			(effects
				(font
					(size 1.016 1.016)
					(thickness 0.1524)
				)
			)
		)
		(duplicate_pad_numbers_are_jumpers no)
		(fp_rect
			(start -0.2794 0.6477)
			(end 0.2794 -0.6477)
			(stroke
				(width 0)
				(type default)
			)
			(fill no)
			(layer "F.CrtYd")
		)
		(fp_rect
			(start -0.2794 0.6477)
			(end 0.2794 -0.6477)
			(stroke
				(width 0)
				(type default)
			)
			(fill no)
			(layer "F.Fab")
		)
		(pad "1" smd custom
			(at 0 -0.2794 90)
			(size 0.0762 0.0762)
			(layers "F.Cu" "F.Mask" "F.Paste")
			(net "SAS_HDD_RX_N2")
			(options
				(clearance outline)
				(anchor circle)
			)
			(primitives
				(gr_poly
					(pts
						(arc
							(start 0.1524 -0.127)
							(mid 0.137521 -0.162921)
							(end 0.1016 -0.1778)
						)
						(arc
							(start -0.1016 -0.1778)
							(mid -0.137521 -0.162921)
							(end -0.1524 -0.127)
						)
						(arc
							(start -0.1524 0.127)
							(mid -0.137521 0.162921)
							(end -0.1016 0.1778)
						)
						(arc
							(start 0.1016 0.1778)
							(mid 0.137521 0.162921)
							(end 0.1524 0.127)
						)
					)
					(width 0)
					(fill yes)
				)
			)
		)
		(pad "2" smd custom
			(at 0 0.2794 90)
			(size 0.0762 0.0762)
			(layers "F.Cu" "F.Mask" "F.Paste")
			(net "PHY_SCC_A_TO_DRV_A_2_DN")
			(options
				(clearance outline)
				(anchor circle)
			)
			(primitives
				(gr_poly
					(pts
						(arc
							(start 0.1524 -0.127)
							(mid 0.137521 -0.162921)
							(end 0.1016 -0.1778)
						)
						(arc
							(start -0.1016 -0.1778)
							(mid -0.137521 -0.162921)
							(end -0.1524 -0.127)
						)
						(arc
							(start -0.1524 0.127)
							(mid -0.137521 0.162921)
							(end -0.1016 0.1778)
						)
						(arc
							(start 0.1016 0.1778)
							(mid 0.137521 0.162921)
							(end 0.1524 0.127)
						)
					)
					(width 0)
					(fill yes)
				)
			)
		)
	)
	(footprint ""
		(layer "F.Cu")
		(at 356.289102 -162.749992 -90)
		(property "Reference" "VIA27"
			(at 0 0 270)
			(layer "F.SilkS")
			(hide yes)
			(effects
				(font
					(size 1.27 1.27)
				)
			)
		)
		(property "Value" "100OHM-8L-1D6MM-L18L16-GP"
			(at -3.7211 -4.5085 270)
			(unlocked yes)
			(layer "F.Fab")
			(hide yes)
			(effects
				(font
					(size 1.016 1.016)
					(thickness 0.1524)
				)
			)
		)
		(property "Device Type" "VIA-PCIE-4P-394076"
			(at -3.7211 -6.0325 270)
			(unlocked yes)
			(layer "F.Fab")
			(hide yes)
			(effects
				(font
					(size 1.016 1.016)
					(thickness 0.1524)
				)
			)
		)
		(duplicate_pad_numbers_are_jumpers no)
		(fp_rect
			(start -1.9685 0.381)
			(end 1.9685 -0.381)
			(stroke
				(width 0)
				(type default)
			)
			(fill no)
			(layer "F.CrtYd")
		)
		(fp_rect
			(start -1.9685 0.381)
			(end 1.9685 -0.381)
			(stroke
				(width 0)
				(type default)
			)
			(fill no)
			(layer "F.Fab")
		)
		(pad "1" thru_hole circle
			(at -1.5875 0 270)
			(size 0.508 0.508)
			(drill 0.254)
			(layers "*.Cu" "*.Mask")
			(remove_unused_layers no)
			(net "GND")
			(clearance 0.127)
			(thermal_gap 0.127)
		)
		(pad "2" thru_hole circle
			(at -0.5715 0 270)
			(size 0.508 0.508)
			(drill 0.254)
			(layers "*.Cu" "*.Mask")
			(remove_unused_layers no)
			(net "PHY_DRV_A_TO_SCC_A_19_DP")
			(clearance 0.127)
			(thermal_gap 0.127)
		)
		(pad "3" thru_hole circle
			(at 0.5715 0 270)
			(size 0.508 0.508)
			(drill 0.254)
			(layers "*.Cu" "*.Mask")
			(remove_unused_layers no)
			(net "PHY_DRV_A_TO_SCC_A_19_DN")
			(clearance 0.127)
			(thermal_gap 0.127)
		)
		(pad "4" thru_hole circle
			(at 1.5875 0 270)
			(size 0.508 0.508)
			(drill 0.254)
			(layers "*.Cu" "*.Mask")
			(remove_unused_layers no)
			(net "GND")
			(clearance 0.127)
			(thermal_gap 0.127)
		)
	)
	(footprint ""
		(layer "F.Cu")
		(at 80.900016 -324.39991)
		(property "Reference" "RLED27"
			(at 0 0 0)
			(layer "F.SilkS")
			(hide yes)
			(effects
				(font
					(size 1.27 1.27)
				)
			)
		)
		(property "Value" "LED-BY-19-GP"
			(at -2.132076 1.414018 0)
			(unlocked yes)
			(layer "F.Fab")
			(hide yes)
			(effects
				(font
					(size 1.016 1.016)
					(thickness 0.1524)
				)
			)
		)
		(property "Device Type" "LED-1615-4PH26"
			(at -2.132076 -0.109982 0)
			(unlocked yes)
			(layer "F.Fab")
			(hide yes)
			(effects
				(font
					(size 1.016 1.016)
					(thickness 0.1524)
				)
			)
		)
		(duplicate_pad_numbers_are_jumpers no)
		(fp_line
			(start -1.2954 0.254)
			(end -1.2954 1.6002)
			(stroke
				(width 0.508)
				(type default)
			)
			(layer "F.SilkS")
		)
		(fp_line
			(start -1.2954 1.6002)
			(end 1.2954 1.6002)
			(stroke
				(width 0.508)
				(type default)
			)
			(layer "F.SilkS")
		)
		(fp_line
			(start -1.1176 -1.4224)
			(end 1.1176 -1.4224)
			(stroke
				(width 0.1524)
				(type default)
			)
			(layer "F.SilkS")
		)
		(fp_line
			(start -1.1176 1.4224)
			(end -1.1176 -1.4224)
			(stroke
				(width 0.1524)
				(type default)
			)
			(layer "F.SilkS")
		)
		(fp_line
			(start 1.1176 -1.4224)
			(end 1.1176 1.4224)
			(stroke
				(width 0.1524)
				(type default)
			)
			(layer "F.SilkS")
		)
		(fp_line
			(start 1.1176 1.4224)
			(end -1.1176 1.4224)
			(stroke
				(width 0.1524)
				(type default)
			)
			(layer "F.SilkS")
		)
		(fp_line
			(start 1.2954 1.6002)
			(end 1.2954 0.254)
			(stroke
				(width 0.508)
				(type default)
			)
			(layer "F.SilkS")
		)
		(fp_rect
			(start -0.7493 0.8001)
			(end 0.7493 -0.8001)
			(stroke
				(width 0)
				(type default)
			)
			(fill no)
			(layer "F.CrtYd")
		)
		(fp_poly
			(pts
				(xy -1.3716 1.6764) (xy -1.3716 -1.6764) (xy 1.3716 -1.6764) (xy 1.3716 0.0635) (xy 0.7493 0.0635)
				(xy 0.7493 -0.8001) (xy -0.7493 -0.8001) (xy -0.7493 0.8001) (xy 0.7493 0.8001) (xy 0.7493 0.0762)
				(xy 1.3716 0.0762) (xy 1.3716 1.6764)
			)
			(stroke
				(width 0)
				(type default)
			)
			(fill no)
			(layer "F.CrtYd")
		)
		(fp_rect
			(start -1.3716 1.6764)
			(end 1.3716 -1.6764)
			(stroke
				(width 0)
				(type default)
			)
			(fill no)
			(layer "F.Fab")
		)
		(pad "1" smd rect
			(at 0.50038 -0.73025)
			(size 0.7112 0.8636)
			(layers "F.Cu" "F.Mask" "F.Paste")
			(net "DRV_ACT_26")
		)
		(pad "2" smd rect
			(at -0.50038 -0.73025)
			(size 0.7112 0.8636)
			(layers "F.Cu" "F.Mask" "F.Paste")
			(net "FLT_HDD26")
		)
		(pad "3" smd rect
			(at 0.50038 0.73025)
			(size 0.7112 0.8636)
			(layers "F.Cu" "F.Mask" "F.Paste")
			(net "DRV_ACT_26_N")
		)
		(pad "4" smd rect
			(at -0.50038 0.73025)
			(size 0.7112 0.8636)
			(layers "F.Cu" "F.Mask" "F.Paste")
			(net "FLT_HDD26_N")
		)
	)
	(footprint ""
		(layer "F.Cu")
		(at 143.072866 -130.894074)
		(property "Reference" "C546"
			(at 0 0 0)
			(layer "F.SilkS")
			(hide yes)
			(effects
				(font
					(size 1.27 1.27)
				)
			)
		)
		(property "Value" "SC2D2U25V5KX-2-GP"
			(at -0.0762 -6.1214 0)
			(unlocked yes)
			(layer "F.Fab")
			(hide yes)
			(effects
				(font
					(size 1.016 1.016)
					(thickness 0.1524)
				)
			)
		)
		(property "Device Type" "C805H54"
			(at -0.0762 -8.1534 0)
			(unlocked yes)
			(layer "F.Fab")
			(hide yes)
			(effects
				(font
					(size 1.016 1.016)
					(thickness 0.1524)
				)
			)
		)
		(duplicate_pad_numbers_are_jumpers no)
		(fp_line
			(start 0.635 0)
			(end -0.635 0)
			(stroke
				(width 0.508)
				(type default)
			)
			(layer "F.SilkS")
		)
		(fp_rect
			(start -0.9652 1.778)
			(end 0.9652 -1.778)
			(stroke
				(width 0)
				(type default)
			)
			(fill no)
			(layer "F.CrtYd")
		)
		(fp_poly
			(pts
				(xy -0.9652 -1.778) (xy 0.9652 -1.778) (xy 0.9652 1.778) (xy -0.9652 1.778)
			)
			(stroke
				(width 0)
				(type default)
			)
			(fill no)
			(layer "F.Fab")
		)
		(pad "1" smd rect
			(at 0 -0.9652)
			(size 1.397 1.143)
			(layers "F.Cu" "F.Mask" "F.Paste")
			(net "COMP_A_PGOOD")
		)
		(pad "2" smd rect
			(at 0 0.9652)
			(size 1.397 1.143)
			(layers "F.Cu" "F.Mask" "F.Paste")
			(net "GND")
		)
	)
	(footprint ""
		(layer "F.Cu")
		(at 365.0488 -143.4084 180)
		(property "Reference" "R1071"
			(at 0 0 180)
			(layer "F.SilkS")
			(hide yes)
			(effects
				(font
					(size 1.27 1.27)
				)
			)
		)
		(property "Value" "100R2D-GP"
			(at 0.064008 -3.993896 180)
			(unlocked yes)
			(layer "F.Fab")
			(hide yes)
			(effects
				(font
					(size 1.016 1.016)
					(thickness 0.1524)
				)
			)
		)
		(property "Device Type" "R402H14"
			(at 0.064008 -5.517896 180)
			(unlocked yes)
			(layer "F.Fab")
			(hide yes)
			(effects
				(font
					(size 1.016 1.016)
					(thickness 0.1524)
				)
			)
		)
		(duplicate_pad_numbers_are_jumpers no)
		(fp_line
			(start 0.508 -0.9398)
			(end -0.508 -0.9398)
			(stroke
				(width 0.1524)
				(type default)
			)
			(layer "F.SilkS")
		)
		(fp_line
			(start -0.508 -0.9398)
			(end -0.508 0.9398)
			(stroke
				(width 0.1524)
				(type default)
			)
			(layer "F.SilkS")
		)
		(fp_rect
			(start -0.508 0.9398)
			(end 0.508 -0.9398)
			(stroke
				(width 0)
				(type default)
			)
			(fill no)
			(layer "F.CrtYd")
		)
		(fp_rect
			(start -0.508 0.9398)
			(end 0.508 -0.9398)
			(stroke
				(width 0)
				(type default)
			)
			(fill no)
			(layer "F.Fab")
		)
		(pad "1" smd custom
			(at 0 -0.4445 180)
			(size 0.1397 0.1397)
			(layers "F.Cu" "F.Mask" "F.Paste")
			(net "MB1_TEMP")
			(options
				(clearance outline)
				(anchor circle)
			)
			(primitives
				(gr_poly
					(pts
						(arc
							(start -0.1778 -0.2794)
							(mid -0.249642 -0.249642)
							(end -0.2794 -0.1778)
						)
						(arc
							(start -0.2794 0.1778)
							(mid -0.249642 0.249642)
							(end -0.1778 0.2794)
						)
						(arc
							(start 0.1778 0.2794)
							(mid 0.249642 0.249642)
							(end 0.2794 0.1778)
						)
						(arc
							(start 0.2794 -0.1778)
							(mid 0.249642 -0.249642)
							(end 0.1778 -0.2794)
						)
					)
					(width 0)
					(fill yes)
				)
			)
		)
		(pad "2" smd custom
			(at 0 0.4445 180)
			(size 0.1397 0.1397)
			(layers "F.Cu" "F.Mask" "F.Paste")
			(net "MB1_TEMP_B")
			(options
				(clearance outline)
				(anchor circle)
			)
			(primitives
				(gr_poly
					(pts
						(arc
							(start -0.1778 -0.2794)
							(mid -0.249642 -0.249642)
							(end -0.2794 -0.1778)
						)
						(arc
							(start -0.2794 0.1778)
							(mid -0.249642 0.249642)
							(end -0.1778 0.2794)
						)
						(arc
							(start 0.1778 0.2794)
							(mid 0.249642 0.249642)
							(end 0.2794 0.1778)
						)
						(arc
							(start 0.2794 -0.1778)
							(mid 0.249642 -0.249642)
							(end 0.1778 -0.2794)
						)
					)
					(width 0)
					(fill yes)
				)
			)
		)
	)
	(footprint ""
		(layer "F.Cu")
		(at 341.376762 -33.995868 90)
		(property "Reference" "R379"
			(at 0 0 90)
			(layer "F.SilkS")
			(hide yes)
			(effects
				(font
					(size 1.27 1.27)
				)
			)
		)
		(property "Value" "100KR2F-L1-GP"
			(at 0.064008 -3.993896 90)
			(unlocked yes)
			(layer "F.Fab")
			(hide yes)
			(effects
				(font
					(size 1.016 1.016)
					(thickness 0.1524)
				)
			)
		)
		(property "Device Type" "R402H16"
			(at 0.064008 -5.517896 90)
			(unlocked yes)
			(layer "F.Fab")
			(hide yes)
			(effects
				(font
					(size 1.016 1.016)
					(thickness 0.1524)
				)
			)
		)
		(duplicate_pad_numbers_are_jumpers no)
		(fp_line
			(start 0.508 -0.9398)
			(end -0.508 -0.9398)
			(stroke
				(width 0.1524)
				(type default)
			)
			(layer "F.SilkS")
		)
		(fp_line
			(start -0.508 -0.9398)
			(end -0.508 0.9398)
			(stroke
				(width 0.1524)
				(type default)
			)
			(layer "F.SilkS")
		)
		(fp_rect
			(start -0.508 0.9398)
			(end 0.508 -0.9398)
			(stroke
				(width 0)
				(type default)
			)
			(fill no)
			(layer "F.CrtYd")
		)
		(fp_rect
			(start -0.508 0.9398)
			(end 0.508 -0.9398)
			(stroke
				(width 0)
				(type default)
			)
			(fill no)
			(layer "F.Fab")
		)
		(pad "1" smd custom
			(at 0 -0.4445 90)
			(size 0.1397 0.1397)
			(layers "F.Cu" "F.Mask" "F.Paste")
			(net "P3V3_STBY_B")
			(options
				(clearance outline)
				(anchor circle)
			)
			(primitives
				(gr_poly
					(pts
						(arc
							(start -0.1778 -0.2794)
							(mid -0.249642 -0.249642)
							(end -0.2794 -0.1778)
						)
						(arc
							(start -0.2794 0.1778)
							(mid -0.249642 0.249642)
							(end -0.1778 0.2794)
						)
						(arc
							(start 0.1778 0.2794)
							(mid 0.249642 0.249642)
							(end 0.2794 0.1778)
						)
						(arc
							(start 0.2794 -0.1778)
							(mid 0.249642 -0.249642)
							(end 0.1778 -0.2794)
						)
					)
					(width 0)
					(fill yes)
				)
			)
		)
		(pad "2" smd custom
			(at 0 0.4445 90)
			(size 0.1397 0.1397)
			(layers "F.Cu" "F.Mask" "F.Paste")
			(net "IOM_B_INS_N")
			(options
				(clearance outline)
				(anchor circle)
			)
			(primitives
				(gr_poly
					(pts
						(arc
							(start -0.1778 -0.2794)
							(mid -0.249642 -0.249642)
							(end -0.2794 -0.1778)
						)
						(arc
							(start -0.2794 0.1778)
							(mid -0.249642 0.249642)
							(end -0.1778 0.2794)
						)
						(arc
							(start 0.1778 0.2794)
							(mid 0.249642 0.249642)
							(end 0.2794 0.1778)
						)
						(arc
							(start 0.2794 -0.1778)
							(mid 0.249642 -0.249642)
							(end 0.1778 -0.2794)
						)
					)
					(width 0)
					(fill yes)
				)
			)
		)
	)
	(footprint ""
		(layer "F.Cu")
		(at 95.563436 -159.219392 90)
		(property "Reference" "C220"
			(at 0 0 90)
			(layer "F.SilkS")
			(hide yes)
			(effects
				(font
					(size 1.27 1.27)
				)
			)
		)
		(property "Value" "SCD01U16V1KX-GP"
			(at -2.8321 -1.7399 90)
			(unlocked yes)
			(layer "F.Fab")
			(hide yes)
			(effects
				(font
					(size 1.016 1.016)
					(thickness 0.1524)
				)
			)
		)
		(property "Device Type" "C0201H13"
			(at -2.8321 -3.2639 90)
			(unlocked yes)
			(layer "F.Fab")
			(hide yes)
			(effects
				(font
					(size 1.016 1.016)
					(thickness 0.1524)
				)
			)
		)
		(duplicate_pad_numbers_are_jumpers no)
		(fp_rect
			(start -0.2794 0.6477)
			(end 0.2794 -0.6477)
			(stroke
				(width 0)
				(type default)
			)
			(fill no)
			(layer "F.CrtYd")
		)
		(fp_rect
			(start -0.2794 0.6477)
			(end 0.2794 -0.6477)
			(stroke
				(width 0)
				(type default)
			)
			(fill no)
			(layer "F.Fab")
		)
		(pad "1" smd custom
			(at 0 -0.2794 90)
			(size 0.0762 0.0762)
			(layers "F.Cu" "F.Mask" "F.Paste")
			(net "SAS_HDD_RX_N14")
			(options
				(clearance outline)
				(anchor circle)
			)
			(primitives
				(gr_poly
					(pts
						(arc
							(start 0.1524 -0.127)
							(mid 0.137521 -0.162921)
							(end 0.1016 -0.1778)
						)
						(arc
							(start -0.1016 -0.1778)
							(mid -0.137521 -0.162921)
							(end -0.1524 -0.127)
						)
						(arc
							(start -0.1524 0.127)
							(mid -0.137521 0.162921)
							(end -0.1016 0.1778)
						)
						(arc
							(start 0.1016 0.1778)
							(mid 0.137521 0.162921)
							(end 0.1524 0.127)
						)
					)
					(width 0)
					(fill yes)
				)
			)
		)
		(pad "2" smd custom
			(at 0 0.2794 90)
			(size 0.0762 0.0762)
			(layers "F.Cu" "F.Mask" "F.Paste")
			(net "PHY_SCC_A_TO_DRV_A_14_DN")
			(options
				(clearance outline)
				(anchor circle)
			)
			(primitives
				(gr_poly
					(pts
						(arc
							(start 0.1524 -0.127)
							(mid 0.137521 -0.162921)
							(end 0.1016 -0.1778)
						)
						(arc
							(start -0.1016 -0.1778)
							(mid -0.137521 -0.162921)
							(end -0.1524 -0.127)
						)
						(arc
							(start -0.1524 0.127)
							(mid -0.137521 0.162921)
							(end -0.1016 0.1778)
						)
						(arc
							(start 0.1016 0.1778)
							(mid 0.137521 0.162921)
							(end 0.1524 0.127)
						)
					)
					(width 0)
					(fill yes)
				)
			)
		)
	)
	(footprint ""
		(layer "F.Cu")
		(at 175.550068 -209.399886)
		(property "Reference" "FLED6"
			(at 0 0 0)
			(layer "F.SilkS")
			(hide yes)
			(effects
				(font
					(size 1.27 1.27)
				)
			)
		)
		(property "Value" "LED-BY-19-GP"
			(at -2.132076 1.414018 0)
			(unlocked yes)
			(layer "F.Fab")
			(hide yes)
			(effects
				(font
					(size 1.016 1.016)
					(thickness 0.1524)
				)
			)
		)
		(property "Device Type" "LED-1615-4PH26"
			(at -2.132076 -0.109982 0)
			(unlocked yes)
			(layer "F.Fab")
			(hide yes)
			(effects
				(font
					(size 1.016 1.016)
					(thickness 0.1524)
				)
			)
		)
		(duplicate_pad_numbers_are_jumpers no)
		(fp_line
			(start -1.2954 0.254)
			(end -1.2954 1.6002)
			(stroke
				(width 0.508)
				(type default)
			)
			(layer "F.SilkS")
		)
		(fp_line
			(start -1.2954 1.6002)
			(end 1.2954 1.6002)
			(stroke
				(width 0.508)
				(type default)
			)
			(layer "F.SilkS")
		)
		(fp_line
			(start -1.1176 -1.4224)
			(end 1.1176 -1.4224)
			(stroke
				(width 0.1524)
				(type default)
			)
			(layer "F.SilkS")
		)
		(fp_line
			(start -1.1176 1.4224)
			(end -1.1176 -1.4224)
			(stroke
				(width 0.1524)
				(type default)
			)
			(layer "F.SilkS")
		)
		(fp_line
			(start 1.1176 -1.4224)
			(end 1.1176 1.4224)
			(stroke
				(width 0.1524)
				(type default)
			)
			(layer "F.SilkS")
		)
		(fp_line
			(start 1.1176 1.4224)
			(end -1.1176 1.4224)
			(stroke
				(width 0.1524)
				(type default)
			)
			(layer "F.SilkS")
		)
		(fp_line
			(start 1.2954 1.6002)
			(end 1.2954 0.254)
			(stroke
				(width 0.508)
				(type default)
			)
			(layer "F.SilkS")
		)
		(fp_rect
			(start -0.7493 0.8001)
			(end 0.7493 -0.8001)
			(stroke
				(width 0)
				(type default)
			)
			(fill no)
			(layer "F.CrtYd")
		)
		(fp_poly
			(pts
				(xy -1.3716 1.6764) (xy -1.3716 -1.6764) (xy 1.3716 -1.6764) (xy 1.3716 0.0635) (xy 0.7493 0.0635)
				(xy 0.7493 -0.8001) (xy -0.7493 -0.8001) (xy -0.7493 0.8001) (xy 0.7493 0.8001) (xy 0.7493 0.0762)
				(xy 1.3716 0.0762) (xy 1.3716 1.6764)
			)
			(stroke
				(width 0)
				(type default)
			)
			(fill no)
			(layer "F.CrtYd")
		)
		(fp_rect
			(start -1.3716 1.6764)
			(end 1.3716 -1.6764)
			(stroke
				(width 0)
				(type default)
			)
			(fill no)
			(layer "F.Fab")
		)
		(pad "1" smd rect
			(at 0.50038 -0.73025)
			(size 0.7112 0.8636)
			(layers "F.Cu" "F.Mask" "F.Paste")
			(net "DRV_ACT_5")
		)
		(pad "2" smd rect
			(at -0.50038 -0.73025)
			(size 0.7112 0.8636)
			(layers "F.Cu" "F.Mask" "F.Paste")
			(net "FLT_HDD5")
		)
		(pad "3" smd rect
			(at 0.50038 0.73025)
			(size 0.7112 0.8636)
			(layers "F.Cu" "F.Mask" "F.Paste")
			(net "DRV_ACT_5_N")
		)
		(pad "4" smd rect
			(at -0.50038 0.73025)
			(size 0.7112 0.8636)
			(layers "F.Cu" "F.Mask" "F.Paste")
			(net "FLT_HDD5_N")
		)
	)
	(footprint ""
		(layer "F.Cu")
		(at 460.5909 -282.872942 -90)
		(property "Reference" "Q60"
			(at 0 0 270)
			(layer "F.SilkS")
			(hide yes)
			(effects
				(font
					(size 1.27 1.27)
				)
			)
		)
		(property "Value" "AO4406AL-GP"
			(at -3.707384 -1.5367 270)
			(unlocked yes)
			(layer "F.Fab")
			(hide yes)
			(effects
				(font
					(size 1.016 1.016)
					(thickness 0.1524)
				)
			)
		)
		(property "Device Type" "SOIC8H69"
			(at -3.707384 -3.0607 270)
			(unlocked yes)
			(layer "F.Fab")
			(hide yes)
			(effects
				(font
					(size 1.016 1.016)
					(thickness 0.1524)
				)
			)
		)
		(duplicate_pad_numbers_are_jumpers no)
		(fp_line
			(start -2.6289 3.4417)
			(end -2.6289 1.4732)
			(stroke
				(width 0.381)
				(type default)
			)
			(layer "F.SilkS")
		)
		(fp_line
			(start -2.7432 1.4224)
			(end -2.6416 1.4224)
			(stroke
				(width 0.1524)
				(type default)
			)
			(layer "F.SilkS")
		)
		(fp_line
			(start -2.7432 1.4224)
			(end 2.1336 1.4224)
			(stroke
				(width 0.1524)
				(type default)
			)
			(layer "F.SilkS")
		)
		(fp_line
			(start 2.1336 1.4224)
			(end 2.1336 -1.4224)
			(stroke
				(width 0.1524)
				(type default)
			)
			(layer "F.SilkS")
		)
		(fp_line
			(start -2.1844 -0.0508)
			(end -2.7178 0.508)
			(stroke
				(width 0.1524)
				(type default)
			)
			(layer "F.SilkS")
		)
		(fp_line
			(start -2.7178 -0.508)
			(end -2.1844 -0.0508)
			(stroke
				(width 0.1524)
				(type default)
			)
			(layer "F.SilkS")
		)
		(fp_line
			(start -2.7432 -1.4224)
			(end -2.7432 1.4224)
			(stroke
				(width 0.1524)
				(type default)
			)
			(layer "F.SilkS")
		)
		(fp_line
			(start 2.1336 -1.4224)
			(end -2.7432 -1.4224)
			(stroke
				(width 0.1524)
				(type default)
			)
			(layer "F.SilkS")
		)
		(fp_poly
			(pts
				(xy -2.2098 -1.4224) (xy -2.2098 1.4224) (xy 2.2098 1.4224) (xy 2.2098 -1.4224)
			)
			(stroke
				(width 0)
				(type default)
			)
			(fill yes)
			(layer "F.SilkS")
		)
		(fp_rect
			(start -2.450084 2.999994)
			(end 2.450084 -2.999994)
			(stroke
				(width 0)
				(type default)
			)
			(fill no)
			(layer "F.CrtYd")
		)
		(fp_poly
			(pts
				(xy -2.8194 3.6322) (xy -2.8194 -3.6322) (xy 2.8194 -3.6322) (xy 2.8194 1.18364) (xy 2.450084 1.18364)
				(xy 2.450084 -2.999994) (xy -2.450084 -2.999994) (xy -2.450084 2.999994) (xy 2.450084 2.999994)
				(xy 2.450084 1.18618) (xy 2.8194 1.18618) (xy 2.8194 3.6322)
			)
			(stroke
				(width 0)
				(type default)
			)
			(fill no)
			(layer "F.CrtYd")
		)
		(fp_rect
			(start -2.8194 3.6322)
			(end 2.8194 -3.6322)
			(stroke
				(width 0)
				(type default)
			)
			(fill no)
			(layer "F.Fab")
		)
		(pad "1" smd rect
			(at -1.905 2.54 270)
			(size 0.635 1.651)
			(layers "F.Cu" "F.Mask" "F.Paste")
			(net "P5V_HDD10")
		)
		(pad "2" smd rect
			(at -0.635 2.54 270)
			(size 0.635 1.651)
			(layers "F.Cu" "F.Mask" "F.Paste")
			(net "P5V_HDD10")
		)
		(pad "3" smd rect
			(at 0.635 2.54 270)
			(size 0.635 1.651)
			(layers "F.Cu" "F.Mask" "F.Paste")
			(net "P5V_HDD10")
		)
		(pad "4" smd rect
			(at 1.905 2.54 270)
			(size 0.635 1.651)
			(layers "F.Cu" "F.Mask" "F.Paste")
			(net "SW_HDD_P10")
		)
		(pad "5" smd rect
			(at 1.905 -2.54 270)
			(size 0.635 1.651)
			(layers "F.Cu" "F.Mask" "F.Paste")
			(net "P5V_A_3")
		)
		(pad "6" smd rect
			(at 0.635 -2.54 270)
			(size 0.635 1.651)
			(layers "F.Cu" "F.Mask" "F.Paste")
			(net "P5V_A_3")
		)
		(pad "7" smd rect
			(at -0.635 -2.54 270)
			(size 0.635 1.651)
			(layers "F.Cu" "F.Mask" "F.Paste")
			(net "P5V_A_3")
		)
		(pad "8" smd rect
			(at -1.905 -2.54 270)
			(size 0.635 1.651)
			(layers "F.Cu" "F.Mask" "F.Paste")
			(net "P5V_A_3")
		)
	)
	(footprint ""
		(layer "F.Cu")
		(at 349.758 -295.0718 -90)
		(property "Reference" "R295"
			(at 0 0 270)
			(layer "F.SilkS")
			(hide yes)
			(effects
				(font
					(size 1.27 1.27)
				)
			)
		)
		(property "Value" "220R3F-1-GP"
			(at -0.0254 -2.5146 270)
			(unlocked yes)
			(layer "F.Fab")
			(hide yes)
			(effects
				(font
					(size 1.016 1.016)
					(thickness 0.1524)
				)
			)
		)
		(property "Device Type" "R603H22"
			(at -0.0254 -4.0386 270)
			(unlocked yes)
			(layer "F.Fab")
			(hide yes)
			(effects
				(font
					(size 1.016 1.016)
					(thickness 0.1524)
				)
			)
		)
		(duplicate_pad_numbers_are_jumpers no)
		(fp_line
			(start -0.4826 0)
			(end -0.2032 0)
			(stroke
				(width 0.2032)
				(type default)
			)
			(layer "F.SilkS")
		)
		(fp_line
			(start 0.2032 0)
			(end 0.4826 0)
			(stroke
				(width 0.2032)
				(type default)
			)
			(layer "F.SilkS")
		)
		(fp_rect
			(start -0.5842 1.3335)
			(end 0.5842 -1.3335)
			(stroke
				(width 0)
				(type default)
			)
			(fill no)
			(layer "F.CrtYd")
		)
		(fp_rect
			(start -0.5842 1.3335)
			(end 0.5842 -1.3335)
			(stroke
				(width 0)
				(type default)
			)
			(fill no)
			(layer "F.Fab")
		)
		(pad "1" smd custom
			(at 0 -0.762 270)
			(size 0.2159 0.2159)
			(layers "F.Cu" "F.Mask" "F.Paste")
			(net "HDD_PRSNT_7")
			(options
				(clearance outline)
				(anchor circle)
			)
			(primitives
				(gr_poly
					(pts
						(arc
							(start -0.3302 -0.4318)
							(mid -0.402042 -0.402042)
							(end -0.4318 -0.3302)
						)
						(arc
							(start -0.4318 0.3302)
							(mid -0.402042 0.402042)
							(end -0.3302 0.4318)
						)
						(arc
							(start 0.3302 0.4318)
							(mid 0.402042 0.402042)
							(end 0.4318 0.3302)
						)
						(arc
							(start 0.4318 -0.3302)
							(mid 0.402042 -0.402042)
							(end 0.3302 -0.4318)
						)
					)
					(width 0)
					(fill yes)
				)
			)
		)
		(pad "2" smd custom
			(at 0 0.762 270)
			(size 0.2159 0.2159)
			(layers "F.Cu" "F.Mask" "F.Paste")
			(net "DRIVE_A_7_INS")
			(options
				(clearance outline)
				(anchor circle)
			)
			(primitives
				(gr_poly
					(pts
						(arc
							(start -0.3302 -0.4318)
							(mid -0.402042 -0.402042)
							(end -0.4318 -0.3302)
						)
						(arc
							(start -0.4318 0.3302)
							(mid -0.402042 0.402042)
							(end -0.3302 0.4318)
						)
						(arc
							(start 0.3302 0.4318)
							(mid 0.402042 0.402042)
							(end 0.4318 0.3302)
						)
						(arc
							(start 0.4318 -0.3302)
							(mid 0.402042 -0.402042)
							(end 0.3302 -0.4318)
						)
					)
					(width 0)
					(fill yes)
				)
			)
		)
	)
	(footprint ""
		(layer "F.Cu")
		(at 286.100012 -406.699974 -90)
		(property "Reference" "PWR1"
			(at 0 0 270)
			(layer "F.SilkS")
			(hide yes)
			(effects
				(font
					(size 1.27 1.27)
				)
			)
		)
		(property "Value" "AMP-CONN8-2R-2-GP"
			(at 15.875 6.604 270)
			(unlocked yes)
			(layer "F.Fab")
			(hide yes)
			(effects
				(font
					(size 1.016 1.016)
					(thickness 0.1524)
				)
			)
		)
		(property "Device Type" "PREFIT-8P-5697-1H404"
			(at 15.875 5.08 270)
			(unlocked yes)
			(layer "F.Fab")
			(hide yes)
			(effects
				(font
					(size 1.016 1.016)
					(thickness 0.1524)
				)
			)
		)
		(duplicate_pad_numbers_are_jumpers no)
		(fp_line
			(start -1.4478 8.2804)
			(end -1.4478 -1.9558)
			(stroke
				(width 0.1524)
				(type default)
			)
			(layer "F.SilkS")
		)
		(fp_line
			(start 4.6482 8.2804)
			(end -1.4478 8.2804)
			(stroke
				(width 0.1524)
				(type default)
			)
			(layer "F.SilkS")
		)
		(fp_line
			(start -1.4478 -1.9558)
			(end 4.6482 -1.9558)
			(stroke
				(width 0.1524)
				(type default)
			)
			(layer "F.SilkS")
		)
		(fp_line
			(start 4.6482 -1.9558)
			(end 4.6482 8.2804)
			(stroke
				(width 0.1524)
				(type default)
			)
			(layer "F.SilkS")
		)
		(fp_poly
			(pts
				(xy -1.4478 8.2804) (xy -1.4478 -0.864616) (xy -0.8636 -0.864616) (xy -0.8636 8.128) (xy 4.063492 8.128)
				(xy 4.063492 -0.864616) (xy 4.6482 -0.864616) (xy 4.6482 8.2804)
			)
			(stroke
				(width 0)
				(type default)
			)
			(fill yes)
			(layer "F.SilkS")
		)
		(fp_poly
			(pts
				(arc
					(start 0.2032 7.8486)
					(mid 0 8.0518)
					(end -0.2032 7.8486)
				)
				(arc
					(start -0.2032 7.6454)
					(mid 0 7.4422)
					(end 0.2032 7.6454)
				)
			)
			(stroke
				(width 0)
				(type default)
			)
			(fill yes)
			(layer "F.SilkS")
		)
		(fp_poly
			(pts
				(arc
					(start 3.403092 7.8486)
					(mid 3.199892 8.0518)
					(end 2.996692 7.8486)
				)
				(arc
					(start 2.996692 7.6454)
					(mid 3.199892 7.4422)
					(end 3.403092 7.6454)
				)
			)
			(stroke
				(width 0)
				(type default)
			)
			(fill yes)
			(layer "F.SilkS")
		)
		(fp_rect
			(start -5.6134 11.938)
			(end 8.8138 -5.6134)
			(stroke
				(width 0)
				(type default)
			)
			(fill no)
			(layer "B.CrtYd")
		)
		(fp_rect
			(start -1.1938 8.0264)
			(end 4.3942 -1.7018)
			(stroke
				(width 0)
				(type default)
			)
			(fill no)
			(layer "F.CrtYd")
		)
		(fp_poly
			(pts
				(xy -6.1976 13.0302) (xy -6.1976 -6.7056) (xy 9.398 -6.7056) (xy 9.398 0) (xy 4.9022 0) (xy 4.9022 -2.2098)
				(xy -1.7018 -2.2098) (xy -1.7018 8.5344) (xy 4.9022 8.5344) (xy 4.9022 0.0127) (xy 9.398 0.0127)
				(xy 9.398 13.0302)
			)
			(stroke
				(width 0)
				(type default)
			)
			(fill no)
			(layer "F.CrtYd")
		)
		(fp_poly
			(pts
				(xy -1.7018 8.5344) (xy -1.7018 -2.2098) (xy 4.9022 -2.2098) (xy 4.9022 0) (xy 4.3942 0) (xy 4.3942 -1.7018)
				(xy -1.1938 -1.7018) (xy -1.1938 8.0264) (xy 4.3942 8.0264) (xy 4.3942 0.0127) (xy 4.9022 0.0127)
				(xy 4.9022 8.5344)
			)
			(stroke
				(width 0)
				(type default)
			)
			(fill no)
			(layer "F.CrtYd")
		)
		(fp_rect
			(start -10.6172 16.9418)
			(end 13.8176 -10.6172)
			(stroke
				(width 0)
				(type default)
			)
			(fill no)
			(layer "B.Fab")
		)
		(fp_rect
			(start -5.6134 11.938)
			(end 8.8138 -5.6134)
			(stroke
				(width 0)
				(type default)
			)
			(fill no)
			(layer "B.Fab")
		)
		(fp_rect
			(start -11.2014 18.034)
			(end 14.4018 -11.7094)
			(stroke
				(width 0)
				(type default)
			)
			(fill no)
			(layer "F.Fab")
		)
		(fp_rect
			(start -6.1976 13.0302)
			(end 9.398 -6.7056)
			(stroke
				(width 0)
				(type default)
			)
			(fill no)
			(layer "F.Fab")
		)
		(fp_rect
			(start -1.7018 8.5344)
			(end 4.9022 -2.2098)
			(stroke
				(width 0)
				(type default)
			)
			(fill no)
			(layer "F.Fab")
		)
		(fp_text user "Pre Fit"
			(at -1.778 -1.3462 270)
			(unlocked yes)
			(layer "F.SilkS")
			(effects
				(font
					(size 1.016 1.016)
					(thickness 0.1524)
				)
				(justify left)
			)
		)
		(fp_text user "Can not place BGA,CSP,Wave Solder Component"
			(at -24.9428 14.9352 270)
			(unlocked yes)
			(layer "B.Fab")
			(effects
				(font
					(size 1.016 1.016)
					(thickness 0.1524)
				)
				(justify left)
			)
		)
		(fp_text user "Can not place BGA,CSP,Wave Solder Component"
			(at -22.987 15.9258 270)
			(unlocked yes)
			(layer "F.Fab")
			(effects
				(font
					(size 1.016 1.016)
					(thickness 0.1524)
				)
				(justify left)
			)
		)
		(fp_text user "High Limit 2mm"
			(at -6.604 11.3538 270)
			(unlocked yes)
			(layer "F.Fab")
			(effects
				(font
					(size 1.016 1.016)
					(thickness 0.1524)
				)
				(justify left)
			)
		)
		(pad "A1" thru_hole oval
			(at 0 0 270)
			(size 1.2192 2.921)
			(drill 0.739902
				(offset 0 0.849884)
			)
			(layers "*.Cu" "*.Mask")
			(remove_unused_layers no)
			(net "P12V_A")
			(clearance 0.127)
			(thermal_gap 0.127)
			(padstack
				(mode front_inner_back)
				(layer "Inner"
					(shape circle)
					(size 1.2192 1.2192)
					(clearance 0.127)
				)
				(layer "B.Cu"
					(shape circle)
					(size 1.2192 1.2192)
					(clearance 0.127)
				)
			)
		)
		(pad "A2" thru_hole circle
			(at 0 1.700022 270)
			(size 1.2192 1.2192)
			(drill 0.739902)
			(layers "*.Cu" "*.Mask")
			(remove_unused_layers no)
			(net "P12V_A")
			(clearance 0.127)
			(thermal_gap 0.127)
		)
		(pad "A3" thru_hole oval
			(at 0 4.629912 270)
			(size 1.2192 2.921)
			(drill 0.739902
				(offset 0 0.849884)
			)
			(layers "*.Cu" "*.Mask")
			(remove_unused_layers no)
			(net "P12V_A")
			(clearance 0.127)
			(thermal_gap 0.127)
			(padstack
				(mode front_inner_back)
				(layer "Inner"
					(shape circle)
					(size 1.2192 1.2192)
					(clearance 0.127)
				)
				(layer "B.Cu"
					(shape circle)
					(size 1.2192 1.2192)
					(clearance 0.127)
				)
			)
		)
		(pad "A4" thru_hole circle
			(at 0 6.329934 270)
			(size 1.2192 1.2192)
			(drill 0.739902)
			(layers "*.Cu" "*.Mask")
			(remove_unused_layers no)
			(net "P12V_A")
			(clearance 0.127)
			(thermal_gap 0.127)
		)
		(pad "B1" thru_hole oval
			(at 3.199892 0 270)
			(size 1.2192 2.921)
			(drill 0.739902
				(offset 0 0.849884)
			)
			(layers "*.Cu" "*.Mask")
			(remove_unused_layers no)
			(net "GND")
			(clearance 0.127)
			(thermal_gap 0.127)
			(padstack
				(mode front_inner_back)
				(layer "Inner"
					(shape circle)
					(size 1.2192 1.2192)
					(clearance 0.127)
				)
				(layer "B.Cu"
					(shape circle)
					(size 1.2192 1.2192)
					(clearance 0.127)
				)
			)
		)
		(pad "B2" thru_hole circle
			(at 3.199892 1.700022 270)
			(size 1.2192 1.2192)
			(drill 0.739902)
			(layers "*.Cu" "*.Mask")
			(remove_unused_layers no)
			(net "GND")
			(clearance 0.127)
			(thermal_gap 0.127)
		)
		(pad "B3" thru_hole oval
			(at 3.199892 4.629912 270)
			(size 1.2192 2.921)
			(drill 0.739902
				(offset 0 0.849884)
			)
			(layers "*.Cu" "*.Mask")
			(remove_unused_layers no)
			(net "GND")
			(clearance 0.127)
			(thermal_gap 0.127)
			(padstack
				(mode front_inner_back)
				(layer "Inner"
					(shape circle)
					(size 1.2192 1.2192)
					(clearance 0.127)
				)
				(layer "B.Cu"
					(shape circle)
					(size 1.2192 1.2192)
					(clearance 0.127)
				)
			)
		)
		(pad "B4" thru_hole circle
			(at 3.199892 6.329934 270)
			(size 1.2192 1.2192)
			(drill 0.739902)
			(layers "*.Cu" "*.Mask")
			(remove_unused_layers no)
			(net "GND")
			(clearance 0.127)
			(thermal_gap 0.127)
		)
		(zone
			(layer "F.Cu")
			(hatch none 0.5)
			(connect_pads
				(clearance 0)
			)
			(min_thickness 0.25)
			(keepout
				(tracks allowed)
				(vias not_allowed)
				(pads allowed)
				(copperpour not_allowed)
				(footprints allowed)
			)
			(placement
				(enabled no)
				(sheetname "")
			)
			(fill
				(thermal_gap 0.5)
				(thermal_bridge_width 0.5)
				(island_removal_mode 0)
			)
			(polygon
				(pts
					(xy 278.91994 -407.549858) (xy 278.91994 -402.649944) (xy 286.949896 -402.649944) (xy 286.949896 -407.549858)
				)
			)
		)
		(zone
			(layer "F.Cu")
			(hatch none 0.5)
			(connect_pads
				(clearance 0)
			)
			(min_thickness 0.25)
			(keepout
				(tracks not_allowed)
				(vias allowed)
				(pads allowed)
				(copperpour not_allowed)
				(footprints allowed)
			)
			(placement
				(enabled no)
				(sheetname "")
			)
			(fill
				(thermal_gap 0.5)
				(thermal_bridge_width 0.5)
				(island_removal_mode 0)
			)
			(polygon
				(pts
					(xy 278.91994 -407.549858) (xy 278.91994 -402.649944) (xy 286.949896 -402.649944) (xy 286.949896 -407.549858)
				)
			)
		)
	)
	(footprint ""
		(layer "F.Cu")
		(at 256.286 -233.045 90)
		(property "Reference" "Q17"
			(at 0 0 90)
			(layer "F.SilkS")
			(hide yes)
			(effects
				(font
					(size 1.27 1.27)
				)
			)
		)
		(property "Value" "SSM3K324R-GP"
			(at 0.127 -8.9662 90)
			(unlocked yes)
			(layer "F.Fab")
			(hide yes)
			(effects
				(font
					(size 1.016 1.016)
					(thickness 0.1524)
				)
			)
		)
		(property "Device Type" "SOT23DGS2D4H35"
			(at 0.127 -10.4902 90)
			(unlocked yes)
			(layer "F.Fab")
			(hide yes)
			(effects
				(font
					(size 1.016 1.016)
					(thickness 0.1524)
				)
			)
		)
		(duplicate_pad_numbers_are_jumpers no)
		(fp_line
			(start 1.651 -1.778)
			(end -1.651 -1.778)
			(stroke
				(width 0.1524)
				(type default)
			)
			(layer "F.SilkS")
		)
		(fp_line
			(start -1.651 -1.778)
			(end -1.651 1.778)
			(stroke
				(width 0.1524)
				(type default)
			)
			(layer "F.SilkS")
		)
		(fp_line
			(start 1.651 1.778)
			(end 1.651 -1.778)
			(stroke
				(width 0.1524)
				(type default)
			)
			(layer "F.SilkS")
		)
		(fp_line
			(start -1.651 1.778)
			(end 1.651 1.778)
			(stroke
				(width 0.1524)
				(type default)
			)
			(layer "F.SilkS")
		)
		(fp_poly
			(pts
				(xy -1.778 1.8796) (xy -1.778 -1.8796) (xy 1.778 -1.8796) (xy 1.778 1.8796)
			)
			(stroke
				(width 0)
				(type default)
			)
			(fill no)
			(layer "F.CrtYd")
		)
		(fp_poly
			(pts
				(xy -1.778 1.8796) (xy -1.778 -1.8796) (xy 1.778 -1.8796) (xy 1.778 1.8796)
			)
			(stroke
				(width 0)
				(type default)
			)
			(fill no)
			(layer "F.Fab")
		)
		(pad "D" smd custom
			(at 0 -0.9525 90)
			(size 0.1905 0.1905)
			(layers "F.Cu" "F.Mask" "F.Paste")
			(net "P3V3_STBY_A")
			(options
				(clearance outline)
				(anchor circle)
			)
			(primitives
				(gr_poly
					(pts
						(arc
							(start -0.1778 0.5715)
							(mid -0.321484 0.511984)
							(end -0.381 0.3683)
						)
						(arc
							(start -0.381 -0.3683)
							(mid -0.321484 -0.511984)
							(end -0.1778 -0.5715)
						)
						(arc
							(start 0.1778 -0.5715)
							(mid 0.321484 -0.511984)
							(end 0.381 -0.3683)
						)
						(arc
							(start 0.381 0.3683)
							(mid 0.321484 0.511984)
							(end 0.1778 0.5715)
						)
					)
					(width 0)
					(fill yes)
				)
			)
		)
		(pad "G" smd custom
			(at -0.98425 0.9525 90)
			(size 0.1905 0.1905)
			(layers "F.Cu" "F.Mask" "F.Paste")
			(net "SCC_FULL_PWR_EN_5V")
			(options
				(clearance outline)
				(anchor circle)
			)
			(primitives
				(gr_poly
					(pts
						(arc
							(start -0.1778 0.5715)
							(mid -0.321484 0.511984)
							(end -0.381 0.3683)
						)
						(arc
							(start -0.381 -0.3683)
							(mid -0.321484 -0.511984)
							(end -0.1778 -0.5715)
						)
						(arc
							(start 0.1778 -0.5715)
							(mid 0.321484 -0.511984)
							(end 0.381 -0.3683)
						)
						(arc
							(start 0.381 0.3683)
							(mid 0.321484 0.511984)
							(end 0.1778 0.5715)
						)
					)
					(width 0)
					(fill yes)
				)
			)
		)
		(pad "S" smd custom
			(at 0.98425 0.9525 90)
			(size 0.1905 0.1905)
			(layers "F.Cu" "F.Mask" "F.Paste")
			(net "GPIO_VCC_U9")
			(options
				(clearance outline)
				(anchor circle)
			)
			(primitives
				(gr_poly
					(pts
						(arc
							(start -0.1778 0.5715)
							(mid -0.321484 0.511984)
							(end -0.381 0.3683)
						)
						(arc
							(start -0.381 -0.3683)
							(mid -0.321484 -0.511984)
							(end -0.1778 -0.5715)
						)
						(arc
							(start 0.1778 -0.5715)
							(mid 0.321484 -0.511984)
							(end 0.381 -0.3683)
						)
						(arc
							(start 0.381 0.3683)
							(mid 0.321484 0.511984)
							(end 0.1778 0.5715)
						)
					)
					(width 0)
					(fill yes)
				)
			)
		)
	)
	(footprint ""
		(layer "F.Cu")
		(at 444.6397 -65.039494 -90)
		(property "Reference" "R916"
			(at 0 0 270)
			(layer "F.SilkS")
			(hide yes)
			(effects
				(font
					(size 1.27 1.27)
				)
			)
		)
		(property "Value" "220R3F-1-GP"
			(at -0.0254 -2.5146 270)
			(unlocked yes)
			(layer "F.Fab")
			(hide yes)
			(effects
				(font
					(size 1.016 1.016)
					(thickness 0.1524)
				)
			)
		)
		(property "Device Type" "R603H22"
			(at -0.0254 -4.0386 270)
			(unlocked yes)
			(layer "F.Fab")
			(hide yes)
			(effects
				(font
					(size 1.016 1.016)
					(thickness 0.1524)
				)
			)
		)
		(duplicate_pad_numbers_are_jumpers no)
		(fp_line
			(start -0.4826 0)
			(end -0.2032 0)
			(stroke
				(width 0.2032)
				(type default)
			)
			(layer "F.SilkS")
		)
		(fp_line
			(start 0.2032 0)
			(end 0.4826 0)
			(stroke
				(width 0.2032)
				(type default)
			)
			(layer "F.SilkS")
		)
		(fp_rect
			(start -0.5842 1.3335)
			(end 0.5842 -1.3335)
			(stroke
				(width 0)
				(type default)
			)
			(fill no)
			(layer "F.CrtYd")
		)
		(fp_rect
			(start -0.5842 1.3335)
			(end 0.5842 -1.3335)
			(stroke
				(width 0)
				(type default)
			)
			(fill no)
			(layer "F.Fab")
		)
		(pad "1" smd custom
			(at 0 -0.762 270)
			(size 0.2159 0.2159)
			(layers "F.Cu" "F.Mask" "F.Paste")
			(net "HDD_PRSNT_34")
			(options
				(clearance outline)
				(anchor circle)
			)
			(primitives
				(gr_poly
					(pts
						(arc
							(start -0.3302 -0.4318)
							(mid -0.402042 -0.402042)
							(end -0.4318 -0.3302)
						)
						(arc
							(start -0.4318 0.3302)
							(mid -0.402042 0.402042)
							(end -0.3302 0.4318)
						)
						(arc
							(start 0.3302 0.4318)
							(mid 0.402042 0.402042)
							(end 0.4318 0.3302)
						)
						(arc
							(start 0.4318 -0.3302)
							(mid 0.402042 -0.402042)
							(end 0.3302 -0.4318)
						)
					)
					(width 0)
					(fill yes)
				)
			)
		)
		(pad "2" smd custom
			(at 0 0.762 270)
			(size 0.2159 0.2159)
			(layers "F.Cu" "F.Mask" "F.Paste")
			(net "DRIVE_A_34_INS")
			(options
				(clearance outline)
				(anchor circle)
			)
			(primitives
				(gr_poly
					(pts
						(arc
							(start -0.3302 -0.4318)
							(mid -0.402042 -0.402042)
							(end -0.4318 -0.3302)
						)
						(arc
							(start -0.4318 0.3302)
							(mid -0.402042 0.402042)
							(end -0.3302 0.4318)
						)
						(arc
							(start 0.3302 0.4318)
							(mid 0.402042 0.402042)
							(end 0.4318 0.3302)
						)
						(arc
							(start 0.4318 -0.3302)
							(mid 0.402042 -0.402042)
							(end 0.3302 -0.4318)
						)
					)
					(width 0)
					(fill yes)
				)
			)
		)
	)
	(footprint ""
		(layer "F.Cu")
		(at 412.912052 -176.127918 -90)
		(property "Reference" "C315"
			(at 0 0 270)
			(layer "F.SilkS")
			(hide yes)
			(effects
				(font
					(size 1.27 1.27)
				)
			)
		)
		(property "Value" "SCD01U50V2KX-1GP"
			(at 1.1811 -2.7051 270)
			(unlocked yes)
			(layer "F.Fab")
			(hide yes)
			(effects
				(font
					(size 1.016 1.016)
					(thickness 0.1524)
				)
			)
		)
		(property "Device Type" "C402H22"
			(at 1.1811 -4.2291 270)
			(unlocked yes)
			(layer "F.Fab")
			(hide yes)
			(effects
				(font
					(size 1.016 1.016)
					(thickness 0.1524)
				)
			)
		)
		(duplicate_pad_numbers_are_jumpers no)
		(fp_rect
			(start -0.4318 0.9525)
			(end 0.4318 -0.9525)
			(stroke
				(width 0)
				(type default)
			)
			(fill no)
			(layer "F.CrtYd")
		)
		(fp_rect
			(start -0.4318 0.9525)
			(end 0.4318 -0.9525)
			(stroke
				(width 0)
				(type default)
			)
			(fill no)
			(layer "F.Fab")
		)
		(pad "1" smd custom
			(at 0 -0.4445 270)
			(size 0.1524 0.1524)
			(layers "F.Cu" "F.Mask" "F.Paste")
			(net "HDD_PRSNT_21")
			(options
				(clearance outline)
				(anchor circle)
			)
			(primitives
				(gr_poly
					(pts
						(arc
							(start 0.3048 -0.2032)
							(mid 0.275042 -0.275042)
							(end 0.2032 -0.3048)
						)
						(arc
							(start -0.2032 -0.3048)
							(mid -0.275042 -0.275042)
							(end -0.3048 -0.2032)
						)
						(arc
							(start -0.3048 0.2032)
							(mid -0.275042 0.275042)
							(end -0.2032 0.3048)
						)
						(arc
							(start 0.2032 0.3048)
							(mid 0.275042 0.275042)
							(end 0.3048 0.2032)
						)
					)
					(width 0)
					(fill yes)
				)
			)
		)
		(pad "2" smd custom
			(at 0 0.4445 270)
			(size 0.1524 0.1524)
			(layers "F.Cu" "F.Mask" "F.Paste")
			(net "GND")
			(options
				(clearance outline)
				(anchor circle)
			)
			(primitives
				(gr_poly
					(pts
						(arc
							(start 0.3048 -0.2032)
							(mid 0.275042 -0.275042)
							(end 0.2032 -0.3048)
						)
						(arc
							(start -0.2032 -0.3048)
							(mid -0.275042 -0.275042)
							(end -0.3048 -0.2032)
						)
						(arc
							(start -0.3048 0.2032)
							(mid -0.275042 0.275042)
							(end -0.2032 0.3048)
						)
						(arc
							(start 0.2032 0.3048)
							(mid 0.275042 0.275042)
							(end 0.3048 0.2032)
						)
					)
					(width 0)
					(fill yes)
				)
			)
		)
	)
	(footprint ""
		(layer "F.Cu")
		(at 416.284664 -274.219416 -90)
		(property "Reference" "C155"
			(at 0 0 270)
			(layer "F.SilkS")
			(hide yes)
			(effects
				(font
					(size 1.27 1.27)
				)
			)
		)
		(property "Value" "SCD01U16V1KX-GP"
			(at -2.8321 -1.7399 270)
			(unlocked yes)
			(layer "F.Fab")
			(hide yes)
			(effects
				(font
					(size 1.016 1.016)
					(thickness 0.1524)
				)
			)
		)
		(property "Device Type" "C0201H13"
			(at -2.8321 -3.2639 270)
			(unlocked yes)
			(layer "F.Fab")
			(hide yes)
			(effects
				(font
					(size 1.016 1.016)
					(thickness 0.1524)
				)
			)
		)
		(duplicate_pad_numbers_are_jumpers no)
		(fp_rect
			(start -0.2794 0.6477)
			(end 0.2794 -0.6477)
			(stroke
				(width 0)
				(type default)
			)
			(fill no)
			(layer "F.CrtYd")
		)
		(fp_rect
			(start -0.2794 0.6477)
			(end 0.2794 -0.6477)
			(stroke
				(width 0)
				(type default)
			)
			(fill no)
			(layer "F.Fab")
		)
		(pad "1" smd custom
			(at 0 -0.2794 270)
			(size 0.0762 0.0762)
			(layers "F.Cu" "F.Mask" "F.Paste")
			(net "SAS_HDD_RX_N9")
			(options
				(clearance outline)
				(anchor circle)
			)
			(primitives
				(gr_poly
					(pts
						(arc
							(start 0.1524 -0.127)
							(mid 0.137521 -0.162921)
							(end 0.1016 -0.1778)
						)
						(arc
							(start -0.1016 -0.1778)
							(mid -0.137521 -0.162921)
							(end -0.1524 -0.127)
						)
						(arc
							(start -0.1524 0.127)
							(mid -0.137521 0.162921)
							(end -0.1016 0.1778)
						)
						(arc
							(start 0.1016 0.1778)
							(mid 0.137521 0.162921)
							(end 0.1524 0.127)
						)
					)
					(width 0)
					(fill yes)
				)
			)
		)
		(pad "2" smd custom
			(at 0 0.2794 270)
			(size 0.0762 0.0762)
			(layers "F.Cu" "F.Mask" "F.Paste")
			(net "PHY_SCC_A_TO_DRV_A_9_DN")
			(options
				(clearance outline)
				(anchor circle)
			)
			(primitives
				(gr_poly
					(pts
						(arc
							(start 0.1524 -0.127)
							(mid 0.137521 -0.162921)
							(end 0.1016 -0.1778)
						)
						(arc
							(start -0.1016 -0.1778)
							(mid -0.137521 -0.162921)
							(end -0.1524 -0.127)
						)
						(arc
							(start -0.1524 0.127)
							(mid -0.137521 0.162921)
							(end -0.1016 0.1778)
						)
						(arc
							(start 0.1016 0.1778)
							(mid 0.137521 0.162921)
							(end 0.1524 0.127)
						)
					)
					(width 0)
					(fill yes)
				)
			)
		)
	)
	(footprint ""
		(layer "F.Cu")
		(at 481.24999 -5.500116)
		(property "Reference" ""
			(at 0 0 0)
			(layer "F.SilkS")
			(hide yes)
			(effects
				(font
					(size 1.27 1.27)
				)
			)
		)
		(property "Value" "*"
			(at -4.729734 -0.095504 0)
			(unlocked yes)
			(layer "F.Fab")
			(hide yes)
			(effects
				(font
					(size 1.016 1.016)
					(thickness 0.1524)
				)
			)
		)
		(duplicate_pad_numbers_are_jumpers no)
		(fp_poly
			(pts
				(arc
					(start 4.064 0)
					(mid -4.064 0)
					(end 4.064 0)
				)
			)
			(stroke
				(width 0)
				(type default)
			)
			(fill no)
			(layer "B.CrtYd")
		)
		(fp_poly
			(pts
				(arc
					(start 4.064 0)
					(mid -4.064 0)
					(end 4.064 0)
				)
			)
			(stroke
				(width 0)
				(type default)
			)
			(fill no)
			(layer "F.CrtYd")
		)
		(fp_poly
			(pts
				(arc
					(start 4.064 0)
					(mid -4.064 0)
					(end 4.064 0)
				)
			)
			(stroke
				(width 0)
				(type default)
			)
			(fill no)
			(layer "B.Fab")
		)
		(fp_poly
			(pts
				(arc
					(start 4.064 0)
					(mid -4.064 0)
					(end 4.064 0)
				)
			)
			(stroke
				(width 0)
				(type default)
			)
			(fill no)
			(layer "F.Fab")
		)
		(pad "1" thru_hole circle
			(at 0 0)
			(size 7.5184 7.5184)
			(drill 4.2164)
			(layers "*.Cu" "*.Mask")
			(remove_unused_layers no)
			(net "Net_61")
			(clearance -1.143)
			(thermal_gap 0.3048)
			(padstack
				(mode front_inner_back)
				(layer "Inner"
					(shape circle)
					(size 4.6228 4.6228)
					(clearance 0.3048)
				)
				(layer "B.Cu"
					(shape circle)
					(size 7.5184 7.5184)
					(clearance -1.143)
				)
			)
		)
	)
	(footprint ""
		(layer "F.Cu")
		(at 394.56995 -73.954894 180)
		(property "Reference" "C461"
			(at 0 0 180)
			(layer "F.SilkS")
			(hide yes)
			(effects
				(font
					(size 1.27 1.27)
				)
			)
		)
		(property "Value" "SC4D7U25V5KX-1-GP"
			(at -0.0762 -6.1214 180)
			(unlocked yes)
			(layer "F.Fab")
			(hide yes)
			(effects
				(font
					(size 1.016 1.016)
					(thickness 0.1524)
				)
			)
		)
		(property "Device Type" "C805H58"
			(at -0.0762 -8.1534 180)
			(unlocked yes)
			(layer "F.Fab")
			(hide yes)
			(effects
				(font
					(size 1.016 1.016)
					(thickness 0.1524)
				)
			)
		)
		(duplicate_pad_numbers_are_jumpers no)
		(fp_line
			(start 0.635 0)
			(end -0.635 0)
			(stroke
				(width 0.508)
				(type default)
			)
			(layer "F.SilkS")
		)
		(fp_rect
			(start -0.9652 1.778)
			(end 0.9652 -1.778)
			(stroke
				(width 0)
				(type default)
			)
			(fill no)
			(layer "F.CrtYd")
		)
		(fp_poly
			(pts
				(xy -0.9652 -1.778) (xy 0.9652 -1.778) (xy 0.9652 1.778) (xy -0.9652 1.778)
			)
			(stroke
				(width 0)
				(type default)
			)
			(fill no)
			(layer "F.Fab")
		)
		(pad "1" smd rect
			(at 0 -0.9652 180)
			(size 1.397 1.143)
			(layers "F.Cu" "F.Mask" "F.Paste")
			(net "P12V_HDD32")
		)
		(pad "2" smd rect
			(at 0 0.9652 180)
			(size 1.397 1.143)
			(layers "F.Cu" "F.Mask" "F.Paste")
			(net "GND")
		)
	)
	(footprint ""
		(layer "F.Cu")
		(at 190.8302 -68.707)
		(property "Reference" "TP147"
			(at 0 0 0)
			(layer "F.SilkS")
			(hide yes)
			(effects
				(font
					(size 1.27 1.27)
				)
			)
		)
		(property "Value" "TPAD32-GP"
			(at -0.0508 -1.6764 0)
			(unlocked yes)
			(layer "F.Fab")
			(hide yes)
			(effects
				(font
					(size 1.016 1.016)
					(thickness 0.1524)
				)
			)
		)
		(property "Device Type" "TPAD32"
			(at -0.0508 -3.2004 0)
			(unlocked yes)
			(layer "F.Fab")
			(hide yes)
			(effects
				(font
					(size 1.016 1.016)
					(thickness 0.1524)
				)
			)
		)
		(duplicate_pad_numbers_are_jumpers no)
		(fp_poly
			(pts
				(arc
					(start 0.4064 0)
					(mid -0.4064 0)
					(end 0.4064 0)
				)
			)
			(stroke
				(width 0)
				(type default)
			)
			(fill no)
			(layer "F.CrtYd")
		)
		(fp_poly
			(pts
				(arc
					(start 0.7112 0)
					(mid -0.7112 0)
					(end 0.7112 0)
				)
			)
			(stroke
				(width 0)
				(type default)
			)
			(fill no)
			(layer "F.Fab")
		)
		(pad "1" smd circle
			(at 0 0)
			(size 0.8128 0.8128)
			(layers "F.Cu" "F.Mask" "F.Paste")
			(net "ACT_HDD_29")
		)
	)
	(footprint ""
		(layer "F.Cu")
		(at 320.990468 -242.210844)
		(property "Reference" "R241"
			(at 0 0 0)
			(layer "F.SilkS")
			(hide yes)
			(effects
				(font
					(size 1.27 1.27)
				)
			)
		)
		(property "Value" "130R3F-GP"
			(at -0.0254 -2.5146 0)
			(unlocked yes)
			(layer "F.Fab")
			(hide yes)
			(effects
				(font
					(size 1.016 1.016)
					(thickness 0.1524)
				)
			)
		)
		(property "Device Type" "R603H22"
			(at -0.0254 -4.0386 0)
			(unlocked yes)
			(layer "F.Fab")
			(hide yes)
			(effects
				(font
					(size 1.016 1.016)
					(thickness 0.1524)
				)
			)
		)
		(duplicate_pad_numbers_are_jumpers no)
		(fp_line
			(start -0.4826 0)
			(end -0.2032 0)
			(stroke
				(width 0.2032)
				(type default)
			)
			(layer "F.SilkS")
		)
		(fp_line
			(start 0.2032 0)
			(end 0.4826 0)
			(stroke
				(width 0.2032)
				(type default)
			)
			(layer "F.SilkS")
		)
		(fp_rect
			(start -0.5842 1.3335)
			(end 0.5842 -1.3335)
			(stroke
				(width 0)
				(type default)
			)
			(fill no)
			(layer "F.CrtYd")
		)
		(fp_rect
			(start -0.5842 1.3335)
			(end 0.5842 -1.3335)
			(stroke
				(width 0)
				(type default)
			)
			(fill no)
			(layer "F.Fab")
		)
		(pad "1" smd custom
			(at 0 -0.762)
			(size 0.2159 0.2159)
			(layers "F.Cu" "F.Mask" "F.Paste")
			(net "P5V_A_3")
			(options
				(clearance outline)
				(anchor circle)
			)
			(primitives
				(gr_poly
					(pts
						(arc
							(start -0.3302 -0.4318)
							(mid -0.402042 -0.402042)
							(end -0.4318 -0.3302)
						)
						(arc
							(start -0.4318 0.3302)
							(mid -0.402042 0.402042)
							(end -0.3302 0.4318)
						)
						(arc
							(start 0.3302 0.4318)
							(mid 0.402042 0.402042)
							(end 0.4318 0.3302)
						)
						(arc
							(start 0.4318 -0.3302)
							(mid 0.402042 -0.402042)
							(end 0.3302 -0.4318)
						)
					)
					(width 0)
					(fill yes)
				)
			)
		)
		(pad "2" smd custom
			(at 0 0.762)
			(size 0.2159 0.2159)
			(layers "F.Cu" "F.Mask" "F.Paste")
			(net "FLT_HDD6")
			(options
				(clearance outline)
				(anchor circle)
			)
			(primitives
				(gr_poly
					(pts
						(arc
							(start -0.3302 -0.4318)
							(mid -0.402042 -0.402042)
							(end -0.4318 -0.3302)
						)
						(arc
							(start -0.4318 0.3302)
							(mid -0.402042 0.402042)
							(end -0.3302 0.4318)
						)
						(arc
							(start 0.3302 0.4318)
							(mid 0.402042 0.402042)
							(end 0.4318 0.3302)
						)
						(arc
							(start 0.4318 -0.3302)
							(mid 0.402042 -0.402042)
							(end 0.3302 -0.4318)
						)
					)
					(width 0)
					(fill yes)
				)
			)
		)
	)
	(footprint ""
		(layer "F.Cu")
		(at 346.700094 -324.39991)
		(property "Reference" "RLED32"
			(at 0 0 0)
			(layer "F.SilkS")
			(hide yes)
			(effects
				(font
					(size 1.27 1.27)
				)
			)
		)
		(property "Value" "LED-BY-19-GP"
			(at -2.132076 1.414018 0)
			(unlocked yes)
			(layer "F.Fab")
			(hide yes)
			(effects
				(font
					(size 1.016 1.016)
					(thickness 0.1524)
				)
			)
		)
		(property "Device Type" "LED-1615-4PH26"
			(at -2.132076 -0.109982 0)
			(unlocked yes)
			(layer "F.Fab")
			(hide yes)
			(effects
				(font
					(size 1.016 1.016)
					(thickness 0.1524)
				)
			)
		)
		(duplicate_pad_numbers_are_jumpers no)
		(fp_line
			(start -1.2954 0.254)
			(end -1.2954 1.6002)
			(stroke
				(width 0.508)
				(type default)
			)
			(layer "F.SilkS")
		)
		(fp_line
			(start -1.2954 1.6002)
			(end 1.2954 1.6002)
			(stroke
				(width 0.508)
				(type default)
			)
			(layer "F.SilkS")
		)
		(fp_line
			(start -1.1176 -1.4224)
			(end 1.1176 -1.4224)
			(stroke
				(width 0.1524)
				(type default)
			)
			(layer "F.SilkS")
		)
		(fp_line
			(start -1.1176 1.4224)
			(end -1.1176 -1.4224)
			(stroke
				(width 0.1524)
				(type default)
			)
			(layer "F.SilkS")
		)
		(fp_line
			(start 1.1176 -1.4224)
			(end 1.1176 1.4224)
			(stroke
				(width 0.1524)
				(type default)
			)
			(layer "F.SilkS")
		)
		(fp_line
			(start 1.1176 1.4224)
			(end -1.1176 1.4224)
			(stroke
				(width 0.1524)
				(type default)
			)
			(layer "F.SilkS")
		)
		(fp_line
			(start 1.2954 1.6002)
			(end 1.2954 0.254)
			(stroke
				(width 0.508)
				(type default)
			)
			(layer "F.SilkS")
		)
		(fp_rect
			(start -0.7493 0.8001)
			(end 0.7493 -0.8001)
			(stroke
				(width 0)
				(type default)
			)
			(fill no)
			(layer "F.CrtYd")
		)
		(fp_poly
			(pts
				(xy -1.3716 1.6764) (xy -1.3716 -1.6764) (xy 1.3716 -1.6764) (xy 1.3716 0.0635) (xy 0.7493 0.0635)
				(xy 0.7493 -0.8001) (xy -0.7493 -0.8001) (xy -0.7493 0.8001) (xy 0.7493 0.8001) (xy 0.7493 0.0762)
				(xy 1.3716 0.0762) (xy 1.3716 1.6764)
			)
			(stroke
				(width 0)
				(type default)
			)
			(fill no)
			(layer "F.CrtYd")
		)
		(fp_rect
			(start -1.3716 1.6764)
			(end 1.3716 -1.6764)
			(stroke
				(width 0)
				(type default)
			)
			(fill no)
			(layer "F.Fab")
		)
		(pad "1" smd rect
			(at 0.50038 -0.73025)
			(size 0.7112 0.8636)
			(layers "F.Cu" "F.Mask" "F.Paste")
			(net "DRV_ACT_31")
		)
		(pad "2" smd rect
			(at -0.50038 -0.73025)
			(size 0.7112 0.8636)
			(layers "F.Cu" "F.Mask" "F.Paste")
			(net "FLT_HDD31")
		)
		(pad "3" smd rect
			(at 0.50038 0.73025)
			(size 0.7112 0.8636)
			(layers "F.Cu" "F.Mask" "F.Paste")
			(net "DRV_ACT_31_N")
		)
		(pad "4" smd rect
			(at -0.50038 0.73025)
			(size 0.7112 0.8636)
			(layers "F.Cu" "F.Mask" "F.Paste")
			(net "FLT_HDD31_N")
		)
	)
	(footprint ""
		(layer "F.Cu")
		(at 132.718302 -303.893728)
		(property "Reference" "Q255"
			(at 0 0 0)
			(layer "F.SilkS")
			(hide yes)
			(effects
				(font
					(size 1.27 1.27)
				)
			)
		)
		(property "Value" "2N7002K-2-GP"
			(at 0.127 -8.9662 0)
			(unlocked yes)
			(layer "F.Fab")
			(hide yes)
			(effects
				(font
					(size 1.016 1.016)
					(thickness 0.1524)
				)
			)
		)
		(property "Device Type" "SOT23DGS2D4H44"
			(at 0.127 -10.4902 0)
			(unlocked yes)
			(layer "F.Fab")
			(hide yes)
			(effects
				(font
					(size 1.016 1.016)
					(thickness 0.1524)
				)
			)
		)
		(duplicate_pad_numbers_are_jumpers no)
		(fp_line
			(start -1.651 -1.778)
			(end -1.651 1.778)
			(stroke
				(width 0.1524)
				(type default)
			)
			(layer "F.SilkS")
		)
		(fp_line
			(start -1.651 1.778)
			(end 1.651 1.778)
			(stroke
				(width 0.1524)
				(type default)
			)
			(layer "F.SilkS")
		)
		(fp_line
			(start 1.651 -1.778)
			(end -1.651 -1.778)
			(stroke
				(width 0.1524)
				(type default)
			)
			(layer "F.SilkS")
		)
		(fp_line
			(start 1.651 1.778)
			(end 1.651 -1.778)
			(stroke
				(width 0.1524)
				(type default)
			)
			(layer "F.SilkS")
		)
		(fp_poly
			(pts
				(xy -1.778 1.8796) (xy -1.778 -1.8796) (xy 1.778 -1.8796) (xy 1.778 1.8796)
			)
			(stroke
				(width 0)
				(type default)
			)
			(fill no)
			(layer "F.CrtYd")
		)
		(fp_poly
			(pts
				(xy -1.778 1.8796) (xy -1.778 -1.8796) (xy 1.778 -1.8796) (xy 1.778 1.8796)
			)
			(stroke
				(width 0)
				(type default)
			)
			(fill no)
			(layer "F.Fab")
		)
		(pad "D" smd custom
			(at 0 -0.9525)
			(size 0.1905 0.1905)
			(layers "F.Cu" "F.Mask" "F.Paste")
			(net "FLT_HDD28_N")
			(options
				(clearance outline)
				(anchor circle)
			)
			(primitives
				(gr_poly
					(pts
						(arc
							(start -0.1778 0.5715)
							(mid -0.321484 0.511984)
							(end -0.381 0.3683)
						)
						(arc
							(start -0.381 -0.3683)
							(mid -0.321484 -0.511984)
							(end -0.1778 -0.5715)
						)
						(arc
							(start 0.1778 -0.5715)
							(mid 0.321484 -0.511984)
							(end 0.381 -0.3683)
						)
						(arc
							(start 0.381 0.3683)
							(mid 0.321484 0.511984)
							(end 0.1778 0.5715)
						)
					)
					(width 0)
					(fill yes)
				)
			)
		)
		(pad "G" smd custom
			(at -0.98425 0.9525)
			(size 0.1905 0.1905)
			(layers "F.Cu" "F.Mask" "F.Paste")
			(net "DRIVE_B_28_FLT_LED")
			(options
				(clearance outline)
				(anchor circle)
			)
			(primitives
				(gr_poly
					(pts
						(arc
							(start -0.1778 0.5715)
							(mid -0.321484 0.511984)
							(end -0.381 0.3683)
						)
						(arc
							(start -0.381 -0.3683)
							(mid -0.321484 -0.511984)
							(end -0.1778 -0.5715)
						)
						(arc
							(start 0.1778 -0.5715)
							(mid 0.321484 -0.511984)
							(end 0.381 -0.3683)
						)
						(arc
							(start 0.381 0.3683)
							(mid 0.321484 0.511984)
							(end 0.1778 0.5715)
						)
					)
					(width 0)
					(fill yes)
				)
			)
		)
		(pad "S" smd custom
			(at 0.98425 0.9525)
			(size 0.1905 0.1905)
			(layers "F.Cu" "F.Mask" "F.Paste")
			(net "GND")
			(options
				(clearance outline)
				(anchor circle)
			)
			(primitives
				(gr_poly
					(pts
						(arc
							(start -0.1778 0.5715)
							(mid -0.321484 0.511984)
							(end -0.381 0.3683)
						)
						(arc
							(start -0.381 -0.3683)
							(mid -0.321484 -0.511984)
							(end -0.1778 -0.5715)
						)
						(arc
							(start 0.1778 -0.5715)
							(mid 0.321484 -0.511984)
							(end 0.381 -0.3683)
						)
						(arc
							(start 0.381 0.3683)
							(mid 0.321484 0.511984)
							(end 0.1778 0.5715)
						)
					)
					(width 0)
					(fill yes)
				)
			)
		)
	)
	(footprint ""
		(layer "F.Cu")
		(at 276.098 -272.288 180)
		(property "Reference" "R112"
			(at 0 0 180)
			(layer "F.SilkS")
			(hide yes)
			(effects
				(font
					(size 1.27 1.27)
				)
			)
		)
		(property "Value" "4K7R2F-GP"
			(at 0.064008 -3.993896 180)
			(unlocked yes)
			(layer "F.Fab")
			(hide yes)
			(effects
				(font
					(size 1.016 1.016)
					(thickness 0.1524)
				)
			)
		)
		(property "Device Type" "R402H16"
			(at 0.064008 -5.517896 180)
			(unlocked yes)
			(layer "F.Fab")
			(hide yes)
			(effects
				(font
					(size 1.016 1.016)
					(thickness 0.1524)
				)
			)
		)
		(duplicate_pad_numbers_are_jumpers no)
		(fp_line
			(start 0.508 -0.9398)
			(end -0.508 -0.9398)
			(stroke
				(width 0.1524)
				(type default)
			)
			(layer "F.SilkS")
		)
		(fp_line
			(start -0.508 -0.9398)
			(end -0.508 0.9398)
			(stroke
				(width 0.1524)
				(type default)
			)
			(layer "F.SilkS")
		)
		(fp_rect
			(start -0.508 0.9398)
			(end 0.508 -0.9398)
			(stroke
				(width 0)
				(type default)
			)
			(fill no)
			(layer "F.CrtYd")
		)
		(fp_rect
			(start -0.508 0.9398)
			(end 0.508 -0.9398)
			(stroke
				(width 0)
				(type default)
			)
			(fill no)
			(layer "F.Fab")
		)
		(pad "1" smd custom
			(at 0 -0.4445 180)
			(size 0.1397 0.1397)
			(layers "F.Cu" "F.Mask" "F.Paste")
			(net "P3V3_STBY_A")
			(options
				(clearance outline)
				(anchor circle)
			)
			(primitives
				(gr_poly
					(pts
						(arc
							(start -0.1778 -0.2794)
							(mid -0.249642 -0.249642)
							(end -0.2794 -0.1778)
						)
						(arc
							(start -0.2794 0.1778)
							(mid -0.249642 0.249642)
							(end -0.1778 0.2794)
						)
						(arc
							(start 0.1778 0.2794)
							(mid 0.249642 0.249642)
							(end 0.2794 0.1778)
						)
						(arc
							(start 0.2794 -0.1778)
							(mid 0.249642 -0.249642)
							(end 0.1778 -0.2794)
						)
					)
					(width 0)
					(fill yes)
				)
			)
		)
		(pad "2" smd custom
			(at 0 0.4445 180)
			(size 0.1397 0.1397)
			(layers "F.Cu" "F.Mask" "F.Paste")
			(net "IO_EXP1_HDD_FAULT_A2")
			(options
				(clearance outline)
				(anchor circle)
			)
			(primitives
				(gr_poly
					(pts
						(arc
							(start -0.1778 -0.2794)
							(mid -0.249642 -0.249642)
							(end -0.2794 -0.1778)
						)
						(arc
							(start -0.2794 0.1778)
							(mid -0.249642 0.249642)
							(end -0.1778 0.2794)
						)
						(arc
							(start 0.1778 0.2794)
							(mid 0.249642 0.249642)
							(end 0.2794 0.1778)
						)
						(arc
							(start 0.2794 -0.1778)
							(mid 0.249642 -0.249642)
							(end 0.1778 -0.2794)
						)
					)
					(width 0)
					(fill yes)
				)
			)
		)
	)
	(footprint ""
		(layer "F.Cu")
		(at 260.150102 29.249878 180)
		(property "Reference" "IO3"
			(at 0 0 180)
			(layer "F.SilkS")
			(hide yes)
			(effects
				(font
					(size 1.27 1.27)
				)
			)
		)
		(property "Value" "SKT-SAS15P-14P-45-GP"
			(at -20.7645 -8.9789 180)
			(unlocked yes)
			(layer "F.Fab")
			(hide yes)
			(effects
				(font
					(size 1.016 1.016)
					(thickness 0.1524)
				)
			)
		)
		(property "Device Type" "10120818-001C-TRLF"
			(at -20.7645 -10.5029 180)
			(unlocked yes)
			(layer "F.Fab")
			(hide yes)
			(effects
				(font
					(size 1.016 1.016)
					(thickness 0.1524)
				)
			)
		)
		(duplicate_pad_numbers_are_jumpers no)
		(fp_line
			(start 23.4188 3.0099)
			(end 8.509 3.0099)
			(stroke
				(width 0.1524)
				(type default)
			)
			(layer "F.SilkS")
		)
		(fp_line
			(start 23.4188 -3.2512)
			(end 23.4188 3.0099)
			(stroke
				(width 0.1524)
				(type default)
			)
			(layer "F.SilkS")
		)
		(fp_line
			(start 15.5067 -3.3401)
			(end 16.2687 -3.3401)
			(stroke
				(width 0.3302)
				(type default)
			)
			(layer "F.SilkS")
		)
		(fp_line
			(start 8.509 4.2926)
			(end 1.651 4.2926)
			(stroke
				(width 0.1524)
				(type default)
			)
			(layer "F.SilkS")
		)
		(fp_line
			(start 8.509 3.0099)
			(end 8.509 4.2926)
			(stroke
				(width 0.1524)
				(type default)
			)
			(layer "F.SilkS")
		)
		(fp_line
			(start 1.651 4.2926)
			(end 1.651 3.0099)
			(stroke
				(width 0.1524)
				(type default)
			)
			(layer "F.SilkS")
		)
		(fp_line
			(start 1.651 3.0099)
			(end -23.4188 3.0099)
			(stroke
				(width 0.1524)
				(type default)
			)
			(layer "F.SilkS")
		)
		(fp_line
			(start -23.4188 3.0099)
			(end -23.4188 -3.2512)
			(stroke
				(width 0.1524)
				(type default)
			)
			(layer "F.SilkS")
		)
		(fp_line
			(start -23.4188 -3.2512)
			(end 23.4188 -3.2512)
			(stroke
				(width 0.1524)
				(type default)
			)
			(layer "F.SilkS")
		)
		(fp_poly
			(pts
				(xy 15.868904 -3.230372) (xy 16.503904 -3.865372) (xy 15.233904 -3.865372)
			)
			(stroke
				(width 0)
				(type default)
			)
			(fill yes)
			(layer "F.SilkS")
		)
		(fp_poly
			(pts
				(xy -22.8727 -2.7559) (xy 22.8727 -2.7559) (xy 22.8727 2.7559) (xy 8.255 2.7559) (xy 8.255 3.5179)
				(xy 1.905 3.5179) (xy 1.905 2.7559) (xy -22.8727 2.7559)
			)
			(stroke
				(width 0)
				(type default)
			)
			(fill no)
			(layer "F.CrtYd")
		)
		(fp_poly
			(pts
				(xy 1.397 4.5466) (xy 1.397 3.2639) (xy -23.6728 3.2639) (xy -23.6728 -3.5052) (xy 23.6728 -3.5052)
				(xy 23.6728 -0.00635) (xy 22.8727 -0.00635) (xy 22.8727 -2.7559) (xy -22.8727 -2.7559) (xy -22.8727 2.7559)
				(xy 1.905 2.7559) (xy 1.905 3.5179) (xy 8.255 3.5179) (xy 8.255 2.7559) (xy 22.8727 2.7559) (xy 22.8727 0.00635)
				(xy 23.6728 0.00635) (xy 23.6728 3.2639) (xy 8.763 3.2639) (xy 8.763 4.5466)
			)
			(stroke
				(width 0)
				(type default)
			)
			(fill no)
			(layer "F.CrtYd")
		)
		(fp_poly
			(pts
				(xy 1.397 4.5466) (xy 1.397 3.2639) (xy -23.6728 3.2639) (xy -23.6728 -3.5052) (xy 23.6728 -3.5052)
				(xy 23.6728 3.2639) (xy 8.763 3.2639) (xy 8.763 4.5466)
			)
			(stroke
				(width 0)
				(type default)
			)
			(fill no)
			(layer "F.Fab")
		)
		(pad "" np_thru_hole circle
			(at -18.874994 0 180)
			(size 0.254 0.254)
			(drill 1.3462)
			(layers "*.Cu" "*.Mask")
			(clearance 0.9017)
			(thermal_gap 0.9017)
		)
		(pad "" np_thru_hole circle
			(at 18.874994 0 180)
			(size 0.254 0.254)
			(drill 0.9398)
			(layers "*.Cu" "*.Mask")
			(clearance 0.6985)
			(thermal_gap 0.6985)
		)
		(pad "G1" smd rect
			(at 21.874988 0 180)
			(size 2.5908 2.5908)
			(layers "F.Cu" "F.Mask" "F.Paste")
			(net "GND")
		)
		(pad "G2" smd rect
			(at -21.874988 0 180)
			(size 2.5908 2.5908)
			(layers "F.Cu" "F.Mask" "F.Paste")
			(net "GND")
		)
		(pad "P1" smd rect
			(at 1.905 -1.82499 180)
			(size 0.6096 2.3622)
			(layers "F.Cu" "F.Mask" "F.Paste")
			(net "P5V_USB_A")
		)
		(pad "P2" smd rect
			(at 0.635 -1.82499 180)
			(size 0.6096 2.3622)
			(layers "F.Cu" "F.Mask" "F.Paste")
			(net "P5V_USB_B")
		)
		(pad "P3" smd rect
			(at -0.635 -1.82499 180)
			(size 0.6096 2.3622)
			(layers "F.Cu" "F.Mask" "F.Paste")
			(net "ENCL_FAULT_LED_B")
		)
		(pad "P4" smd rect
			(at -1.905 -1.82499 180)
			(size 0.6096 2.3622)
			(layers "F.Cu" "F.Mask" "F.Paste")
			(net "SYS_PWR_LED_B")
		)
		(pad "P5" smd rect
			(at -3.175 -1.82499 180)
			(size 0.6096 2.3622)
			(layers "F.Cu" "F.Mask" "F.Paste")
			(net "P3V3_STBY_B")
		)
		(pad "P6" smd rect
			(at -4.445 -1.82499 180)
			(size 0.6096 2.3622)
			(layers "F.Cu" "F.Mask" "F.Paste")
			(net "RST_BTN_B_N")
		)
		(pad "P7" smd rect
			(at -5.715 -1.82499 180)
			(size 0.6096 2.3622)
			(layers "F.Cu" "F.Mask" "F.Paste")
			(net "GND")
		)
		(pad "P8" smd rect
			(at -6.985 -1.82499 180)
			(size 0.6096 2.3622)
			(layers "F.Cu" "F.Mask" "F.Paste")
			(net "I2C_DPB_B_SCL")
		)
		(pad "P9" smd rect
			(at -8.255 -1.82499 180)
			(size 0.6096 2.3622)
			(layers "F.Cu" "F.Mask" "F.Paste")
			(net "I2C_DPB_B_SDA")
		)
		(pad "P10" smd rect
			(at -9.525 -1.82499 180)
			(size 0.6096 2.3622)
			(layers "F.Cu" "F.Mask" "F.Paste")
			(net "DPB_PWR_BTN_B")
		)
		(pad "P11" smd rect
			(at -10.795 -1.82499 180)
			(size 0.6096 2.3622)
			(layers "F.Cu" "F.Mask" "F.Paste")
			(net "UART_IOC_B_TX")
		)
		(pad "P12" smd rect
			(at -12.065 -1.82499 180)
			(size 0.6096 2.3622)
			(layers "F.Cu" "F.Mask" "F.Paste")
			(net "UART_IOC_B_RX")
		)
		(pad "P13" smd rect
			(at -13.335 -1.82499 180)
			(size 0.6096 2.3622)
			(layers "F.Cu" "F.Mask" "F.Paste")
			(net "GND")
		)
		(pad "P14" smd rect
			(at -14.605 -1.82499 180)
			(size 0.6096 2.3622)
			(layers "F.Cu" "F.Mask" "F.Paste")
			(net "UART_EXP_B_TX")
		)
		(pad "P15" smd rect
			(at -15.875 -1.82499 180)
			(size 0.6096 2.3622)
			(layers "F.Cu" "F.Mask" "F.Paste")
			(net "UART_EXP_B_RX")
		)
		(pad "S1" smd rect
			(at 15.875 -1.82499 180)
			(size 0.6096 2.3622)
			(layers "F.Cu" "F.Mask" "F.Paste")
			(net "UART_EXP_A_TX")
		)
		(pad "S2" smd rect
			(at 14.605 -1.82499 180)
			(size 0.6096 2.3622)
			(layers "F.Cu" "F.Mask" "F.Paste")
			(net "UART_EXP_A_RX")
		)
		(pad "S3" smd rect
			(at 13.335 -1.82499 180)
			(size 0.6096 2.3622)
			(layers "F.Cu" "F.Mask" "F.Paste")
			(net "GND")
		)
		(pad "S4" smd rect
			(at 12.065 -1.82499 180)
			(size 0.6096 2.3622)
			(layers "F.Cu" "F.Mask" "F.Paste")
			(net "UART_IOC_A_TX")
		)
		(pad "S5" smd rect
			(at 10.795 -1.82499 180)
			(size 0.6096 2.3622)
			(layers "F.Cu" "F.Mask" "F.Paste")
			(net "UART_IOC_A_RX")
		)
		(pad "S6" smd rect
			(at 9.525 -1.82499 180)
			(size 0.6096 2.3622)
			(layers "F.Cu" "F.Mask" "F.Paste")
			(net "GND")
		)
		(pad "S7" smd rect
			(at 8.255 -1.82499 180)
			(size 0.6096 2.3622)
			(layers "F.Cu" "F.Mask" "F.Paste")
			(net "DPB_PWR_BTN_A")
		)
		(pad "S8" smd rect
			(at 7.480046 2.845054 180)
			(size 0.508 2.3622)
			(layers "F.Cu" "F.Mask" "F.Paste")
			(net "I2C_DPB_A_SCL_BUF")
		)
		(pad "S9" smd rect
			(at 6.679946 2.845054 180)
			(size 0.508 2.3622)
			(layers "F.Cu" "F.Mask" "F.Paste")
			(net "I2C_DPB_A_SDA_BUF")
		)
		(pad "S10" smd rect
			(at 5.8801 2.845054 180)
			(size 0.508 2.3622)
			(layers "F.Cu" "F.Mask" "F.Paste")
			(net "RST_BTN_A_N")
		)
		(pad "S11" smd rect
			(at 5.08 2.845054 180)
			(size 0.508 2.3622)
			(layers "F.Cu" "F.Mask" "F.Paste")
			(net "P3V3_STBY_A")
		)
		(pad "S12" smd rect
			(at 4.2799 2.845054 180)
			(size 0.508 2.3622)
			(layers "F.Cu" "F.Mask" "F.Paste")
			(net "SYS_PWR_LED_A")
		)
		(pad "S13" smd rect
			(at 3.480054 2.845054 180)
			(size 0.508 2.3622)
			(layers "F.Cu" "F.Mask" "F.Paste")
			(net "ENCL_FAULT_LED_A")
		)
		(pad "S14" smd rect
			(at 2.679954 2.845054 180)
			(size 0.508 2.3622)
			(layers "F.Cu" "F.Mask" "F.Paste")
			(net "Net_1196")
		)
		(zone
			(layer "F.Cu")
			(hatch none 0.5)
			(connect_pads
				(clearance 0)
			)
			(min_thickness 0.25)
			(keepout
				(tracks not_allowed)
				(vias allowed)
				(pads allowed)
				(copperpour not_allowed)
				(footprints allowed)
			)
			(placement
				(enabled no)
				(sheetname "")
			)
			(fill
				(thermal_gap 0.5)
				(thermal_bridge_width 0.5)
				(island_removal_mode 0)
			)
			(polygon
				(pts
					(xy 243.411502 32.907478) (xy 243.411502 25.833578) (xy 236.477302 25.833578) (xy 236.477302 26.938478)
					(xy 240.592102 26.938478) (xy 240.592102 31.561278) (xy 236.477302 31.561278) (xy 236.477302 32.907478)
				)
			)
		)
		(zone
			(layer "F.Cu")
			(hatch none 0.5)
			(connect_pads
				(clearance 0)
			)
			(min_thickness 0.25)
			(keepout
				(tracks allowed)
				(vias not_allowed)
				(pads allowed)
				(copperpour not_allowed)
				(footprints allowed)
			)
			(placement
				(enabled no)
				(sheetname "")
			)
			(fill
				(thermal_gap 0.5)
				(thermal_bridge_width 0.5)
				(island_removal_mode 0)
			)
			(polygon
				(pts
					(xy 243.411502 32.907478) (xy 243.411502 25.833578) (xy 236.477302 25.833578) (xy 236.477302 26.938478)
					(xy 240.592102 26.938478) (xy 240.592102 31.561278) (xy 236.477302 31.561278) (xy 236.477302 32.907478)
				)
			)
		)
		(zone
			(layer "F.Cu")
			(hatch none 0.5)
			(connect_pads
				(clearance 0)
			)
			(min_thickness 0.25)
			(keepout
				(tracks allowed)
				(vias not_allowed)
				(pads allowed)
				(copperpour not_allowed)
				(footprints allowed)
			)
			(placement
				(enabled no)
				(sheetname "")
			)
			(fill
				(thermal_gap 0.5)
				(thermal_bridge_width 0.5)
				(island_removal_mode 0)
			)
			(polygon
				(pts
					(xy 276.888702 32.907478) (xy 276.888702 25.833578) (xy 283.822902 25.833578) (xy 283.822902 26.938478)
					(xy 279.708102 26.938478) (xy 279.708102 31.561278) (xy 283.822902 31.561278) (xy 283.822902 32.907478)
				)
			)
		)
		(zone
			(layer "F.Cu")
			(hatch none 0.5)
			(connect_pads
				(clearance 0)
			)
			(min_thickness 0.25)
			(keepout
				(tracks not_allowed)
				(vias allowed)
				(pads allowed)
				(copperpour not_allowed)
				(footprints allowed)
			)
			(placement
				(enabled no)
				(sheetname "")
			)
			(fill
				(thermal_gap 0.5)
				(thermal_bridge_width 0.5)
				(island_removal_mode 0)
			)
			(polygon
				(pts
					(xy 276.888702 32.907478) (xy 276.888702 25.833578) (xy 283.822902 25.833578) (xy 283.822902 26.938478)
					(xy 279.708102 26.938478) (xy 279.708102 31.561278) (xy 283.822902 31.561278) (xy 283.822902 32.907478)
				)
			)
		)
		(zone
			(layers "F.Cu" "B.Cu" "In1.Cu" "In2.Cu" "In3.Cu" "In4.Cu" "In5.Cu" "In6.Cu"
				"In7.Cu" "In8.Cu" "In9.Cu" "In10.Cu"
			)
			(hatch none 0.5)
			(connect_pads
				(clearance 0)
			)
			(min_thickness 0.25)
			(keepout
				(tracks not_allowed)
				(vias allowed)
				(pads allowed)
				(copperpour not_allowed)
				(footprints allowed)
			)
			(placement
				(enabled no)
				(sheetname "")
			)
			(fill
				(thermal_gap 0.5)
				(thermal_bridge_width 0.5)
				(island_removal_mode 0)
			)
			(polygon
				(pts
					(arc
						(start 242.049808 29.249878)
						(mid 240.500408 29.249878)
						(end 242.049808 29.249878)
					)
				)
			)
		)
		(zone
			(layers "F.Cu" "B.Cu" "In1.Cu" "In2.Cu" "In3.Cu" "In4.Cu" "In5.Cu" "In6.Cu"
				"In7.Cu" "In8.Cu" "In9.Cu" "In10.Cu"
			)
			(hatch none 0.5)
			(connect_pads
				(clearance 0)
			)
			(min_thickness 0.25)
			(keepout
				(tracks not_allowed)
				(vias allowed)
				(pads allowed)
				(copperpour not_allowed)
				(footprints allowed)
			)
			(placement
				(enabled no)
				(sheetname "")
			)
			(fill
				(thermal_gap 0.5)
				(thermal_bridge_width 0.5)
				(island_removal_mode 0)
			)
			(polygon
				(pts
					(arc
						(start 280.002996 29.249878)
						(mid 278.047196 29.249878)
						(end 280.002996 29.249878)
					)
				)
			)
		)
	)
	(footprint ""
		(layer "F.Cu")
		(at 359.0036 -144.6784)
		(property "Reference" "R1072"
			(at 0 0 0)
			(layer "F.SilkS")
			(hide yes)
			(effects
				(font
					(size 1.27 1.27)
				)
			)
		)
		(property "Value" "100R2D-GP"
			(at 0.064008 -3.993896 0)
			(unlocked yes)
			(layer "F.Fab")
			(hide yes)
			(effects
				(font
					(size 1.016 1.016)
					(thickness 0.1524)
				)
			)
		)
		(property "Device Type" "R402H14"
			(at 0.064008 -5.517896 0)
			(unlocked yes)
			(layer "F.Fab")
			(hide yes)
			(effects
				(font
					(size 1.016 1.016)
					(thickness 0.1524)
				)
			)
		)
		(duplicate_pad_numbers_are_jumpers no)
		(fp_line
			(start -0.508 -0.9398)
			(end -0.508 0.9398)
			(stroke
				(width 0.1524)
				(type default)
			)
			(layer "F.SilkS")
		)
		(fp_line
			(start 0.508 -0.9398)
			(end -0.508 -0.9398)
			(stroke
				(width 0.1524)
				(type default)
			)
			(layer "F.SilkS")
		)
		(fp_rect
			(start -0.508 0.9398)
			(end 0.508 -0.9398)
			(stroke
				(width 0)
				(type default)
			)
			(fill no)
			(layer "F.CrtYd")
		)
		(fp_rect
			(start -0.508 0.9398)
			(end 0.508 -0.9398)
			(stroke
				(width 0)
				(type default)
			)
			(fill no)
			(layer "F.Fab")
		)
		(pad "1" smd custom
			(at 0 -0.4445)
			(size 0.1397 0.1397)
			(layers "F.Cu" "F.Mask" "F.Paste")
			(net "GND")
			(options
				(clearance outline)
				(anchor circle)
			)
			(primitives
				(gr_poly
					(pts
						(arc
							(start -0.1778 -0.2794)
							(mid -0.249642 -0.249642)
							(end -0.2794 -0.1778)
						)
						(arc
							(start -0.2794 0.1778)
							(mid -0.249642 0.249642)
							(end -0.1778 0.2794)
						)
						(arc
							(start 0.1778 0.2794)
							(mid 0.249642 0.249642)
							(end 0.2794 0.1778)
						)
						(arc
							(start 0.2794 -0.1778)
							(mid 0.249642 -0.249642)
							(end 0.1778 -0.2794)
						)
					)
					(width 0)
					(fill yes)
				)
			)
		)
		(pad "2" smd custom
			(at 0 0.4445)
			(size 0.1397 0.1397)
			(layers "F.Cu" "F.Mask" "F.Paste")
			(net "MB1_TEMP_E")
			(options
				(clearance outline)
				(anchor circle)
			)
			(primitives
				(gr_poly
					(pts
						(arc
							(start -0.1778 -0.2794)
							(mid -0.249642 -0.249642)
							(end -0.2794 -0.1778)
						)
						(arc
							(start -0.2794 0.1778)
							(mid -0.249642 0.249642)
							(end -0.1778 0.2794)
						)
						(arc
							(start 0.1778 0.2794)
							(mid 0.249642 0.249642)
							(end 0.2794 0.1778)
						)
						(arc
							(start 0.2794 -0.1778)
							(mid 0.249642 -0.249642)
							(end 0.1778 -0.2794)
						)
					)
					(width 0)
					(fill yes)
				)
			)
		)
	)
	(footprint ""
		(layer "F.Cu")
		(at 392.91895 -74.335894 180)
		(property "Reference" "C463"
			(at 0 0 180)
			(layer "F.SilkS")
			(hide yes)
			(effects
				(font
					(size 1.27 1.27)
				)
			)
		)
		(property "Value" "SC1U25V3KX-GP"
			(at 0 -2.8194 180)
			(unlocked yes)
			(layer "F.Fab")
			(hide yes)
			(effects
				(font
					(size 1.016 1.016)
					(thickness 0.1524)
				)
			)
		)
		(property "Device Type" "C603H36"
			(at 0 -4.3434 180)
			(unlocked yes)
			(layer "F.Fab")
			(hide yes)
			(effects
				(font
					(size 1.016 1.016)
					(thickness 0.1524)
				)
			)
		)
		(duplicate_pad_numbers_are_jumpers no)
		(fp_line
			(start 0.508 0)
			(end -0.508 0)
			(stroke
				(width 0.2032)
				(type default)
			)
			(layer "F.SilkS")
		)
		(fp_rect
			(start -0.5842 1.3335)
			(end 0.5842 -1.3335)
			(stroke
				(width 0)
				(type default)
			)
			(fill no)
			(layer "F.CrtYd")
		)
		(fp_rect
			(start -0.5842 1.3335)
			(end 0.5842 -1.3335)
			(stroke
				(width 0)
				(type default)
			)
			(fill no)
			(layer "F.Fab")
		)
		(pad "1" smd custom
			(at 0 -0.762 180)
			(size 0.2159 0.2159)
			(layers "F.Cu" "F.Mask" "F.Paste")
			(net "P12V_HDD32")
			(options
				(clearance outline)
				(anchor circle)
			)
			(primitives
				(gr_poly
					(pts
						(arc
							(start -0.3302 -0.4318)
							(mid -0.402042 -0.402042)
							(end -0.4318 -0.3302)
						)
						(arc
							(start -0.4318 0.3302)
							(mid -0.402042 0.402042)
							(end -0.3302 0.4318)
						)
						(arc
							(start 0.3302 0.4318)
							(mid 0.402042 0.402042)
							(end 0.4318 0.3302)
						)
						(arc
							(start 0.4318 -0.3302)
							(mid 0.402042 -0.402042)
							(end 0.3302 -0.4318)
						)
					)
					(width 0)
					(fill yes)
				)
			)
		)
		(pad "2" smd custom
			(at 0 0.762 180)
			(size 0.2159 0.2159)
			(layers "F.Cu" "F.Mask" "F.Paste")
			(net "GND")
			(options
				(clearance outline)
				(anchor circle)
			)
			(primitives
				(gr_poly
					(pts
						(arc
							(start -0.3302 -0.4318)
							(mid -0.402042 -0.402042)
							(end -0.4318 -0.3302)
						)
						(arc
							(start -0.4318 0.3302)
							(mid -0.402042 0.402042)
							(end -0.3302 0.4318)
						)
						(arc
							(start 0.3302 0.4318)
							(mid 0.402042 0.402042)
							(end 0.4318 0.3302)
						)
						(arc
							(start 0.4318 -0.3302)
							(mid 0.402042 -0.402042)
							(end 0.3302 -0.4318)
						)
					)
					(width 0)
					(fill yes)
				)
			)
		)
	)
	(footprint ""
		(layer "F.Cu")
		(at 477.2406 -48.067976 180)
		(property "Reference" "R935"
			(at 0 0 180)
			(layer "F.SilkS")
			(hide yes)
			(effects
				(font
					(size 1.27 1.27)
				)
			)
		)
		(property "Value" "10KR2F-2-GP"
			(at 0.064008 -3.993896 180)
			(unlocked yes)
			(layer "F.Fab")
			(hide yes)
			(effects
				(font
					(size 1.016 1.016)
					(thickness 0.1524)
				)
			)
		)
		(property "Device Type" "R402H16"
			(at 0.064008 -5.517896 180)
			(unlocked yes)
			(layer "F.Fab")
			(hide yes)
			(effects
				(font
					(size 1.016 1.016)
					(thickness 0.1524)
				)
			)
		)
		(duplicate_pad_numbers_are_jumpers no)
		(fp_line
			(start 0.508 -0.9398)
			(end -0.508 -0.9398)
			(stroke
				(width 0.1524)
				(type default)
			)
			(layer "F.SilkS")
		)
		(fp_line
			(start -0.508 -0.9398)
			(end -0.508 0.9398)
			(stroke
				(width 0.1524)
				(type default)
			)
			(layer "F.SilkS")
		)
		(fp_rect
			(start -0.508 0.9398)
			(end 0.508 -0.9398)
			(stroke
				(width 0)
				(type default)
			)
			(fill no)
			(layer "F.CrtYd")
		)
		(fp_rect
			(start -0.508 0.9398)
			(end 0.508 -0.9398)
			(stroke
				(width 0)
				(type default)
			)
			(fill no)
			(layer "F.Fab")
		)
		(pad "1" smd custom
			(at 0 -0.4445 180)
			(size 0.1397 0.1397)
			(layers "F.Cu" "F.Mask" "F.Paste")
			(net "P3V3_STBY_A")
			(options
				(clearance outline)
				(anchor circle)
			)
			(primitives
				(gr_poly
					(pts
						(arc
							(start -0.1778 -0.2794)
							(mid -0.249642 -0.249642)
							(end -0.2794 -0.1778)
						)
						(arc
							(start -0.2794 0.1778)
							(mid -0.249642 0.249642)
							(end -0.1778 0.2794)
						)
						(arc
							(start 0.1778 0.2794)
							(mid 0.249642 0.249642)
							(end 0.2794 0.1778)
						)
						(arc
							(start 0.2794 -0.1778)
							(mid 0.249642 -0.249642)
							(end 0.1778 -0.2794)
						)
					)
					(width 0)
					(fill yes)
				)
			)
		)
		(pad "2" smd custom
			(at 0 0.4445 180)
			(size 0.1397 0.1397)
			(layers "F.Cu" "F.Mask" "F.Paste")
			(net "HDD_PRSNT_35")
			(options
				(clearance outline)
				(anchor circle)
			)
			(primitives
				(gr_poly
					(pts
						(arc
							(start -0.1778 -0.2794)
							(mid -0.249642 -0.249642)
							(end -0.2794 -0.1778)
						)
						(arc
							(start -0.2794 0.1778)
							(mid -0.249642 0.249642)
							(end -0.1778 0.2794)
						)
						(arc
							(start 0.1778 0.2794)
							(mid 0.249642 0.249642)
							(end 0.2794 0.1778)
						)
						(arc
							(start 0.2794 -0.1778)
							(mid 0.249642 -0.249642)
							(end 0.1778 -0.2794)
						)
					)
					(width 0)
					(fill yes)
				)
			)
		)
	)
	(footprint ""
		(layer "F.Cu")
		(at 141.042898 -168.507918 -90)
		(property "Reference" "R513"
			(at 0 0 270)
			(layer "F.SilkS")
			(hide yes)
			(effects
				(font
					(size 1.27 1.27)
				)
			)
		)
		(property "Value" "300KR2F-GP"
			(at 0.064008 -3.993896 270)
			(unlocked yes)
			(layer "F.Fab")
			(hide yes)
			(effects
				(font
					(size 1.016 1.016)
					(thickness 0.1524)
				)
			)
		)
		(property "Device Type" "R402H16"
			(at 0.064008 -5.517896 270)
			(unlocked yes)
			(layer "F.Fab")
			(hide yes)
			(effects
				(font
					(size 1.016 1.016)
					(thickness 0.1524)
				)
			)
		)
		(duplicate_pad_numbers_are_jumpers no)
		(fp_line
			(start -0.508 -0.9398)
			(end -0.508 0.9398)
			(stroke
				(width 0.1524)
				(type default)
			)
			(layer "F.SilkS")
		)
		(fp_line
			(start 0.508 -0.9398)
			(end -0.508 -0.9398)
			(stroke
				(width 0.1524)
				(type default)
			)
			(layer "F.SilkS")
		)
		(fp_rect
			(start -0.508 0.9398)
			(end 0.508 -0.9398)
			(stroke
				(width 0)
				(type default)
			)
			(fill no)
			(layer "F.CrtYd")
		)
		(fp_rect
			(start -0.508 0.9398)
			(end 0.508 -0.9398)
			(stroke
				(width 0)
				(type default)
			)
			(fill no)
			(layer "F.Fab")
		)
		(pad "1" smd custom
			(at 0 -0.4445 270)
			(size 0.1397 0.1397)
			(layers "F.Cu" "F.Mask" "F.Paste")
			(net "SW_HDD_N16")
			(options
				(clearance outline)
				(anchor circle)
			)
			(primitives
				(gr_poly
					(pts
						(arc
							(start -0.1778 -0.2794)
							(mid -0.249642 -0.249642)
							(end -0.2794 -0.1778)
						)
						(arc
							(start -0.2794 0.1778)
							(mid -0.249642 0.249642)
							(end -0.1778 0.2794)
						)
						(arc
							(start 0.1778 0.2794)
							(mid 0.249642 0.249642)
							(end 0.2794 0.1778)
						)
						(arc
							(start 0.2794 -0.1778)
							(mid 0.249642 -0.249642)
							(end 0.1778 -0.2794)
						)
					)
					(width 0)
					(fill yes)
				)
			)
		)
		(pad "2" smd custom
			(at 0 0.4445 270)
			(size 0.1397 0.1397)
			(layers "F.Cu" "F.Mask" "F.Paste")
			(net "P12V_A")
			(options
				(clearance outline)
				(anchor circle)
			)
			(primitives
				(gr_poly
					(pts
						(arc
							(start -0.1778 -0.2794)
							(mid -0.249642 -0.249642)
							(end -0.2794 -0.1778)
						)
						(arc
							(start -0.2794 0.1778)
							(mid -0.249642 0.249642)
							(end -0.1778 0.2794)
						)
						(arc
							(start 0.1778 0.2794)
							(mid 0.249642 0.249642)
							(end 0.2794 0.1778)
						)
						(arc
							(start 0.2794 -0.1778)
							(mid 0.249642 -0.249642)
							(end 0.1778 -0.2794)
						)
					)
					(width 0)
					(fill yes)
				)
			)
		)
	)
	(footprint ""
		(layer "F.Cu")
		(at 222.6437 -91.2114 -90)
		(property "Reference" "R200"
			(at 0 0 270)
			(layer "F.SilkS")
			(hide yes)
			(effects
				(font
					(size 1.27 1.27)
				)
			)
		)
		(property "Value" "4K7R2F-GP"
			(at 0.064008 -3.993896 270)
			(unlocked yes)
			(layer "F.Fab")
			(hide yes)
			(effects
				(font
					(size 1.016 1.016)
					(thickness 0.1524)
				)
			)
		)
		(property "Device Type" "R402H16"
			(at 0.064008 -5.517896 270)
			(unlocked yes)
			(layer "F.Fab")
			(hide yes)
			(effects
				(font
					(size 1.016 1.016)
					(thickness 0.1524)
				)
			)
		)
		(duplicate_pad_numbers_are_jumpers no)
		(fp_line
			(start -0.508 -0.9398)
			(end -0.508 0.9398)
			(stroke
				(width 0.1524)
				(type default)
			)
			(layer "F.SilkS")
		)
		(fp_line
			(start 0.508 -0.9398)
			(end -0.508 -0.9398)
			(stroke
				(width 0.1524)
				(type default)
			)
			(layer "F.SilkS")
		)
		(fp_rect
			(start -0.508 0.9398)
			(end 0.508 -0.9398)
			(stroke
				(width 0)
				(type default)
			)
			(fill no)
			(layer "F.CrtYd")
		)
		(fp_rect
			(start -0.508 0.9398)
			(end 0.508 -0.9398)
			(stroke
				(width 0)
				(type default)
			)
			(fill no)
			(layer "F.Fab")
		)
		(pad "1" smd custom
			(at 0 -0.4445 270)
			(size 0.1397 0.1397)
			(layers "F.Cu" "F.Mask" "F.Paste")
			(net "COMP_A_POWER_FAIL_N")
			(options
				(clearance outline)
				(anchor circle)
			)
			(primitives
				(gr_poly
					(pts
						(arc
							(start -0.1778 -0.2794)
							(mid -0.249642 -0.249642)
							(end -0.2794 -0.1778)
						)
						(arc
							(start -0.2794 0.1778)
							(mid -0.249642 0.249642)
							(end -0.1778 0.2794)
						)
						(arc
							(start 0.1778 0.2794)
							(mid 0.249642 0.249642)
							(end 0.2794 0.1778)
						)
						(arc
							(start 0.2794 -0.1778)
							(mid 0.249642 -0.249642)
							(end 0.1778 -0.2794)
						)
					)
					(width 0)
					(fill yes)
				)
			)
		)
		(pad "2" smd custom
			(at 0 0.4445 270)
			(size 0.1397 0.1397)
			(layers "F.Cu" "F.Mask" "F.Paste")
			(net "P3V3_STBY_A")
			(options
				(clearance outline)
				(anchor circle)
			)
			(primitives
				(gr_poly
					(pts
						(arc
							(start -0.1778 -0.2794)
							(mid -0.249642 -0.249642)
							(end -0.2794 -0.1778)
						)
						(arc
							(start -0.2794 0.1778)
							(mid -0.249642 0.249642)
							(end -0.1778 0.2794)
						)
						(arc
							(start 0.1778 0.2794)
							(mid 0.249642 0.249642)
							(end 0.2794 0.1778)
						)
						(arc
							(start 0.2794 -0.1778)
							(mid 0.249642 -0.249642)
							(end 0.1778 -0.2794)
						)
					)
					(width 0)
					(fill yes)
				)
			)
		)
	)
	(footprint ""
		(layer "F.Cu")
		(at 50.456846 -179.683918 90)
		(property "Reference" "R430"
			(at 0 0 90)
			(layer "F.SilkS")
			(hide yes)
			(effects
				(font
					(size 1.27 1.27)
				)
			)
		)
		(property "Value" "2R6F-GP"
			(at -0.0508 -4.8514 90)
			(unlocked yes)
			(layer "F.Fab")
			(hide yes)
			(effects
				(font
					(size 1.016 1.016)
					(thickness 0.1524)
				)
			)
		)
		(property "Device Type" "R1206H26"
			(at 0 -6.3754 90)
			(unlocked yes)
			(layer "F.Fab")
			(hide yes)
			(effects
				(font
					(size 1.016 1.016)
					(thickness 0.1524)
				)
			)
		)
		(duplicate_pad_numbers_are_jumpers no)
		(fp_line
			(start 1.016 -2.2352)
			(end 1.016 2.2352)
			(stroke
				(width 0.1524)
				(type default)
			)
			(layer "F.SilkS")
		)
		(fp_line
			(start -1.016 -2.2352)
			(end 1.016 -2.2352)
			(stroke
				(width 0.1524)
				(type default)
			)
			(layer "F.SilkS")
		)
		(fp_line
			(start 1.016 2.2352)
			(end -1.016 2.2352)
			(stroke
				(width 0.1524)
				(type default)
			)
			(layer "F.SilkS")
		)
		(fp_line
			(start -1.016 2.2352)
			(end -1.016 -2.2352)
			(stroke
				(width 0.1524)
				(type default)
			)
			(layer "F.SilkS")
		)
		(fp_rect
			(start -1.0922 2.3114)
			(end 1.0922 -2.3114)
			(stroke
				(width 0)
				(type default)
			)
			(fill no)
			(layer "F.CrtYd")
		)
		(fp_poly
			(pts
				(xy -1.0922 -2.3114) (xy 1.0922 -2.3114) (xy 1.0922 2.3114) (xy -1.0922 2.3114)
			)
			(stroke
				(width 0)
				(type default)
			)
			(fill no)
			(layer "F.Fab")
		)
		(pad "1" smd rect
			(at 0 -1.397 90)
			(size 1.651 1.27)
			(layers "F.Cu" "F.Mask" "F.Paste")
			(net "P12V_HDD13")
		)
		(pad "2" smd rect
			(at 0 1.397 90)
			(size 1.651 1.27)
			(layers "F.Cu" "F.Mask" "F.Paste")
			(net "12V_PRE_13")
		)
	)
	(footprint ""
		(layer "F.Cu")
		(at 222.885 -365.125)
		(property "Reference" "R176"
			(at 0 0 0)
			(layer "F.SilkS")
			(hide yes)
			(effects
				(font
					(size 1.27 1.27)
				)
			)
		)
		(property "Value" "4K7R2F-GP"
			(at 0.064008 -3.993896 0)
			(unlocked yes)
			(layer "F.Fab")
			(hide yes)
			(effects
				(font
					(size 1.016 1.016)
					(thickness 0.1524)
				)
			)
		)
		(property "Device Type" "R402H16"
			(at 0.064008 -5.517896 0)
			(unlocked yes)
			(layer "F.Fab")
			(hide yes)
			(effects
				(font
					(size 1.016 1.016)
					(thickness 0.1524)
				)
			)
		)
		(duplicate_pad_numbers_are_jumpers no)
		(fp_line
			(start -0.508 -0.9398)
			(end -0.508 0.9398)
			(stroke
				(width 0.1524)
				(type default)
			)
			(layer "F.SilkS")
		)
		(fp_line
			(start 0.508 -0.9398)
			(end -0.508 -0.9398)
			(stroke
				(width 0.1524)
				(type default)
			)
			(layer "F.SilkS")
		)
		(fp_rect
			(start -0.508 0.9398)
			(end 0.508 -0.9398)
			(stroke
				(width 0)
				(type default)
			)
			(fill no)
			(layer "F.CrtYd")
		)
		(fp_rect
			(start -0.508 0.9398)
			(end 0.508 -0.9398)
			(stroke
				(width 0)
				(type default)
			)
			(fill no)
			(layer "F.Fab")
		)
		(pad "1" smd custom
			(at 0 -0.4445)
			(size 0.1397 0.1397)
			(layers "F.Cu" "F.Mask" "F.Paste")
			(net "IO_EXP3_HDD_FAULT_A1")
			(options
				(clearance outline)
				(anchor circle)
			)
			(primitives
				(gr_poly
					(pts
						(arc
							(start -0.1778 -0.2794)
							(mid -0.249642 -0.249642)
							(end -0.2794 -0.1778)
						)
						(arc
							(start -0.2794 0.1778)
							(mid -0.249642 0.249642)
							(end -0.1778 0.2794)
						)
						(arc
							(start 0.1778 0.2794)
							(mid 0.249642 0.249642)
							(end 0.2794 0.1778)
						)
						(arc
							(start 0.2794 -0.1778)
							(mid 0.249642 -0.249642)
							(end 0.1778 -0.2794)
						)
					)
					(width 0)
					(fill yes)
				)
			)
		)
		(pad "2" smd custom
			(at 0 0.4445)
			(size 0.1397 0.1397)
			(layers "F.Cu" "F.Mask" "F.Paste")
			(net "GND")
			(options
				(clearance outline)
				(anchor circle)
			)
			(primitives
				(gr_poly
					(pts
						(arc
							(start -0.1778 -0.2794)
							(mid -0.249642 -0.249642)
							(end -0.2794 -0.1778)
						)
						(arc
							(start -0.2794 0.1778)
							(mid -0.249642 0.249642)
							(end -0.1778 0.2794)
						)
						(arc
							(start 0.1778 0.2794)
							(mid 0.249642 0.249642)
							(end 0.2794 0.1778)
						)
						(arc
							(start 0.2794 -0.1778)
							(mid 0.249642 -0.249642)
							(end 0.1778 -0.2794)
						)
					)
					(width 0)
					(fill yes)
				)
			)
		)
	)
	(footprint ""
		(layer "F.Cu")
		(at 303.816766 -262.567674 -90)
		(property "Reference" "R447"
			(at 0 0 270)
			(layer "F.SilkS")
			(hide yes)
			(effects
				(font
					(size 1.27 1.27)
				)
			)
		)
		(property "Value" "1KR2F-3-GP"
			(at 0.064008 -3.993896 270)
			(unlocked yes)
			(layer "F.Fab")
			(hide yes)
			(effects
				(font
					(size 1.016 1.016)
					(thickness 0.1524)
				)
			)
		)
		(property "Device Type" "R402H16"
			(at 0.064008 -5.517896 270)
			(unlocked yes)
			(layer "F.Fab")
			(hide yes)
			(effects
				(font
					(size 1.016 1.016)
					(thickness 0.1524)
				)
			)
		)
		(duplicate_pad_numbers_are_jumpers no)
		(fp_line
			(start -0.508 -0.9398)
			(end -0.508 0.9398)
			(stroke
				(width 0.1524)
				(type default)
			)
			(layer "F.SilkS")
		)
		(fp_line
			(start 0.508 -0.9398)
			(end -0.508 -0.9398)
			(stroke
				(width 0.1524)
				(type default)
			)
			(layer "F.SilkS")
		)
		(fp_rect
			(start -0.508 0.9398)
			(end 0.508 -0.9398)
			(stroke
				(width 0)
				(type default)
			)
			(fill no)
			(layer "F.CrtYd")
		)
		(fp_rect
			(start -0.508 0.9398)
			(end 0.508 -0.9398)
			(stroke
				(width 0)
				(type default)
			)
			(fill no)
			(layer "F.Fab")
		)
		(pad "1" smd custom
			(at 0 -0.4445 270)
			(size 0.1397 0.1397)
			(layers "F.Cu" "F.Mask" "F.Paste")
			(net "P3V3_STBY_A")
			(options
				(clearance outline)
				(anchor circle)
			)
			(primitives
				(gr_poly
					(pts
						(arc
							(start -0.1778 -0.2794)
							(mid -0.249642 -0.249642)
							(end -0.2794 -0.1778)
						)
						(arc
							(start -0.2794 0.1778)
							(mid -0.249642 0.249642)
							(end -0.1778 0.2794)
						)
						(arc
							(start 0.1778 0.2794)
							(mid 0.249642 0.249642)
							(end 0.2794 0.1778)
						)
						(arc
							(start 0.2794 -0.1778)
							(mid 0.249642 -0.249642)
							(end 0.1778 -0.2794)
						)
					)
					(width 0)
					(fill yes)
				)
			)
		)
		(pad "2" smd custom
			(at 0 0.4445 270)
			(size 0.1397 0.1397)
			(layers "F.Cu" "F.Mask" "F.Paste")
			(net "I2C_BMC_B_EXP_A_SDA")
			(options
				(clearance outline)
				(anchor circle)
			)
			(primitives
				(gr_poly
					(pts
						(arc
							(start -0.1778 -0.2794)
							(mid -0.249642 -0.249642)
							(end -0.2794 -0.1778)
						)
						(arc
							(start -0.2794 0.1778)
							(mid -0.249642 0.249642)
							(end -0.1778 0.2794)
						)
						(arc
							(start 0.1778 0.2794)
							(mid 0.249642 0.249642)
							(end 0.2794 0.1778)
						)
						(arc
							(start 0.2794 -0.1778)
							(mid 0.249642 -0.249642)
							(end 0.1778 -0.2794)
						)
					)
					(width 0)
					(fill yes)
				)
			)
		)
	)
	(footprint ""
		(layer "F.Cu")
		(at 363.020102 -73.954894 180)
		(property "Reference" "C447"
			(at 0 0 180)
			(layer "F.SilkS")
			(hide yes)
			(effects
				(font
					(size 1.27 1.27)
				)
			)
		)
		(property "Value" "SC4D7U25V5KX-1-GP"
			(at -0.0762 -6.1214 180)
			(unlocked yes)
			(layer "F.Fab")
			(hide yes)
			(effects
				(font
					(size 1.016 1.016)
					(thickness 0.1524)
				)
			)
		)
		(property "Device Type" "C805H58"
			(at -0.0762 -8.1534 180)
			(unlocked yes)
			(layer "F.Fab")
			(hide yes)
			(effects
				(font
					(size 1.016 1.016)
					(thickness 0.1524)
				)
			)
		)
		(duplicate_pad_numbers_are_jumpers no)
		(fp_line
			(start 0.635 0)
			(end -0.635 0)
			(stroke
				(width 0.508)
				(type default)
			)
			(layer "F.SilkS")
		)
		(fp_rect
			(start -0.9652 1.778)
			(end 0.9652 -1.778)
			(stroke
				(width 0)
				(type default)
			)
			(fill no)
			(layer "F.CrtYd")
		)
		(fp_poly
			(pts
				(xy -0.9652 -1.778) (xy 0.9652 -1.778) (xy 0.9652 1.778) (xy -0.9652 1.778)
			)
			(stroke
				(width 0)
				(type default)
			)
			(fill no)
			(layer "F.Fab")
		)
		(pad "1" smd rect
			(at 0 -0.9652 180)
			(size 1.397 1.143)
			(layers "F.Cu" "F.Mask" "F.Paste")
			(net "P12V_HDD31")
		)
		(pad "2" smd rect
			(at 0 0.9652 180)
			(size 1.397 1.143)
			(layers "F.Cu" "F.Mask" "F.Paste")
			(net "GND")
		)
	)
	(footprint ""
		(layer "F.Cu")
		(at 64.013334 -273.660616 90)
		(property "Reference" "C52"
			(at 0 0 90)
			(layer "F.SilkS")
			(hide yes)
			(effects
				(font
					(size 1.27 1.27)
				)
			)
		)
		(property "Value" "SCD01U16V1KX-GP"
			(at -2.8321 -1.7399 90)
			(unlocked yes)
			(layer "F.Fab")
			(hide yes)
			(effects
				(font
					(size 1.016 1.016)
					(thickness 0.1524)
				)
			)
		)
		(property "Device Type" "C0201H13"
			(at -2.8321 -3.2639 90)
			(unlocked yes)
			(layer "F.Fab")
			(hide yes)
			(effects
				(font
					(size 1.016 1.016)
					(thickness 0.1524)
				)
			)
		)
		(duplicate_pad_numbers_are_jumpers no)
		(fp_rect
			(start -0.2794 0.6477)
			(end 0.2794 -0.6477)
			(stroke
				(width 0)
				(type default)
			)
			(fill no)
			(layer "F.CrtYd")
		)
		(fp_rect
			(start -0.2794 0.6477)
			(end 0.2794 -0.6477)
			(stroke
				(width 0)
				(type default)
			)
			(fill no)
			(layer "F.Fab")
		)
		(pad "1" smd custom
			(at 0 -0.2794 90)
			(size 0.0762 0.0762)
			(layers "F.Cu" "F.Mask" "F.Paste")
			(net "SAS_HDD_RX_P1")
			(options
				(clearance outline)
				(anchor circle)
			)
			(primitives
				(gr_poly
					(pts
						(arc
							(start 0.1524 -0.127)
							(mid 0.137521 -0.162921)
							(end 0.1016 -0.1778)
						)
						(arc
							(start -0.1016 -0.1778)
							(mid -0.137521 -0.162921)
							(end -0.1524 -0.127)
						)
						(arc
							(start -0.1524 0.127)
							(mid -0.137521 0.162921)
							(end -0.1016 0.1778)
						)
						(arc
							(start 0.1016 0.1778)
							(mid 0.137521 0.162921)
							(end 0.1524 0.127)
						)
					)
					(width 0)
					(fill yes)
				)
			)
		)
		(pad "2" smd custom
			(at 0 0.2794 90)
			(size 0.0762 0.0762)
			(layers "F.Cu" "F.Mask" "F.Paste")
			(net "PHY_SCC_A_TO_DRV_A_1_DP")
			(options
				(clearance outline)
				(anchor circle)
			)
			(primitives
				(gr_poly
					(pts
						(arc
							(start 0.1524 -0.127)
							(mid 0.137521 -0.162921)
							(end 0.1016 -0.1778)
						)
						(arc
							(start -0.1016 -0.1778)
							(mid -0.137521 -0.162921)
							(end -0.1524 -0.127)
						)
						(arc
							(start -0.1524 0.127)
							(mid -0.137521 0.162921)
							(end -0.1016 0.1778)
						)
						(arc
							(start 0.1016 0.1778)
							(mid 0.137521 0.162921)
							(end 0.1524 0.127)
						)
					)
					(width 0)
					(fill yes)
				)
			)
		)
	)
	(footprint ""
		(layer "F.Cu")
		(at 118.382796 -177.270918)
		(property "Reference" "R474"
			(at 0 0 0)
			(layer "F.SilkS")
			(hide yes)
			(effects
				(font
					(size 1.27 1.27)
				)
			)
		)
		(property "Value" "2R6F-GP"
			(at -0.0508 -4.8514 0)
			(unlocked yes)
			(layer "F.Fab")
			(hide yes)
			(effects
				(font
					(size 1.016 1.016)
					(thickness 0.1524)
				)
			)
		)
		(property "Device Type" "R1206H26"
			(at 0 -6.3754 0)
			(unlocked yes)
			(layer "F.Fab")
			(hide yes)
			(effects
				(font
					(size 1.016 1.016)
					(thickness 0.1524)
				)
			)
		)
		(duplicate_pad_numbers_are_jumpers no)
		(fp_line
			(start -1.016 -2.2352)
			(end 1.016 -2.2352)
			(stroke
				(width 0.1524)
				(type default)
			)
			(layer "F.SilkS")
		)
		(fp_line
			(start -1.016 2.2352)
			(end -1.016 -2.2352)
			(stroke
				(width 0.1524)
				(type default)
			)
			(layer "F.SilkS")
		)
		(fp_line
			(start 1.016 -2.2352)
			(end 1.016 2.2352)
			(stroke
				(width 0.1524)
				(type default)
			)
			(layer "F.SilkS")
		)
		(fp_line
			(start 1.016 2.2352)
			(end -1.016 2.2352)
			(stroke
				(width 0.1524)
				(type default)
			)
			(layer "F.SilkS")
		)
		(fp_rect
			(start -1.0922 2.3114)
			(end 1.0922 -2.3114)
			(stroke
				(width 0)
				(type default)
			)
			(fill no)
			(layer "F.CrtYd")
		)
		(fp_poly
			(pts
				(xy -1.0922 -2.3114) (xy 1.0922 -2.3114) (xy 1.0922 2.3114) (xy -1.0922 2.3114)
			)
			(stroke
				(width 0)
				(type default)
			)
			(fill no)
			(layer "F.Fab")
		)
		(pad "1" smd rect
			(at 0 -1.397)
			(size 1.651 1.27)
			(layers "F.Cu" "F.Mask" "F.Paste")
			(net "P5V_HDD15")
		)
		(pad "2" smd rect
			(at 0 1.397)
			(size 1.651 1.27)
			(layers "F.Cu" "F.Mask" "F.Paste")
			(net "5V_PRE_15")
		)
	)
	(footprint ""
		(layer "F.Cu")
		(at 458.3049 -160.252918 -90)
		(property "Reference" "Q133"
			(at 0 0 270)
			(layer "F.SilkS")
			(hide yes)
			(effects
				(font
					(size 1.27 1.27)
				)
			)
		)
		(property "Value" "2N7002KDW-GP"
			(at -2.3622 -8.2042 270)
			(unlocked yes)
			(layer "F.Fab")
			(hide yes)
			(effects
				(font
					(size 1.016 1.016)
					(thickness 0.1524)
				)
			)
		)
		(property "Device Type" "SOT-363H44"
			(at -2.3622 -10.1092 270)
			(unlocked yes)
			(layer "F.Fab")
			(hide yes)
			(effects
				(font
					(size 1.016 1.016)
					(thickness 0.1524)
				)
			)
		)
		(duplicate_pad_numbers_are_jumpers no)
		(fp_line
			(start -1.4478 1.7018)
			(end 1.4478 1.7018)
			(stroke
				(width 0.1524)
				(type default)
			)
			(layer "F.SilkS")
		)
		(fp_line
			(start 1.4478 1.7018)
			(end 1.4478 -1.7018)
			(stroke
				(width 0.1524)
				(type default)
			)
			(layer "F.SilkS")
		)
		(fp_line
			(start -1.27 1.524)
			(end -1.27 0.6604)
			(stroke
				(width 0.4826)
				(type default)
			)
			(layer "F.SilkS")
		)
		(fp_line
			(start -1.4478 -1.7018)
			(end -1.4478 1.7018)
			(stroke
				(width 0.1524)
				(type default)
			)
			(layer "F.SilkS")
		)
		(fp_line
			(start 1.4478 -1.7018)
			(end -1.4478 -1.7018)
			(stroke
				(width 0.1524)
				(type default)
			)
			(layer "F.SilkS")
		)
		(fp_poly
			(pts
				(xy -1.524 -1.778) (xy 1.524 -1.778) (xy 1.524 1.778) (xy -1.524 1.778)
			)
			(stroke
				(width 0)
				(type default)
			)
			(fill no)
			(layer "F.CrtYd")
		)
		(fp_poly
			(pts
				(xy -1.524 -1.778) (xy 1.524 -1.778) (xy 1.524 1.778) (xy -1.524 1.778)
			)
			(stroke
				(width 0)
				(type default)
			)
			(fill no)
			(layer "F.Fab")
		)
		(pad "1" smd rect
			(at -0.65024 0.9398 270)
			(size 0.4064 1.016)
			(layers "F.Cu" "F.Mask" "F.Paste")
			(net "GND")
		)
		(pad "2" smd rect
			(at 0 0.9398 270)
			(size 0.4064 1.016)
			(layers "F.Cu" "F.Mask" "F.Paste")
			(net "SW_PWR_R_HDD22")
		)
		(pad "3" smd rect
			(at 0.65024 0.9398 270)
			(size 0.4064 1.016)
			(layers "F.Cu" "F.Mask" "F.Paste")
			(net "SW_HDD_P22")
		)
		(pad "4" smd rect
			(at 0.65024 -0.9398 270)
			(size 0.4064 1.016)
			(layers "F.Cu" "F.Mask" "F.Paste")
			(net "GND")
		)
		(pad "5" smd rect
			(at 0 -0.9398 270)
			(size 0.4064 1.016)
			(layers "F.Cu" "F.Mask" "F.Paste")
			(net "SW_HDD_G22")
		)
		(pad "6" smd rect
			(at -0.65024 -0.9398 270)
			(size 0.4064 1.016)
			(layers "F.Cu" "F.Mask" "F.Paste")
			(net "SW_HDD_R22")
		)
	)
	(footprint ""
		(layer "F.Cu")
		(at 259.96773 21.69795 -90)
		(property "Reference" "C45"
			(at 0 0 270)
			(layer "F.SilkS")
			(hide yes)
			(effects
				(font
					(size 1.27 1.27)
				)
			)
		)
		(property "Value" "SC47U16V0MX-GP"
			(at -0.00254 -4.78536 270)
			(unlocked yes)
			(layer "F.Fab")
			(hide yes)
			(effects
				(font
					(size 1.016 1.016)
					(thickness 0.1524)
				)
			)
		)
		(property "Device Type" "C1210H107"
			(at -0.00254 -6.38048 270)
			(unlocked yes)
			(layer "F.Fab")
			(hide yes)
			(effects
				(font
					(size 1.016 1.016)
					(thickness 0.1524)
				)
			)
		)
		(duplicate_pad_numbers_are_jumpers no)
		(fp_line
			(start -1.5748 2.3368)
			(end 1.5748 2.3368)
			(stroke
				(width 0.1524)
				(type default)
			)
			(layer "F.SilkS")
		)
		(fp_line
			(start 1.5748 2.3368)
			(end 1.5748 0.762)
			(stroke
				(width 0.1524)
				(type default)
			)
			(layer "F.SilkS")
		)
		(fp_line
			(start -1.5748 0.762)
			(end -1.5748 2.3368)
			(stroke
				(width 0.1524)
				(type default)
			)
			(layer "F.SilkS")
		)
		(fp_line
			(start 1.5748 -0.762)
			(end 1.5748 -2.3368)
			(stroke
				(width 0.1524)
				(type default)
			)
			(layer "F.SilkS")
		)
		(fp_line
			(start -1.5748 -2.3368)
			(end -1.5748 -0.762)
			(stroke
				(width 0.1524)
				(type default)
			)
			(layer "F.SilkS")
		)
		(fp_line
			(start 1.5748 -2.3368)
			(end -1.5748 -2.3368)
			(stroke
				(width 0.1524)
				(type default)
			)
			(layer "F.SilkS")
		)
		(fp_rect
			(start -1.651 2.413)
			(end 1.651 -2.413)
			(stroke
				(width 0)
				(type default)
			)
			(fill no)
			(layer "F.CrtYd")
		)
		(fp_poly
			(pts
				(xy 1.651 2.413) (xy 1.651 -2.413) (xy -1.651 -2.413) (xy -1.651 2.413)
			)
			(stroke
				(width 0)
				(type default)
			)
			(fill no)
			(layer "F.Fab")
		)
		(pad "1" smd rect
			(at 0 -1.4732 270)
			(size 2.794 1.397)
			(layers "F.Cu" "F.Mask" "F.Paste")
			(net "P5V_USB_A")
		)
		(pad "2" smd rect
			(at 0 1.4732 270)
			(size 2.794 1.397)
			(layers "F.Cu" "F.Mask" "F.Paste")
			(net "GND")
		)
	)
	(footprint ""
		(layer "F.Cu")
		(at 463.674968 -9.19988)
		(property "Reference" ""
			(at 0 0 0)
			(layer "F.SilkS")
			(hide yes)
			(effects
				(font
					(size 1.27 1.27)
				)
			)
		)
		(property "Value" "*"
			(at -6.1214 1.4351 0)
			(unlocked yes)
			(layer "F.Fab")
			(hide yes)
			(effects
				(font
					(size 1.016 1.016)
					(thickness 0.1524)
				)
			)
		)
		(duplicate_pad_numbers_are_jumpers no)
		(fp_poly
			(pts
				(arc
					(start 5.0673 0)
					(mid -5.0673 0)
					(end 5.0673 0)
				)
			)
			(stroke
				(width 0)
				(type default)
			)
			(fill no)
			(layer "B.CrtYd")
		)
		(fp_poly
			(pts
				(arc
					(start 5.0673 0)
					(mid -5.0673 0)
					(end 5.0673 0)
				)
			)
			(stroke
				(width 0)
				(type default)
			)
			(fill no)
			(layer "F.CrtYd")
		)
		(fp_poly
			(pts
				(arc
					(start 5.0673 0)
					(mid -5.0673 0)
					(end 5.0673 0)
				)
			)
			(stroke
				(width 0)
				(type default)
			)
			(fill no)
			(layer "B.Fab")
		)
		(fp_poly
			(pts
				(arc
					(start 5.0673 0)
					(mid -5.0673 0)
					(end 5.0673 0)
				)
			)
			(stroke
				(width 0)
				(type default)
			)
			(fill no)
			(layer "F.Fab")
		)
		(pad "1" thru_hole circle
			(at 0 0)
			(size 9.525 9.525)
			(drill 5.715)
			(layers "*.Cu" "*.Mask")
			(remove_unused_layers no)
			(net "Net_109")
			(clearance -1.397)
			(thermal_gap 0.3048)
			(padstack
				(mode front_inner_back)
				(layer "Inner"
					(shape circle)
					(size 6.1214 6.1214)
					(clearance 0.3048)
				)
				(layer "B.Cu"
					(shape circle)
					(size 9.525 9.525)
					(clearance -1.397)
				)
			)
		)
		(zone
			(layers "F.Cu" "B.Cu" "In1.Cu" "In2.Cu" "In3.Cu" "In4.Cu" "In5.Cu" "In6.Cu"
				"In7.Cu" "In8.Cu" "In9.Cu" "In10.Cu"
			)
			(hatch none 0.5)
			(connect_pads
				(clearance 0)
			)
			(min_thickness 0.25)
			(keepout
				(tracks not_allowed)
				(vias allowed)
				(pads allowed)
				(copperpour not_allowed)
				(footprints allowed)
			)
			(placement
				(enabled no)
				(sheetname "")
			)
			(fill
				(thermal_gap 0.5)
				(thermal_bridge_width 0.5)
				(island_removal_mode 0)
			)
			(polygon
				(pts
					(arc
						(start 468.437468 -9.19988)
						(mid 458.912468 -9.19988)
						(end 468.437468 -9.19988)
					)
				)
			)
		)
	)
	(footprint ""
		(layer "F.Cu")
		(at 282.3464 -280.2636)
		(property "Reference" "C38"
			(at 0 0 0)
			(layer "F.SilkS")
			(hide yes)
			(effects
				(font
					(size 1.27 1.27)
				)
			)
		)
		(property "Value" "SCD1U16V2KX-3GP"
			(at 1.1811 -2.7051 0)
			(unlocked yes)
			(layer "F.Fab")
			(hide yes)
			(effects
				(font
					(size 1.016 1.016)
					(thickness 0.1524)
				)
			)
		)
		(property "Device Type" "C402H22"
			(at 1.1811 -4.2291 0)
			(unlocked yes)
			(layer "F.Fab")
			(hide yes)
			(effects
				(font
					(size 1.016 1.016)
					(thickness 0.1524)
				)
			)
		)
		(duplicate_pad_numbers_are_jumpers no)
		(fp_rect
			(start -0.4318 0.9525)
			(end 0.4318 -0.9525)
			(stroke
				(width 0)
				(type default)
			)
			(fill no)
			(layer "F.CrtYd")
		)
		(fp_rect
			(start -0.4318 0.9525)
			(end 0.4318 -0.9525)
			(stroke
				(width 0)
				(type default)
			)
			(fill no)
			(layer "F.Fab")
		)
		(pad "1" smd custom
			(at 0 -0.4445)
			(size 0.1524 0.1524)
			(layers "F.Cu" "F.Mask" "F.Paste")
			(net "P3V3_STBY_A")
			(options
				(clearance outline)
				(anchor circle)
			)
			(primitives
				(gr_poly
					(pts
						(arc
							(start 0.3048 -0.2032)
							(mid 0.275042 -0.275042)
							(end 0.2032 -0.3048)
						)
						(arc
							(start -0.2032 -0.3048)
							(mid -0.275042 -0.275042)
							(end -0.3048 -0.2032)
						)
						(arc
							(start -0.3048 0.2032)
							(mid -0.275042 0.275042)
							(end -0.2032 0.3048)
						)
						(arc
							(start 0.2032 0.3048)
							(mid 0.275042 0.275042)
							(end 0.3048 0.2032)
						)
					)
					(width 0)
					(fill yes)
				)
			)
		)
		(pad "2" smd custom
			(at 0 0.4445)
			(size 0.1524 0.1524)
			(layers "F.Cu" "F.Mask" "F.Paste")
			(net "GND")
			(options
				(clearance outline)
				(anchor circle)
			)
			(primitives
				(gr_poly
					(pts
						(arc
							(start 0.3048 -0.2032)
							(mid 0.275042 -0.275042)
							(end 0.2032 -0.3048)
						)
						(arc
							(start -0.2032 -0.3048)
							(mid -0.275042 -0.275042)
							(end -0.3048 -0.2032)
						)
						(arc
							(start -0.3048 0.2032)
							(mid -0.275042 0.275042)
							(end -0.2032 0.3048)
						)
						(arc
							(start 0.2032 0.3048)
							(mid 0.275042 0.275042)
							(end 0.3048 0.2032)
						)
					)
					(width 0)
					(fill yes)
				)
			)
		)
	)
	(footprint ""
		(layer "F.Cu")
		(at 79.924148 -53.126894 -90)
		(property "Reference" "C386"
			(at 0 0 270)
			(layer "F.SilkS")
			(hide yes)
			(effects
				(font
					(size 1.27 1.27)
				)
			)
		)
		(property "Value" "SCD033U25V2KX-GP"
			(at 1.1811 -2.7051 270)
			(unlocked yes)
			(layer "F.Fab")
			(hide yes)
			(effects
				(font
					(size 1.016 1.016)
					(thickness 0.1524)
				)
			)
		)
		(property "Device Type" "C402H22"
			(at 1.1811 -4.2291 270)
			(unlocked yes)
			(layer "F.Fab")
			(hide yes)
			(effects
				(font
					(size 1.016 1.016)
					(thickness 0.1524)
				)
			)
		)
		(duplicate_pad_numbers_are_jumpers no)
		(fp_rect
			(start -0.4318 0.9525)
			(end 0.4318 -0.9525)
			(stroke
				(width 0)
				(type default)
			)
			(fill no)
			(layer "F.CrtYd")
		)
		(fp_rect
			(start -0.4318 0.9525)
			(end 0.4318 -0.9525)
			(stroke
				(width 0)
				(type default)
			)
			(fill no)
			(layer "F.Fab")
		)
		(pad "1" smd custom
			(at 0 -0.4445 270)
			(size 0.1524 0.1524)
			(layers "F.Cu" "F.Mask" "F.Paste")
			(net "SW_HDD_P26")
			(options
				(clearance outline)
				(anchor circle)
			)
			(primitives
				(gr_poly
					(pts
						(arc
							(start 0.3048 -0.2032)
							(mid 0.275042 -0.275042)
							(end 0.2032 -0.3048)
						)
						(arc
							(start -0.2032 -0.3048)
							(mid -0.275042 -0.275042)
							(end -0.3048 -0.2032)
						)
						(arc
							(start -0.3048 0.2032)
							(mid -0.275042 0.275042)
							(end -0.2032 0.3048)
						)
						(arc
							(start 0.2032 0.3048)
							(mid 0.275042 0.275042)
							(end 0.3048 0.2032)
						)
					)
					(width 0)
					(fill yes)
				)
			)
		)
		(pad "2" smd custom
			(at 0 0.4445 270)
			(size 0.1524 0.1524)
			(layers "F.Cu" "F.Mask" "F.Paste")
			(net "GND")
			(options
				(clearance outline)
				(anchor circle)
			)
			(primitives
				(gr_poly
					(pts
						(arc
							(start 0.3048 -0.2032)
							(mid 0.275042 -0.275042)
							(end 0.2032 -0.3048)
						)
						(arc
							(start -0.2032 -0.3048)
							(mid -0.275042 -0.275042)
							(end -0.3048 -0.2032)
						)
						(arc
							(start -0.3048 0.2032)
							(mid -0.275042 0.275042)
							(end -0.2032 0.3048)
						)
						(arc
							(start 0.2032 0.3048)
							(mid 0.275042 0.275042)
							(end 0.3048 0.2032)
						)
					)
					(width 0)
					(fill yes)
				)
			)
		)
	)
	(footprint ""
		(layer "F.Cu")
		(at 67.206876 -304.385472 180)
		(property "Reference" "R228"
			(at 0 0 180)
			(layer "F.SilkS")
			(hide yes)
			(effects
				(font
					(size 1.27 1.27)
				)
			)
		)
		(property "Value" "130R3F-GP"
			(at -0.0254 -2.5146 180)
			(unlocked yes)
			(layer "F.Fab")
			(hide yes)
			(effects
				(font
					(size 1.016 1.016)
					(thickness 0.1524)
				)
			)
		)
		(property "Device Type" "R603H22"
			(at -0.0254 -4.0386 180)
			(unlocked yes)
			(layer "F.Fab")
			(hide yes)
			(effects
				(font
					(size 1.016 1.016)
					(thickness 0.1524)
				)
			)
		)
		(duplicate_pad_numbers_are_jumpers no)
		(fp_line
			(start 0.2032 0)
			(end 0.4826 0)
			(stroke
				(width 0.2032)
				(type default)
			)
			(layer "F.SilkS")
		)
		(fp_line
			(start -0.4826 0)
			(end -0.2032 0)
			(stroke
				(width 0.2032)
				(type default)
			)
			(layer "F.SilkS")
		)
		(fp_rect
			(start -0.5842 1.3335)
			(end 0.5842 -1.3335)
			(stroke
				(width 0)
				(type default)
			)
			(fill no)
			(layer "F.CrtYd")
		)
		(fp_rect
			(start -0.5842 1.3335)
			(end 0.5842 -1.3335)
			(stroke
				(width 0)
				(type default)
			)
			(fill no)
			(layer "F.Fab")
		)
		(pad "1" smd custom
			(at 0 -0.762 180)
			(size 0.2159 0.2159)
			(layers "F.Cu" "F.Mask" "F.Paste")
			(net "P5V_B")
			(options
				(clearance outline)
				(anchor circle)
			)
			(primitives
				(gr_poly
					(pts
						(arc
							(start -0.3302 -0.4318)
							(mid -0.402042 -0.402042)
							(end -0.4318 -0.3302)
						)
						(arc
							(start -0.4318 0.3302)
							(mid -0.402042 0.402042)
							(end -0.3302 0.4318)
						)
						(arc
							(start 0.3302 0.4318)
							(mid 0.402042 0.402042)
							(end 0.4318 0.3302)
						)
						(arc
							(start 0.4318 -0.3302)
							(mid 0.402042 -0.402042)
							(end 0.3302 -0.4318)
						)
					)
					(width 0)
					(fill yes)
				)
			)
		)
		(pad "2" smd custom
			(at 0 0.762 180)
			(size 0.2159 0.2159)
			(layers "F.Cu" "F.Mask" "F.Paste")
			(net "FLT_HDD26")
			(options
				(clearance outline)
				(anchor circle)
			)
			(primitives
				(gr_poly
					(pts
						(arc
							(start -0.3302 -0.4318)
							(mid -0.402042 -0.402042)
							(end -0.4318 -0.3302)
						)
						(arc
							(start -0.4318 0.3302)
							(mid -0.402042 0.402042)
							(end -0.3302 0.4318)
						)
						(arc
							(start 0.3302 0.4318)
							(mid 0.402042 0.402042)
							(end 0.4318 0.3302)
						)
						(arc
							(start 0.4318 -0.3302)
							(mid 0.402042 -0.402042)
							(end 0.3302 -0.4318)
						)
					)
					(width 0)
					(fill yes)
				)
			)
		)
	)
	(footprint ""
		(layer "F.Cu")
		(at 22.970998 -161.014918 -90)
		(property "Reference" "R414"
			(at 0 0 270)
			(layer "F.SilkS")
			(hide yes)
			(effects
				(font
					(size 1.27 1.27)
				)
			)
		)
		(property "Value" "1KR2F-3-GP"
			(at 0.064008 -3.993896 270)
			(unlocked yes)
			(layer "F.Fab")
			(hide yes)
			(effects
				(font
					(size 1.016 1.016)
					(thickness 0.1524)
				)
			)
		)
		(property "Device Type" "R402H16"
			(at 0.064008 -5.517896 270)
			(unlocked yes)
			(layer "F.Fab")
			(hide yes)
			(effects
				(font
					(size 1.016 1.016)
					(thickness 0.1524)
				)
			)
		)
		(duplicate_pad_numbers_are_jumpers no)
		(fp_line
			(start -0.508 -0.9398)
			(end -0.508 0.9398)
			(stroke
				(width 0.1524)
				(type default)
			)
			(layer "F.SilkS")
		)
		(fp_line
			(start 0.508 -0.9398)
			(end -0.508 -0.9398)
			(stroke
				(width 0.1524)
				(type default)
			)
			(layer "F.SilkS")
		)
		(fp_rect
			(start -0.508 0.9398)
			(end 0.508 -0.9398)
			(stroke
				(width 0)
				(type default)
			)
			(fill no)
			(layer "F.CrtYd")
		)
		(fp_rect
			(start -0.508 0.9398)
			(end 0.508 -0.9398)
			(stroke
				(width 0)
				(type default)
			)
			(fill no)
			(layer "F.Fab")
		)
		(pad "1" smd custom
			(at 0 -0.4445 270)
			(size 0.1397 0.1397)
			(layers "F.Cu" "F.Mask" "F.Paste")
			(net "P3V3_STBY_A")
			(options
				(clearance outline)
				(anchor circle)
			)
			(primitives
				(gr_poly
					(pts
						(arc
							(start -0.1778 -0.2794)
							(mid -0.249642 -0.249642)
							(end -0.2794 -0.1778)
						)
						(arc
							(start -0.2794 0.1778)
							(mid -0.249642 0.249642)
							(end -0.1778 0.2794)
						)
						(arc
							(start 0.1778 0.2794)
							(mid 0.249642 0.249642)
							(end 0.2794 0.1778)
						)
						(arc
							(start 0.2794 -0.1778)
							(mid 0.249642 -0.249642)
							(end 0.1778 -0.2794)
						)
					)
					(width 0)
					(fill yes)
				)
			)
		)
		(pad "2" smd custom
			(at 0 0.4445 270)
			(size 0.1397 0.1397)
			(layers "F.Cu" "F.Mask" "F.Paste")
			(net "SW_PWR_R_HDD12")
			(options
				(clearance outline)
				(anchor circle)
			)
			(primitives
				(gr_poly
					(pts
						(arc
							(start -0.1778 -0.2794)
							(mid -0.249642 -0.249642)
							(end -0.2794 -0.1778)
						)
						(arc
							(start -0.2794 0.1778)
							(mid -0.249642 0.249642)
							(end -0.1778 0.2794)
						)
						(arc
							(start 0.1778 0.2794)
							(mid 0.249642 0.249642)
							(end 0.2794 0.1778)
						)
						(arc
							(start 0.2794 -0.1778)
							(mid 0.249642 -0.249642)
							(end 0.1778 -0.2794)
						)
					)
					(width 0)
					(fill yes)
				)
			)
		)
	)
	(footprint ""
		(layer "F.Cu")
		(at 427.390052 -48.554894 -90)
		(property "Reference" "R896"
			(at 0 0 270)
			(layer "F.SilkS")
			(hide yes)
			(effects
				(font
					(size 1.27 1.27)
				)
			)
		)
		(property "Value" "4K7R2J-2-GP"
			(at 0.064008 -3.993896 270)
			(unlocked yes)
			(layer "F.Fab")
			(hide yes)
			(effects
				(font
					(size 1.016 1.016)
					(thickness 0.1524)
				)
			)
		)
		(property "Device Type" "R402H16"
			(at 0.064008 -5.517896 270)
			(unlocked yes)
			(layer "F.Fab")
			(hide yes)
			(effects
				(font
					(size 1.016 1.016)
					(thickness 0.1524)
				)
			)
		)
		(duplicate_pad_numbers_are_jumpers no)
		(fp_line
			(start -0.508 -0.9398)
			(end -0.508 0.9398)
			(stroke
				(width 0.1524)
				(type default)
			)
			(layer "F.SilkS")
		)
		(fp_line
			(start 0.508 -0.9398)
			(end -0.508 -0.9398)
			(stroke
				(width 0.1524)
				(type default)
			)
			(layer "F.SilkS")
		)
		(fp_rect
			(start -0.508 0.9398)
			(end 0.508 -0.9398)
			(stroke
				(width 0)
				(type default)
			)
			(fill no)
			(layer "F.CrtYd")
		)
		(fp_rect
			(start -0.508 0.9398)
			(end 0.508 -0.9398)
			(stroke
				(width 0)
				(type default)
			)
			(fill no)
			(layer "F.Fab")
		)
		(pad "1" smd custom
			(at 0 -0.4445 270)
			(size 0.1397 0.1397)
			(layers "F.Cu" "F.Mask" "F.Paste")
			(net "P12V_A")
			(options
				(clearance outline)
				(anchor circle)
			)
			(primitives
				(gr_poly
					(pts
						(arc
							(start -0.1778 -0.2794)
							(mid -0.249642 -0.249642)
							(end -0.2794 -0.1778)
						)
						(arc
							(start -0.2794 0.1778)
							(mid -0.249642 0.249642)
							(end -0.1778 0.2794)
						)
						(arc
							(start 0.1778 0.2794)
							(mid 0.249642 0.249642)
							(end 0.2794 0.1778)
						)
						(arc
							(start 0.2794 -0.1778)
							(mid 0.249642 -0.249642)
							(end 0.1778 -0.2794)
						)
					)
					(width 0)
					(fill yes)
				)
			)
		)
		(pad "2" smd custom
			(at 0 0.4445 270)
			(size 0.1397 0.1397)
			(layers "F.Cu" "F.Mask" "F.Paste")
			(net "SW_HDD_P33")
			(options
				(clearance outline)
				(anchor circle)
			)
			(primitives
				(gr_poly
					(pts
						(arc
							(start -0.1778 -0.2794)
							(mid -0.249642 -0.249642)
							(end -0.2794 -0.1778)
						)
						(arc
							(start -0.2794 0.1778)
							(mid -0.249642 0.249642)
							(end -0.1778 0.2794)
						)
						(arc
							(start 0.1778 0.2794)
							(mid 0.249642 0.249642)
							(end 0.2794 0.1778)
						)
						(arc
							(start 0.2794 -0.1778)
							(mid 0.249642 -0.249642)
							(end 0.1778 -0.2794)
						)
					)
					(width 0)
					(fill yes)
				)
			)
		)
	)
	(footprint ""
		(layer "F.Cu")
		(at 259.6896 -284.4292 180)
		(property "Reference" "R106"
			(at 0 0 180)
			(layer "F.SilkS")
			(hide yes)
			(effects
				(font
					(size 1.27 1.27)
				)
			)
		)
		(property "Value" "0R2J-2-GP"
			(at 0.064008 -3.993896 180)
			(unlocked yes)
			(layer "F.Fab")
			(hide yes)
			(effects
				(font
					(size 1.016 1.016)
					(thickness 0.1524)
				)
			)
		)
		(property "Device Type" "R402H16"
			(at 0.064008 -5.517896 180)
			(unlocked yes)
			(layer "F.Fab")
			(hide yes)
			(effects
				(font
					(size 1.016 1.016)
					(thickness 0.1524)
				)
			)
		)
		(duplicate_pad_numbers_are_jumpers no)
		(fp_line
			(start 0.508 -0.9398)
			(end -0.508 -0.9398)
			(stroke
				(width 0.1524)
				(type default)
			)
			(layer "F.SilkS")
		)
		(fp_line
			(start -0.508 -0.9398)
			(end -0.508 0.9398)
			(stroke
				(width 0.1524)
				(type default)
			)
			(layer "F.SilkS")
		)
		(fp_rect
			(start -0.508 0.9398)
			(end 0.508 -0.9398)
			(stroke
				(width 0)
				(type default)
			)
			(fill no)
			(layer "F.CrtYd")
		)
		(fp_rect
			(start -0.508 0.9398)
			(end 0.508 -0.9398)
			(stroke
				(width 0)
				(type default)
			)
			(fill no)
			(layer "F.Fab")
		)
		(pad "1" smd custom
			(at 0 -0.4445 180)
			(size 0.1397 0.1397)
			(layers "F.Cu" "F.Mask" "F.Paste")
			(net "IO_EXP0_LED_SDA")
			(options
				(clearance outline)
				(anchor circle)
			)
			(primitives
				(gr_poly
					(pts
						(arc
							(start -0.1778 -0.2794)
							(mid -0.249642 -0.249642)
							(end -0.2794 -0.1778)
						)
						(arc
							(start -0.2794 0.1778)
							(mid -0.249642 0.249642)
							(end -0.1778 0.2794)
						)
						(arc
							(start 0.1778 0.2794)
							(mid 0.249642 0.249642)
							(end 0.2794 0.1778)
						)
						(arc
							(start 0.2794 -0.1778)
							(mid 0.249642 -0.249642)
							(end 0.1778 -0.2794)
						)
					)
					(width 0)
					(fill yes)
				)
			)
		)
		(pad "2" smd custom
			(at 0 0.4445 180)
			(size 0.1397 0.1397)
			(layers "F.Cu" "F.Mask" "F.Paste")
			(net "I2C_DRIVE_A_FLT_LED_SDA")
			(options
				(clearance outline)
				(anchor circle)
			)
			(primitives
				(gr_poly
					(pts
						(arc
							(start -0.1778 -0.2794)
							(mid -0.249642 -0.249642)
							(end -0.2794 -0.1778)
						)
						(arc
							(start -0.2794 0.1778)
							(mid -0.249642 0.249642)
							(end -0.1778 0.2794)
						)
						(arc
							(start 0.1778 0.2794)
							(mid 0.249642 0.249642)
							(end 0.2794 0.1778)
						)
						(arc
							(start 0.2794 -0.1778)
							(mid 0.249642 -0.249642)
							(end 0.1778 -0.2794)
						)
					)
					(width 0)
					(fill yes)
				)
			)
		)
	)
	(footprint ""
		(layer "F.Cu")
		(at 415.579052 -295.064942 -90)
		(property "Reference" "R341"
			(at 0 0 270)
			(layer "F.SilkS")
			(hide yes)
			(effects
				(font
					(size 1.27 1.27)
				)
			)
		)
		(property "Value" "220R3F-1-GP"
			(at -0.0254 -2.5146 270)
			(unlocked yes)
			(layer "F.Fab")
			(hide yes)
			(effects
				(font
					(size 1.016 1.016)
					(thickness 0.1524)
				)
			)
		)
		(property "Device Type" "R603H22"
			(at -0.0254 -4.0386 270)
			(unlocked yes)
			(layer "F.Fab")
			(hide yes)
			(effects
				(font
					(size 1.016 1.016)
					(thickness 0.1524)
				)
			)
		)
		(duplicate_pad_numbers_are_jumpers no)
		(fp_line
			(start -0.4826 0)
			(end -0.2032 0)
			(stroke
				(width 0.2032)
				(type default)
			)
			(layer "F.SilkS")
		)
		(fp_line
			(start 0.2032 0)
			(end 0.4826 0)
			(stroke
				(width 0.2032)
				(type default)
			)
			(layer "F.SilkS")
		)
		(fp_rect
			(start -0.5842 1.3335)
			(end 0.5842 -1.3335)
			(stroke
				(width 0)
				(type default)
			)
			(fill no)
			(layer "F.CrtYd")
		)
		(fp_rect
			(start -0.5842 1.3335)
			(end 0.5842 -1.3335)
			(stroke
				(width 0)
				(type default)
			)
			(fill no)
			(layer "F.Fab")
		)
		(pad "1" smd custom
			(at 0 -0.762 270)
			(size 0.2159 0.2159)
			(layers "F.Cu" "F.Mask" "F.Paste")
			(net "HDD_PRSNT_9")
			(options
				(clearance outline)
				(anchor circle)
			)
			(primitives
				(gr_poly
					(pts
						(arc
							(start -0.3302 -0.4318)
							(mid -0.402042 -0.402042)
							(end -0.4318 -0.3302)
						)
						(arc
							(start -0.4318 0.3302)
							(mid -0.402042 0.402042)
							(end -0.3302 0.4318)
						)
						(arc
							(start 0.3302 0.4318)
							(mid 0.402042 0.402042)
							(end 0.4318 0.3302)
						)
						(arc
							(start 0.4318 -0.3302)
							(mid 0.402042 -0.402042)
							(end 0.3302 -0.4318)
						)
					)
					(width 0)
					(fill yes)
				)
			)
		)
		(pad "2" smd custom
			(at 0 0.762 270)
			(size 0.2159 0.2159)
			(layers "F.Cu" "F.Mask" "F.Paste")
			(net "DRIVE_A_9_INS")
			(options
				(clearance outline)
				(anchor circle)
			)
			(primitives
				(gr_poly
					(pts
						(arc
							(start -0.3302 -0.4318)
							(mid -0.402042 -0.402042)
							(end -0.4318 -0.3302)
						)
						(arc
							(start -0.4318 0.3302)
							(mid -0.402042 0.402042)
							(end -0.3302 0.4318)
						)
						(arc
							(start 0.3302 0.4318)
							(mid 0.402042 0.402042)
							(end 0.4318 0.3302)
						)
						(arc
							(start 0.4318 -0.3302)
							(mid 0.402042 -0.402042)
							(end 0.3302 -0.4318)
						)
					)
					(width 0)
					(fill yes)
				)
			)
		)
	)
	(footprint ""
		(layer "F.Cu")
		(at 272.542 -328.905108 180)
		(property "Reference" "VIA55"
			(at 0 0 180)
			(layer "F.SilkS")
			(hide yes)
			(effects
				(font
					(size 1.27 1.27)
				)
			)
		)
		(property "Value" "100OHM-8L-1D6MM-L18L16-GP"
			(at -3.7211 -4.5085 180)
			(unlocked yes)
			(layer "F.Fab")
			(hide yes)
			(effects
				(font
					(size 1.016 1.016)
					(thickness 0.1524)
				)
			)
		)
		(property "Device Type" "VIA-PCIE-4P-394076"
			(at -3.7211 -6.0325 180)
			(unlocked yes)
			(layer "F.Fab")
			(hide yes)
			(effects
				(font
					(size 1.016 1.016)
					(thickness 0.1524)
				)
			)
		)
		(duplicate_pad_numbers_are_jumpers no)
		(fp_rect
			(start -1.9685 0.381)
			(end 1.9685 -0.381)
			(stroke
				(width 0)
				(type default)
			)
			(fill no)
			(layer "F.CrtYd")
		)
		(fp_rect
			(start -1.9685 0.381)
			(end 1.9685 -0.381)
			(stroke
				(width 0)
				(type default)
			)
			(fill no)
			(layer "F.Fab")
		)
		(pad "1" thru_hole circle
			(at -1.5875 0 180)
			(size 0.508 0.508)
			(drill 0.254)
			(layers "*.Cu" "*.Mask")
			(remove_unused_layers no)
			(net "GND")
			(clearance 0.127)
			(thermal_gap 0.127)
		)
		(pad "2" thru_hole circle
			(at -0.5715 0 180)
			(size 0.508 0.508)
			(drill 0.254)
			(layers "*.Cu" "*.Mask")
			(remove_unused_layers no)
			(net "PHY_SCC_A_TO_DRV_A_17_DP")
			(clearance 0.127)
			(thermal_gap 0.127)
		)
		(pad "3" thru_hole circle
			(at 0.5715 0 180)
			(size 0.508 0.508)
			(drill 0.254)
			(layers "*.Cu" "*.Mask")
			(remove_unused_layers no)
			(net "PHY_SCC_A_TO_DRV_A_17_DN")
			(clearance 0.127)
			(thermal_gap 0.127)
		)
		(pad "4" thru_hole circle
			(at 1.5875 0 180)
			(size 0.508 0.508)
			(drill 0.254)
			(layers "*.Cu" "*.Mask")
			(remove_unused_layers no)
			(net "GND")
			(clearance 0.127)
			(thermal_gap 0.127)
		)
	)
	(footprint ""
		(layer "F.Cu")
		(at 118.890796 -304.462942 180)
		(property "Reference" "C86"
			(at 0 0 180)
			(layer "F.SilkS")
			(hide yes)
			(effects
				(font
					(size 1.27 1.27)
				)
			)
		)
		(property "Value" "SC1U25V3KX-GP"
			(at 0 -2.8194 180)
			(unlocked yes)
			(layer "F.Fab")
			(hide yes)
			(effects
				(font
					(size 1.016 1.016)
					(thickness 0.1524)
				)
			)
		)
		(property "Device Type" "C603H36"
			(at 0 -4.3434 180)
			(unlocked yes)
			(layer "F.Fab")
			(hide yes)
			(effects
				(font
					(size 1.016 1.016)
					(thickness 0.1524)
				)
			)
		)
		(duplicate_pad_numbers_are_jumpers no)
		(fp_line
			(start 0.508 0)
			(end -0.508 0)
			(stroke
				(width 0.2032)
				(type default)
			)
			(layer "F.SilkS")
		)
		(fp_rect
			(start -0.5842 1.3335)
			(end 0.5842 -1.3335)
			(stroke
				(width 0)
				(type default)
			)
			(fill no)
			(layer "F.CrtYd")
		)
		(fp_rect
			(start -0.5842 1.3335)
			(end 0.5842 -1.3335)
			(stroke
				(width 0)
				(type default)
			)
			(fill no)
			(layer "F.Fab")
		)
		(pad "1" smd custom
			(at 0 -0.762 180)
			(size 0.2159 0.2159)
			(layers "F.Cu" "F.Mask" "F.Paste")
			(net "P12V_HDD3")
			(options
				(clearance outline)
				(anchor circle)
			)
			(primitives
				(gr_poly
					(pts
						(arc
							(start -0.3302 -0.4318)
							(mid -0.402042 -0.402042)
							(end -0.4318 -0.3302)
						)
						(arc
							(start -0.4318 0.3302)
							(mid -0.402042 0.402042)
							(end -0.3302 0.4318)
						)
						(arc
							(start 0.3302 0.4318)
							(mid 0.402042 0.402042)
							(end 0.4318 0.3302)
						)
						(arc
							(start 0.4318 -0.3302)
							(mid 0.402042 -0.402042)
							(end 0.3302 -0.4318)
						)
					)
					(width 0)
					(fill yes)
				)
			)
		)
		(pad "2" smd custom
			(at 0 0.762 180)
			(size 0.2159 0.2159)
			(layers "F.Cu" "F.Mask" "F.Paste")
			(net "GND")
			(options
				(clearance outline)
				(anchor circle)
			)
			(primitives
				(gr_poly
					(pts
						(arc
							(start -0.3302 -0.4318)
							(mid -0.402042 -0.402042)
							(end -0.4318 -0.3302)
						)
						(arc
							(start -0.4318 0.3302)
							(mid -0.402042 0.402042)
							(end -0.3302 0.4318)
						)
						(arc
							(start 0.3302 0.4318)
							(mid 0.402042 0.402042)
							(end 0.4318 0.3302)
						)
						(arc
							(start 0.4318 -0.3302)
							(mid 0.402042 -0.402042)
							(end 0.3302 -0.4318)
						)
					)
					(width 0)
					(fill yes)
				)
			)
		)
	)
	(footprint ""
		(layer "F.Cu")
		(at 478.30359 -270.265652 90)
		(property "Reference" "C189"
			(at 0 0 90)
			(layer "F.SilkS")
			(hide yes)
			(effects
				(font
					(size 1.27 1.27)
				)
			)
		)
		(property "Value" "SCD01U50V2KX-1GP"
			(at 1.1811 -2.7051 90)
			(unlocked yes)
			(layer "F.Fab")
			(hide yes)
			(effects
				(font
					(size 1.016 1.016)
					(thickness 0.1524)
				)
			)
		)
		(property "Device Type" "C402H22"
			(at 1.1811 -4.2291 90)
			(unlocked yes)
			(layer "F.Fab")
			(hide yes)
			(effects
				(font
					(size 1.016 1.016)
					(thickness 0.1524)
				)
			)
		)
		(duplicate_pad_numbers_are_jumpers no)
		(fp_rect
			(start -0.4318 0.9525)
			(end 0.4318 -0.9525)
			(stroke
				(width 0)
				(type default)
			)
			(fill no)
			(layer "F.CrtYd")
		)
		(fp_rect
			(start -0.4318 0.9525)
			(end 0.4318 -0.9525)
			(stroke
				(width 0)
				(type default)
			)
			(fill no)
			(layer "F.Fab")
		)
		(pad "1" smd custom
			(at 0 -0.4445 90)
			(size 0.1524 0.1524)
			(layers "F.Cu" "F.Mask" "F.Paste")
			(net "HDD_PRSNT_11")
			(options
				(clearance outline)
				(anchor circle)
			)
			(primitives
				(gr_poly
					(pts
						(arc
							(start 0.3048 -0.2032)
							(mid 0.275042 -0.275042)
							(end 0.2032 -0.3048)
						)
						(arc
							(start -0.2032 -0.3048)
							(mid -0.275042 -0.275042)
							(end -0.3048 -0.2032)
						)
						(arc
							(start -0.3048 0.2032)
							(mid -0.275042 0.275042)
							(end -0.2032 0.3048)
						)
						(arc
							(start 0.2032 0.3048)
							(mid 0.275042 0.275042)
							(end 0.3048 0.2032)
						)
					)
					(width 0)
					(fill yes)
				)
			)
		)
		(pad "2" smd custom
			(at 0 0.4445 90)
			(size 0.1524 0.1524)
			(layers "F.Cu" "F.Mask" "F.Paste")
			(net "GND")
			(options
				(clearance outline)
				(anchor circle)
			)
			(primitives
				(gr_poly
					(pts
						(arc
							(start 0.3048 -0.2032)
							(mid 0.275042 -0.275042)
							(end 0.2032 -0.3048)
						)
						(arc
							(start -0.2032 -0.3048)
							(mid -0.275042 -0.275042)
							(end -0.3048 -0.2032)
						)
						(arc
							(start -0.3048 0.2032)
							(mid -0.275042 0.275042)
							(end -0.2032 0.3048)
						)
						(arc
							(start 0.2032 0.3048)
							(mid 0.275042 0.275042)
							(end 0.3048 0.2032)
						)
					)
					(width 0)
					(fill yes)
				)
			)
		)
	)
	(footprint ""
		(layer "F.Cu")
		(at 136.9949 -127.254)
		(property "Reference" "R309"
			(at 0 0 0)
			(layer "F.SilkS")
			(hide yes)
			(effects
				(font
					(size 1.27 1.27)
				)
			)
		)
		(property "Value" "91R3F-1-GP"
			(at -0.0254 -2.5146 0)
			(unlocked yes)
			(layer "F.Fab")
			(hide yes)
			(effects
				(font
					(size 1.016 1.016)
					(thickness 0.1524)
				)
			)
		)
		(property "Device Type" "R603H22"
			(at -0.0254 -4.0386 0)
			(unlocked yes)
			(layer "F.Fab")
			(hide yes)
			(effects
				(font
					(size 1.016 1.016)
					(thickness 0.1524)
				)
			)
		)
		(duplicate_pad_numbers_are_jumpers no)
		(fp_line
			(start -0.4826 0)
			(end -0.2032 0)
			(stroke
				(width 0.2032)
				(type default)
			)
			(layer "F.SilkS")
		)
		(fp_line
			(start 0.2032 0)
			(end 0.4826 0)
			(stroke
				(width 0.2032)
				(type default)
			)
			(layer "F.SilkS")
		)
		(fp_rect
			(start -0.5842 1.3335)
			(end 0.5842 -1.3335)
			(stroke
				(width 0)
				(type default)
			)
			(fill no)
			(layer "F.CrtYd")
		)
		(fp_rect
			(start -0.5842 1.3335)
			(end 0.5842 -1.3335)
			(stroke
				(width 0)
				(type default)
			)
			(fill no)
			(layer "F.Fab")
		)
		(pad "1" smd custom
			(at 0 -0.762)
			(size 0.2159 0.2159)
			(layers "F.Cu" "F.Mask" "F.Paste")
			(net "P5V_A_2")
			(options
				(clearance outline)
				(anchor circle)
			)
			(primitives
				(gr_poly
					(pts
						(arc
							(start -0.3302 -0.4318)
							(mid -0.402042 -0.402042)
							(end -0.4318 -0.3302)
						)
						(arc
							(start -0.4318 0.3302)
							(mid -0.402042 0.402042)
							(end -0.3302 0.4318)
						)
						(arc
							(start 0.3302 0.4318)
							(mid 0.402042 0.402042)
							(end 0.4318 0.3302)
						)
						(arc
							(start 0.4318 -0.3302)
							(mid 0.402042 -0.402042)
							(end 0.3302 -0.4318)
						)
					)
					(width 0)
					(fill yes)
				)
			)
		)
		(pad "2" smd custom
			(at 0 0.762)
			(size 0.2159 0.2159)
			(layers "F.Cu" "F.Mask" "F.Paste")
			(net "DRV_ACT_16")
			(options
				(clearance outline)
				(anchor circle)
			)
			(primitives
				(gr_poly
					(pts
						(arc
							(start -0.3302 -0.4318)
							(mid -0.402042 -0.402042)
							(end -0.4318 -0.3302)
						)
						(arc
							(start -0.4318 0.3302)
							(mid -0.402042 0.402042)
							(end -0.3302 0.4318)
						)
						(arc
							(start 0.3302 0.4318)
							(mid 0.402042 0.402042)
							(end 0.4318 0.3302)
						)
						(arc
							(start 0.4318 -0.3302)
							(mid 0.402042 -0.402042)
							(end 0.3302 -0.4318)
						)
					)
					(width 0)
					(fill yes)
				)
			)
		)
	)
	(footprint ""
		(layer "F.Cu")
		(at 381.5842 -298.704)
		(property "Reference" "TP42"
			(at 0 0 0)
			(layer "F.SilkS")
			(hide yes)
			(effects
				(font
					(size 1.27 1.27)
				)
			)
		)
		(property "Value" "TPAD32-GP"
			(at -0.0508 -1.6764 0)
			(unlocked yes)
			(layer "F.Fab")
			(hide yes)
			(effects
				(font
					(size 1.016 1.016)
					(thickness 0.1524)
				)
			)
		)
		(property "Device Type" "TPAD32"
			(at -0.0508 -3.2004 0)
			(unlocked yes)
			(layer "F.Fab")
			(hide yes)
			(effects
				(font
					(size 1.016 1.016)
					(thickness 0.1524)
				)
			)
		)
		(duplicate_pad_numbers_are_jumpers no)
		(fp_poly
			(pts
				(arc
					(start 0.4064 0)
					(mid -0.4064 0)
					(end 0.4064 0)
				)
			)
			(stroke
				(width 0)
				(type default)
			)
			(fill no)
			(layer "F.CrtYd")
		)
		(fp_poly
			(pts
				(arc
					(start 0.7112 0)
					(mid -0.7112 0)
					(end 0.7112 0)
				)
			)
			(stroke
				(width 0)
				(type default)
			)
			(fill no)
			(layer "F.Fab")
		)
		(pad "1" smd circle
			(at 0 0)
			(size 0.8128 0.8128)
			(layers "F.Cu" "F.Mask" "F.Paste")
			(net "ACT_HDD_8")
		)
	)
	(footprint ""
		(layer "F.Cu")
		(at 33.3248 -207.79994)
		(property "Reference" ""
			(at 0 0 0)
			(layer "F.SilkS")
			(hide yes)
			(effects
				(font
					(size 1.27 1.27)
				)
			)
		)
		(property "Value" "*"
			(at -8.398764 -8.057642 0)
			(unlocked yes)
			(layer "F.Fab")
			(hide yes)
			(effects
				(font
					(size 1.016 1.016)
					(thickness 0.1524)
				)
			)
		)
		(duplicate_pad_numbers_are_jumpers no)
		(fp_poly
			(pts
				(arc
					(start 7.3152 0)
					(mid 0 7.3152)
					(end -7.3152 0)
				)
				(arc
					(start -7.3152 -5.9944)
					(mid 0 -13.3096)
					(end 7.3152 -5.9944)
				)
			)
			(stroke
				(width 0)
				(type default)
			)
			(fill no)
			(layer "B.CrtYd")
		)
		(fp_poly
			(pts
				(arc
					(start 7.3152 0)
					(mid 0 7.3152)
					(end -7.3152 0)
				)
				(arc
					(start -7.3152 -5.9944)
					(mid 0 -13.3096)
					(end 7.3152 -5.9944)
				)
			)
			(stroke
				(width 0)
				(type default)
			)
			(fill no)
			(layer "F.CrtYd")
		)
		(fp_poly
			(pts
				(arc
					(start 7.3152 0)
					(mid 0 7.3152)
					(end -7.3152 0)
				)
				(arc
					(start -7.3152 -5.9944)
					(mid 0 -13.3096)
					(end 7.3152 -5.9944)
				)
			)
			(stroke
				(width 0)
				(type default)
			)
			(fill no)
			(layer "B.Fab")
		)
		(fp_poly
			(pts
				(arc
					(start 7.3152 0)
					(mid 0 7.3152)
					(end -7.3152 0)
				)
				(arc
					(start -7.3152 -5.9944)
					(mid 0 -13.3096)
					(end 7.3152 -5.9944)
				)
			)
			(stroke
				(width 0)
				(type default)
			)
			(fill no)
			(layer "F.Fab")
		)
		(pad "1" thru_hole oval
			(at 0 0)
			(size 14.0208 20.0152)
			(drill 0.0254
				(offset 0 -2.9972)
			)
			(layers "*.Cu" "*.Mask")
			(remove_unused_layers no)
			(net "Net_103")
			(clearance -1.002284)
			(thermal_gap 0.1524)
			(padstack
				(mode front_inner_back)
				(layer "Inner"
					(shape custom)
					(size 2.928012 2.928012)
					(options
						(anchor circle)
					)
					(primitives
						(gr_poly
							(pts
								(arc
									(start 4.571746 -2.084324)
									(mid 0.000333 7.430372)
									(end -4.571492 -2.084324)
								)
								(arc
									(start -4.571492 -2.084324)
									(mid -3.570296 -3.611977)
									(end -2.875026 -5.30098)
								)
								(arc
									(start -2.875026 -5.30098)
									(mid 0.000217 -7.43089)
									(end 2.87528 -5.30098)
								)
								(arc
									(start 2.87528 -5.30098)
									(mid 3.570511 -3.611956)
									(end 4.571746 -2.084324)
								)
							)
							(width 0)
							(fill yes)
						)
					)
					(clearance 0.1524)
				)
				(layer "B.Cu"
					(shape oval)
					(size 14.0208 20.0152)
					(offset 0 -2.9972)
					(clearance -1.002284)
				)
			)
		)
		(zone
			(layers "F.Cu" "B.Cu" "In1.Cu" "In2.Cu" "In3.Cu" "In4.Cu" "In5.Cu" "In6.Cu"
				"In7.Cu" "In8.Cu" "In9.Cu" "In10.Cu"
			)
			(hatch none 0.5)
			(connect_pads
				(clearance 0)
			)
			(min_thickness 0.25)
			(keepout
				(tracks not_allowed)
				(vias allowed)
				(pads allowed)
				(copperpour not_allowed)
				(footprints allowed)
			)
			(placement
				(enabled no)
				(sheetname "")
			)
			(fill
				(thermal_gap 0.5)
				(thermal_bridge_width 0.5)
				(island_removal_mode 0)
			)
			(polygon
				(pts
					(arc
						(start 26.3144 -213.79434)
						(mid 33.3248 -220.80474)
						(end 40.3352 -213.79434)
					)
					(arc
						(start 40.3352 -207.79994)
						(mid 33.3248 -200.78954)
						(end 26.3144 -207.79994)
					)
				)
			)
		)
	)
	(footprint ""
		(layer "F.Cu")
		(at 468.903304 -179.683918 -90)
		(property "Reference" "C344"
			(at 0 0 270)
			(layer "F.SilkS")
			(hide yes)
			(effects
				(font
					(size 1.27 1.27)
				)
			)
		)
		(property "Value" "SC4D7U25V5KX-1-GP"
			(at -0.0762 -6.1214 270)
			(unlocked yes)
			(layer "F.Fab")
			(hide yes)
			(effects
				(font
					(size 1.016 1.016)
					(thickness 0.1524)
				)
			)
		)
		(property "Device Type" "C805H58"
			(at -0.0762 -8.1534 270)
			(unlocked yes)
			(layer "F.Fab")
			(hide yes)
			(effects
				(font
					(size 1.016 1.016)
					(thickness 0.1524)
				)
			)
		)
		(duplicate_pad_numbers_are_jumpers no)
		(fp_line
			(start 0.635 0)
			(end -0.635 0)
			(stroke
				(width 0.508)
				(type default)
			)
			(layer "F.SilkS")
		)
		(fp_rect
			(start -0.9652 1.778)
			(end 0.9652 -1.778)
			(stroke
				(width 0)
				(type default)
			)
			(fill no)
			(layer "F.CrtYd")
		)
		(fp_poly
			(pts
				(xy -0.9652 -1.778) (xy 0.9652 -1.778) (xy 0.9652 1.778) (xy -0.9652 1.778)
			)
			(stroke
				(width 0)
				(type default)
			)
			(fill no)
			(layer "F.Fab")
		)
		(pad "1" smd rect
			(at 0 -0.9652 270)
			(size 1.397 1.143)
			(layers "F.Cu" "F.Mask" "F.Paste")
			(net "P12V_HDD23")
		)
		(pad "2" smd rect
			(at 0 0.9652 270)
			(size 1.397 1.143)
			(layers "F.Cu" "F.Mask" "F.Paste")
			(net "GND")
		)
	)
	(footprint ""
		(layer "F.Cu")
		(at 180.7464 -159.871918 -90)
		(property "Reference" "R531"
			(at 0 0 270)
			(layer "F.SilkS")
			(hide yes)
			(effects
				(font
					(size 1.27 1.27)
				)
			)
		)
		(property "Value" "0R2J-2-GP"
			(at 0.064008 -3.993896 270)
			(unlocked yes)
			(layer "F.Fab")
			(hide yes)
			(effects
				(font
					(size 1.016 1.016)
					(thickness 0.1524)
				)
			)
		)
		(property "Device Type" "R402H16"
			(at 0.064008 -5.517896 270)
			(unlocked yes)
			(layer "F.Fab")
			(hide yes)
			(effects
				(font
					(size 1.016 1.016)
					(thickness 0.1524)
				)
			)
		)
		(duplicate_pad_numbers_are_jumpers no)
		(fp_line
			(start -0.508 -0.9398)
			(end -0.508 0.9398)
			(stroke
				(width 0.1524)
				(type default)
			)
			(layer "F.SilkS")
		)
		(fp_line
			(start 0.508 -0.9398)
			(end -0.508 -0.9398)
			(stroke
				(width 0.1524)
				(type default)
			)
			(layer "F.SilkS")
		)
		(fp_rect
			(start -0.508 0.9398)
			(end 0.508 -0.9398)
			(stroke
				(width 0)
				(type default)
			)
			(fill no)
			(layer "F.CrtYd")
		)
		(fp_rect
			(start -0.508 0.9398)
			(end 0.508 -0.9398)
			(stroke
				(width 0)
				(type default)
			)
			(fill no)
			(layer "F.Fab")
		)
		(pad "1" smd custom
			(at 0 -0.4445 270)
			(size 0.1397 0.1397)
			(layers "F.Cu" "F.Mask" "F.Paste")
			(net "DRIVE_A_17_PWR")
			(options
				(clearance outline)
				(anchor circle)
			)
			(primitives
				(gr_poly
					(pts
						(arc
							(start -0.1778 -0.2794)
							(mid -0.249642 -0.249642)
							(end -0.2794 -0.1778)
						)
						(arc
							(start -0.2794 0.1778)
							(mid -0.249642 0.249642)
							(end -0.1778 0.2794)
						)
						(arc
							(start 0.1778 0.2794)
							(mid 0.249642 0.249642)
							(end 0.2794 0.1778)
						)
						(arc
							(start 0.2794 -0.1778)
							(mid 0.249642 -0.249642)
							(end 0.1778 -0.2794)
						)
					)
					(width 0)
					(fill yes)
				)
			)
		)
		(pad "2" smd custom
			(at 0 0.4445 270)
			(size 0.1397 0.1397)
			(layers "F.Cu" "F.Mask" "F.Paste")
			(net "SW_PWR_R_HDD17")
			(options
				(clearance outline)
				(anchor circle)
			)
			(primitives
				(gr_poly
					(pts
						(arc
							(start -0.1778 -0.2794)
							(mid -0.249642 -0.249642)
							(end -0.2794 -0.1778)
						)
						(arc
							(start -0.2794 0.1778)
							(mid -0.249642 0.249642)
							(end -0.1778 0.2794)
						)
						(arc
							(start 0.1778 0.2794)
							(mid 0.249642 0.249642)
							(end 0.2794 0.1778)
						)
						(arc
							(start 0.2794 -0.1778)
							(mid 0.249642 -0.249642)
							(end 0.1778 -0.2794)
						)
					)
					(width 0)
					(fill yes)
				)
			)
		)
	)
	(footprint ""
		(layer "F.Cu")
		(at 222.928942 -219.304362)
		(property "Reference" "R415"
			(at 0 0 0)
			(layer "F.SilkS")
			(hide yes)
			(effects
				(font
					(size 1.27 1.27)
				)
			)
		)
		(property "Value" "1KR2F-3-GP"
			(at 0.064008 -3.993896 0)
			(unlocked yes)
			(layer "F.Fab")
			(hide yes)
			(effects
				(font
					(size 1.016 1.016)
					(thickness 0.1524)
				)
			)
		)
		(property "Device Type" "R402H16"
			(at 0.064008 -5.517896 0)
			(unlocked yes)
			(layer "F.Fab")
			(hide yes)
			(effects
				(font
					(size 1.016 1.016)
					(thickness 0.1524)
				)
			)
		)
		(duplicate_pad_numbers_are_jumpers no)
		(fp_line
			(start -0.508 -0.9398)
			(end -0.508 0.9398)
			(stroke
				(width 0.1524)
				(type default)
			)
			(layer "F.SilkS")
		)
		(fp_line
			(start 0.508 -0.9398)
			(end -0.508 -0.9398)
			(stroke
				(width 0.1524)
				(type default)
			)
			(layer "F.SilkS")
		)
		(fp_rect
			(start -0.508 0.9398)
			(end 0.508 -0.9398)
			(stroke
				(width 0)
				(type default)
			)
			(fill no)
			(layer "F.CrtYd")
		)
		(fp_rect
			(start -0.508 0.9398)
			(end 0.508 -0.9398)
			(stroke
				(width 0)
				(type default)
			)
			(fill no)
			(layer "F.Fab")
		)
		(pad "1" smd custom
			(at 0 -0.4445)
			(size 0.1397 0.1397)
			(layers "F.Cu" "F.Mask" "F.Paste")
			(net "P3V3_STBY_A")
			(options
				(clearance outline)
				(anchor circle)
			)
			(primitives
				(gr_poly
					(pts
						(arc
							(start -0.1778 -0.2794)
							(mid -0.249642 -0.249642)
							(end -0.2794 -0.1778)
						)
						(arc
							(start -0.2794 0.1778)
							(mid -0.249642 0.249642)
							(end -0.1778 0.2794)
						)
						(arc
							(start 0.1778 0.2794)
							(mid 0.249642 0.249642)
							(end 0.2794 0.1778)
						)
						(arc
							(start 0.2794 -0.1778)
							(mid 0.249642 -0.249642)
							(end 0.1778 -0.2794)
						)
					)
					(width 0)
					(fill yes)
				)
			)
		)
		(pad "2" smd custom
			(at 0 0.4445)
			(size 0.1397 0.1397)
			(layers "F.Cu" "F.Mask" "F.Paste")
			(net "I2C_SCC_A_SDA_BUF")
			(options
				(clearance outline)
				(anchor circle)
			)
			(primitives
				(gr_poly
					(pts
						(arc
							(start -0.1778 -0.2794)
							(mid -0.249642 -0.249642)
							(end -0.2794 -0.1778)
						)
						(arc
							(start -0.2794 0.1778)
							(mid -0.249642 0.249642)
							(end -0.1778 0.2794)
						)
						(arc
							(start 0.1778 0.2794)
							(mid 0.249642 0.249642)
							(end 0.2794 0.1778)
						)
						(arc
							(start 0.2794 -0.1778)
							(mid 0.249642 -0.249642)
							(end 0.1778 -0.2794)
						)
					)
					(width 0)
					(fill yes)
				)
			)
		)
	)
	(footprint ""
		(layer "F.Cu")
		(at 255.993646 -261.326122 180)
		(property "Reference" "R431"
			(at 0 0 180)
			(layer "F.SilkS")
			(hide yes)
			(effects
				(font
					(size 1.27 1.27)
				)
			)
		)
		(property "Value" "1KR2F-3-GP"
			(at 0.064008 -3.993896 180)
			(unlocked yes)
			(layer "F.Fab")
			(hide yes)
			(effects
				(font
					(size 1.016 1.016)
					(thickness 0.1524)
				)
			)
		)
		(property "Device Type" "R402H16"
			(at 0.064008 -5.517896 180)
			(unlocked yes)
			(layer "F.Fab")
			(hide yes)
			(effects
				(font
					(size 1.016 1.016)
					(thickness 0.1524)
				)
			)
		)
		(duplicate_pad_numbers_are_jumpers no)
		(fp_line
			(start 0.508 -0.9398)
			(end -0.508 -0.9398)
			(stroke
				(width 0.1524)
				(type default)
			)
			(layer "F.SilkS")
		)
		(fp_line
			(start -0.508 -0.9398)
			(end -0.508 0.9398)
			(stroke
				(width 0.1524)
				(type default)
			)
			(layer "F.SilkS")
		)
		(fp_rect
			(start -0.508 0.9398)
			(end 0.508 -0.9398)
			(stroke
				(width 0)
				(type default)
			)
			(fill no)
			(layer "F.CrtYd")
		)
		(fp_rect
			(start -0.508 0.9398)
			(end 0.508 -0.9398)
			(stroke
				(width 0)
				(type default)
			)
			(fill no)
			(layer "F.Fab")
		)
		(pad "1" smd custom
			(at 0 -0.4445 180)
			(size 0.1397 0.1397)
			(layers "F.Cu" "F.Mask" "F.Paste")
			(net "P3V3_STBY_A")
			(options
				(clearance outline)
				(anchor circle)
			)
			(primitives
				(gr_poly
					(pts
						(arc
							(start -0.1778 -0.2794)
							(mid -0.249642 -0.249642)
							(end -0.2794 -0.1778)
						)
						(arc
							(start -0.2794 0.1778)
							(mid -0.249642 0.249642)
							(end -0.1778 0.2794)
						)
						(arc
							(start 0.1778 0.2794)
							(mid 0.249642 0.249642)
							(end 0.2794 0.1778)
						)
						(arc
							(start 0.2794 -0.1778)
							(mid 0.249642 -0.249642)
							(end 0.1778 -0.2794)
						)
					)
					(width 0)
					(fill yes)
				)
			)
		)
		(pad "2" smd custom
			(at 0 0.4445 180)
			(size 0.1397 0.1397)
			(layers "F.Cu" "F.Mask" "F.Paste")
			(net "I2C_DRIVE_A_INS_SCL")
			(options
				(clearance outline)
				(anchor circle)
			)
			(primitives
				(gr_poly
					(pts
						(arc
							(start -0.1778 -0.2794)
							(mid -0.249642 -0.249642)
							(end -0.2794 -0.1778)
						)
						(arc
							(start -0.2794 0.1778)
							(mid -0.249642 0.249642)
							(end -0.1778 0.2794)
						)
						(arc
							(start 0.1778 0.2794)
							(mid 0.249642 0.249642)
							(end 0.2794 0.1778)
						)
						(arc
							(start 0.2794 -0.1778)
							(mid 0.249642 -0.249642)
							(end 0.1778 -0.2794)
						)
					)
					(width 0)
					(fill yes)
				)
			)
		)
	)
	(footprint ""
		(layer "F.Cu")
		(at 447.952876 -248.43105 -90)
		(property "Reference" "R1250"
			(at 0 0 270)
			(layer "F.SilkS")
			(hide yes)
			(effects
				(font
					(size 1.27 1.27)
				)
			)
		)
		(property "Value" "3D01R5F-GP"
			(at 0 -8.9535 270)
			(unlocked yes)
			(layer "F.Fab")
			(hide yes)
			(effects
				(font
					(size 1.27 1.016)
					(thickness 0.1524)
				)
			)
		)
		(property "Device Type" "R805H24"
			(at 0 -10.6299 270)
			(unlocked yes)
			(layer "F.Fab")
			(hide yes)
			(effects
				(font
					(size 1.27 1.016)
					(thickness 0.1524)
				)
			)
		)
		(duplicate_pad_numbers_are_jumpers no)
		(fp_line
			(start -0.889 1.7018)
			(end 0.889 1.7018)
			(stroke
				(width 0.1524)
				(type default)
			)
			(layer "F.SilkS")
		)
		(fp_line
			(start 0.889 1.7018)
			(end 0.889 -0.508)
			(stroke
				(width 0.1524)
				(type default)
			)
			(layer "F.SilkS")
		)
		(fp_line
			(start -0.889 0.0762)
			(end -0.889 1.7018)
			(stroke
				(width 0.1524)
				(type default)
			)
			(layer "F.SilkS")
		)
		(fp_line
			(start -0.889 -1.7018)
			(end -0.889 0.2794)
			(stroke
				(width 0.1524)
				(type default)
			)
			(layer "F.SilkS")
		)
		(fp_line
			(start 0.889 -1.7018)
			(end 0.889 -0.381)
			(stroke
				(width 0.1524)
				(type default)
			)
			(layer "F.SilkS")
		)
		(fp_line
			(start 0.889 -1.7018)
			(end -0.889 -1.7018)
			(stroke
				(width 0.1524)
				(type default)
			)
			(layer "F.SilkS")
		)
		(fp_poly
			(pts
				(xy 0.9652 -1.778) (xy 0.9652 1.778) (xy -0.9652 1.778) (xy -0.9652 -1.778)
			)
			(stroke
				(width 0)
				(type default)
			)
			(fill no)
			(layer "F.CrtYd")
		)
		(fp_rect
			(start -0.9652 1.778)
			(end 0.9652 -1.778)
			(stroke
				(width 0)
				(type default)
			)
			(fill no)
			(layer "F.Fab")
		)
		(pad "1" smd rect
			(at 0 -0.9652 270)
			(size 1.397 1.143)
			(layers "F.Cu" "F.Mask" "F.Paste")
			(net "P5V_C_SNB")
		)
		(pad "2" smd rect
			(at 0 0.9652 270)
			(size 1.397 1.143)
			(layers "F.Cu" "F.Mask" "F.Paste")
			(net "GND")
		)
	)
	(footprint ""
		(layer "F.Cu")
		(at 239.649 -256.7178)
		(property "Reference" "C14"
			(at 0 0 0)
			(layer "F.SilkS")
			(hide yes)
			(effects
				(font
					(size 1.27 1.27)
				)
			)
		)
		(property "Value" "SCD1U16V2KX-3GP"
			(at 1.1811 -2.7051 0)
			(unlocked yes)
			(layer "F.Fab")
			(hide yes)
			(effects
				(font
					(size 1.016 1.016)
					(thickness 0.1524)
				)
			)
		)
		(property "Device Type" "C402H22"
			(at 1.1811 -4.2291 0)
			(unlocked yes)
			(layer "F.Fab")
			(hide yes)
			(effects
				(font
					(size 1.016 1.016)
					(thickness 0.1524)
				)
			)
		)
		(duplicate_pad_numbers_are_jumpers no)
		(fp_rect
			(start -0.4318 0.9525)
			(end 0.4318 -0.9525)
			(stroke
				(width 0)
				(type default)
			)
			(fill no)
			(layer "F.CrtYd")
		)
		(fp_rect
			(start -0.4318 0.9525)
			(end 0.4318 -0.9525)
			(stroke
				(width 0)
				(type default)
			)
			(fill no)
			(layer "F.Fab")
		)
		(pad "1" smd custom
			(at 0 -0.4445)
			(size 0.1524 0.1524)
			(layers "F.Cu" "F.Mask" "F.Paste")
			(net "P3V3_STBY_A")
			(options
				(clearance outline)
				(anchor circle)
			)
			(primitives
				(gr_poly
					(pts
						(arc
							(start 0.3048 -0.2032)
							(mid 0.275042 -0.275042)
							(end 0.2032 -0.3048)
						)
						(arc
							(start -0.2032 -0.3048)
							(mid -0.275042 -0.275042)
							(end -0.3048 -0.2032)
						)
						(arc
							(start -0.3048 0.2032)
							(mid -0.275042 0.275042)
							(end -0.2032 0.3048)
						)
						(arc
							(start 0.2032 0.3048)
							(mid 0.275042 0.275042)
							(end 0.3048 0.2032)
						)
					)
					(width 0)
					(fill yes)
				)
			)
		)
		(pad "2" smd custom
			(at 0 0.4445)
			(size 0.1524 0.1524)
			(layers "F.Cu" "F.Mask" "F.Paste")
			(net "GND")
			(options
				(clearance outline)
				(anchor circle)
			)
			(primitives
				(gr_poly
					(pts
						(arc
							(start 0.3048 -0.2032)
							(mid 0.275042 -0.275042)
							(end 0.2032 -0.3048)
						)
						(arc
							(start -0.2032 -0.3048)
							(mid -0.275042 -0.275042)
							(end -0.3048 -0.2032)
						)
						(arc
							(start -0.3048 0.2032)
							(mid -0.275042 0.275042)
							(end -0.2032 0.3048)
						)
						(arc
							(start 0.2032 0.3048)
							(mid 0.275042 0.275042)
							(end 0.3048 0.2032)
						)
					)
					(width 0)
					(fill yes)
				)
			)
		)
	)
	(footprint ""
		(layer "F.Cu")
		(at 51.943 -165.1 -90)
		(property "Reference" "R436"
			(at 0 0 270)
			(layer "F.SilkS")
			(hide yes)
			(effects
				(font
					(size 1.27 1.27)
				)
			)
		)
		(property "Value" "4K7R2J-2-GP"
			(at 0.064008 -3.993896 270)
			(unlocked yes)
			(layer "F.Fab")
			(hide yes)
			(effects
				(font
					(size 1.016 1.016)
					(thickness 0.1524)
				)
			)
		)
		(property "Device Type" "R402H16"
			(at 0.064008 -5.517896 270)
			(unlocked yes)
			(layer "F.Fab")
			(hide yes)
			(effects
				(font
					(size 1.016 1.016)
					(thickness 0.1524)
				)
			)
		)
		(duplicate_pad_numbers_are_jumpers no)
		(fp_line
			(start -0.508 -0.9398)
			(end -0.508 0.9398)
			(stroke
				(width 0.1524)
				(type default)
			)
			(layer "F.SilkS")
		)
		(fp_line
			(start 0.508 -0.9398)
			(end -0.508 -0.9398)
			(stroke
				(width 0.1524)
				(type default)
			)
			(layer "F.SilkS")
		)
		(fp_rect
			(start -0.508 0.9398)
			(end 0.508 -0.9398)
			(stroke
				(width 0)
				(type default)
			)
			(fill no)
			(layer "F.CrtYd")
		)
		(fp_rect
			(start -0.508 0.9398)
			(end 0.508 -0.9398)
			(stroke
				(width 0)
				(type default)
			)
			(fill no)
			(layer "F.Fab")
		)
		(pad "1" smd custom
			(at 0 -0.4445 270)
			(size 0.1397 0.1397)
			(layers "F.Cu" "F.Mask" "F.Paste")
			(net "P12V_A")
			(options
				(clearance outline)
				(anchor circle)
			)
			(primitives
				(gr_poly
					(pts
						(arc
							(start -0.1778 -0.2794)
							(mid -0.249642 -0.249642)
							(end -0.2794 -0.1778)
						)
						(arc
							(start -0.2794 0.1778)
							(mid -0.249642 0.249642)
							(end -0.1778 0.2794)
						)
						(arc
							(start 0.1778 0.2794)
							(mid 0.249642 0.249642)
							(end 0.2794 0.1778)
						)
						(arc
							(start 0.2794 -0.1778)
							(mid 0.249642 -0.249642)
							(end 0.1778 -0.2794)
						)
					)
					(width 0)
					(fill yes)
				)
			)
		)
		(pad "2" smd custom
			(at 0 0.4445 270)
			(size 0.1397 0.1397)
			(layers "F.Cu" "F.Mask" "F.Paste")
			(net "SW_HDD_P13")
			(options
				(clearance outline)
				(anchor circle)
			)
			(primitives
				(gr_poly
					(pts
						(arc
							(start -0.1778 -0.2794)
							(mid -0.249642 -0.249642)
							(end -0.2794 -0.1778)
						)
						(arc
							(start -0.2794 0.1778)
							(mid -0.249642 0.249642)
							(end -0.1778 0.2794)
						)
						(arc
							(start 0.1778 0.2794)
							(mid 0.249642 0.249642)
							(end 0.2794 0.1778)
						)
						(arc
							(start 0.2794 -0.1778)
							(mid 0.249642 -0.249642)
							(end 0.1778 -0.2794)
						)
					)
					(width 0)
					(fill yes)
				)
			)
		)
	)
	(footprint ""
		(layer "F.Cu")
		(at 277.4188 -284.7086)
		(property "Reference" "R116"
			(at 0 0 0)
			(layer "F.SilkS")
			(hide yes)
			(effects
				(font
					(size 1.27 1.27)
				)
			)
		)
		(property "Value" "4K7R2F-GP"
			(at 0.064008 -3.993896 0)
			(unlocked yes)
			(layer "F.Fab")
			(hide yes)
			(effects
				(font
					(size 1.016 1.016)
					(thickness 0.1524)
				)
			)
		)
		(property "Device Type" "R402H16"
			(at 0.064008 -5.517896 0)
			(unlocked yes)
			(layer "F.Fab")
			(hide yes)
			(effects
				(font
					(size 1.016 1.016)
					(thickness 0.1524)
				)
			)
		)
		(duplicate_pad_numbers_are_jumpers no)
		(fp_line
			(start -0.508 -0.9398)
			(end -0.508 0.9398)
			(stroke
				(width 0.1524)
				(type default)
			)
			(layer "F.SilkS")
		)
		(fp_line
			(start 0.508 -0.9398)
			(end -0.508 -0.9398)
			(stroke
				(width 0.1524)
				(type default)
			)
			(layer "F.SilkS")
		)
		(fp_rect
			(start -0.508 0.9398)
			(end 0.508 -0.9398)
			(stroke
				(width 0)
				(type default)
			)
			(fill no)
			(layer "F.CrtYd")
		)
		(fp_rect
			(start -0.508 0.9398)
			(end 0.508 -0.9398)
			(stroke
				(width 0)
				(type default)
			)
			(fill no)
			(layer "F.Fab")
		)
		(pad "1" smd custom
			(at 0 -0.4445)
			(size 0.1397 0.1397)
			(layers "F.Cu" "F.Mask" "F.Paste")
			(net "P3V3_STBY_A")
			(options
				(clearance outline)
				(anchor circle)
			)
			(primitives
				(gr_poly
					(pts
						(arc
							(start -0.1778 -0.2794)
							(mid -0.249642 -0.249642)
							(end -0.2794 -0.1778)
						)
						(arc
							(start -0.2794 0.1778)
							(mid -0.249642 0.249642)
							(end -0.1778 0.2794)
						)
						(arc
							(start 0.1778 0.2794)
							(mid 0.249642 0.249642)
							(end 0.2794 0.1778)
						)
						(arc
							(start 0.2794 -0.1778)
							(mid 0.249642 -0.249642)
							(end 0.1778 -0.2794)
						)
					)
					(width 0)
					(fill yes)
				)
			)
		)
		(pad "2" smd custom
			(at 0 0.4445)
			(size 0.1397 0.1397)
			(layers "F.Cu" "F.Mask" "F.Paste")
			(net "IO_EXP1_HDD_FAULT_A0")
			(options
				(clearance outline)
				(anchor circle)
			)
			(primitives
				(gr_poly
					(pts
						(arc
							(start -0.1778 -0.2794)
							(mid -0.249642 -0.249642)
							(end -0.2794 -0.1778)
						)
						(arc
							(start -0.2794 0.1778)
							(mid -0.249642 0.249642)
							(end -0.1778 0.2794)
						)
						(arc
							(start 0.1778 0.2794)
							(mid 0.249642 0.249642)
							(end 0.2794 0.1778)
						)
						(arc
							(start 0.2794 -0.1778)
							(mid 0.249642 -0.249642)
							(end 0.1778 -0.2794)
						)
					)
					(width 0)
					(fill yes)
				)
			)
		)
	)
	(footprint ""
		(layer "F.Cu")
		(at 180.7464 -46.014894 -90)
		(property "Reference" "R805"
			(at 0 0 270)
			(layer "F.SilkS")
			(hide yes)
			(effects
				(font
					(size 1.27 1.27)
				)
			)
		)
		(property "Value" "1KR2F-3-GP"
			(at 0.064008 -3.993896 270)
			(unlocked yes)
			(layer "F.Fab")
			(hide yes)
			(effects
				(font
					(size 1.016 1.016)
					(thickness 0.1524)
				)
			)
		)
		(property "Device Type" "R402H16"
			(at 0.064008 -5.517896 270)
			(unlocked yes)
			(layer "F.Fab")
			(hide yes)
			(effects
				(font
					(size 1.016 1.016)
					(thickness 0.1524)
				)
			)
		)
		(duplicate_pad_numbers_are_jumpers no)
		(fp_line
			(start -0.508 -0.9398)
			(end -0.508 0.9398)
			(stroke
				(width 0.1524)
				(type default)
			)
			(layer "F.SilkS")
		)
		(fp_line
			(start 0.508 -0.9398)
			(end -0.508 -0.9398)
			(stroke
				(width 0.1524)
				(type default)
			)
			(layer "F.SilkS")
		)
		(fp_rect
			(start -0.508 0.9398)
			(end 0.508 -0.9398)
			(stroke
				(width 0)
				(type default)
			)
			(fill no)
			(layer "F.CrtYd")
		)
		(fp_rect
			(start -0.508 0.9398)
			(end 0.508 -0.9398)
			(stroke
				(width 0)
				(type default)
			)
			(fill no)
			(layer "F.Fab")
		)
		(pad "1" smd custom
			(at 0 -0.4445 270)
			(size 0.1397 0.1397)
			(layers "F.Cu" "F.Mask" "F.Paste")
			(net "P3V3_STBY_A")
			(options
				(clearance outline)
				(anchor circle)
			)
			(primitives
				(gr_poly
					(pts
						(arc
							(start -0.1778 -0.2794)
							(mid -0.249642 -0.249642)
							(end -0.2794 -0.1778)
						)
						(arc
							(start -0.2794 0.1778)
							(mid -0.249642 0.249642)
							(end -0.1778 0.2794)
						)
						(arc
							(start 0.1778 0.2794)
							(mid 0.249642 0.249642)
							(end 0.2794 0.1778)
						)
						(arc
							(start 0.2794 -0.1778)
							(mid 0.249642 -0.249642)
							(end 0.1778 -0.2794)
						)
					)
					(width 0)
					(fill yes)
				)
			)
		)
		(pad "2" smd custom
			(at 0 0.4445 270)
			(size 0.1397 0.1397)
			(layers "F.Cu" "F.Mask" "F.Paste")
			(net "SW_PWR_R_HDD29")
			(options
				(clearance outline)
				(anchor circle)
			)
			(primitives
				(gr_poly
					(pts
						(arc
							(start -0.1778 -0.2794)
							(mid -0.249642 -0.249642)
							(end -0.2794 -0.1778)
						)
						(arc
							(start -0.2794 0.1778)
							(mid -0.249642 0.249642)
							(end -0.1778 0.2794)
						)
						(arc
							(start 0.1778 0.2794)
							(mid 0.249642 0.249642)
							(end 0.2794 0.1778)
						)
						(arc
							(start 0.2794 -0.1778)
							(mid 0.249642 -0.249642)
							(end 0.1778 -0.2794)
						)
					)
					(width 0)
					(fill yes)
				)
			)
		)
	)
	(footprint ""
		(layer "F.Cu")
		(at 336.931 -160.735518 180)
		(property "Reference" "R558"
			(at 0 0 180)
			(layer "F.SilkS")
			(hide yes)
			(effects
				(font
					(size 1.27 1.27)
				)
			)
		)
		(property "Value" "4K7R2J-2-GP"
			(at 0.064008 -3.993896 180)
			(unlocked yes)
			(layer "F.Fab")
			(hide yes)
			(effects
				(font
					(size 1.016 1.016)
					(thickness 0.1524)
				)
			)
		)
		(property "Device Type" "R402H16"
			(at 0.064008 -5.517896 180)
			(unlocked yes)
			(layer "F.Fab")
			(hide yes)
			(effects
				(font
					(size 1.016 1.016)
					(thickness 0.1524)
				)
			)
		)
		(duplicate_pad_numbers_are_jumpers no)
		(fp_line
			(start 0.508 -0.9398)
			(end -0.508 -0.9398)
			(stroke
				(width 0.1524)
				(type default)
			)
			(layer "F.SilkS")
		)
		(fp_line
			(start -0.508 -0.9398)
			(end -0.508 0.9398)
			(stroke
				(width 0.1524)
				(type default)
			)
			(layer "F.SilkS")
		)
		(fp_rect
			(start -0.508 0.9398)
			(end 0.508 -0.9398)
			(stroke
				(width 0)
				(type default)
			)
			(fill no)
			(layer "F.CrtYd")
		)
		(fp_rect
			(start -0.508 0.9398)
			(end 0.508 -0.9398)
			(stroke
				(width 0)
				(type default)
			)
			(fill no)
			(layer "F.Fab")
		)
		(pad "1" smd custom
			(at 0 -0.4445 180)
			(size 0.1397 0.1397)
			(layers "F.Cu" "F.Mask" "F.Paste")
			(net "P12V_A")
			(options
				(clearance outline)
				(anchor circle)
			)
			(primitives
				(gr_poly
					(pts
						(arc
							(start -0.1778 -0.2794)
							(mid -0.249642 -0.249642)
							(end -0.2794 -0.1778)
						)
						(arc
							(start -0.2794 0.1778)
							(mid -0.249642 0.249642)
							(end -0.1778 0.2794)
						)
						(arc
							(start 0.1778 0.2794)
							(mid 0.249642 0.249642)
							(end 0.2794 0.1778)
						)
						(arc
							(start 0.2794 -0.1778)
							(mid 0.249642 -0.249642)
							(end 0.1778 -0.2794)
						)
					)
					(width 0)
					(fill yes)
				)
			)
		)
		(pad "2" smd custom
			(at 0 0.4445 180)
			(size 0.1397 0.1397)
			(layers "F.Cu" "F.Mask" "F.Paste")
			(net "SW_HDD_R18")
			(options
				(clearance outline)
				(anchor circle)
			)
			(primitives
				(gr_poly
					(pts
						(arc
							(start -0.1778 -0.2794)
							(mid -0.249642 -0.249642)
							(end -0.2794 -0.1778)
						)
						(arc
							(start -0.2794 0.1778)
							(mid -0.249642 0.249642)
							(end -0.1778 0.2794)
						)
						(arc
							(start 0.1778 0.2794)
							(mid 0.249642 0.249642)
							(end 0.2794 0.1778)
						)
						(arc
							(start 0.2794 -0.1778)
							(mid 0.249642 -0.249642)
							(end 0.1778 -0.2794)
						)
					)
					(width 0)
					(fill yes)
				)
			)
		)
	)
	(footprint ""
		(layer "F.Cu")
		(at 109.492796 -54.523894 90)
		(property "Reference" "C400"
			(at 0 0 90)
			(layer "F.SilkS")
			(hide yes)
			(effects
				(font
					(size 1.27 1.27)
				)
			)
		)
		(property "Value" "SCD033U25V2KX-GP"
			(at 1.1811 -2.7051 90)
			(unlocked yes)
			(layer "F.Fab")
			(hide yes)
			(effects
				(font
					(size 1.016 1.016)
					(thickness 0.1524)
				)
			)
		)
		(property "Device Type" "C402H22"
			(at 1.1811 -4.2291 90)
			(unlocked yes)
			(layer "F.Fab")
			(hide yes)
			(effects
				(font
					(size 1.016 1.016)
					(thickness 0.1524)
				)
			)
		)
		(duplicate_pad_numbers_are_jumpers no)
		(fp_rect
			(start -0.4318 0.9525)
			(end 0.4318 -0.9525)
			(stroke
				(width 0)
				(type default)
			)
			(fill no)
			(layer "F.CrtYd")
		)
		(fp_rect
			(start -0.4318 0.9525)
			(end 0.4318 -0.9525)
			(stroke
				(width 0)
				(type default)
			)
			(fill no)
			(layer "F.Fab")
		)
		(pad "1" smd custom
			(at 0 -0.4445 90)
			(size 0.1524 0.1524)
			(layers "F.Cu" "F.Mask" "F.Paste")
			(net "P12V_A")
			(options
				(clearance outline)
				(anchor circle)
			)
			(primitives
				(gr_poly
					(pts
						(arc
							(start 0.3048 -0.2032)
							(mid 0.275042 -0.275042)
							(end 0.2032 -0.3048)
						)
						(arc
							(start -0.2032 -0.3048)
							(mid -0.275042 -0.275042)
							(end -0.3048 -0.2032)
						)
						(arc
							(start -0.3048 0.2032)
							(mid -0.275042 0.275042)
							(end -0.2032 0.3048)
						)
						(arc
							(start 0.2032 0.3048)
							(mid 0.275042 0.275042)
							(end 0.3048 0.2032)
						)
					)
					(width 0)
					(fill yes)
				)
			)
		)
		(pad "2" smd custom
			(at 0 0.4445 90)
			(size 0.1524 0.1524)
			(layers "F.Cu" "F.Mask" "F.Paste")
			(net "SW_HDD_N27")
			(options
				(clearance outline)
				(anchor circle)
			)
			(primitives
				(gr_poly
					(pts
						(arc
							(start 0.3048 -0.2032)
							(mid 0.275042 -0.275042)
							(end 0.2032 -0.3048)
						)
						(arc
							(start -0.2032 -0.3048)
							(mid -0.275042 -0.275042)
							(end -0.3048 -0.2032)
						)
						(arc
							(start -0.3048 0.2032)
							(mid -0.275042 0.275042)
							(end -0.2032 0.3048)
						)
						(arc
							(start 0.2032 0.3048)
							(mid 0.275042 0.275042)
							(end 0.3048 0.2032)
						)
					)
					(width 0)
					(fill yes)
				)
			)
		)
	)
	(footprint ""
		(layer "F.Cu")
		(at 14.842998 -169.523918 90)
		(property "Reference" "C205"
			(at 0 0 90)
			(layer "F.SilkS")
			(hide yes)
			(effects
				(font
					(size 1.27 1.27)
				)
			)
		)
		(property "Value" "SCD033U25V2KX-GP"
			(at 1.1811 -2.7051 90)
			(unlocked yes)
			(layer "F.Fab")
			(hide yes)
			(effects
				(font
					(size 1.016 1.016)
					(thickness 0.1524)
				)
			)
		)
		(property "Device Type" "C402H22"
			(at 1.1811 -4.2291 90)
			(unlocked yes)
			(layer "F.Fab")
			(hide yes)
			(effects
				(font
					(size 1.016 1.016)
					(thickness 0.1524)
				)
			)
		)
		(duplicate_pad_numbers_are_jumpers no)
		(fp_rect
			(start -0.4318 0.9525)
			(end 0.4318 -0.9525)
			(stroke
				(width 0)
				(type default)
			)
			(fill no)
			(layer "F.CrtYd")
		)
		(fp_rect
			(start -0.4318 0.9525)
			(end 0.4318 -0.9525)
			(stroke
				(width 0)
				(type default)
			)
			(fill no)
			(layer "F.Fab")
		)
		(pad "1" smd custom
			(at 0 -0.4445 90)
			(size 0.1524 0.1524)
			(layers "F.Cu" "F.Mask" "F.Paste")
			(net "P12V_A")
			(options
				(clearance outline)
				(anchor circle)
			)
			(primitives
				(gr_poly
					(pts
						(arc
							(start 0.3048 -0.2032)
							(mid 0.275042 -0.275042)
							(end 0.2032 -0.3048)
						)
						(arc
							(start -0.2032 -0.3048)
							(mid -0.275042 -0.275042)
							(end -0.3048 -0.2032)
						)
						(arc
							(start -0.3048 0.2032)
							(mid -0.275042 0.275042)
							(end -0.2032 0.3048)
						)
						(arc
							(start 0.2032 0.3048)
							(mid 0.275042 0.275042)
							(end 0.3048 0.2032)
						)
					)
					(width 0)
					(fill yes)
				)
			)
		)
		(pad "2" smd custom
			(at 0 0.4445 90)
			(size 0.1524 0.1524)
			(layers "F.Cu" "F.Mask" "F.Paste")
			(net "SW_HDD_N12")
			(options
				(clearance outline)
				(anchor circle)
			)
			(primitives
				(gr_poly
					(pts
						(arc
							(start 0.3048 -0.2032)
							(mid 0.275042 -0.275042)
							(end 0.2032 -0.3048)
						)
						(arc
							(start -0.2032 -0.3048)
							(mid -0.275042 -0.275042)
							(end -0.3048 -0.2032)
						)
						(arc
							(start -0.3048 0.2032)
							(mid -0.275042 0.275042)
							(end -0.2032 0.3048)
						)
						(arc
							(start 0.2032 0.3048)
							(mid 0.275042 0.275042)
							(end 0.3048 0.2032)
						)
					)
					(width 0)
					(fill yes)
				)
			)
		)
	)
	(footprint ""
		(layer "F.Cu")
		(at 109.492796 -174.857918)
		(property "Reference" "Q92"
			(at 0 0 0)
			(layer "F.SilkS")
			(hide yes)
			(effects
				(font
					(size 1.27 1.27)
				)
			)
		)
		(property "Value" "AO4407AL-GP"
			(at -3.707384 -1.5367 0)
			(unlocked yes)
			(layer "F.Fab")
			(hide yes)
			(effects
				(font
					(size 1.016 1.016)
					(thickness 0.1524)
				)
			)
		)
		(property "Device Type" "SOIC8H69"
			(at -3.707384 -3.0607 0)
			(unlocked yes)
			(layer "F.Fab")
			(hide yes)
			(effects
				(font
					(size 1.016 1.016)
					(thickness 0.1524)
				)
			)
		)
		(duplicate_pad_numbers_are_jumpers no)
		(fp_line
			(start -2.7432 -1.4224)
			(end -2.7432 1.4224)
			(stroke
				(width 0.1524)
				(type default)
			)
			(layer "F.SilkS")
		)
		(fp_line
			(start -2.7432 1.4224)
			(end -2.6416 1.4224)
			(stroke
				(width 0.1524)
				(type default)
			)
			(layer "F.SilkS")
		)
		(fp_line
			(start -2.7432 1.4224)
			(end 2.1336 1.4224)
			(stroke
				(width 0.1524)
				(type default)
			)
			(layer "F.SilkS")
		)
		(fp_line
			(start -2.7178 -0.508)
			(end -2.1844 -0.0508)
			(stroke
				(width 0.1524)
				(type default)
			)
			(layer "F.SilkS")
		)
		(fp_line
			(start -2.6289 3.4417)
			(end -2.6289 1.4732)
			(stroke
				(width 0.381)
				(type default)
			)
			(layer "F.SilkS")
		)
		(fp_line
			(start -2.1844 -0.0508)
			(end -2.7178 0.508)
			(stroke
				(width 0.1524)
				(type default)
			)
			(layer "F.SilkS")
		)
		(fp_line
			(start 2.1336 -1.4224)
			(end -2.7432 -1.4224)
			(stroke
				(width 0.1524)
				(type default)
			)
			(layer "F.SilkS")
		)
		(fp_line
			(start 2.1336 1.4224)
			(end 2.1336 -1.4224)
			(stroke
				(width 0.1524)
				(type default)
			)
			(layer "F.SilkS")
		)
		(fp_poly
			(pts
				(xy -2.2098 -1.4224) (xy -2.2098 1.4224) (xy 2.2098 1.4224) (xy 2.2098 -1.4224)
			)
			(stroke
				(width 0)
				(type default)
			)
			(fill yes)
			(layer "F.SilkS")
		)
		(fp_rect
			(start -2.450084 2.999994)
			(end 2.450084 -2.999994)
			(stroke
				(width 0)
				(type default)
			)
			(fill no)
			(layer "F.CrtYd")
		)
		(fp_poly
			(pts
				(xy -2.8194 3.6322) (xy -2.8194 -3.6322) (xy 2.8194 -3.6322) (xy 2.8194 1.18364) (xy 2.450084 1.18364)
				(xy 2.450084 -2.999994) (xy -2.450084 -2.999994) (xy -2.450084 2.999994) (xy 2.450084 2.999994)
				(xy 2.450084 1.18618) (xy 2.8194 1.18618) (xy 2.8194 3.6322)
			)
			(stroke
				(width 0)
				(type default)
			)
			(fill no)
			(layer "F.CrtYd")
		)
		(fp_rect
			(start -2.8194 3.6322)
			(end 2.8194 -3.6322)
			(stroke
				(width 0)
				(type default)
			)
			(fill no)
			(layer "F.Fab")
		)
		(pad "1" smd rect
			(at -1.905 2.54)
			(size 0.635 1.651)
			(layers "F.Cu" "F.Mask" "F.Paste")
			(net "P12V_A")
		)
		(pad "2" smd rect
			(at -0.635 2.54)
			(size 0.635 1.651)
			(layers "F.Cu" "F.Mask" "F.Paste")
			(net "P12V_A")
		)
		(pad "3" smd rect
			(at 0.635 2.54)
			(size 0.635 1.651)
			(layers "F.Cu" "F.Mask" "F.Paste")
			(net "P12V_A")
		)
		(pad "4" smd rect
			(at 1.905 2.54)
			(size 0.635 1.651)
			(layers "F.Cu" "F.Mask" "F.Paste")
			(net "SW_HDD_N15")
		)
		(pad "5" smd rect
			(at 1.905 -2.54)
			(size 0.635 1.651)
			(layers "F.Cu" "F.Mask" "F.Paste")
			(net "P12V_HDD15")
		)
		(pad "6" smd rect
			(at 0.635 -2.54)
			(size 0.635 1.651)
			(layers "F.Cu" "F.Mask" "F.Paste")
			(net "P12V_HDD15")
		)
		(pad "7" smd rect
			(at -0.635 -2.54)
			(size 0.635 1.651)
			(layers "F.Cu" "F.Mask" "F.Paste")
			(net "P12V_HDD15")
		)
		(pad "8" smd rect
			(at -1.905 -2.54)
			(size 0.635 1.651)
			(layers "F.Cu" "F.Mask" "F.Paste")
			(net "P12V_HDD15")
		)
	)
	(footprint ""
		(layer "F.Cu")
		(at 130.328162 -304.331878 180)
		(property "Reference" "R251"
			(at 0 0 180)
			(layer "F.SilkS")
			(hide yes)
			(effects
				(font
					(size 1.27 1.27)
				)
			)
		)
		(property "Value" "130R3F-GP"
			(at -0.0254 -2.5146 180)
			(unlocked yes)
			(layer "F.Fab")
			(hide yes)
			(effects
				(font
					(size 1.016 1.016)
					(thickness 0.1524)
				)
			)
		)
		(property "Device Type" "R603H22"
			(at -0.0254 -4.0386 180)
			(unlocked yes)
			(layer "F.Fab")
			(hide yes)
			(effects
				(font
					(size 1.016 1.016)
					(thickness 0.1524)
				)
			)
		)
		(duplicate_pad_numbers_are_jumpers no)
		(fp_line
			(start 0.2032 0)
			(end 0.4826 0)
			(stroke
				(width 0.2032)
				(type default)
			)
			(layer "F.SilkS")
		)
		(fp_line
			(start -0.4826 0)
			(end -0.2032 0)
			(stroke
				(width 0.2032)
				(type default)
			)
			(layer "F.SilkS")
		)
		(fp_rect
			(start -0.5842 1.3335)
			(end 0.5842 -1.3335)
			(stroke
				(width 0)
				(type default)
			)
			(fill no)
			(layer "F.CrtYd")
		)
		(fp_rect
			(start -0.5842 1.3335)
			(end 0.5842 -1.3335)
			(stroke
				(width 0)
				(type default)
			)
			(fill no)
			(layer "F.Fab")
		)
		(pad "1" smd custom
			(at 0 -0.762 180)
			(size 0.2159 0.2159)
			(layers "F.Cu" "F.Mask" "F.Paste")
			(net "P5V_B")
			(options
				(clearance outline)
				(anchor circle)
			)
			(primitives
				(gr_poly
					(pts
						(arc
							(start -0.3302 -0.4318)
							(mid -0.402042 -0.402042)
							(end -0.4318 -0.3302)
						)
						(arc
							(start -0.4318 0.3302)
							(mid -0.402042 0.402042)
							(end -0.3302 0.4318)
						)
						(arc
							(start 0.3302 0.4318)
							(mid 0.402042 0.402042)
							(end 0.4318 0.3302)
						)
						(arc
							(start 0.4318 -0.3302)
							(mid 0.402042 -0.402042)
							(end 0.3302 -0.4318)
						)
					)
					(width 0)
					(fill yes)
				)
			)
		)
		(pad "2" smd custom
			(at 0 0.762 180)
			(size 0.2159 0.2159)
			(layers "F.Cu" "F.Mask" "F.Paste")
			(net "FLT_HDD28")
			(options
				(clearance outline)
				(anchor circle)
			)
			(primitives
				(gr_poly
					(pts
						(arc
							(start -0.3302 -0.4318)
							(mid -0.402042 -0.402042)
							(end -0.4318 -0.3302)
						)
						(arc
							(start -0.4318 0.3302)
							(mid -0.402042 0.402042)
							(end -0.3302 0.4318)
						)
						(arc
							(start 0.3302 0.4318)
							(mid 0.402042 0.402042)
							(end 0.4318 0.3302)
						)
						(arc
							(start 0.4318 -0.3302)
							(mid 0.402042 -0.402042)
							(end 0.3302 -0.4318)
						)
					)
					(width 0)
					(fill yes)
				)
			)
		)
	)
	(footprint ""
		(layer "F.Cu")
		(at 161.997898 -176.127918 90)
		(property "Reference" "C253"
			(at 0 0 90)
			(layer "F.SilkS")
			(hide yes)
			(effects
				(font
					(size 1.27 1.27)
				)
			)
		)
		(property "Value" "SCD01U50V2KX-1GP"
			(at 1.1811 -2.7051 90)
			(unlocked yes)
			(layer "F.Fab")
			(hide yes)
			(effects
				(font
					(size 1.016 1.016)
					(thickness 0.1524)
				)
			)
		)
		(property "Device Type" "C402H22"
			(at 1.1811 -4.2291 90)
			(unlocked yes)
			(layer "F.Fab")
			(hide yes)
			(effects
				(font
					(size 1.016 1.016)
					(thickness 0.1524)
				)
			)
		)
		(duplicate_pad_numbers_are_jumpers no)
		(fp_rect
			(start -0.4318 0.9525)
			(end 0.4318 -0.9525)
			(stroke
				(width 0)
				(type default)
			)
			(fill no)
			(layer "F.CrtYd")
		)
		(fp_rect
			(start -0.4318 0.9525)
			(end 0.4318 -0.9525)
			(stroke
				(width 0)
				(type default)
			)
			(fill no)
			(layer "F.Fab")
		)
		(pad "1" smd custom
			(at 0 -0.4445 90)
			(size 0.1524 0.1524)
			(layers "F.Cu" "F.Mask" "F.Paste")
			(net "HDD_PRSNT_16")
			(options
				(clearance outline)
				(anchor circle)
			)
			(primitives
				(gr_poly
					(pts
						(arc
							(start 0.3048 -0.2032)
							(mid 0.275042 -0.275042)
							(end 0.2032 -0.3048)
						)
						(arc
							(start -0.2032 -0.3048)
							(mid -0.275042 -0.275042)
							(end -0.3048 -0.2032)
						)
						(arc
							(start -0.3048 0.2032)
							(mid -0.275042 0.275042)
							(end -0.2032 0.3048)
						)
						(arc
							(start 0.2032 0.3048)
							(mid 0.275042 0.275042)
							(end 0.3048 0.2032)
						)
					)
					(width 0)
					(fill yes)
				)
			)
		)
		(pad "2" smd custom
			(at 0 0.4445 90)
			(size 0.1524 0.1524)
			(layers "F.Cu" "F.Mask" "F.Paste")
			(net "GND")
			(options
				(clearance outline)
				(anchor circle)
			)
			(primitives
				(gr_poly
					(pts
						(arc
							(start 0.3048 -0.2032)
							(mid 0.275042 -0.275042)
							(end 0.2032 -0.3048)
						)
						(arc
							(start -0.2032 -0.3048)
							(mid -0.275042 -0.275042)
							(end -0.3048 -0.2032)
						)
						(arc
							(start -0.3048 0.2032)
							(mid -0.275042 0.275042)
							(end -0.2032 0.3048)
						)
						(arc
							(start 0.2032 0.3048)
							(mid 0.275042 0.275042)
							(end 0.3048 0.2032)
						)
					)
					(width 0)
					(fill yes)
				)
			)
		)
	)
	(footprint ""
		(layer "F.Cu")
		(at 455.227944 -242.722654 180)
		(property "Reference" "Q274"
			(at 0 0 180)
			(layer "F.SilkS")
			(hide yes)
			(effects
				(font
					(size 1.27 1.27)
				)
			)
		)
		(property "Value" "SSM3K324R-GP"
			(at 0.127 -8.9662 180)
			(unlocked yes)
			(layer "F.Fab")
			(hide yes)
			(effects
				(font
					(size 1.016 1.016)
					(thickness 0.1524)
				)
			)
		)
		(property "Device Type" "SOT23DGS2D4H35"
			(at 0.127 -10.4902 180)
			(unlocked yes)
			(layer "F.Fab")
			(hide yes)
			(effects
				(font
					(size 1.016 1.016)
					(thickness 0.1524)
				)
			)
		)
		(duplicate_pad_numbers_are_jumpers no)
		(fp_line
			(start 1.651 1.778)
			(end 1.651 -1.778)
			(stroke
				(width 0.1524)
				(type default)
			)
			(layer "F.SilkS")
		)
		(fp_line
			(start 1.651 -1.778)
			(end -1.651 -1.778)
			(stroke
				(width 0.1524)
				(type default)
			)
			(layer "F.SilkS")
		)
		(fp_line
			(start -1.651 1.778)
			(end 1.651 1.778)
			(stroke
				(width 0.1524)
				(type default)
			)
			(layer "F.SilkS")
		)
		(fp_line
			(start -1.651 -1.778)
			(end -1.651 1.778)
			(stroke
				(width 0.1524)
				(type default)
			)
			(layer "F.SilkS")
		)
		(fp_poly
			(pts
				(xy -1.778 1.8796) (xy -1.778 -1.8796) (xy 1.778 -1.8796) (xy 1.778 1.8796)
			)
			(stroke
				(width 0)
				(type default)
			)
			(fill no)
			(layer "F.CrtYd")
		)
		(fp_poly
			(pts
				(xy -1.778 1.8796) (xy -1.778 -1.8796) (xy 1.778 -1.8796) (xy 1.778 1.8796)
			)
			(stroke
				(width 0)
				(type default)
			)
			(fill no)
			(layer "F.Fab")
		)
		(pad "D" smd custom
			(at 0 -0.9525 180)
			(size 0.1905 0.1905)
			(layers "F.Cu" "F.Mask" "F.Paste")
			(net "DRV_ACT_11_N")
			(options
				(clearance outline)
				(anchor circle)
			)
			(primitives
				(gr_poly
					(pts
						(arc
							(start -0.1778 0.5715)
							(mid -0.321484 0.511984)
							(end -0.381 0.3683)
						)
						(arc
							(start -0.381 -0.3683)
							(mid -0.321484 -0.511984)
							(end -0.1778 -0.5715)
						)
						(arc
							(start 0.1778 -0.5715)
							(mid 0.321484 -0.511984)
							(end 0.381 -0.3683)
						)
						(arc
							(start 0.381 0.3683)
							(mid 0.321484 0.511984)
							(end 0.1778 0.5715)
						)
					)
					(width 0)
					(fill yes)
				)
			)
		)
		(pad "G" smd custom
			(at -0.98425 0.9525 180)
			(size 0.1905 0.1905)
			(layers "F.Cu" "F.Mask" "F.Paste")
			(net "DRIVE_A_11_ACT")
			(options
				(clearance outline)
				(anchor circle)
			)
			(primitives
				(gr_poly
					(pts
						(arc
							(start -0.1778 0.5715)
							(mid -0.321484 0.511984)
							(end -0.381 0.3683)
						)
						(arc
							(start -0.381 -0.3683)
							(mid -0.321484 -0.511984)
							(end -0.1778 -0.5715)
						)
						(arc
							(start 0.1778 -0.5715)
							(mid 0.321484 -0.511984)
							(end 0.381 -0.3683)
						)
						(arc
							(start 0.381 0.3683)
							(mid 0.321484 0.511984)
							(end 0.1778 0.5715)
						)
					)
					(width 0)
					(fill yes)
				)
			)
		)
		(pad "S" smd custom
			(at 0.98425 0.9525 180)
			(size 0.1905 0.1905)
			(layers "F.Cu" "F.Mask" "F.Paste")
			(net "GND")
			(options
				(clearance outline)
				(anchor circle)
			)
			(primitives
				(gr_poly
					(pts
						(arc
							(start -0.1778 0.5715)
							(mid -0.321484 0.511984)
							(end -0.381 0.3683)
						)
						(arc
							(start -0.381 -0.3683)
							(mid -0.321484 -0.511984)
							(end -0.1778 -0.5715)
						)
						(arc
							(start 0.1778 -0.5715)
							(mid 0.321484 -0.511984)
							(end 0.381 -0.3683)
						)
						(arc
							(start 0.381 0.3683)
							(mid 0.321484 0.511984)
							(end 0.1778 0.5715)
						)
					)
					(width 0)
					(fill yes)
				)
			)
		)
	)
	(footprint ""
		(layer "F.Cu")
		(at 332.74 -164.596318 90)
		(property "Reference" "C282"
			(at 0 0 90)
			(layer "F.SilkS")
			(hide yes)
			(effects
				(font
					(size 1.27 1.27)
				)
			)
		)
		(property "Value" "SCD033U25V2KX-GP"
			(at 1.1811 -2.7051 90)
			(unlocked yes)
			(layer "F.Fab")
			(hide yes)
			(effects
				(font
					(size 1.016 1.016)
					(thickness 0.1524)
				)
			)
		)
		(property "Device Type" "C402H22"
			(at 1.1811 -4.2291 90)
			(unlocked yes)
			(layer "F.Fab")
			(hide yes)
			(effects
				(font
					(size 1.016 1.016)
					(thickness 0.1524)
				)
			)
		)
		(duplicate_pad_numbers_are_jumpers no)
		(fp_rect
			(start -0.4318 0.9525)
			(end 0.4318 -0.9525)
			(stroke
				(width 0)
				(type default)
			)
			(fill no)
			(layer "F.CrtYd")
		)
		(fp_rect
			(start -0.4318 0.9525)
			(end 0.4318 -0.9525)
			(stroke
				(width 0)
				(type default)
			)
			(fill no)
			(layer "F.Fab")
		)
		(pad "1" smd custom
			(at 0 -0.4445 90)
			(size 0.1524 0.1524)
			(layers "F.Cu" "F.Mask" "F.Paste")
			(net "SW_HDD_P18")
			(options
				(clearance outline)
				(anchor circle)
			)
			(primitives
				(gr_poly
					(pts
						(arc
							(start 0.3048 -0.2032)
							(mid 0.275042 -0.275042)
							(end 0.2032 -0.3048)
						)
						(arc
							(start -0.2032 -0.3048)
							(mid -0.275042 -0.275042)
							(end -0.3048 -0.2032)
						)
						(arc
							(start -0.3048 0.2032)
							(mid -0.275042 0.275042)
							(end -0.2032 0.3048)
						)
						(arc
							(start 0.2032 0.3048)
							(mid 0.275042 0.275042)
							(end 0.3048 0.2032)
						)
					)
					(width 0)
					(fill yes)
				)
			)
		)
		(pad "2" smd custom
			(at 0 0.4445 90)
			(size 0.1524 0.1524)
			(layers "F.Cu" "F.Mask" "F.Paste")
			(net "GND")
			(options
				(clearance outline)
				(anchor circle)
			)
			(primitives
				(gr_poly
					(pts
						(arc
							(start 0.3048 -0.2032)
							(mid 0.275042 -0.275042)
							(end 0.2032 -0.3048)
						)
						(arc
							(start -0.2032 -0.3048)
							(mid -0.275042 -0.275042)
							(end -0.3048 -0.2032)
						)
						(arc
							(start -0.3048 0.2032)
							(mid -0.275042 0.275042)
							(end -0.2032 0.3048)
						)
						(arc
							(start 0.2032 0.3048)
							(mid 0.275042 0.275042)
							(end 0.3048 0.2032)
						)
					)
					(width 0)
					(fill yes)
				)
			)
		)
	)
	(footprint ""
		(layer "F.Cu")
		(at 219.795344 -19.296888 -90)
		(property "Reference" "C531"
			(at 0 0 270)
			(layer "F.SilkS")
			(hide yes)
			(effects
				(font
					(size 1.27 1.27)
				)
			)
		)
		(property "Value" "SC2D2U25V5KX-2-GP"
			(at -0.0762 -6.1214 270)
			(unlocked yes)
			(layer "F.Fab")
			(hide yes)
			(effects
				(font
					(size 1.016 1.016)
					(thickness 0.1524)
				)
			)
		)
		(property "Device Type" "C805H54"
			(at -0.0762 -8.1534 270)
			(unlocked yes)
			(layer "F.Fab")
			(hide yes)
			(effects
				(font
					(size 1.016 1.016)
					(thickness 0.1524)
				)
			)
		)
		(duplicate_pad_numbers_are_jumpers no)
		(fp_line
			(start 0.635 0)
			(end -0.635 0)
			(stroke
				(width 0.508)
				(type default)
			)
			(layer "F.SilkS")
		)
		(fp_rect
			(start -0.9652 1.778)
			(end 0.9652 -1.778)
			(stroke
				(width 0)
				(type default)
			)
			(fill no)
			(layer "F.CrtYd")
		)
		(fp_poly
			(pts
				(xy -0.9652 -1.778) (xy 0.9652 -1.778) (xy 0.9652 1.778) (xy -0.9652 1.778)
			)
			(stroke
				(width 0)
				(type default)
			)
			(fill no)
			(layer "F.Fab")
		)
		(pad "1" smd rect
			(at 0 -0.9652 270)
			(size 1.397 1.143)
			(layers "F.Cu" "F.Mask" "F.Paste")
			(net "P12V_A_COMP")
		)
		(pad "2" smd rect
			(at 0 0.9652 270)
			(size 1.397 1.143)
			(layers "F.Cu" "F.Mask" "F.Paste")
			(net "GND")
		)
	)
	(footprint ""
		(layer "F.Cu")
		(at 413.512 -68.707)
		(property "Reference" "TP167"
			(at 0 0 0)
			(layer "F.SilkS")
			(hide yes)
			(effects
				(font
					(size 1.27 1.27)
				)
			)
		)
		(property "Value" "TPAD32-GP"
			(at -0.0508 -1.6764 0)
			(unlocked yes)
			(layer "F.Fab")
			(hide yes)
			(effects
				(font
					(size 1.016 1.016)
					(thickness 0.1524)
				)
			)
		)
		(property "Device Type" "TPAD32"
			(at -0.0508 -3.2004 0)
			(unlocked yes)
			(layer "F.Fab")
			(hide yes)
			(effects
				(font
					(size 1.016 1.016)
					(thickness 0.1524)
				)
			)
		)
		(duplicate_pad_numbers_are_jumpers no)
		(fp_poly
			(pts
				(arc
					(start 0.4064 0)
					(mid -0.4064 0)
					(end 0.4064 0)
				)
			)
			(stroke
				(width 0)
				(type default)
			)
			(fill no)
			(layer "F.CrtYd")
		)
		(fp_poly
			(pts
				(arc
					(start 0.7112 0)
					(mid -0.7112 0)
					(end 0.7112 0)
				)
			)
			(stroke
				(width 0)
				(type default)
			)
			(fill no)
			(layer "F.Fab")
		)
		(pad "1" smd circle
			(at 0 0)
			(size 0.8128 0.8128)
			(layers "F.Cu" "F.Mask" "F.Paste")
			(net "ACT_HDD_33")
		)
	)
	(footprint ""
		(layer "F.Cu")
		(at 444.1952 -248.8946 90)
		(property "Reference" "C631"
			(at 0 0 90)
			(layer "F.SilkS")
			(hide yes)
			(effects
				(font
					(size 1.27 1.27)
				)
			)
		)
		(property "Value" "SC10U16V5KX-7-GP-U"
			(at -0.0762 -6.1214 90)
			(unlocked yes)
			(layer "F.Fab")
			(hide yes)
			(effects
				(font
					(size 1.016 1.016)
					(thickness 0.1524)
				)
			)
		)
		(property "Device Type" "C805H58"
			(at -0.0762 -8.1534 90)
			(unlocked yes)
			(layer "F.Fab")
			(hide yes)
			(effects
				(font
					(size 1.016 1.016)
					(thickness 0.1524)
				)
			)
		)
		(duplicate_pad_numbers_are_jumpers no)
		(fp_line
			(start 0.635 0)
			(end -0.635 0)
			(stroke
				(width 0.508)
				(type default)
			)
			(layer "F.SilkS")
		)
		(fp_rect
			(start -0.9652 1.778)
			(end 0.9652 -1.778)
			(stroke
				(width 0)
				(type default)
			)
			(fill no)
			(layer "F.CrtYd")
		)
		(fp_poly
			(pts
				(xy -0.9652 -1.778) (xy 0.9652 -1.778) (xy 0.9652 1.778) (xy -0.9652 1.778)
			)
			(stroke
				(width 0)
				(type default)
			)
			(fill no)
			(layer "F.Fab")
		)
		(pad "1" smd rect
			(at 0 -0.9652 90)
			(size 1.397 1.143)
			(layers "F.Cu" "F.Mask" "F.Paste")
			(net "P12V_A_VIN_U22")
		)
		(pad "2" smd rect
			(at 0 0.9652 90)
			(size 1.397 1.143)
			(layers "F.Cu" "F.Mask" "F.Paste")
			(net "GND")
		)
	)
	(footprint ""
		(layer "F.Cu")
		(at 366.449102 -167.872918 -90)
		(property "Reference" "Q113"
			(at 0 0 270)
			(layer "F.SilkS")
			(hide yes)
			(effects
				(font
					(size 1.27 1.27)
				)
			)
		)
		(property "Value" "AO4406AL-GP"
			(at -3.707384 -1.5367 270)
			(unlocked yes)
			(layer "F.Fab")
			(hide yes)
			(effects
				(font
					(size 1.016 1.016)
					(thickness 0.1524)
				)
			)
		)
		(property "Device Type" "SOIC8H69"
			(at -3.707384 -3.0607 270)
			(unlocked yes)
			(layer "F.Fab")
			(hide yes)
			(effects
				(font
					(size 1.016 1.016)
					(thickness 0.1524)
				)
			)
		)
		(duplicate_pad_numbers_are_jumpers no)
		(fp_line
			(start -2.6289 3.4417)
			(end -2.6289 1.4732)
			(stroke
				(width 0.381)
				(type default)
			)
			(layer "F.SilkS")
		)
		(fp_line
			(start -2.7432 1.4224)
			(end -2.6416 1.4224)
			(stroke
				(width 0.1524)
				(type default)
			)
			(layer "F.SilkS")
		)
		(fp_line
			(start -2.7432 1.4224)
			(end 2.1336 1.4224)
			(stroke
				(width 0.1524)
				(type default)
			)
			(layer "F.SilkS")
		)
		(fp_line
			(start 2.1336 1.4224)
			(end 2.1336 -1.4224)
			(stroke
				(width 0.1524)
				(type default)
			)
			(layer "F.SilkS")
		)
		(fp_line
			(start -2.1844 -0.0508)
			(end -2.7178 0.508)
			(stroke
				(width 0.1524)
				(type default)
			)
			(layer "F.SilkS")
		)
		(fp_line
			(start -2.7178 -0.508)
			(end -2.1844 -0.0508)
			(stroke
				(width 0.1524)
				(type default)
			)
			(layer "F.SilkS")
		)
		(fp_line
			(start -2.7432 -1.4224)
			(end -2.7432 1.4224)
			(stroke
				(width 0.1524)
				(type default)
			)
			(layer "F.SilkS")
		)
		(fp_line
			(start 2.1336 -1.4224)
			(end -2.7432 -1.4224)
			(stroke
				(width 0.1524)
				(type default)
			)
			(layer "F.SilkS")
		)
		(fp_poly
			(pts
				(xy -2.2098 -1.4224) (xy -2.2098 1.4224) (xy 2.2098 1.4224) (xy 2.2098 -1.4224)
			)
			(stroke
				(width 0)
				(type default)
			)
			(fill yes)
			(layer "F.SilkS")
		)
		(fp_rect
			(start -2.450084 2.999994)
			(end 2.450084 -2.999994)
			(stroke
				(width 0)
				(type default)
			)
			(fill no)
			(layer "F.CrtYd")
		)
		(fp_poly
			(pts
				(xy -2.8194 3.6322) (xy -2.8194 -3.6322) (xy 2.8194 -3.6322) (xy 2.8194 1.18364) (xy 2.450084 1.18364)
				(xy 2.450084 -2.999994) (xy -2.450084 -2.999994) (xy -2.450084 2.999994) (xy 2.450084 2.999994)
				(xy 2.450084 1.18618) (xy 2.8194 1.18618) (xy 2.8194 3.6322)
			)
			(stroke
				(width 0)
				(type default)
			)
			(fill no)
			(layer "F.CrtYd")
		)
		(fp_rect
			(start -2.8194 3.6322)
			(end 2.8194 -3.6322)
			(stroke
				(width 0)
				(type default)
			)
			(fill no)
			(layer "F.Fab")
		)
		(pad "1" smd rect
			(at -1.905 2.54 270)
			(size 0.635 1.651)
			(layers "F.Cu" "F.Mask" "F.Paste")
			(net "P5V_HDD19")
		)
		(pad "2" smd rect
			(at -0.635 2.54 270)
			(size 0.635 1.651)
			(layers "F.Cu" "F.Mask" "F.Paste")
			(net "P5V_HDD19")
		)
		(pad "3" smd rect
			(at 0.635 2.54 270)
			(size 0.635 1.651)
			(layers "F.Cu" "F.Mask" "F.Paste")
			(net "P5V_HDD19")
		)
		(pad "4" smd rect
			(at 1.905 2.54 270)
			(size 0.635 1.651)
			(layers "F.Cu" "F.Mask" "F.Paste")
			(net "SW_HDD_P19")
		)
		(pad "5" smd rect
			(at 1.905 -2.54 270)
			(size 0.635 1.651)
			(layers "F.Cu" "F.Mask" "F.Paste")
			(net "P5V_A_3")
		)
		(pad "6" smd rect
			(at 0.635 -2.54 270)
			(size 0.635 1.651)
			(layers "F.Cu" "F.Mask" "F.Paste")
			(net "P5V_A_3")
		)
		(pad "7" smd rect
			(at -0.635 -2.54 270)
			(size 0.635 1.651)
			(layers "F.Cu" "F.Mask" "F.Paste")
			(net "P5V_A_3")
		)
		(pad "8" smd rect
			(at -1.905 -2.54 270)
			(size 0.635 1.651)
			(layers "F.Cu" "F.Mask" "F.Paste")
			(net "P5V_A_3")
		)
	)
	(footprint ""
		(layer "F.Cu")
		(at 334.03921 -33.5534 180)
		(property "Reference" "R1299"
			(at 0 0 180)
			(layer "F.SilkS")
			(hide yes)
			(effects
				(font
					(size 1.27 1.27)
				)
			)
		)
		(property "Value" "2K2R2F-GP"
			(at 0.064008 -3.993896 180)
			(unlocked yes)
			(layer "F.Fab")
			(hide yes)
			(effects
				(font
					(size 1.016 1.016)
					(thickness 0.1524)
				)
			)
		)
		(property "Device Type" "R402H16"
			(at 0.064008 -5.517896 180)
			(unlocked yes)
			(layer "F.Fab")
			(hide yes)
			(effects
				(font
					(size 1.016 1.016)
					(thickness 0.1524)
				)
			)
		)
		(duplicate_pad_numbers_are_jumpers no)
		(fp_line
			(start 0.508 -0.9398)
			(end -0.508 -0.9398)
			(stroke
				(width 0.1524)
				(type default)
			)
			(layer "F.SilkS")
		)
		(fp_line
			(start -0.508 -0.9398)
			(end -0.508 0.9398)
			(stroke
				(width 0.1524)
				(type default)
			)
			(layer "F.SilkS")
		)
		(fp_rect
			(start -0.508 0.9398)
			(end 0.508 -0.9398)
			(stroke
				(width 0)
				(type default)
			)
			(fill no)
			(layer "F.CrtYd")
		)
		(fp_rect
			(start -0.508 0.9398)
			(end 0.508 -0.9398)
			(stroke
				(width 0)
				(type default)
			)
			(fill no)
			(layer "F.Fab")
		)
		(pad "1" smd custom
			(at 0 -0.4445 180)
			(size 0.1397 0.1397)
			(layers "F.Cu" "F.Mask" "F.Paste")
			(net "P3V3_STBY_B")
			(options
				(clearance outline)
				(anchor circle)
			)
			(primitives
				(gr_poly
					(pts
						(arc
							(start -0.1778 -0.2794)
							(mid -0.249642 -0.249642)
							(end -0.2794 -0.1778)
						)
						(arc
							(start -0.2794 0.1778)
							(mid -0.249642 0.249642)
							(end -0.1778 0.2794)
						)
						(arc
							(start 0.1778 0.2794)
							(mid 0.249642 0.249642)
							(end 0.2794 0.1778)
						)
						(arc
							(start 0.2794 -0.1778)
							(mid 0.249642 -0.249642)
							(end 0.1778 -0.2794)
						)
					)
					(width 0)
					(fill yes)
				)
			)
		)
		(pad "2" smd custom
			(at 0 0.4445 180)
			(size 0.1397 0.1397)
			(layers "F.Cu" "F.Mask" "F.Paste")
			(net "I2C_BMC_B_MISC_SDA")
			(options
				(clearance outline)
				(anchor circle)
			)
			(primitives
				(gr_poly
					(pts
						(arc
							(start -0.1778 -0.2794)
							(mid -0.249642 -0.249642)
							(end -0.2794 -0.1778)
						)
						(arc
							(start -0.2794 0.1778)
							(mid -0.249642 0.249642)
							(end -0.1778 0.2794)
						)
						(arc
							(start 0.1778 0.2794)
							(mid 0.249642 0.249642)
							(end 0.2794 0.1778)
						)
						(arc
							(start 0.2794 -0.1778)
							(mid 0.249642 -0.249642)
							(end 0.1778 -0.2794)
						)
					)
					(width 0)
					(fill yes)
				)
			)
		)
	)
	(footprint ""
		(layer "F.Cu")
		(at 97.497646 -304.353468 180)
		(property "Reference" "R233"
			(at 0 0 180)
			(layer "F.SilkS")
			(hide yes)
			(effects
				(font
					(size 1.27 1.27)
				)
			)
		)
		(property "Value" "91R3F-1-GP"
			(at -0.0254 -2.5146 180)
			(unlocked yes)
			(layer "F.Fab")
			(hide yes)
			(effects
				(font
					(size 1.016 1.016)
					(thickness 0.1524)
				)
			)
		)
		(property "Device Type" "R603H22"
			(at -0.0254 -4.0386 180)
			(unlocked yes)
			(layer "F.Fab")
			(hide yes)
			(effects
				(font
					(size 1.016 1.016)
					(thickness 0.1524)
				)
			)
		)
		(duplicate_pad_numbers_are_jumpers no)
		(fp_line
			(start 0.2032 0)
			(end 0.4826 0)
			(stroke
				(width 0.2032)
				(type default)
			)
			(layer "F.SilkS")
		)
		(fp_line
			(start -0.4826 0)
			(end -0.2032 0)
			(stroke
				(width 0.2032)
				(type default)
			)
			(layer "F.SilkS")
		)
		(fp_rect
			(start -0.5842 1.3335)
			(end 0.5842 -1.3335)
			(stroke
				(width 0)
				(type default)
			)
			(fill no)
			(layer "F.CrtYd")
		)
		(fp_rect
			(start -0.5842 1.3335)
			(end 0.5842 -1.3335)
			(stroke
				(width 0)
				(type default)
			)
			(fill no)
			(layer "F.Fab")
		)
		(pad "1" smd custom
			(at 0 -0.762 180)
			(size 0.2159 0.2159)
			(layers "F.Cu" "F.Mask" "F.Paste")
			(net "P5V_B")
			(options
				(clearance outline)
				(anchor circle)
			)
			(primitives
				(gr_poly
					(pts
						(arc
							(start -0.3302 -0.4318)
							(mid -0.402042 -0.402042)
							(end -0.4318 -0.3302)
						)
						(arc
							(start -0.4318 0.3302)
							(mid -0.402042 0.402042)
							(end -0.3302 0.4318)
						)
						(arc
							(start 0.3302 0.4318)
							(mid 0.402042 0.402042)
							(end 0.4318 0.3302)
						)
						(arc
							(start 0.4318 -0.3302)
							(mid 0.402042 -0.402042)
							(end 0.3302 -0.4318)
						)
					)
					(width 0)
					(fill yes)
				)
			)
		)
		(pad "2" smd custom
			(at 0 0.762 180)
			(size 0.2159 0.2159)
			(layers "F.Cu" "F.Mask" "F.Paste")
			(net "DRV_ACT_27")
			(options
				(clearance outline)
				(anchor circle)
			)
			(primitives
				(gr_poly
					(pts
						(arc
							(start -0.3302 -0.4318)
							(mid -0.402042 -0.402042)
							(end -0.4318 -0.3302)
						)
						(arc
							(start -0.4318 0.3302)
							(mid -0.402042 0.402042)
							(end -0.3302 0.4318)
						)
						(arc
							(start 0.3302 0.4318)
							(mid 0.402042 0.402042)
							(end 0.4318 0.3302)
						)
						(arc
							(start 0.4318 -0.3302)
							(mid 0.402042 -0.402042)
							(end 0.3302 -0.4318)
						)
					)
					(width 0)
					(fill yes)
				)
			)
		)
	)
	(footprint ""
		(layer "F.Cu")
		(at 353.184714 -158.660592 -90)
		(property "Reference" "C286"
			(at 0 0 270)
			(layer "F.SilkS")
			(hide yes)
			(effects
				(font
					(size 1.27 1.27)
				)
			)
		)
		(property "Value" "SCD01U16V1KX-GP"
			(at -2.8321 -1.7399 270)
			(unlocked yes)
			(layer "F.Fab")
			(hide yes)
			(effects
				(font
					(size 1.016 1.016)
					(thickness 0.1524)
				)
			)
		)
		(property "Device Type" "C0201H13"
			(at -2.8321 -3.2639 270)
			(unlocked yes)
			(layer "F.Fab")
			(hide yes)
			(effects
				(font
					(size 1.016 1.016)
					(thickness 0.1524)
				)
			)
		)
		(duplicate_pad_numbers_are_jumpers no)
		(fp_rect
			(start -0.2794 0.6477)
			(end 0.2794 -0.6477)
			(stroke
				(width 0)
				(type default)
			)
			(fill no)
			(layer "F.CrtYd")
		)
		(fp_rect
			(start -0.2794 0.6477)
			(end 0.2794 -0.6477)
			(stroke
				(width 0)
				(type default)
			)
			(fill no)
			(layer "F.Fab")
		)
		(pad "1" smd custom
			(at 0 -0.2794 270)
			(size 0.0762 0.0762)
			(layers "F.Cu" "F.Mask" "F.Paste")
			(net "SAS_HDD_RX_P19")
			(options
				(clearance outline)
				(anchor circle)
			)
			(primitives
				(gr_poly
					(pts
						(arc
							(start 0.1524 -0.127)
							(mid 0.137521 -0.162921)
							(end 0.1016 -0.1778)
						)
						(arc
							(start -0.1016 -0.1778)
							(mid -0.137521 -0.162921)
							(end -0.1524 -0.127)
						)
						(arc
							(start -0.1524 0.127)
							(mid -0.137521 0.162921)
							(end -0.1016 0.1778)
						)
						(arc
							(start 0.1016 0.1778)
							(mid 0.137521 0.162921)
							(end 0.1524 0.127)
						)
					)
					(width 0)
					(fill yes)
				)
			)
		)
		(pad "2" smd custom
			(at 0 0.2794 270)
			(size 0.0762 0.0762)
			(layers "F.Cu" "F.Mask" "F.Paste")
			(net "PHY_SCC_A_TO_DRV_A_19_DP")
			(options
				(clearance outline)
				(anchor circle)
			)
			(primitives
				(gr_poly
					(pts
						(arc
							(start 0.1524 -0.127)
							(mid 0.137521 -0.162921)
							(end 0.1016 -0.1778)
						)
						(arc
							(start -0.1016 -0.1778)
							(mid -0.137521 -0.162921)
							(end -0.1524 -0.127)
						)
						(arc
							(start -0.1524 0.127)
							(mid -0.137521 0.162921)
							(end -0.1016 0.1778)
						)
						(arc
							(start 0.1016 0.1778)
							(mid 0.137521 0.162921)
							(end 0.1524 0.127)
						)
					)
					(width 0)
					(fill yes)
				)
			)
		)
	)
	(footprint ""
		(layer "F.Cu")
		(at 244.200172 -360.205528)
		(property "Reference" ""
			(at 0 0 0)
			(layer "F.SilkS")
			(hide yes)
			(effects
				(font
					(size 1.27 1.27)
				)
			)
		)
		(property "Value" "*"
			(at -8.398764 -8.057642 0)
			(unlocked yes)
			(layer "F.Fab")
			(hide yes)
			(effects
				(font
					(size 1.016 1.016)
					(thickness 0.1524)
				)
			)
		)
		(duplicate_pad_numbers_are_jumpers no)
		(fp_poly
			(pts
				(arc
					(start 7.3152 0)
					(mid 0 7.3152)
					(end -7.3152 0)
				)
				(arc
					(start -7.3152 -5.9944)
					(mid 0 -13.3096)
					(end 7.3152 -5.9944)
				)
			)
			(stroke
				(width 0)
				(type default)
			)
			(fill no)
			(layer "B.CrtYd")
		)
		(fp_poly
			(pts
				(arc
					(start 7.3152 0)
					(mid 0 7.3152)
					(end -7.3152 0)
				)
				(arc
					(start -7.3152 -5.9944)
					(mid 0 -13.3096)
					(end 7.3152 -5.9944)
				)
			)
			(stroke
				(width 0)
				(type default)
			)
			(fill no)
			(layer "F.CrtYd")
		)
		(fp_poly
			(pts
				(arc
					(start 7.3152 0)
					(mid 0 7.3152)
					(end -7.3152 0)
				)
				(arc
					(start -7.3152 -5.9944)
					(mid 0 -13.3096)
					(end 7.3152 -5.9944)
				)
			)
			(stroke
				(width 0)
				(type default)
			)
			(fill no)
			(layer "B.Fab")
		)
		(fp_poly
			(pts
				(arc
					(start 7.3152 0)
					(mid 0 7.3152)
					(end -7.3152 0)
				)
				(arc
					(start -7.3152 -5.9944)
					(mid 0 -13.3096)
					(end 7.3152 -5.9944)
				)
			)
			(stroke
				(width 0)
				(type default)
			)
			(fill no)
			(layer "F.Fab")
		)
		(pad "1" thru_hole oval
			(at 0 0)
			(size 14.0208 20.0152)
			(drill 0.0254
				(offset 0 -2.9972)
			)
			(layers "*.Cu" "*.Mask")
			(remove_unused_layers no)
			(net "Net_69")
			(clearance -1.002284)
			(thermal_gap 0.1524)
			(padstack
				(mode front_inner_back)
				(layer "Inner"
					(shape custom)
					(size 2.928012 2.928012)
					(options
						(anchor circle)
					)
					(primitives
						(gr_poly
							(pts
								(arc
									(start 4.571746 -2.084324)
									(mid 0.000333 7.430372)
									(end -4.571492 -2.084324)
								)
								(arc
									(start -4.571492 -2.084324)
									(mid -3.570296 -3.611977)
									(end -2.875026 -5.30098)
								)
								(arc
									(start -2.875026 -5.30098)
									(mid 0.000217 -7.43089)
									(end 2.87528 -5.30098)
								)
								(arc
									(start 2.87528 -5.30098)
									(mid 3.570511 -3.611956)
									(end 4.571746 -2.084324)
								)
							)
							(width 0)
							(fill yes)
						)
					)
					(clearance 0.1524)
				)
				(layer "B.Cu"
					(shape oval)
					(size 14.0208 20.0152)
					(offset 0 -2.9972)
					(clearance -1.002284)
				)
			)
		)
		(zone
			(layers "F.Cu" "B.Cu" "In1.Cu" "In2.Cu" "In3.Cu" "In4.Cu" "In5.Cu" "In6.Cu"
				"In7.Cu" "In8.Cu" "In9.Cu" "In10.Cu"
			)
			(hatch none 0.5)
			(connect_pads
				(clearance 0)
			)
			(min_thickness 0.25)
			(keepout
				(tracks not_allowed)
				(vias allowed)
				(pads allowed)
				(copperpour not_allowed)
				(footprints allowed)
			)
			(placement
				(enabled no)
				(sheetname "")
			)
			(fill
				(thermal_gap 0.5)
				(thermal_bridge_width 0.5)
				(island_removal_mode 0)
			)
			(polygon
				(pts
					(arc
						(start 237.189772 -366.199928)
						(mid 244.200172 -373.210328)
						(end 251.210572 -366.199928)
					)
					(arc
						(start 251.210572 -360.205528)
						(mid 244.200172 -353.195128)
						(end 237.189772 -360.205528)
					)
				)
			)
		)
	)
	(footprint ""
		(layer "F.Cu")
		(at 83.255866 -18.50263 -90)
		(property "Reference" "R63"
			(at 0 0 270)
			(layer "F.SilkS")
			(hide yes)
			(effects
				(font
					(size 1.27 1.27)
				)
			)
		)
		(property "Value" "4K7R2F-GP"
			(at 0.064008 -3.993896 270)
			(unlocked yes)
			(layer "F.Fab")
			(hide yes)
			(effects
				(font
					(size 1.016 1.016)
					(thickness 0.1524)
				)
			)
		)
		(property "Device Type" "R402H16"
			(at 0.064008 -5.517896 270)
			(unlocked yes)
			(layer "F.Fab")
			(hide yes)
			(effects
				(font
					(size 1.016 1.016)
					(thickness 0.1524)
				)
			)
		)
		(duplicate_pad_numbers_are_jumpers no)
		(fp_line
			(start -0.508 -0.9398)
			(end -0.508 0.9398)
			(stroke
				(width 0.1524)
				(type default)
			)
			(layer "F.SilkS")
		)
		(fp_line
			(start 0.508 -0.9398)
			(end -0.508 -0.9398)
			(stroke
				(width 0.1524)
				(type default)
			)
			(layer "F.SilkS")
		)
		(fp_rect
			(start -0.508 0.9398)
			(end 0.508 -0.9398)
			(stroke
				(width 0)
				(type default)
			)
			(fill no)
			(layer "F.CrtYd")
		)
		(fp_rect
			(start -0.508 0.9398)
			(end 0.508 -0.9398)
			(stroke
				(width 0)
				(type default)
			)
			(fill no)
			(layer "F.Fab")
		)
		(pad "1" smd custom
			(at 0 -0.4445 270)
			(size 0.1397 0.1397)
			(layers "F.Cu" "F.Mask" "F.Paste")
			(net "IO_EXP10_A2")
			(options
				(clearance outline)
				(anchor circle)
			)
			(primitives
				(gr_poly
					(pts
						(arc
							(start -0.1778 -0.2794)
							(mid -0.249642 -0.249642)
							(end -0.2794 -0.1778)
						)
						(arc
							(start -0.2794 0.1778)
							(mid -0.249642 0.249642)
							(end -0.1778 0.2794)
						)
						(arc
							(start 0.1778 0.2794)
							(mid 0.249642 0.249642)
							(end 0.2794 0.1778)
						)
						(arc
							(start 0.2794 -0.1778)
							(mid 0.249642 -0.249642)
							(end 0.1778 -0.2794)
						)
					)
					(width 0)
					(fill yes)
				)
			)
		)
		(pad "2" smd custom
			(at 0 0.4445 270)
			(size 0.1397 0.1397)
			(layers "F.Cu" "F.Mask" "F.Paste")
			(net "GND")
			(options
				(clearance outline)
				(anchor circle)
			)
			(primitives
				(gr_poly
					(pts
						(arc
							(start -0.1778 -0.2794)
							(mid -0.249642 -0.249642)
							(end -0.2794 -0.1778)
						)
						(arc
							(start -0.2794 0.1778)
							(mid -0.249642 0.249642)
							(end -0.1778 0.2794)
						)
						(arc
							(start 0.1778 0.2794)
							(mid 0.249642 0.249642)
							(end 0.2794 0.1778)
						)
						(arc
							(start 0.2794 -0.1778)
							(mid 0.249642 -0.249642)
							(end 0.1778 -0.2794)
						)
					)
					(width 0)
					(fill yes)
				)
			)
		)
	)
	(footprint ""
		(layer "F.Cu")
		(at 141.423898 -277.183342 180)
		(property "Reference" "R238"
			(at 0 0 180)
			(layer "F.SilkS")
			(hide yes)
			(effects
				(font
					(size 1.27 1.27)
				)
			)
		)
		(property "Value" "200KR2F-L-GP"
			(at 0.064008 -3.993896 180)
			(unlocked yes)
			(layer "F.Fab")
			(hide yes)
			(effects
				(font
					(size 1.016 1.016)
					(thickness 0.1524)
				)
			)
		)
		(property "Device Type" "R402H16"
			(at 0.064008 -5.517896 180)
			(unlocked yes)
			(layer "F.Fab")
			(hide yes)
			(effects
				(font
					(size 1.016 1.016)
					(thickness 0.1524)
				)
			)
		)
		(duplicate_pad_numbers_are_jumpers no)
		(fp_line
			(start 0.508 -0.9398)
			(end -0.508 -0.9398)
			(stroke
				(width 0.1524)
				(type default)
			)
			(layer "F.SilkS")
		)
		(fp_line
			(start -0.508 -0.9398)
			(end -0.508 0.9398)
			(stroke
				(width 0.1524)
				(type default)
			)
			(layer "F.SilkS")
		)
		(fp_rect
			(start -0.508 0.9398)
			(end 0.508 -0.9398)
			(stroke
				(width 0)
				(type default)
			)
			(fill no)
			(layer "F.CrtYd")
		)
		(fp_rect
			(start -0.508 0.9398)
			(end 0.508 -0.9398)
			(stroke
				(width 0)
				(type default)
			)
			(fill no)
			(layer "F.Fab")
		)
		(pad "1" smd custom
			(at 0 -0.4445 180)
			(size 0.1397 0.1397)
			(layers "F.Cu" "F.Mask" "F.Paste")
			(net "SW_HDD_R4")
			(options
				(clearance outline)
				(anchor circle)
			)
			(primitives
				(gr_poly
					(pts
						(arc
							(start -0.1778 -0.2794)
							(mid -0.249642 -0.249642)
							(end -0.2794 -0.1778)
						)
						(arc
							(start -0.2794 0.1778)
							(mid -0.249642 0.249642)
							(end -0.1778 0.2794)
						)
						(arc
							(start 0.1778 0.2794)
							(mid 0.249642 0.249642)
							(end 0.2794 0.1778)
						)
						(arc
							(start 0.2794 -0.1778)
							(mid 0.249642 -0.249642)
							(end 0.1778 -0.2794)
						)
					)
					(width 0)
					(fill yes)
				)
			)
		)
		(pad "2" smd custom
			(at 0 0.4445 180)
			(size 0.1397 0.1397)
			(layers "F.Cu" "F.Mask" "F.Paste")
			(net "SW_HDD_N4")
			(options
				(clearance outline)
				(anchor circle)
			)
			(primitives
				(gr_poly
					(pts
						(arc
							(start -0.1778 -0.2794)
							(mid -0.249642 -0.249642)
							(end -0.2794 -0.1778)
						)
						(arc
							(start -0.2794 0.1778)
							(mid -0.249642 0.249642)
							(end -0.1778 0.2794)
						)
						(arc
							(start 0.1778 0.2794)
							(mid 0.249642 0.249642)
							(end 0.2794 0.1778)
						)
						(arc
							(start 0.2794 -0.1778)
							(mid 0.249642 -0.249642)
							(end 0.1778 -0.2794)
						)
					)
					(width 0)
					(fill yes)
				)
			)
		)
	)
	(footprint ""
		(layer "F.Cu")
		(at 474.4974 -269.367)
		(property "Reference" "R395"
			(at 0 0 0)
			(layer "F.SilkS")
			(hide yes)
			(effects
				(font
					(size 1.27 1.27)
				)
			)
		)
		(property "Value" "4K7R2J-2-GP"
			(at 0.064008 -3.993896 0)
			(unlocked yes)
			(layer "F.Fab")
			(hide yes)
			(effects
				(font
					(size 1.016 1.016)
					(thickness 0.1524)
				)
			)
		)
		(property "Device Type" "R402H16"
			(at 0.064008 -5.517896 0)
			(unlocked yes)
			(layer "F.Fab")
			(hide yes)
			(effects
				(font
					(size 1.016 1.016)
					(thickness 0.1524)
				)
			)
		)
		(duplicate_pad_numbers_are_jumpers no)
		(fp_line
			(start -0.508 -0.9398)
			(end -0.508 0.9398)
			(stroke
				(width 0.1524)
				(type default)
			)
			(layer "F.SilkS")
		)
		(fp_line
			(start 0.508 -0.9398)
			(end -0.508 -0.9398)
			(stroke
				(width 0.1524)
				(type default)
			)
			(layer "F.SilkS")
		)
		(fp_rect
			(start -0.508 0.9398)
			(end 0.508 -0.9398)
			(stroke
				(width 0)
				(type default)
			)
			(fill no)
			(layer "F.CrtYd")
		)
		(fp_rect
			(start -0.508 0.9398)
			(end 0.508 -0.9398)
			(stroke
				(width 0)
				(type default)
			)
			(fill no)
			(layer "F.Fab")
		)
		(pad "1" smd custom
			(at 0 -0.4445)
			(size 0.1397 0.1397)
			(layers "F.Cu" "F.Mask" "F.Paste")
			(net "SW_PWR_R_HDD11")
			(options
				(clearance outline)
				(anchor circle)
			)
			(primitives
				(gr_poly
					(pts
						(arc
							(start -0.1778 -0.2794)
							(mid -0.249642 -0.249642)
							(end -0.2794 -0.1778)
						)
						(arc
							(start -0.2794 0.1778)
							(mid -0.249642 0.249642)
							(end -0.1778 0.2794)
						)
						(arc
							(start 0.1778 0.2794)
							(mid 0.249642 0.249642)
							(end 0.2794 0.1778)
						)
						(arc
							(start 0.2794 -0.1778)
							(mid 0.249642 -0.249642)
							(end 0.1778 -0.2794)
						)
					)
					(width 0)
					(fill yes)
				)
			)
		)
		(pad "2" smd custom
			(at 0 0.4445)
			(size 0.1397 0.1397)
			(layers "F.Cu" "F.Mask" "F.Paste")
			(net "GND")
			(options
				(clearance outline)
				(anchor circle)
			)
			(primitives
				(gr_poly
					(pts
						(arc
							(start -0.1778 -0.2794)
							(mid -0.249642 -0.249642)
							(end -0.2794 -0.1778)
						)
						(arc
							(start -0.2794 0.1778)
							(mid -0.249642 0.249642)
							(end -0.1778 0.2794)
						)
						(arc
							(start 0.1778 0.2794)
							(mid 0.249642 0.249642)
							(end 0.2794 0.1778)
						)
						(arc
							(start 0.2794 -0.1778)
							(mid 0.249642 -0.249642)
							(end 0.1778 -0.2794)
						)
					)
					(width 0)
					(fill yes)
				)
			)
		)
	)
	(footprint ""
		(layer "F.Cu")
		(at 20.684998 -55.285894 180)
		(property "Reference" "Q144"
			(at 0 0 180)
			(layer "F.SilkS")
			(hide yes)
			(effects
				(font
					(size 1.27 1.27)
				)
			)
		)
		(property "Value" "AO4406AL-GP"
			(at -3.707384 -1.5367 180)
			(unlocked yes)
			(layer "F.Fab")
			(hide yes)
			(effects
				(font
					(size 1.016 1.016)
					(thickness 0.1524)
				)
			)
		)
		(property "Device Type" "SOIC8H69"
			(at -3.707384 -3.0607 180)
			(unlocked yes)
			(layer "F.Fab")
			(hide yes)
			(effects
				(font
					(size 1.016 1.016)
					(thickness 0.1524)
				)
			)
		)
		(duplicate_pad_numbers_are_jumpers no)
		(fp_line
			(start 2.1336 1.4224)
			(end 2.1336 -1.4224)
			(stroke
				(width 0.1524)
				(type default)
			)
			(layer "F.SilkS")
		)
		(fp_line
			(start 2.1336 -1.4224)
			(end -2.7432 -1.4224)
			(stroke
				(width 0.1524)
				(type default)
			)
			(layer "F.SilkS")
		)
		(fp_line
			(start -2.1844 -0.0508)
			(end -2.7178 0.508)
			(stroke
				(width 0.1524)
				(type default)
			)
			(layer "F.SilkS")
		)
		(fp_line
			(start -2.6289 3.4417)
			(end -2.6289 1.4732)
			(stroke
				(width 0.381)
				(type default)
			)
			(layer "F.SilkS")
		)
		(fp_line
			(start -2.7178 -0.508)
			(end -2.1844 -0.0508)
			(stroke
				(width 0.1524)
				(type default)
			)
			(layer "F.SilkS")
		)
		(fp_line
			(start -2.7432 1.4224)
			(end 2.1336 1.4224)
			(stroke
				(width 0.1524)
				(type default)
			)
			(layer "F.SilkS")
		)
		(fp_line
			(start -2.7432 1.4224)
			(end -2.6416 1.4224)
			(stroke
				(width 0.1524)
				(type default)
			)
			(layer "F.SilkS")
		)
		(fp_line
			(start -2.7432 -1.4224)
			(end -2.7432 1.4224)
			(stroke
				(width 0.1524)
				(type default)
			)
			(layer "F.SilkS")
		)
		(fp_poly
			(pts
				(xy -2.2098 -1.4224) (xy -2.2098 1.4224) (xy 2.2098 1.4224) (xy 2.2098 -1.4224)
			)
			(stroke
				(width 0)
				(type default)
			)
			(fill yes)
			(layer "F.SilkS")
		)
		(fp_rect
			(start -2.450084 2.999994)
			(end 2.450084 -2.999994)
			(stroke
				(width 0)
				(type default)
			)
			(fill no)
			(layer "F.CrtYd")
		)
		(fp_poly
			(pts
				(xy -2.8194 3.6322) (xy -2.8194 -3.6322) (xy 2.8194 -3.6322) (xy 2.8194 1.18364) (xy 2.450084 1.18364)
				(xy 2.450084 -2.999994) (xy -2.450084 -2.999994) (xy -2.450084 2.999994) (xy 2.450084 2.999994)
				(xy 2.450084 1.18618) (xy 2.8194 1.18618) (xy 2.8194 3.6322)
			)
			(stroke
				(width 0)
				(type default)
			)
			(fill no)
			(layer "F.CrtYd")
		)
		(fp_rect
			(start -2.8194 3.6322)
			(end 2.8194 -3.6322)
			(stroke
				(width 0)
				(type default)
			)
			(fill no)
			(layer "F.Fab")
		)
		(pad "1" smd rect
			(at -1.905 2.54 180)
			(size 0.635 1.651)
			(layers "F.Cu" "F.Mask" "F.Paste")
			(net "P5V_HDD24")
		)
		(pad "2" smd rect
			(at -0.635 2.54 180)
			(size 0.635 1.651)
			(layers "F.Cu" "F.Mask" "F.Paste")
			(net "P5V_HDD24")
		)
		(pad "3" smd rect
			(at 0.635 2.54 180)
			(size 0.635 1.651)
			(layers "F.Cu" "F.Mask" "F.Paste")
			(net "P5V_HDD24")
		)
		(pad "4" smd rect
			(at 1.905 2.54 180)
			(size 0.635 1.651)
			(layers "F.Cu" "F.Mask" "F.Paste")
			(net "SW_HDD_P24")
		)
		(pad "5" smd rect
			(at 1.905 -2.54 180)
			(size 0.635 1.651)
			(layers "F.Cu" "F.Mask" "F.Paste")
			(net "P5V_A_2")
		)
		(pad "6" smd rect
			(at 0.635 -2.54 180)
			(size 0.635 1.651)
			(layers "F.Cu" "F.Mask" "F.Paste")
			(net "P5V_A_2")
		)
		(pad "7" smd rect
			(at -0.635 -2.54 180)
			(size 0.635 1.651)
			(layers "F.Cu" "F.Mask" "F.Paste")
			(net "P5V_A_2")
		)
		(pad "8" smd rect
			(at -1.905 -2.54 180)
			(size 0.635 1.651)
			(layers "F.Cu" "F.Mask" "F.Paste")
			(net "P5V_A_2")
		)
	)
	(footprint ""
		(layer "F.Cu")
		(at 264.496042 -216.865962)
		(property "Reference" "U15"
			(at 0 0 0)
			(layer "F.SilkS")
			(hide yes)
			(effects
				(font
					(size 1.27 1.27)
				)
			)
		)
		(property "Value" "PCA9511ADP-T-GP"
			(at 0 -13.1572 0)
			(unlocked yes)
			(layer "F.Fab")
			(hide yes)
			(effects
				(font
					(size 1.016 1.016)
					(thickness 0.1524)
				)
			)
		)
		(property "Device Type" "SSOIC8-2H44"
			(at 0 -15.1892 0)
			(unlocked yes)
			(layer "F.Fab")
			(hide yes)
			(effects
				(font
					(size 1.016 1.016)
					(thickness 0.1524)
				)
			)
		)
		(duplicate_pad_numbers_are_jumpers no)
		(fp_line
			(start -1.9304 -1.016)
			(end 1.0922 -1.016)
			(stroke
				(width 0.1524)
				(type default)
			)
			(layer "F.SilkS")
		)
		(fp_line
			(start -1.9304 1.016)
			(end -1.9304 -1.016)
			(stroke
				(width 0.1524)
				(type default)
			)
			(layer "F.SilkS")
		)
		(fp_line
			(start -1.7018 1.0414)
			(end -1.7018 2.9718)
			(stroke
				(width 0.635)
				(type default)
			)
			(layer "F.SilkS")
		)
		(fp_line
			(start -1.524 0)
			(end -1.9304 -0.4064)
			(stroke
				(width 0.1524)
				(type default)
			)
			(layer "F.SilkS")
		)
		(fp_line
			(start -1.524 0)
			(end -1.9304 0.4064)
			(stroke
				(width 0.1524)
				(type default)
			)
			(layer "F.SilkS")
		)
		(fp_line
			(start 1.0922 -1.016)
			(end 1.0922 1.016)
			(stroke
				(width 0.1524)
				(type default)
			)
			(layer "F.SilkS")
		)
		(fp_line
			(start 1.0922 1.016)
			(end -1.9304 1.016)
			(stroke
				(width 0.1524)
				(type default)
			)
			(layer "F.SilkS")
		)
		(fp_poly
			(pts
				(xy -1.1938 -1.016) (xy 1.0922 -1.016) (xy 1.0922 1.016) (xy -1.1938 1.016)
			)
			(stroke
				(width 0)
				(type default)
			)
			(fill yes)
			(layer "F.SilkS")
		)
		(fp_rect
			(start -2.0066 3.3401)
			(end 2.0066 -3.3401)
			(stroke
				(width 0)
				(type default)
			)
			(fill no)
			(layer "F.CrtYd")
		)
		(fp_poly
			(pts
				(xy -2.0066 -3.3401) (xy 2.0066 -3.3401) (xy 2.0066 3.3401) (xy -2.0066 3.3401)
			)
			(stroke
				(width 0)
				(type default)
			)
			(fill no)
			(layer "F.Fab")
		)
		(pad "1" smd rect
			(at -0.97536 2.0701)
			(size 0.4064 1.524)
			(layers "F.Cu" "F.Mask" "F.Paste")
			(net "I2C_DPB_BUFF_EN")
		)
		(pad "2" smd rect
			(at -0.32512 2.0701)
			(size 0.4064 1.524)
			(layers "F.Cu" "F.Mask" "F.Paste")
			(net "I2C_DPB_A_SCL_BUF")
		)
		(pad "3" smd rect
			(at 0.32512 2.0701)
			(size 0.4064 1.524)
			(layers "F.Cu" "F.Mask" "F.Paste")
			(net "I2C_DPB_A_SCL")
		)
		(pad "4" smd rect
			(at 0.97536 2.0701)
			(size 0.4064 1.524)
			(layers "F.Cu" "F.Mask" "F.Paste")
			(net "GND")
		)
		(pad "5" smd rect
			(at 0.97536 -2.0701)
			(size 0.4064 1.524)
			(layers "F.Cu" "F.Mask" "F.Paste")
			(net "I2C_DPB_BUFF_READY")
		)
		(pad "6" smd rect
			(at 0.32512 -2.0701)
			(size 0.4064 1.524)
			(layers "F.Cu" "F.Mask" "F.Paste")
			(net "I2C_DPB_A_SDA")
		)
		(pad "7" smd rect
			(at -0.32512 -2.0701)
			(size 0.4064 1.524)
			(layers "F.Cu" "F.Mask" "F.Paste")
			(net "I2C_DPB_A_SDA_BUF")
		)
		(pad "8" smd rect
			(at -0.97536 -2.0701)
			(size 0.4064 1.524)
			(layers "F.Cu" "F.Mask" "F.Paste")
			(net "P3V3_STBY_A")
		)
	)
	(footprint ""
		(layer "F.Cu")
		(at 222.645478 -96.13773 90)
		(property "Reference" "R996"
			(at 0 0 90)
			(layer "F.SilkS")
			(hide yes)
			(effects
				(font
					(size 1.27 1.27)
				)
			)
		)
		(property "Value" "100KR2F-L1-GP"
			(at 0.064008 -3.993896 90)
			(unlocked yes)
			(layer "F.Fab")
			(hide yes)
			(effects
				(font
					(size 1.016 1.016)
					(thickness 0.1524)
				)
			)
		)
		(property "Device Type" "R402H16"
			(at 0.064008 -5.517896 90)
			(unlocked yes)
			(layer "F.Fab")
			(hide yes)
			(effects
				(font
					(size 1.016 1.016)
					(thickness 0.1524)
				)
			)
		)
		(duplicate_pad_numbers_are_jumpers no)
		(fp_line
			(start 0.508 -0.9398)
			(end -0.508 -0.9398)
			(stroke
				(width 0.1524)
				(type default)
			)
			(layer "F.SilkS")
		)
		(fp_line
			(start -0.508 -0.9398)
			(end -0.508 0.9398)
			(stroke
				(width 0.1524)
				(type default)
			)
			(layer "F.SilkS")
		)
		(fp_rect
			(start -0.508 0.9398)
			(end 0.508 -0.9398)
			(stroke
				(width 0)
				(type default)
			)
			(fill no)
			(layer "F.CrtYd")
		)
		(fp_rect
			(start -0.508 0.9398)
			(end 0.508 -0.9398)
			(stroke
				(width 0)
				(type default)
			)
			(fill no)
			(layer "F.Fab")
		)
		(pad "1" smd custom
			(at 0 -0.4445 90)
			(size 0.1397 0.1397)
			(layers "F.Cu" "F.Mask" "F.Paste")
			(net "P3V3_STBY_A")
			(options
				(clearance outline)
				(anchor circle)
			)
			(primitives
				(gr_poly
					(pts
						(arc
							(start -0.1778 -0.2794)
							(mid -0.249642 -0.249642)
							(end -0.2794 -0.1778)
						)
						(arc
							(start -0.2794 0.1778)
							(mid -0.249642 0.249642)
							(end -0.1778 0.2794)
						)
						(arc
							(start 0.1778 0.2794)
							(mid 0.249642 0.249642)
							(end 0.2794 0.1778)
						)
						(arc
							(start 0.2794 -0.1778)
							(mid 0.249642 -0.249642)
							(end 0.1778 -0.2794)
						)
					)
					(width 0)
					(fill yes)
				)
			)
		)
		(pad "2" smd custom
			(at 0 0.4445 90)
			(size 0.1397 0.1397)
			(layers "F.Cu" "F.Mask" "F.Paste")
			(net "COMP_A_PRI_INS_N")
			(options
				(clearance outline)
				(anchor circle)
			)
			(primitives
				(gr_poly
					(pts
						(arc
							(start -0.1778 -0.2794)
							(mid -0.249642 -0.249642)
							(end -0.2794 -0.1778)
						)
						(arc
							(start -0.2794 0.1778)
							(mid -0.249642 0.249642)
							(end -0.1778 0.2794)
						)
						(arc
							(start 0.1778 0.2794)
							(mid 0.249642 0.249642)
							(end 0.2794 0.1778)
						)
						(arc
							(start 0.2794 -0.1778)
							(mid 0.249642 -0.249642)
							(end 0.1778 -0.2794)
						)
					)
					(width 0)
					(fill yes)
				)
			)
		)
	)
	(footprint ""
		(layer "F.Cu")
		(at 410.350208 -294.438324 180)
		(property "Reference" "R310"
			(at 0 0 180)
			(layer "F.SilkS")
			(hide yes)
			(effects
				(font
					(size 1.27 1.27)
				)
			)
		)
		(property "Value" "91R3F-1-GP"
			(at -0.0254 -2.5146 180)
			(unlocked yes)
			(layer "F.Fab")
			(hide yes)
			(effects
				(font
					(size 1.016 1.016)
					(thickness 0.1524)
				)
			)
		)
		(property "Device Type" "R603H22"
			(at -0.0254 -4.0386 180)
			(unlocked yes)
			(layer "F.Fab")
			(hide yes)
			(effects
				(font
					(size 1.016 1.016)
					(thickness 0.1524)
				)
			)
		)
		(duplicate_pad_numbers_are_jumpers no)
		(fp_line
			(start 0.2032 0)
			(end 0.4826 0)
			(stroke
				(width 0.2032)
				(type default)
			)
			(layer "F.SilkS")
		)
		(fp_line
			(start -0.4826 0)
			(end -0.2032 0)
			(stroke
				(width 0.2032)
				(type default)
			)
			(layer "F.SilkS")
		)
		(fp_rect
			(start -0.5842 1.3335)
			(end 0.5842 -1.3335)
			(stroke
				(width 0)
				(type default)
			)
			(fill no)
			(layer "F.CrtYd")
		)
		(fp_rect
			(start -0.5842 1.3335)
			(end 0.5842 -1.3335)
			(stroke
				(width 0)
				(type default)
			)
			(fill no)
			(layer "F.Fab")
		)
		(pad "1" smd custom
			(at 0 -0.762 180)
			(size 0.2159 0.2159)
			(layers "F.Cu" "F.Mask" "F.Paste")
			(net "P5V_B")
			(options
				(clearance outline)
				(anchor circle)
			)
			(primitives
				(gr_poly
					(pts
						(arc
							(start -0.3302 -0.4318)
							(mid -0.402042 -0.402042)
							(end -0.4318 -0.3302)
						)
						(arc
							(start -0.4318 0.3302)
							(mid -0.402042 0.402042)
							(end -0.3302 0.4318)
						)
						(arc
							(start 0.3302 0.4318)
							(mid 0.402042 0.402042)
							(end 0.4318 0.3302)
						)
						(arc
							(start 0.4318 -0.3302)
							(mid 0.402042 -0.402042)
							(end 0.3302 -0.4318)
						)
					)
					(width 0)
					(fill yes)
				)
			)
		)
		(pad "2" smd custom
			(at 0 0.762 180)
			(size 0.2159 0.2159)
			(layers "F.Cu" "F.Mask" "F.Paste")
			(net "DRV_ACT_33")
			(options
				(clearance outline)
				(anchor circle)
			)
			(primitives
				(gr_poly
					(pts
						(arc
							(start -0.3302 -0.4318)
							(mid -0.402042 -0.402042)
							(end -0.4318 -0.3302)
						)
						(arc
							(start -0.4318 0.3302)
							(mid -0.402042 0.402042)
							(end -0.3302 0.4318)
						)
						(arc
							(start 0.3302 0.4318)
							(mid 0.402042 0.402042)
							(end 0.4318 0.3302)
						)
						(arc
							(start 0.4318 -0.3302)
							(mid 0.402042 -0.402042)
							(end 0.3302 -0.4318)
						)
					)
					(width 0)
					(fill yes)
				)
			)
		)
	)
	(footprint ""
		(layer "F.Cu")
		(at 381.36195 -292.194742 90)
		(property "Reference" "R314"
			(at 0 0 90)
			(layer "F.SilkS")
			(hide yes)
			(effects
				(font
					(size 1.27 1.27)
				)
			)
		)
		(property "Value" "10KR2F-2-GP"
			(at 0.064008 -3.993896 90)
			(unlocked yes)
			(layer "F.Fab")
			(hide yes)
			(effects
				(font
					(size 1.016 1.016)
					(thickness 0.1524)
				)
			)
		)
		(property "Device Type" "R402H16"
			(at 0.064008 -5.517896 90)
			(unlocked yes)
			(layer "F.Fab")
			(hide yes)
			(effects
				(font
					(size 1.016 1.016)
					(thickness 0.1524)
				)
			)
		)
		(duplicate_pad_numbers_are_jumpers no)
		(fp_line
			(start 0.508 -0.9398)
			(end -0.508 -0.9398)
			(stroke
				(width 0.1524)
				(type default)
			)
			(layer "F.SilkS")
		)
		(fp_line
			(start -0.508 -0.9398)
			(end -0.508 0.9398)
			(stroke
				(width 0.1524)
				(type default)
			)
			(layer "F.SilkS")
		)
		(fp_rect
			(start -0.508 0.9398)
			(end 0.508 -0.9398)
			(stroke
				(width 0)
				(type default)
			)
			(fill no)
			(layer "F.CrtYd")
		)
		(fp_rect
			(start -0.508 0.9398)
			(end 0.508 -0.9398)
			(stroke
				(width 0)
				(type default)
			)
			(fill no)
			(layer "F.Fab")
		)
		(pad "1" smd custom
			(at 0 -0.4445 90)
			(size 0.1397 0.1397)
			(layers "F.Cu" "F.Mask" "F.Paste")
			(net "P3V3_STBY_A")
			(options
				(clearance outline)
				(anchor circle)
			)
			(primitives
				(gr_poly
					(pts
						(arc
							(start -0.1778 -0.2794)
							(mid -0.249642 -0.249642)
							(end -0.2794 -0.1778)
						)
						(arc
							(start -0.2794 0.1778)
							(mid -0.249642 0.249642)
							(end -0.1778 0.2794)
						)
						(arc
							(start 0.1778 0.2794)
							(mid 0.249642 0.249642)
							(end 0.2794 0.1778)
						)
						(arc
							(start 0.2794 -0.1778)
							(mid 0.249642 -0.249642)
							(end 0.1778 -0.2794)
						)
					)
					(width 0)
					(fill yes)
				)
			)
		)
		(pad "2" smd custom
			(at 0 0.4445 90)
			(size 0.1397 0.1397)
			(layers "F.Cu" "F.Mask" "F.Paste")
			(net "HDD_PRSNT_8")
			(options
				(clearance outline)
				(anchor circle)
			)
			(primitives
				(gr_poly
					(pts
						(arc
							(start -0.1778 -0.2794)
							(mid -0.249642 -0.249642)
							(end -0.2794 -0.1778)
						)
						(arc
							(start -0.2794 0.1778)
							(mid -0.249642 0.249642)
							(end -0.1778 0.2794)
						)
						(arc
							(start 0.1778 0.2794)
							(mid 0.249642 0.249642)
							(end 0.2794 0.1778)
						)
						(arc
							(start 0.2794 -0.1778)
							(mid 0.249642 -0.249642)
							(end 0.1778 -0.2794)
						)
					)
					(width 0)
					(fill yes)
				)
			)
		)
	)
	(footprint ""
		(layer "F.Cu")
		(at 32.463486 -158.660592 90)
		(property "Reference" "C195"
			(at 0 0 90)
			(layer "F.SilkS")
			(hide yes)
			(effects
				(font
					(size 1.27 1.27)
				)
			)
		)
		(property "Value" "SCD01U16V1KX-GP"
			(at -2.8321 -1.7399 90)
			(unlocked yes)
			(layer "F.Fab")
			(hide yes)
			(effects
				(font
					(size 1.016 1.016)
					(thickness 0.1524)
				)
			)
		)
		(property "Device Type" "C0201H13"
			(at -2.8321 -3.2639 90)
			(unlocked yes)
			(layer "F.Fab")
			(hide yes)
			(effects
				(font
					(size 1.016 1.016)
					(thickness 0.1524)
				)
			)
		)
		(duplicate_pad_numbers_are_jumpers no)
		(fp_rect
			(start -0.2794 0.6477)
			(end 0.2794 -0.6477)
			(stroke
				(width 0)
				(type default)
			)
			(fill no)
			(layer "F.CrtYd")
		)
		(fp_rect
			(start -0.2794 0.6477)
			(end 0.2794 -0.6477)
			(stroke
				(width 0)
				(type default)
			)
			(fill no)
			(layer "F.Fab")
		)
		(pad "1" smd custom
			(at 0 -0.2794 90)
			(size 0.0762 0.0762)
			(layers "F.Cu" "F.Mask" "F.Paste")
			(net "SAS_HDD_RX_P12")
			(options
				(clearance outline)
				(anchor circle)
			)
			(primitives
				(gr_poly
					(pts
						(arc
							(start 0.1524 -0.127)
							(mid 0.137521 -0.162921)
							(end 0.1016 -0.1778)
						)
						(arc
							(start -0.1016 -0.1778)
							(mid -0.137521 -0.162921)
							(end -0.1524 -0.127)
						)
						(arc
							(start -0.1524 0.127)
							(mid -0.137521 0.162921)
							(end -0.1016 0.1778)
						)
						(arc
							(start 0.1016 0.1778)
							(mid 0.137521 0.162921)
							(end 0.1524 0.127)
						)
					)
					(width 0)
					(fill yes)
				)
			)
		)
		(pad "2" smd custom
			(at 0 0.2794 90)
			(size 0.0762 0.0762)
			(layers "F.Cu" "F.Mask" "F.Paste")
			(net "PHY_SCC_A_TO_DRV_A_12_DP")
			(options
				(clearance outline)
				(anchor circle)
			)
			(primitives
				(gr_poly
					(pts
						(arc
							(start 0.1524 -0.127)
							(mid 0.137521 -0.162921)
							(end 0.1016 -0.1778)
						)
						(arc
							(start -0.1016 -0.1778)
							(mid -0.137521 -0.162921)
							(end -0.1524 -0.127)
						)
						(arc
							(start -0.1524 0.127)
							(mid -0.137521 0.162921)
							(end -0.1016 0.1778)
						)
						(arc
							(start 0.1016 0.1778)
							(mid 0.137521 0.162921)
							(end 0.1524 0.127)
						)
					)
					(width 0)
					(fill yes)
				)
			)
		)
	)
	(footprint ""
		(layer "F.Cu")
		(at 17.145 -127.254)
		(property "Reference" "R273"
			(at 0 0 0)
			(layer "F.SilkS")
			(hide yes)
			(effects
				(font
					(size 1.27 1.27)
				)
			)
		)
		(property "Value" "130R3F-GP"
			(at -0.0254 -2.5146 0)
			(unlocked yes)
			(layer "F.Fab")
			(hide yes)
			(effects
				(font
					(size 1.016 1.016)
					(thickness 0.1524)
				)
			)
		)
		(property "Device Type" "R603H22"
			(at -0.0254 -4.0386 0)
			(unlocked yes)
			(layer "F.Fab")
			(hide yes)
			(effects
				(font
					(size 1.016 1.016)
					(thickness 0.1524)
				)
			)
		)
		(duplicate_pad_numbers_are_jumpers no)
		(fp_line
			(start -0.4826 0)
			(end -0.2032 0)
			(stroke
				(width 0.2032)
				(type default)
			)
			(layer "F.SilkS")
		)
		(fp_line
			(start 0.2032 0)
			(end 0.4826 0)
			(stroke
				(width 0.2032)
				(type default)
			)
			(layer "F.SilkS")
		)
		(fp_rect
			(start -0.5842 1.3335)
			(end 0.5842 -1.3335)
			(stroke
				(width 0)
				(type default)
			)
			(fill no)
			(layer "F.CrtYd")
		)
		(fp_rect
			(start -0.5842 1.3335)
			(end 0.5842 -1.3335)
			(stroke
				(width 0)
				(type default)
			)
			(fill no)
			(layer "F.Fab")
		)
		(pad "1" smd custom
			(at 0 -0.762)
			(size 0.2159 0.2159)
			(layers "F.Cu" "F.Mask" "F.Paste")
			(net "P5V_A_1")
			(options
				(clearance outline)
				(anchor circle)
			)
			(primitives
				(gr_poly
					(pts
						(arc
							(start -0.3302 -0.4318)
							(mid -0.402042 -0.402042)
							(end -0.4318 -0.3302)
						)
						(arc
							(start -0.4318 0.3302)
							(mid -0.402042 0.402042)
							(end -0.3302 0.4318)
						)
						(arc
							(start 0.3302 0.4318)
							(mid 0.402042 0.402042)
							(end 0.4318 0.3302)
						)
						(arc
							(start 0.4318 -0.3302)
							(mid 0.402042 -0.402042)
							(end 0.3302 -0.4318)
						)
					)
					(width 0)
					(fill yes)
				)
			)
		)
		(pad "2" smd custom
			(at 0 0.762)
			(size 0.2159 0.2159)
			(layers "F.Cu" "F.Mask" "F.Paste")
			(net "FLT_HDD12")
			(options
				(clearance outline)
				(anchor circle)
			)
			(primitives
				(gr_poly
					(pts
						(arc
							(start -0.3302 -0.4318)
							(mid -0.402042 -0.402042)
							(end -0.4318 -0.3302)
						)
						(arc
							(start -0.4318 0.3302)
							(mid -0.402042 0.402042)
							(end -0.3302 0.4318)
						)
						(arc
							(start 0.3302 0.4318)
							(mid 0.402042 0.402042)
							(end 0.4318 0.3302)
						)
						(arc
							(start 0.4318 -0.3302)
							(mid 0.402042 -0.402042)
							(end 0.3302 -0.4318)
						)
					)
					(width 0)
					(fill yes)
				)
			)
		)
	)
	(footprint ""
		(layer "F.Cu")
		(at 356.289102 -47.749968 -90)
		(property "Reference" "VIA72"
			(at 0 0 270)
			(layer "F.SilkS")
			(hide yes)
			(effects
				(font
					(size 1.27 1.27)
				)
			)
		)
		(property "Value" "100OHM-8L-1D6MM-L18L16-GP"
			(at -3.7211 -4.5085 270)
			(unlocked yes)
			(layer "F.Fab")
			(hide yes)
			(effects
				(font
					(size 1.016 1.016)
					(thickness 0.1524)
				)
			)
		)
		(property "Device Type" "VIA-PCIE-4P-394076"
			(at -3.7211 -6.0325 270)
			(unlocked yes)
			(layer "F.Fab")
			(hide yes)
			(effects
				(font
					(size 1.016 1.016)
					(thickness 0.1524)
				)
			)
		)
		(duplicate_pad_numbers_are_jumpers no)
		(fp_rect
			(start -1.9685 0.381)
			(end 1.9685 -0.381)
			(stroke
				(width 0)
				(type default)
			)
			(fill no)
			(layer "F.CrtYd")
		)
		(fp_rect
			(start -1.9685 0.381)
			(end 1.9685 -0.381)
			(stroke
				(width 0)
				(type default)
			)
			(fill no)
			(layer "F.Fab")
		)
		(pad "1" thru_hole circle
			(at -1.5875 0 270)
			(size 0.508 0.508)
			(drill 0.254)
			(layers "*.Cu" "*.Mask")
			(remove_unused_layers no)
			(net "GND")
			(clearance 0.127)
			(thermal_gap 0.127)
		)
		(pad "2" thru_hole circle
			(at -0.5715 0 270)
			(size 0.508 0.508)
			(drill 0.254)
			(layers "*.Cu" "*.Mask")
			(remove_unused_layers no)
			(net "PHY_DRV_A_TO_SCC_A_31_DP")
			(clearance 0.127)
			(thermal_gap 0.127)
		)
		(pad "3" thru_hole circle
			(at 0.5715 0 270)
			(size 0.508 0.508)
			(drill 0.254)
			(layers "*.Cu" "*.Mask")
			(remove_unused_layers no)
			(net "PHY_DRV_A_TO_SCC_A_31_DN")
			(clearance 0.127)
			(thermal_gap 0.127)
		)
		(pad "4" thru_hole circle
			(at 1.5875 0 270)
			(size 0.508 0.508)
			(drill 0.254)
			(layers "*.Cu" "*.Mask")
			(remove_unused_layers no)
			(net "GND")
			(clearance 0.127)
			(thermal_gap 0.127)
		)
	)
	(footprint ""
		(layer "F.Cu")
		(at 38.100254 -303.904396)
		(property "Reference" "Q252"
			(at 0 0 0)
			(layer "F.SilkS")
			(hide yes)
			(effects
				(font
					(size 1.27 1.27)
				)
			)
		)
		(property "Value" "2N7002K-2-GP"
			(at 0.127 -8.9662 0)
			(unlocked yes)
			(layer "F.Fab")
			(hide yes)
			(effects
				(font
					(size 1.016 1.016)
					(thickness 0.1524)
				)
			)
		)
		(property "Device Type" "SOT23DGS2D4H44"
			(at 0.127 -10.4902 0)
			(unlocked yes)
			(layer "F.Fab")
			(hide yes)
			(effects
				(font
					(size 1.016 1.016)
					(thickness 0.1524)
				)
			)
		)
		(duplicate_pad_numbers_are_jumpers no)
		(fp_line
			(start -1.651 -1.778)
			(end -1.651 1.778)
			(stroke
				(width 0.1524)
				(type default)
			)
			(layer "F.SilkS")
		)
		(fp_line
			(start -1.651 1.778)
			(end 1.651 1.778)
			(stroke
				(width 0.1524)
				(type default)
			)
			(layer "F.SilkS")
		)
		(fp_line
			(start 1.651 -1.778)
			(end -1.651 -1.778)
			(stroke
				(width 0.1524)
				(type default)
			)
			(layer "F.SilkS")
		)
		(fp_line
			(start 1.651 1.778)
			(end 1.651 -1.778)
			(stroke
				(width 0.1524)
				(type default)
			)
			(layer "F.SilkS")
		)
		(fp_poly
			(pts
				(xy -1.778 1.8796) (xy -1.778 -1.8796) (xy 1.778 -1.8796) (xy 1.778 1.8796)
			)
			(stroke
				(width 0)
				(type default)
			)
			(fill no)
			(layer "F.CrtYd")
		)
		(fp_poly
			(pts
				(xy -1.778 1.8796) (xy -1.778 -1.8796) (xy 1.778 -1.8796) (xy 1.778 1.8796)
			)
			(stroke
				(width 0)
				(type default)
			)
			(fill no)
			(layer "F.Fab")
		)
		(pad "D" smd custom
			(at 0 -0.9525)
			(size 0.1905 0.1905)
			(layers "F.Cu" "F.Mask" "F.Paste")
			(net "FLT_HDD25_N")
			(options
				(clearance outline)
				(anchor circle)
			)
			(primitives
				(gr_poly
					(pts
						(arc
							(start -0.1778 0.5715)
							(mid -0.321484 0.511984)
							(end -0.381 0.3683)
						)
						(arc
							(start -0.381 -0.3683)
							(mid -0.321484 -0.511984)
							(end -0.1778 -0.5715)
						)
						(arc
							(start 0.1778 -0.5715)
							(mid 0.321484 -0.511984)
							(end 0.381 -0.3683)
						)
						(arc
							(start 0.381 0.3683)
							(mid 0.321484 0.511984)
							(end 0.1778 0.5715)
						)
					)
					(width 0)
					(fill yes)
				)
			)
		)
		(pad "G" smd custom
			(at -0.98425 0.9525)
			(size 0.1905 0.1905)
			(layers "F.Cu" "F.Mask" "F.Paste")
			(net "DRIVE_B_25_FLT_LED")
			(options
				(clearance outline)
				(anchor circle)
			)
			(primitives
				(gr_poly
					(pts
						(arc
							(start -0.1778 0.5715)
							(mid -0.321484 0.511984)
							(end -0.381 0.3683)
						)
						(arc
							(start -0.381 -0.3683)
							(mid -0.321484 -0.511984)
							(end -0.1778 -0.5715)
						)
						(arc
							(start 0.1778 -0.5715)
							(mid 0.321484 -0.511984)
							(end 0.381 -0.3683)
						)
						(arc
							(start 0.381 0.3683)
							(mid 0.321484 0.511984)
							(end 0.1778 0.5715)
						)
					)
					(width 0)
					(fill yes)
				)
			)
		)
		(pad "S" smd custom
			(at 0.98425 0.9525)
			(size 0.1905 0.1905)
			(layers "F.Cu" "F.Mask" "F.Paste")
			(net "GND")
			(options
				(clearance outline)
				(anchor circle)
			)
			(primitives
				(gr_poly
					(pts
						(arc
							(start -0.1778 0.5715)
							(mid -0.321484 0.511984)
							(end -0.381 0.3683)
						)
						(arc
							(start -0.381 -0.3683)
							(mid -0.321484 -0.511984)
							(end -0.1778 -0.5715)
						)
						(arc
							(start 0.1778 -0.5715)
							(mid 0.321484 -0.511984)
							(end 0.381 -0.3683)
						)
						(arc
							(start 0.381 0.3683)
							(mid 0.321484 0.511984)
							(end 0.1778 0.5715)
						)
					)
					(width 0)
					(fill yes)
				)
			)
		)
	)
	(footprint ""
		(layer "F.Cu")
		(at 81.002886 -31.405322 180)
		(property "Reference" "R56"
			(at 0 0 180)
			(layer "F.SilkS")
			(hide yes)
			(effects
				(font
					(size 1.27 1.27)
				)
			)
		)
		(property "Value" "0R2J-2-GP"
			(at 0.064008 -3.993896 180)
			(unlocked yes)
			(layer "F.Fab")
			(hide yes)
			(effects
				(font
					(size 1.016 1.016)
					(thickness 0.1524)
				)
			)
		)
		(property "Device Type" "R402H16"
			(at 0.064008 -5.517896 180)
			(unlocked yes)
			(layer "F.Fab")
			(hide yes)
			(effects
				(font
					(size 1.016 1.016)
					(thickness 0.1524)
				)
			)
		)
		(duplicate_pad_numbers_are_jumpers no)
		(fp_line
			(start 0.508 -0.9398)
			(end -0.508 -0.9398)
			(stroke
				(width 0.1524)
				(type default)
			)
			(layer "F.SilkS")
		)
		(fp_line
			(start -0.508 -0.9398)
			(end -0.508 0.9398)
			(stroke
				(width 0.1524)
				(type default)
			)
			(layer "F.SilkS")
		)
		(fp_rect
			(start -0.508 0.9398)
			(end 0.508 -0.9398)
			(stroke
				(width 0)
				(type default)
			)
			(fill no)
			(layer "F.CrtYd")
		)
		(fp_rect
			(start -0.508 0.9398)
			(end 0.508 -0.9398)
			(stroke
				(width 0)
				(type default)
			)
			(fill no)
			(layer "F.Fab")
		)
		(pad "1" smd custom
			(at 0 -0.4445 180)
			(size 0.1397 0.1397)
			(layers "F.Cu" "F.Mask" "F.Paste")
			(net "IO_EXP10_SDA")
			(options
				(clearance outline)
				(anchor circle)
			)
			(primitives
				(gr_poly
					(pts
						(arc
							(start -0.1778 -0.2794)
							(mid -0.249642 -0.249642)
							(end -0.2794 -0.1778)
						)
						(arc
							(start -0.2794 0.1778)
							(mid -0.249642 0.249642)
							(end -0.1778 0.2794)
						)
						(arc
							(start 0.1778 0.2794)
							(mid 0.249642 0.249642)
							(end 0.2794 0.1778)
						)
						(arc
							(start 0.2794 -0.1778)
							(mid 0.249642 -0.249642)
							(end 0.1778 -0.2794)
						)
					)
					(width 0)
					(fill yes)
				)
			)
		)
		(pad "2" smd custom
			(at 0 0.4445 180)
			(size 0.1397 0.1397)
			(layers "F.Cu" "F.Mask" "F.Paste")
			(net "I2C_BMC_A_MISC_SDA")
			(options
				(clearance outline)
				(anchor circle)
			)
			(primitives
				(gr_poly
					(pts
						(arc
							(start -0.1778 -0.2794)
							(mid -0.249642 -0.249642)
							(end -0.2794 -0.1778)
						)
						(arc
							(start -0.2794 0.1778)
							(mid -0.249642 0.249642)
							(end -0.1778 0.2794)
						)
						(arc
							(start 0.1778 0.2794)
							(mid 0.249642 0.249642)
							(end 0.2794 0.1778)
						)
						(arc
							(start 0.2794 -0.1778)
							(mid 0.249642 -0.249642)
							(end 0.1778 -0.2794)
						)
					)
					(width 0)
					(fill yes)
				)
			)
		)
	)
	(footprint ""
		(layer "F.Cu")
		(at 47.916846 -159.490918 180)
		(property "Reference" "R445"
			(at 0 0 180)
			(layer "F.SilkS")
			(hide yes)
			(effects
				(font
					(size 1.27 1.27)
				)
			)
		)
		(property "Value" "200KR2F-L-GP"
			(at 0.064008 -3.993896 180)
			(unlocked yes)
			(layer "F.Fab")
			(hide yes)
			(effects
				(font
					(size 1.016 1.016)
					(thickness 0.1524)
				)
			)
		)
		(property "Device Type" "R402H16"
			(at 0.064008 -5.517896 180)
			(unlocked yes)
			(layer "F.Fab")
			(hide yes)
			(effects
				(font
					(size 1.016 1.016)
					(thickness 0.1524)
				)
			)
		)
		(duplicate_pad_numbers_are_jumpers no)
		(fp_line
			(start 0.508 -0.9398)
			(end -0.508 -0.9398)
			(stroke
				(width 0.1524)
				(type default)
			)
			(layer "F.SilkS")
		)
		(fp_line
			(start -0.508 -0.9398)
			(end -0.508 0.9398)
			(stroke
				(width 0.1524)
				(type default)
			)
			(layer "F.SilkS")
		)
		(fp_rect
			(start -0.508 0.9398)
			(end 0.508 -0.9398)
			(stroke
				(width 0)
				(type default)
			)
			(fill no)
			(layer "F.CrtYd")
		)
		(fp_rect
			(start -0.508 0.9398)
			(end 0.508 -0.9398)
			(stroke
				(width 0)
				(type default)
			)
			(fill no)
			(layer "F.Fab")
		)
		(pad "1" smd custom
			(at 0 -0.4445 180)
			(size 0.1397 0.1397)
			(layers "F.Cu" "F.Mask" "F.Paste")
			(net "SW_HDD_R13")
			(options
				(clearance outline)
				(anchor circle)
			)
			(primitives
				(gr_poly
					(pts
						(arc
							(start -0.1778 -0.2794)
							(mid -0.249642 -0.249642)
							(end -0.2794 -0.1778)
						)
						(arc
							(start -0.2794 0.1778)
							(mid -0.249642 0.249642)
							(end -0.1778 0.2794)
						)
						(arc
							(start 0.1778 0.2794)
							(mid 0.249642 0.249642)
							(end 0.2794 0.1778)
						)
						(arc
							(start 0.2794 -0.1778)
							(mid 0.249642 -0.249642)
							(end 0.1778 -0.2794)
						)
					)
					(width 0)
					(fill yes)
				)
			)
		)
		(pad "2" smd custom
			(at 0 0.4445 180)
			(size 0.1397 0.1397)
			(layers "F.Cu" "F.Mask" "F.Paste")
			(net "SW_HDD_N13")
			(options
				(clearance outline)
				(anchor circle)
			)
			(primitives
				(gr_poly
					(pts
						(arc
							(start -0.1778 -0.2794)
							(mid -0.249642 -0.249642)
							(end -0.2794 -0.1778)
						)
						(arc
							(start -0.2794 0.1778)
							(mid -0.249642 0.249642)
							(end -0.1778 0.2794)
						)
						(arc
							(start 0.1778 0.2794)
							(mid 0.249642 0.249642)
							(end 0.2794 0.1778)
						)
						(arc
							(start 0.2794 -0.1778)
							(mid 0.249642 -0.249642)
							(end 0.1778 -0.2794)
						)
					)
					(width 0)
					(fill yes)
				)
			)
		)
	)
	(footprint ""
		(layer "F.Cu")
		(at 264.301732 19.287744 90)
		(property "Reference" "R137"
			(at 0 0 90)
			(layer "F.SilkS")
			(hide yes)
			(effects
				(font
					(size 1.27 1.27)
				)
			)
		)
		(property "Value" "4K7R2F-GP"
			(at 0.064008 -3.993896 90)
			(unlocked yes)
			(layer "F.Fab")
			(hide yes)
			(effects
				(font
					(size 1.016 1.016)
					(thickness 0.1524)
				)
			)
		)
		(property "Device Type" "R402H16"
			(at 0.064008 -5.517896 90)
			(unlocked yes)
			(layer "F.Fab")
			(hide yes)
			(effects
				(font
					(size 1.016 1.016)
					(thickness 0.1524)
				)
			)
		)
		(duplicate_pad_numbers_are_jumpers no)
		(fp_line
			(start 0.508 -0.9398)
			(end -0.508 -0.9398)
			(stroke
				(width 0.1524)
				(type default)
			)
			(layer "F.SilkS")
		)
		(fp_line
			(start -0.508 -0.9398)
			(end -0.508 0.9398)
			(stroke
				(width 0.1524)
				(type default)
			)
			(layer "F.SilkS")
		)
		(fp_rect
			(start -0.508 0.9398)
			(end 0.508 -0.9398)
			(stroke
				(width 0)
				(type default)
			)
			(fill no)
			(layer "F.CrtYd")
		)
		(fp_rect
			(start -0.508 0.9398)
			(end 0.508 -0.9398)
			(stroke
				(width 0)
				(type default)
			)
			(fill no)
			(layer "F.Fab")
		)
		(pad "1" smd custom
			(at 0 -0.4445 90)
			(size 0.1397 0.1397)
			(layers "F.Cu" "F.Mask" "F.Paste")
			(net "USB_OCS_N1")
			(options
				(clearance outline)
				(anchor circle)
			)
			(primitives
				(gr_poly
					(pts
						(arc
							(start -0.1778 -0.2794)
							(mid -0.249642 -0.249642)
							(end -0.2794 -0.1778)
						)
						(arc
							(start -0.2794 0.1778)
							(mid -0.249642 0.249642)
							(end -0.1778 0.2794)
						)
						(arc
							(start 0.1778 0.2794)
							(mid 0.249642 0.249642)
							(end 0.2794 0.1778)
						)
						(arc
							(start 0.2794 -0.1778)
							(mid 0.249642 -0.249642)
							(end 0.1778 -0.2794)
						)
					)
					(width 0)
					(fill yes)
				)
			)
		)
		(pad "2" smd custom
			(at 0 0.4445 90)
			(size 0.1397 0.1397)
			(layers "F.Cu" "F.Mask" "F.Paste")
			(net "GND")
			(options
				(clearance outline)
				(anchor circle)
			)
			(primitives
				(gr_poly
					(pts
						(arc
							(start -0.1778 -0.2794)
							(mid -0.249642 -0.249642)
							(end -0.2794 -0.1778)
						)
						(arc
							(start -0.2794 0.1778)
							(mid -0.249642 0.249642)
							(end -0.1778 0.2794)
						)
						(arc
							(start 0.1778 0.2794)
							(mid 0.249642 0.249642)
							(end 0.2794 0.1778)
						)
						(arc
							(start 0.2794 -0.1778)
							(mid 0.249642 -0.249642)
							(end 0.1778 -0.2794)
						)
					)
					(width 0)
					(fill yes)
				)
			)
		)
	)
	(footprint ""
		(layer "F.Cu")
		(at 246.47906 -292.989 -90)
		(property "Reference" "R14"
			(at 0 0 270)
			(layer "F.SilkS")
			(hide yes)
			(effects
				(font
					(size 1.27 1.27)
				)
			)
		)
		(property "Value" "4K7R2J-2-GP"
			(at 0.064008 -3.993896 270)
			(unlocked yes)
			(layer "F.Fab")
			(hide yes)
			(effects
				(font
					(size 1.016 1.016)
					(thickness 0.1524)
				)
			)
		)
		(property "Device Type" "R402H16"
			(at 0.064008 -5.517896 270)
			(unlocked yes)
			(layer "F.Fab")
			(hide yes)
			(effects
				(font
					(size 1.016 1.016)
					(thickness 0.1524)
				)
			)
		)
		(duplicate_pad_numbers_are_jumpers no)
		(fp_line
			(start -0.508 -0.9398)
			(end -0.508 0.9398)
			(stroke
				(width 0.1524)
				(type default)
			)
			(layer "F.SilkS")
		)
		(fp_line
			(start 0.508 -0.9398)
			(end -0.508 -0.9398)
			(stroke
				(width 0.1524)
				(type default)
			)
			(layer "F.SilkS")
		)
		(fp_rect
			(start -0.508 0.9398)
			(end 0.508 -0.9398)
			(stroke
				(width 0)
				(type default)
			)
			(fill no)
			(layer "F.CrtYd")
		)
		(fp_rect
			(start -0.508 0.9398)
			(end 0.508 -0.9398)
			(stroke
				(width 0)
				(type default)
			)
			(fill no)
			(layer "F.Fab")
		)
		(pad "1" smd custom
			(at 0 -0.4445 270)
			(size 0.1397 0.1397)
			(layers "F.Cu" "F.Mask" "F.Paste")
			(net "P3V3_STBY_A")
			(options
				(clearance outline)
				(anchor circle)
			)
			(primitives
				(gr_poly
					(pts
						(arc
							(start -0.1778 -0.2794)
							(mid -0.249642 -0.249642)
							(end -0.2794 -0.1778)
						)
						(arc
							(start -0.2794 0.1778)
							(mid -0.249642 0.249642)
							(end -0.1778 0.2794)
						)
						(arc
							(start 0.1778 0.2794)
							(mid 0.249642 0.249642)
							(end 0.2794 0.1778)
						)
						(arc
							(start 0.2794 -0.1778)
							(mid 0.249642 -0.249642)
							(end 0.1778 -0.2794)
						)
					)
					(width 0)
					(fill yes)
				)
			)
		)
		(pad "2" smd custom
			(at 0 0.4445 270)
			(size 0.1397 0.1397)
			(layers "F.Cu" "F.Mask" "F.Paste")
			(net "BMC_A_TO_EXP_A_RESET_N")
			(options
				(clearance outline)
				(anchor circle)
			)
			(primitives
				(gr_poly
					(pts
						(arc
							(start -0.1778 -0.2794)
							(mid -0.249642 -0.249642)
							(end -0.2794 -0.1778)
						)
						(arc
							(start -0.2794 0.1778)
							(mid -0.249642 0.249642)
							(end -0.1778 0.2794)
						)
						(arc
							(start 0.1778 0.2794)
							(mid 0.249642 0.249642)
							(end 0.2794 0.1778)
						)
						(arc
							(start 0.2794 -0.1778)
							(mid 0.249642 -0.249642)
							(end 0.1778 -0.2794)
						)
					)
					(width 0)
					(fill yes)
				)
			)
		)
	)
	(footprint ""
		(layer "F.Cu")
		(at 259.025644 -390.536938 90)
		(property "Reference" "R1166"
			(at 0 0 90)
			(layer "F.SilkS")
			(hide yes)
			(effects
				(font
					(size 1.27 1.27)
				)
			)
		)
		(property "Value" "D0003R4026F-GP"
			(at -6.737858 -1.79959 90)
			(unlocked yes)
			(layer "F.Fab")
			(hide yes)
			(effects
				(font
					(size 1.016 1.016)
					(thickness 0.1524)
				)
			)
		)
		(property "Device Type" "RL4026-4PH149"
			(at -6.737858 -3.32359 90)
			(unlocked yes)
			(layer "F.Fab")
			(hide yes)
			(effects
				(font
					(size 1.016 1.016)
					(thickness 0.1524)
				)
			)
		)
		(duplicate_pad_numbers_are_jumpers no)
		(fp_line
			(start 5.588 -3.937)
			(end 5.588 3.937)
			(stroke
				(width 0.1524)
				(type default)
			)
			(layer "F.SilkS")
		)
		(fp_line
			(start -5.588 -3.937)
			(end 5.588 -3.937)
			(stroke
				(width 0.1524)
				(type default)
			)
			(layer "F.SilkS")
		)
		(fp_line
			(start -5.6769 2.4765)
			(end -5.6769 4.0259)
			(stroke
				(width 0.3302)
				(type default)
			)
			(layer "F.SilkS")
		)
		(fp_line
			(start 5.588 3.937)
			(end -5.588 3.937)
			(stroke
				(width 0.1524)
				(type default)
			)
			(layer "F.SilkS")
		)
		(fp_line
			(start -5.588 3.937)
			(end -5.588 -3.937)
			(stroke
				(width 0.1524)
				(type default)
			)
			(layer "F.SilkS")
		)
		(fp_line
			(start -5.6769 4.0259)
			(end -4.1402 4.0259)
			(stroke
				(width 0.3302)
				(type default)
			)
			(layer "F.SilkS")
		)
		(fp_poly
			(pts
				(xy -4.703572 3.998468) (xy -5.289804 4.5847) (xy -4.11734 4.5847)
			)
			(stroke
				(width 0)
				(type default)
			)
			(fill yes)
			(layer "F.SilkS")
		)
		(fp_rect
			(start -5.0546 3.302)
			(end 5.0546 -3.302)
			(stroke
				(width 0)
				(type default)
			)
			(fill no)
			(layer "F.CrtYd")
		)
		(fp_poly
			(pts
				(xy -5.842 4.191) (xy -5.842 -4.191) (xy 5.842 -4.191) (xy 5.842 -0.00635) (xy 5.0546 -0.00635)
				(xy 5.0546 -3.302) (xy -5.0546 -3.302) (xy -5.0546 3.302) (xy 5.0546 3.302) (xy 5.0546 0.00635)
				(xy 5.842 0.00635) (xy 5.842 4.191)
			)
			(stroke
				(width 0)
				(type default)
			)
			(fill no)
			(layer "F.CrtYd")
		)
		(fp_rect
			(start -5.842 4.191)
			(end 5.842 -4.191)
			(stroke
				(width 0)
				(type default)
			)
			(fill no)
			(layer "F.Fab")
		)
		(pad "1" smd rect
			(at -4.115054 0.890016 90)
			(size 2.4384 5.588)
			(layers "F.Cu" "F.Mask" "F.Paste")
			(net "MB3_P12V_IN_R")
		)
		(pad "2" smd rect
			(at 4.115054 0.890016 90)
			(size 2.4384 5.588)
			(layers "F.Cu" "F.Mask" "F.Paste")
			(net "P12V_IN")
		)
		(pad "3" smd rect
			(at -4.115054 -3.245104 90)
			(size 2.4384 0.889)
			(layers "F.Cu" "F.Mask" "F.Paste")
			(net "MB3_CM_SENSE_R1_N")
		)
		(pad "4" smd rect
			(at 4.115054 -3.245104 90)
			(size 2.4384 0.889)
			(layers "F.Cu" "F.Mask" "F.Paste")
			(net "MB3_CM_SENSE_R1_P")
		)
		(zone
			(layer "F.Cu")
			(hatch none 0.5)
			(connect_pads
				(clearance 0)
			)
			(min_thickness 0.25)
			(keepout
				(tracks allowed)
				(vias not_allowed)
				(pads allowed)
				(copperpour not_allowed)
				(footprints allowed)
			)
			(placement
				(enabled no)
				(sheetname "")
			)
			(fill
				(thermal_gap 0.5)
				(thermal_bridge_width 0.5)
				(island_removal_mode 0)
			)
			(polygon
				(pts
					(xy 256.22504 -393.432792) (xy 257.12166 -393.432792) (xy 257.12166 -395.871192) (xy 256.22504 -395.871192)
				)
			)
		)
		(zone
			(layer "F.Cu")
			(hatch none 0.5)
			(connect_pads
				(clearance 0)
			)
			(min_thickness 0.25)
			(keepout
				(tracks allowed)
				(vias not_allowed)
				(pads allowed)
				(copperpour not_allowed)
				(footprints allowed)
			)
			(placement
				(enabled no)
				(sheetname "")
			)
			(fill
				(thermal_gap 0.5)
				(thermal_bridge_width 0.5)
				(island_removal_mode 0)
			)
			(polygon
				(pts
					(xy 256.22504 -385.202684) (xy 257.12166 -385.202684) (xy 257.12166 -387.641084) (xy 256.22504 -387.641084)
				)
			)
		)
		(zone
			(layer "F.Cu")
			(hatch none 0.5)
			(connect_pads
				(clearance 0)
			)
			(min_thickness 0.25)
			(keepout
				(tracks not_allowed)
				(vias allowed)
				(pads allowed)
				(copperpour not_allowed)
				(footprints allowed)
			)
			(placement
				(enabled no)
				(sheetname "")
			)
			(fill
				(thermal_gap 0.5)
				(thermal_bridge_width 0.5)
				(island_removal_mode 0)
			)
			(polygon
				(pts
					(xy 257.12166 -393.432792) (xy 257.12166 -395.871192) (xy 256.22504 -395.871192) (xy 256.22504 -393.432792)
				)
			)
		)
		(zone
			(layer "F.Cu")
			(hatch none 0.5)
			(connect_pads
				(clearance 0)
			)
			(min_thickness 0.25)
			(keepout
				(tracks not_allowed)
				(vias allowed)
				(pads allowed)
				(copperpour not_allowed)
				(footprints allowed)
			)
			(placement
				(enabled no)
				(sheetname "")
			)
			(fill
				(thermal_gap 0.5)
				(thermal_bridge_width 0.5)
				(island_removal_mode 0)
			)
			(polygon
				(pts
					(xy 257.12166 -385.202684) (xy 257.12166 -387.641084) (xy 256.22504 -387.641084) (xy 256.22504 -385.202684)
				)
			)
		)
	)
	(footprint ""
		(layer "F.Cu")
		(at 172.593 -174.857918)
		(property "Reference" "Q104"
			(at 0 0 0)
			(layer "F.SilkS")
			(hide yes)
			(effects
				(font
					(size 1.27 1.27)
				)
			)
		)
		(property "Value" "AO4407AL-GP"
			(at -3.707384 -1.5367 0)
			(unlocked yes)
			(layer "F.Fab")
			(hide yes)
			(effects
				(font
					(size 1.016 1.016)
					(thickness 0.1524)
				)
			)
		)
		(property "Device Type" "SOIC8H69"
			(at -3.707384 -3.0607 0)
			(unlocked yes)
			(layer "F.Fab")
			(hide yes)
			(effects
				(font
					(size 1.016 1.016)
					(thickness 0.1524)
				)
			)
		)
		(duplicate_pad_numbers_are_jumpers no)
		(fp_line
			(start -2.7432 -1.4224)
			(end -2.7432 1.4224)
			(stroke
				(width 0.1524)
				(type default)
			)
			(layer "F.SilkS")
		)
		(fp_line
			(start -2.7432 1.4224)
			(end -2.6416 1.4224)
			(stroke
				(width 0.1524)
				(type default)
			)
			(layer "F.SilkS")
		)
		(fp_line
			(start -2.7432 1.4224)
			(end 2.1336 1.4224)
			(stroke
				(width 0.1524)
				(type default)
			)
			(layer "F.SilkS")
		)
		(fp_line
			(start -2.7178 -0.508)
			(end -2.1844 -0.0508)
			(stroke
				(width 0.1524)
				(type default)
			)
			(layer "F.SilkS")
		)
		(fp_line
			(start -2.6289 3.4417)
			(end -2.6289 1.4732)
			(stroke
				(width 0.381)
				(type default)
			)
			(layer "F.SilkS")
		)
		(fp_line
			(start -2.1844 -0.0508)
			(end -2.7178 0.508)
			(stroke
				(width 0.1524)
				(type default)
			)
			(layer "F.SilkS")
		)
		(fp_line
			(start 2.1336 -1.4224)
			(end -2.7432 -1.4224)
			(stroke
				(width 0.1524)
				(type default)
			)
			(layer "F.SilkS")
		)
		(fp_line
			(start 2.1336 1.4224)
			(end 2.1336 -1.4224)
			(stroke
				(width 0.1524)
				(type default)
			)
			(layer "F.SilkS")
		)
		(fp_poly
			(pts
				(xy -2.2098 -1.4224) (xy -2.2098 1.4224) (xy 2.2098 1.4224) (xy 2.2098 -1.4224)
			)
			(stroke
				(width 0)
				(type default)
			)
			(fill yes)
			(layer "F.SilkS")
		)
		(fp_rect
			(start -2.450084 2.999994)
			(end 2.450084 -2.999994)
			(stroke
				(width 0)
				(type default)
			)
			(fill no)
			(layer "F.CrtYd")
		)
		(fp_poly
			(pts
				(xy -2.8194 3.6322) (xy -2.8194 -3.6322) (xy 2.8194 -3.6322) (xy 2.8194 1.18364) (xy 2.450084 1.18364)
				(xy 2.450084 -2.999994) (xy -2.450084 -2.999994) (xy -2.450084 2.999994) (xy 2.450084 2.999994)
				(xy 2.450084 1.18618) (xy 2.8194 1.18618) (xy 2.8194 3.6322)
			)
			(stroke
				(width 0)
				(type default)
			)
			(fill no)
			(layer "F.CrtYd")
		)
		(fp_rect
			(start -2.8194 3.6322)
			(end 2.8194 -3.6322)
			(stroke
				(width 0)
				(type default)
			)
			(fill no)
			(layer "F.Fab")
		)
		(pad "1" smd rect
			(at -1.905 2.54)
			(size 0.635 1.651)
			(layers "F.Cu" "F.Mask" "F.Paste")
			(net "P12V_A")
		)
		(pad "2" smd rect
			(at -0.635 2.54)
			(size 0.635 1.651)
			(layers "F.Cu" "F.Mask" "F.Paste")
			(net "P12V_A")
		)
		(pad "3" smd rect
			(at 0.635 2.54)
			(size 0.635 1.651)
			(layers "F.Cu" "F.Mask" "F.Paste")
			(net "P12V_A")
		)
		(pad "4" smd rect
			(at 1.905 2.54)
			(size 0.635 1.651)
			(layers "F.Cu" "F.Mask" "F.Paste")
			(net "SW_HDD_N17")
		)
		(pad "5" smd rect
			(at 1.905 -2.54)
			(size 0.635 1.651)
			(layers "F.Cu" "F.Mask" "F.Paste")
			(net "P12V_HDD17")
		)
		(pad "6" smd rect
			(at 0.635 -2.54)
			(size 0.635 1.651)
			(layers "F.Cu" "F.Mask" "F.Paste")
			(net "P12V_HDD17")
		)
		(pad "7" smd rect
			(at -0.635 -2.54)
			(size 0.635 1.651)
			(layers "F.Cu" "F.Mask" "F.Paste")
			(net "P12V_HDD17")
		)
		(pad "8" smd rect
			(at -1.905 -2.54)
			(size 0.635 1.651)
			(layers "F.Cu" "F.Mask" "F.Paste")
			(net "P12V_HDD17")
		)
	)
	(footprint ""
		(layer "F.Cu")
		(at 240.03 -395.9098 180)
		(property "Reference" "C590"
			(at 0 0 180)
			(layer "F.SilkS")
			(hide yes)
			(effects
				(font
					(size 1.27 1.27)
				)
			)
		)
		(property "Value" "SCD1U25V2KX-2-GP"
			(at 1.1811 -2.7051 180)
			(unlocked yes)
			(layer "F.Fab")
			(hide yes)
			(effects
				(font
					(size 1.016 1.016)
					(thickness 0.1524)
				)
			)
		)
		(property "Device Type" "C402H22"
			(at 1.1811 -4.2291 180)
			(unlocked yes)
			(layer "F.Fab")
			(hide yes)
			(effects
				(font
					(size 1.016 1.016)
					(thickness 0.1524)
				)
			)
		)
		(duplicate_pad_numbers_are_jumpers no)
		(fp_rect
			(start -0.4318 0.9525)
			(end 0.4318 -0.9525)
			(stroke
				(width 0)
				(type default)
			)
			(fill no)
			(layer "F.CrtYd")
		)
		(fp_rect
			(start -0.4318 0.9525)
			(end 0.4318 -0.9525)
			(stroke
				(width 0)
				(type default)
			)
			(fill no)
			(layer "F.Fab")
		)
		(pad "1" smd custom
			(at 0 -0.4445 180)
			(size 0.1524 0.1524)
			(layers "F.Cu" "F.Mask" "F.Paste")
			(net "MB3_ISET_R")
			(options
				(clearance outline)
				(anchor circle)
			)
			(primitives
				(gr_poly
					(pts
						(arc
							(start 0.3048 -0.2032)
							(mid 0.275042 -0.275042)
							(end 0.2032 -0.3048)
						)
						(arc
							(start -0.2032 -0.3048)
							(mid -0.275042 -0.275042)
							(end -0.3048 -0.2032)
						)
						(arc
							(start -0.3048 0.2032)
							(mid -0.275042 0.275042)
							(end -0.2032 0.3048)
						)
						(arc
							(start 0.2032 0.3048)
							(mid 0.275042 0.275042)
							(end 0.3048 0.2032)
						)
					)
					(width 0)
					(fill yes)
				)
			)
		)
		(pad "2" smd custom
			(at 0 0.4445 180)
			(size 0.1524 0.1524)
			(layers "F.Cu" "F.Mask" "F.Paste")
			(net "AGND_CURRENT_DPB")
			(options
				(clearance outline)
				(anchor circle)
			)
			(primitives
				(gr_poly
					(pts
						(arc
							(start 0.3048 -0.2032)
							(mid 0.275042 -0.275042)
							(end 0.2032 -0.3048)
						)
						(arc
							(start -0.2032 -0.3048)
							(mid -0.275042 -0.275042)
							(end -0.3048 -0.2032)
						)
						(arc
							(start -0.3048 0.2032)
							(mid -0.275042 0.275042)
							(end -0.2032 0.3048)
						)
						(arc
							(start 0.2032 0.3048)
							(mid 0.275042 0.275042)
							(end 0.3048 0.2032)
						)
					)
					(width 0)
					(fill yes)
				)
			)
		)
	)
	(footprint ""
		(layer "F.Cu")
		(at 55.790846 -304.462942 180)
		(property "Reference" "C60"
			(at 0 0 180)
			(layer "F.SilkS")
			(hide yes)
			(effects
				(font
					(size 1.27 1.27)
				)
			)
		)
		(property "Value" "SC1U25V3KX-GP"
			(at 0 -2.8194 180)
			(unlocked yes)
			(layer "F.Fab")
			(hide yes)
			(effects
				(font
					(size 1.016 1.016)
					(thickness 0.1524)
				)
			)
		)
		(property "Device Type" "C603H36"
			(at 0 -4.3434 180)
			(unlocked yes)
			(layer "F.Fab")
			(hide yes)
			(effects
				(font
					(size 1.016 1.016)
					(thickness 0.1524)
				)
			)
		)
		(duplicate_pad_numbers_are_jumpers no)
		(fp_line
			(start 0.508 0)
			(end -0.508 0)
			(stroke
				(width 0.2032)
				(type default)
			)
			(layer "F.SilkS")
		)
		(fp_rect
			(start -0.5842 1.3335)
			(end 0.5842 -1.3335)
			(stroke
				(width 0)
				(type default)
			)
			(fill no)
			(layer "F.CrtYd")
		)
		(fp_rect
			(start -0.5842 1.3335)
			(end 0.5842 -1.3335)
			(stroke
				(width 0)
				(type default)
			)
			(fill no)
			(layer "F.Fab")
		)
		(pad "1" smd custom
			(at 0 -0.762 180)
			(size 0.2159 0.2159)
			(layers "F.Cu" "F.Mask" "F.Paste")
			(net "P12V_HDD1")
			(options
				(clearance outline)
				(anchor circle)
			)
			(primitives
				(gr_poly
					(pts
						(arc
							(start -0.3302 -0.4318)
							(mid -0.402042 -0.402042)
							(end -0.4318 -0.3302)
						)
						(arc
							(start -0.4318 0.3302)
							(mid -0.402042 0.402042)
							(end -0.3302 0.4318)
						)
						(arc
							(start 0.3302 0.4318)
							(mid 0.402042 0.402042)
							(end 0.4318 0.3302)
						)
						(arc
							(start 0.4318 -0.3302)
							(mid 0.402042 -0.402042)
							(end 0.3302 -0.4318)
						)
					)
					(width 0)
					(fill yes)
				)
			)
		)
		(pad "2" smd custom
			(at 0 0.762 180)
			(size 0.2159 0.2159)
			(layers "F.Cu" "F.Mask" "F.Paste")
			(net "GND")
			(options
				(clearance outline)
				(anchor circle)
			)
			(primitives
				(gr_poly
					(pts
						(arc
							(start -0.3302 -0.4318)
							(mid -0.402042 -0.402042)
							(end -0.4318 -0.3302)
						)
						(arc
							(start -0.4318 0.3302)
							(mid -0.402042 0.402042)
							(end -0.3302 0.4318)
						)
						(arc
							(start 0.3302 0.4318)
							(mid 0.402042 0.402042)
							(end 0.4318 0.3302)
						)
						(arc
							(start 0.4318 -0.3302)
							(mid 0.402042 -0.402042)
							(end 0.3302 -0.4318)
						)
					)
					(width 0)
					(fill yes)
				)
			)
		)
	)
	(footprint ""
		(layer "F.Cu")
		(at 138.018266 -135.339074 -90)
		(property "Reference" "R1043"
			(at 0 0 270)
			(layer "F.SilkS")
			(hide yes)
			(effects
				(font
					(size 1.27 1.27)
				)
			)
		)
		(property "Value" "0R2J-2-GP"
			(at 0.064008 -3.993896 270)
			(unlocked yes)
			(layer "F.Fab")
			(hide yes)
			(effects
				(font
					(size 1.016 1.016)
					(thickness 0.1524)
				)
			)
		)
		(property "Device Type" "R402H16"
			(at 0.064008 -5.517896 270)
			(unlocked yes)
			(layer "F.Fab")
			(hide yes)
			(effects
				(font
					(size 1.016 1.016)
					(thickness 0.1524)
				)
			)
		)
		(duplicate_pad_numbers_are_jumpers no)
		(fp_line
			(start -0.508 -0.9398)
			(end -0.508 0.9398)
			(stroke
				(width 0.1524)
				(type default)
			)
			(layer "F.SilkS")
		)
		(fp_line
			(start 0.508 -0.9398)
			(end -0.508 -0.9398)
			(stroke
				(width 0.1524)
				(type default)
			)
			(layer "F.SilkS")
		)
		(fp_rect
			(start -0.508 0.9398)
			(end 0.508 -0.9398)
			(stroke
				(width 0)
				(type default)
			)
			(fill no)
			(layer "F.CrtYd")
		)
		(fp_rect
			(start -0.508 0.9398)
			(end 0.508 -0.9398)
			(stroke
				(width 0)
				(type default)
			)
			(fill no)
			(layer "F.Fab")
		)
		(pad "1" smd custom
			(at 0 -0.4445 270)
			(size 0.1397 0.1397)
			(layers "F.Cu" "F.Mask" "F.Paste")
			(net "MB0_SDA_R")
			(options
				(clearance outline)
				(anchor circle)
			)
			(primitives
				(gr_poly
					(pts
						(arc
							(start -0.1778 -0.2794)
							(mid -0.249642 -0.249642)
							(end -0.2794 -0.1778)
						)
						(arc
							(start -0.2794 0.1778)
							(mid -0.249642 0.249642)
							(end -0.1778 0.2794)
						)
						(arc
							(start 0.1778 0.2794)
							(mid 0.249642 0.249642)
							(end 0.2794 0.1778)
						)
						(arc
							(start 0.2794 -0.1778)
							(mid 0.249642 -0.249642)
							(end 0.1778 -0.2794)
						)
					)
					(width 0)
					(fill yes)
				)
			)
		)
		(pad "2" smd custom
			(at 0 0.4445 270)
			(size 0.1397 0.1397)
			(layers "F.Cu" "F.Mask" "F.Paste")
			(net "I2C_BMC_A_MISC_SDA")
			(options
				(clearance outline)
				(anchor circle)
			)
			(primitives
				(gr_poly
					(pts
						(arc
							(start -0.1778 -0.2794)
							(mid -0.249642 -0.249642)
							(end -0.2794 -0.1778)
						)
						(arc
							(start -0.2794 0.1778)
							(mid -0.249642 0.249642)
							(end -0.1778 0.2794)
						)
						(arc
							(start 0.1778 0.2794)
							(mid 0.249642 0.249642)
							(end 0.2794 0.1778)
						)
						(arc
							(start 0.2794 -0.1778)
							(mid 0.249642 -0.249642)
							(end 0.1778 -0.2794)
						)
					)
					(width 0)
					(fill yes)
				)
			)
		)
	)
	(footprint ""
		(layer "F.Cu")
		(at 332.74 -48.554894 -90)
		(property "Reference" "R827"
			(at 0 0 270)
			(layer "F.SilkS")
			(hide yes)
			(effects
				(font
					(size 1.27 1.27)
				)
			)
		)
		(property "Value" "4K7R2J-2-GP"
			(at 0.064008 -3.993896 270)
			(unlocked yes)
			(layer "F.Fab")
			(hide yes)
			(effects
				(font
					(size 1.016 1.016)
					(thickness 0.1524)
				)
			)
		)
		(property "Device Type" "R402H16"
			(at 0.064008 -5.517896 270)
			(unlocked yes)
			(layer "F.Fab")
			(hide yes)
			(effects
				(font
					(size 1.016 1.016)
					(thickness 0.1524)
				)
			)
		)
		(duplicate_pad_numbers_are_jumpers no)
		(fp_line
			(start -0.508 -0.9398)
			(end -0.508 0.9398)
			(stroke
				(width 0.1524)
				(type default)
			)
			(layer "F.SilkS")
		)
		(fp_line
			(start 0.508 -0.9398)
			(end -0.508 -0.9398)
			(stroke
				(width 0.1524)
				(type default)
			)
			(layer "F.SilkS")
		)
		(fp_rect
			(start -0.508 0.9398)
			(end 0.508 -0.9398)
			(stroke
				(width 0)
				(type default)
			)
			(fill no)
			(layer "F.CrtYd")
		)
		(fp_rect
			(start -0.508 0.9398)
			(end 0.508 -0.9398)
			(stroke
				(width 0)
				(type default)
			)
			(fill no)
			(layer "F.Fab")
		)
		(pad "1" smd custom
			(at 0 -0.4445 270)
			(size 0.1397 0.1397)
			(layers "F.Cu" "F.Mask" "F.Paste")
			(net "P12V_A")
			(options
				(clearance outline)
				(anchor circle)
			)
			(primitives
				(gr_poly
					(pts
						(arc
							(start -0.1778 -0.2794)
							(mid -0.249642 -0.249642)
							(end -0.2794 -0.1778)
						)
						(arc
							(start -0.2794 0.1778)
							(mid -0.249642 0.249642)
							(end -0.1778 0.2794)
						)
						(arc
							(start 0.1778 0.2794)
							(mid 0.249642 0.249642)
							(end 0.2794 0.1778)
						)
						(arc
							(start 0.2794 -0.1778)
							(mid 0.249642 -0.249642)
							(end 0.1778 -0.2794)
						)
					)
					(width 0)
					(fill yes)
				)
			)
		)
		(pad "2" smd custom
			(at 0 0.4445 270)
			(size 0.1397 0.1397)
			(layers "F.Cu" "F.Mask" "F.Paste")
			(net "SW_HDD_P30")
			(options
				(clearance outline)
				(anchor circle)
			)
			(primitives
				(gr_poly
					(pts
						(arc
							(start -0.1778 -0.2794)
							(mid -0.249642 -0.249642)
							(end -0.2794 -0.1778)
						)
						(arc
							(start -0.2794 0.1778)
							(mid -0.249642 0.249642)
							(end -0.1778 0.2794)
						)
						(arc
							(start 0.1778 0.2794)
							(mid 0.249642 0.249642)
							(end 0.2794 0.1778)
						)
						(arc
							(start 0.2794 -0.1778)
							(mid 0.249642 -0.249642)
							(end 0.1778 -0.2794)
						)
					)
					(width 0)
					(fill yes)
				)
			)
		)
	)
	(footprint ""
		(layer "F.Cu")
		(at 362.310426 -134.558278 180)
		(property "Reference" "C567"
			(at 0 0 180)
			(layer "F.SilkS")
			(hide yes)
			(effects
				(font
					(size 1.27 1.27)
				)
			)
		)
		(property "Value" "SC1U16V3KX-5GP"
			(at 0 -2.8194 180)
			(unlocked yes)
			(layer "F.Fab")
			(hide yes)
			(effects
				(font
					(size 1.016 1.016)
					(thickness 0.1524)
				)
			)
		)
		(property "Device Type" "C603H36"
			(at 0 -4.3434 180)
			(unlocked yes)
			(layer "F.Fab")
			(hide yes)
			(effects
				(font
					(size 1.016 1.016)
					(thickness 0.1524)
				)
			)
		)
		(duplicate_pad_numbers_are_jumpers no)
		(fp_line
			(start 0.508 0)
			(end -0.508 0)
			(stroke
				(width 0.2032)
				(type default)
			)
			(layer "F.SilkS")
		)
		(fp_rect
			(start -0.5842 1.3335)
			(end 0.5842 -1.3335)
			(stroke
				(width 0)
				(type default)
			)
			(fill no)
			(layer "F.CrtYd")
		)
		(fp_rect
			(start -0.5842 1.3335)
			(end 0.5842 -1.3335)
			(stroke
				(width 0)
				(type default)
			)
			(fill no)
			(layer "F.Fab")
		)
		(pad "1" smd custom
			(at 0 -0.762 180)
			(size 0.2159 0.2159)
			(layers "F.Cu" "F.Mask" "F.Paste")
			(net "MB1_CM_UV_R")
			(options
				(clearance outline)
				(anchor circle)
			)
			(primitives
				(gr_poly
					(pts
						(arc
							(start -0.3302 -0.4318)
							(mid -0.402042 -0.402042)
							(end -0.4318 -0.3302)
						)
						(arc
							(start -0.4318 0.3302)
							(mid -0.402042 0.402042)
							(end -0.3302 0.4318)
						)
						(arc
							(start 0.3302 0.4318)
							(mid 0.402042 0.402042)
							(end 0.4318 0.3302)
						)
						(arc
							(start 0.4318 -0.3302)
							(mid 0.402042 -0.402042)
							(end 0.3302 -0.4318)
						)
					)
					(width 0)
					(fill yes)
				)
			)
		)
		(pad "2" smd custom
			(at 0 0.762 180)
			(size 0.2159 0.2159)
			(layers "F.Cu" "F.Mask" "F.Paste")
			(net "AGND_CURRENT_MONOB")
			(options
				(clearance outline)
				(anchor circle)
			)
			(primitives
				(gr_poly
					(pts
						(arc
							(start -0.3302 -0.4318)
							(mid -0.402042 -0.402042)
							(end -0.4318 -0.3302)
						)
						(arc
							(start -0.4318 0.3302)
							(mid -0.402042 0.402042)
							(end -0.3302 0.4318)
						)
						(arc
							(start 0.3302 0.4318)
							(mid 0.402042 0.402042)
							(end 0.4318 0.3302)
						)
						(arc
							(start 0.4318 -0.3302)
							(mid 0.402042 -0.402042)
							(end 0.3302 -0.4318)
						)
					)
					(width 0)
					(fill yes)
				)
			)
		)
	)
	(footprint ""
		(layer "F.Cu")
		(at 86.085934 -25.04821)
		(property "Reference" "U17"
			(at 0 0 0)
			(layer "F.SilkS")
			(hide yes)
			(effects
				(font
					(size 1.27 1.27)
				)
			)
		)
		(property "Value" "TCA9555PWR-GP"
			(at 0 -6.9342 0)
			(unlocked yes)
			(layer "F.Fab")
			(hide yes)
			(effects
				(font
					(size 1.016 1.016)
					(thickness 0.1524)
				)
			)
		)
		(property "Device Type" "TSOIC24H48"
			(at 0 -8.5852 0)
			(unlocked yes)
			(layer "F.Fab")
			(hide yes)
			(effects
				(font
					(size 1.016 1.016)
					(thickness 0.1524)
				)
			)
		)
		(duplicate_pad_numbers_are_jumpers no)
		(fp_line
			(start -4.2291 -1.397)
			(end 3.81 -1.397)
			(stroke
				(width 0.1524)
				(type default)
			)
			(layer "F.SilkS")
		)
		(fp_line
			(start -4.2291 -0.8001)
			(end -3.429 0)
			(stroke
				(width 0.1524)
				(type default)
			)
			(layer "F.SilkS")
		)
		(fp_line
			(start -4.2291 3.937)
			(end -4.2291 -1.397)
			(stroke
				(width 0.1524)
				(type default)
			)
			(layer "F.SilkS")
		)
		(fp_line
			(start -4.22656 3.81)
			(end -4.2291 1.397)
			(stroke
				(width 0.508)
				(type default)
			)
			(layer "F.SilkS")
		)
		(fp_line
			(start -3.429 0)
			(end -4.2291 0.8001)
			(stroke
				(width 0.1524)
				(type default)
			)
			(layer "F.SilkS")
		)
		(fp_line
			(start 3.81 -1.397)
			(end 3.81 1.397)
			(stroke
				(width 0.1524)
				(type default)
			)
			(layer "F.SilkS")
		)
		(fp_line
			(start 3.81 1.397)
			(end -4.2291 1.397)
			(stroke
				(width 0.1524)
				(type default)
			)
			(layer "F.SilkS")
		)
		(fp_poly
			(pts
				(xy -3.90652 -1.8542) (xy 3.90652 -1.8542) (xy 3.90652 1.8542) (xy -3.90652 1.8542)
			)
			(stroke
				(width 0)
				(type default)
			)
			(fill yes)
			(layer "F.SilkS")
		)
		(fp_poly
			(pts
				(xy -4.2164 3.81) (xy 4.2164 3.81) (xy 4.22656 -3.81) (xy -4.2164 -3.81)
			)
			(stroke
				(width 0)
				(type default)
			)
			(fill no)
			(layer "F.CrtYd")
		)
		(fp_poly
			(pts
				(xy -4.22656 -3.81) (xy 4.22656 -3.81) (xy 4.22656 3.81) (xy -4.22656 3.81)
			)
			(stroke
				(width 0)
				(type default)
			)
			(fill no)
			(layer "F.Fab")
		)
		(pad "1" smd rect
			(at -3.57632 2.8194)
			(size 0.3556 1.524)
			(layers "F.Cu" "F.Mask" "F.Paste")
			(net "BMC_A_MISC_ALERT_N")
		)
		(pad "2" smd rect
			(at -2.92608 2.8194)
			(size 0.3556 1.524)
			(layers "F.Cu" "F.Mask" "F.Paste")
			(net "IO_EXP10_A1")
		)
		(pad "3" smd rect
			(at -2.27584 2.8194)
			(size 0.3556 1.524)
			(layers "F.Cu" "F.Mask" "F.Paste")
			(net "IO_EXP10_A2")
		)
		(pad "4" smd rect
			(at -1.6256 2.8194)
			(size 0.3556 1.524)
			(layers "F.Cu" "F.Mask" "F.Paste")
			(net "COMP_A_INS_N")
		)
		(pad "5" smd rect
			(at -0.97536 2.8194)
			(size 0.3556 1.524)
			(layers "F.Cu" "F.Mask" "F.Paste")
			(net "FAN_0_INS_N")
		)
		(pad "6" smd rect
			(at -0.32512 2.8194)
			(size 0.3556 1.524)
			(layers "F.Cu" "F.Mask" "F.Paste")
			(net "FAN_1_INS_N")
		)
		(pad "7" smd rect
			(at 0.32512 2.8194)
			(size 0.3556 1.524)
			(layers "F.Cu" "F.Mask" "F.Paste")
			(net "FAN_2_INS_N")
		)
		(pad "8" smd rect
			(at 0.97536 2.8194)
			(size 0.3556 1.524)
			(layers "F.Cu" "F.Mask" "F.Paste")
			(net "FAN_3_INS_N")
		)
		(pad "9" smd rect
			(at 1.6256 2.8194)
			(size 0.3556 1.524)
			(layers "F.Cu" "F.Mask" "F.Paste")
			(net "IOM_B_INS_N")
		)
		(pad "10" smd rect
			(at 2.27584 2.8194)
			(size 0.3556 1.524)
			(layers "F.Cu" "F.Mask" "F.Paste")
			(net "SCC_A_INS_N")
		)
		(pad "11" smd rect
			(at 2.92608 2.8194)
			(size 0.3556 1.524)
			(layers "F.Cu" "F.Mask" "F.Paste")
			(net "SCC_B_INS_N")
		)
		(pad "12" smd rect
			(at 3.57632 2.8194)
			(size 0.3556 1.524)
			(layers "F.Cu" "F.Mask" "F.Paste")
			(net "GND")
		)
		(pad "13" smd rect
			(at 3.57632 -2.8194)
			(size 0.3556 1.524)
			(layers "F.Cu" "F.Mask" "F.Paste")
			(net "SCC_A_TYPE_0")
		)
		(pad "14" smd rect
			(at 2.92608 -2.8194)
			(size 0.3556 1.524)
			(layers "F.Cu" "F.Mask" "F.Paste")
			(net "SCC_A_TYPE_1")
		)
		(pad "15" smd rect
			(at 2.27584 -2.8194)
			(size 0.3556 1.524)
			(layers "F.Cu" "F.Mask" "F.Paste")
			(net "SCC_A_TYPE_2")
		)
		(pad "16" smd rect
			(at 1.6256 -2.8194)
			(size 0.3556 1.524)
			(layers "F.Cu" "F.Mask" "F.Paste")
			(net "SCC_A_TYPE_3")
		)
		(pad "17" smd rect
			(at 0.97536 -2.8194)
			(size 0.3556 1.524)
			(layers "F.Cu" "F.Mask" "F.Paste")
			(net "SCC_A_STBY_PGOOD")
		)
		(pad "18" smd rect
			(at 0.32512 -2.8194)
			(size 0.3556 1.524)
			(layers "F.Cu" "F.Mask" "F.Paste")
			(net "SCC_A_FULL_PGOOD")
		)
		(pad "19" smd rect
			(at -0.32512 -2.8194)
			(size 0.3556 1.524)
			(layers "F.Cu" "F.Mask" "F.Paste")
			(net "COMP_A_PGOOD")
		)
		(pad "20" smd rect
			(at -0.97536 -2.8194)
			(size 0.3556 1.524)
			(layers "F.Cu" "F.Mask" "F.Paste")
			(net "DRAWER_CLOSED_N")
		)
		(pad "21" smd rect
			(at -1.6256 -2.8194)
			(size 0.3556 1.524)
			(layers "F.Cu" "F.Mask" "F.Paste")
			(net "IO_EXP10_A0")
		)
		(pad "22" smd rect
			(at -2.27584 -2.8194)
			(size 0.3556 1.524)
			(layers "F.Cu" "F.Mask" "F.Paste")
			(net "IO_EXP10_SCL")
		)
		(pad "23" smd rect
			(at -2.92608 -2.8194)
			(size 0.3556 1.524)
			(layers "F.Cu" "F.Mask" "F.Paste")
			(net "IO_EXP10_SDA")
		)
		(pad "24" smd rect
			(at -3.57632 -2.8194)
			(size 0.3556 1.524)
			(layers "F.Cu" "F.Mask" "F.Paste")
			(net "P3V3_STBY_A")
		)
	)
	(footprint ""
		(layer "F.Cu")
		(at 133.252718 -301.413164 90)
		(property "Reference" "R570"
			(at 0 0 90)
			(layer "F.SilkS")
			(hide yes)
			(effects
				(font
					(size 1.27 1.27)
				)
			)
		)
		(property "Value" "4K7R2J-2-GP"
			(at 0.064008 -3.993896 90)
			(unlocked yes)
			(layer "F.Fab")
			(hide yes)
			(effects
				(font
					(size 1.016 1.016)
					(thickness 0.1524)
				)
			)
		)
		(property "Device Type" "R402H16"
			(at 0.064008 -5.517896 90)
			(unlocked yes)
			(layer "F.Fab")
			(hide yes)
			(effects
				(font
					(size 1.016 1.016)
					(thickness 0.1524)
				)
			)
		)
		(duplicate_pad_numbers_are_jumpers no)
		(fp_line
			(start 0.508 -0.9398)
			(end -0.508 -0.9398)
			(stroke
				(width 0.1524)
				(type default)
			)
			(layer "F.SilkS")
		)
		(fp_line
			(start -0.508 -0.9398)
			(end -0.508 0.9398)
			(stroke
				(width 0.1524)
				(type default)
			)
			(layer "F.SilkS")
		)
		(fp_rect
			(start -0.508 0.9398)
			(end 0.508 -0.9398)
			(stroke
				(width 0)
				(type default)
			)
			(fill no)
			(layer "F.CrtYd")
		)
		(fp_rect
			(start -0.508 0.9398)
			(end 0.508 -0.9398)
			(stroke
				(width 0)
				(type default)
			)
			(fill no)
			(layer "F.Fab")
		)
		(pad "1" smd custom
			(at 0 -0.4445 90)
			(size 0.1397 0.1397)
			(layers "F.Cu" "F.Mask" "F.Paste")
			(net "DRIVE_B_28_FLT_LED")
			(options
				(clearance outline)
				(anchor circle)
			)
			(primitives
				(gr_poly
					(pts
						(arc
							(start -0.1778 -0.2794)
							(mid -0.249642 -0.249642)
							(end -0.2794 -0.1778)
						)
						(arc
							(start -0.2794 0.1778)
							(mid -0.249642 0.249642)
							(end -0.1778 0.2794)
						)
						(arc
							(start 0.1778 0.2794)
							(mid 0.249642 0.249642)
							(end 0.2794 0.1778)
						)
						(arc
							(start 0.2794 -0.1778)
							(mid 0.249642 -0.249642)
							(end 0.1778 -0.2794)
						)
					)
					(width 0)
					(fill yes)
				)
			)
		)
		(pad "2" smd custom
			(at 0 0.4445 90)
			(size 0.1397 0.1397)
			(layers "F.Cu" "F.Mask" "F.Paste")
			(net "GND")
			(options
				(clearance outline)
				(anchor circle)
			)
			(primitives
				(gr_poly
					(pts
						(arc
							(start -0.1778 -0.2794)
							(mid -0.249642 -0.249642)
							(end -0.2794 -0.1778)
						)
						(arc
							(start -0.2794 0.1778)
							(mid -0.249642 0.249642)
							(end -0.1778 0.2794)
						)
						(arc
							(start 0.1778 0.2794)
							(mid 0.249642 0.249642)
							(end 0.2794 0.1778)
						)
						(arc
							(start 0.2794 -0.1778)
							(mid 0.249642 -0.249642)
							(end 0.1778 -0.2794)
						)
					)
					(width 0)
					(fill yes)
				)
			)
		)
	)
	(footprint ""
		(layer "F.Cu")
		(at 426.120052 -61.127894 -90)
		(property "Reference" "R888"
			(at 0 0 270)
			(layer "F.SilkS")
			(hide yes)
			(effects
				(font
					(size 1.27 1.27)
				)
			)
		)
		(property "Value" "2R6F-GP"
			(at -0.0508 -4.8514 270)
			(unlocked yes)
			(layer "F.Fab")
			(hide yes)
			(effects
				(font
					(size 1.016 1.016)
					(thickness 0.1524)
				)
			)
		)
		(property "Device Type" "R1206H26"
			(at 0 -6.3754 270)
			(unlocked yes)
			(layer "F.Fab")
			(hide yes)
			(effects
				(font
					(size 1.016 1.016)
					(thickness 0.1524)
				)
			)
		)
		(duplicate_pad_numbers_are_jumpers no)
		(fp_line
			(start -1.016 2.2352)
			(end -1.016 -2.2352)
			(stroke
				(width 0.1524)
				(type default)
			)
			(layer "F.SilkS")
		)
		(fp_line
			(start 1.016 2.2352)
			(end -1.016 2.2352)
			(stroke
				(width 0.1524)
				(type default)
			)
			(layer "F.SilkS")
		)
		(fp_line
			(start -1.016 -2.2352)
			(end 1.016 -2.2352)
			(stroke
				(width 0.1524)
				(type default)
			)
			(layer "F.SilkS")
		)
		(fp_line
			(start 1.016 -2.2352)
			(end 1.016 2.2352)
			(stroke
				(width 0.1524)
				(type default)
			)
			(layer "F.SilkS")
		)
		(fp_rect
			(start -1.0922 2.3114)
			(end 1.0922 -2.3114)
			(stroke
				(width 0)
				(type default)
			)
			(fill no)
			(layer "F.CrtYd")
		)
		(fp_poly
			(pts
				(xy -1.0922 -2.3114) (xy 1.0922 -2.3114) (xy 1.0922 2.3114) (xy -1.0922 2.3114)
			)
			(stroke
				(width 0)
				(type default)
			)
			(fill no)
			(layer "F.Fab")
		)
		(pad "1" smd rect
			(at 0 -1.397 270)
			(size 1.651 1.27)
			(layers "F.Cu" "F.Mask" "F.Paste")
			(net "P5V_HDD33")
		)
		(pad "2" smd rect
			(at 0 1.397 270)
			(size 1.651 1.27)
			(layers "F.Cu" "F.Mask" "F.Paste")
			(net "5V_PRE_33")
		)
	)
	(footprint ""
		(layer "F.Cu")
		(at 174.0662 -284.473142 -90)
		(property "Reference" "R260"
			(at 0 0 270)
			(layer "F.SilkS")
			(hide yes)
			(effects
				(font
					(size 1.27 1.27)
				)
			)
		)
		(property "Value" "300KR2F-GP"
			(at 0.064008 -3.993896 270)
			(unlocked yes)
			(layer "F.Fab")
			(hide yes)
			(effects
				(font
					(size 1.016 1.016)
					(thickness 0.1524)
				)
			)
		)
		(property "Device Type" "R402H16"
			(at 0.064008 -5.517896 270)
			(unlocked yes)
			(layer "F.Fab")
			(hide yes)
			(effects
				(font
					(size 1.016 1.016)
					(thickness 0.1524)
				)
			)
		)
		(duplicate_pad_numbers_are_jumpers no)
		(fp_line
			(start -0.508 -0.9398)
			(end -0.508 0.9398)
			(stroke
				(width 0.1524)
				(type default)
			)
			(layer "F.SilkS")
		)
		(fp_line
			(start 0.508 -0.9398)
			(end -0.508 -0.9398)
			(stroke
				(width 0.1524)
				(type default)
			)
			(layer "F.SilkS")
		)
		(fp_rect
			(start -0.508 0.9398)
			(end 0.508 -0.9398)
			(stroke
				(width 0)
				(type default)
			)
			(fill no)
			(layer "F.CrtYd")
		)
		(fp_rect
			(start -0.508 0.9398)
			(end 0.508 -0.9398)
			(stroke
				(width 0)
				(type default)
			)
			(fill no)
			(layer "F.Fab")
		)
		(pad "1" smd custom
			(at 0 -0.4445 270)
			(size 0.1397 0.1397)
			(layers "F.Cu" "F.Mask" "F.Paste")
			(net "SW_HDD_N5")
			(options
				(clearance outline)
				(anchor circle)
			)
			(primitives
				(gr_poly
					(pts
						(arc
							(start -0.1778 -0.2794)
							(mid -0.249642 -0.249642)
							(end -0.2794 -0.1778)
						)
						(arc
							(start -0.2794 0.1778)
							(mid -0.249642 0.249642)
							(end -0.1778 0.2794)
						)
						(arc
							(start 0.1778 0.2794)
							(mid 0.249642 0.249642)
							(end 0.2794 0.1778)
						)
						(arc
							(start 0.2794 -0.1778)
							(mid 0.249642 -0.249642)
							(end 0.1778 -0.2794)
						)
					)
					(width 0)
					(fill yes)
				)
			)
		)
		(pad "2" smd custom
			(at 0 0.4445 270)
			(size 0.1397 0.1397)
			(layers "F.Cu" "F.Mask" "F.Paste")
			(net "P12V_A")
			(options
				(clearance outline)
				(anchor circle)
			)
			(primitives
				(gr_poly
					(pts
						(arc
							(start -0.1778 -0.2794)
							(mid -0.249642 -0.249642)
							(end -0.2794 -0.1778)
						)
						(arc
							(start -0.2794 0.1778)
							(mid -0.249642 0.249642)
							(end -0.1778 0.2794)
						)
						(arc
							(start 0.1778 0.2794)
							(mid 0.249642 0.249642)
							(end 0.2794 0.1778)
						)
						(arc
							(start 0.2794 -0.1778)
							(mid 0.249642 -0.249642)
							(end 0.1778 -0.2794)
						)
					)
					(width 0)
					(fill yes)
				)
			)
		)
	)
	(footprint ""
		(layer "F.Cu")
		(at 235.676694 -244.146578 180)
		(property "Reference" "R68"
			(at 0 0 180)
			(layer "F.SilkS")
			(hide yes)
			(effects
				(font
					(size 1.27 1.27)
				)
			)
		)
		(property "Value" "4K7R2F-GP"
			(at 0.064008 -3.993896 180)
			(unlocked yes)
			(layer "F.Fab")
			(hide yes)
			(effects
				(font
					(size 1.016 1.016)
					(thickness 0.1524)
				)
			)
		)
		(property "Device Type" "R402H16"
			(at 0.064008 -5.517896 180)
			(unlocked yes)
			(layer "F.Fab")
			(hide yes)
			(effects
				(font
					(size 1.016 1.016)
					(thickness 0.1524)
				)
			)
		)
		(duplicate_pad_numbers_are_jumpers no)
		(fp_line
			(start 0.508 -0.9398)
			(end -0.508 -0.9398)
			(stroke
				(width 0.1524)
				(type default)
			)
			(layer "F.SilkS")
		)
		(fp_line
			(start -0.508 -0.9398)
			(end -0.508 0.9398)
			(stroke
				(width 0.1524)
				(type default)
			)
			(layer "F.SilkS")
		)
		(fp_rect
			(start -0.508 0.9398)
			(end 0.508 -0.9398)
			(stroke
				(width 0)
				(type default)
			)
			(fill no)
			(layer "F.CrtYd")
		)
		(fp_rect
			(start -0.508 0.9398)
			(end 0.508 -0.9398)
			(stroke
				(width 0)
				(type default)
			)
			(fill no)
			(layer "F.Fab")
		)
		(pad "1" smd custom
			(at 0 -0.4445 180)
			(size 0.1397 0.1397)
			(layers "F.Cu" "F.Mask" "F.Paste")
			(net "IO_EXP1_A1")
			(options
				(clearance outline)
				(anchor circle)
			)
			(primitives
				(gr_poly
					(pts
						(arc
							(start -0.1778 -0.2794)
							(mid -0.249642 -0.249642)
							(end -0.2794 -0.1778)
						)
						(arc
							(start -0.2794 0.1778)
							(mid -0.249642 0.249642)
							(end -0.1778 0.2794)
						)
						(arc
							(start 0.1778 0.2794)
							(mid 0.249642 0.249642)
							(end 0.2794 0.1778)
						)
						(arc
							(start 0.2794 -0.1778)
							(mid 0.249642 -0.249642)
							(end 0.1778 -0.2794)
						)
					)
					(width 0)
					(fill yes)
				)
			)
		)
		(pad "2" smd custom
			(at 0 0.4445 180)
			(size 0.1397 0.1397)
			(layers "F.Cu" "F.Mask" "F.Paste")
			(net "GND")
			(options
				(clearance outline)
				(anchor circle)
			)
			(primitives
				(gr_poly
					(pts
						(arc
							(start -0.1778 -0.2794)
							(mid -0.249642 -0.249642)
							(end -0.2794 -0.1778)
						)
						(arc
							(start -0.2794 0.1778)
							(mid -0.249642 0.249642)
							(end -0.1778 0.2794)
						)
						(arc
							(start 0.1778 0.2794)
							(mid 0.249642 0.249642)
							(end 0.2794 0.1778)
						)
						(arc
							(start 0.2794 -0.1778)
							(mid 0.249642 -0.249642)
							(end 0.1778 -0.2794)
						)
					)
					(width 0)
					(fill yes)
				)
			)
		)
	)
	(footprint ""
		(layer "F.Cu")
		(at 38.059614 -298.219368)
		(property "Reference" "Q288"
			(at 0 0 0)
			(layer "F.SilkS")
			(hide yes)
			(effects
				(font
					(size 1.27 1.27)
				)
			)
		)
		(property "Value" "SSM3K324R-GP"
			(at 0.127 -8.9662 0)
			(unlocked yes)
			(layer "F.Fab")
			(hide yes)
			(effects
				(font
					(size 1.016 1.016)
					(thickness 0.1524)
				)
			)
		)
		(property "Device Type" "SOT23DGS2D4H35"
			(at 0.127 -10.4902 0)
			(unlocked yes)
			(layer "F.Fab")
			(hide yes)
			(effects
				(font
					(size 1.016 1.016)
					(thickness 0.1524)
				)
			)
		)
		(duplicate_pad_numbers_are_jumpers no)
		(fp_line
			(start -1.651 -1.778)
			(end -1.651 1.778)
			(stroke
				(width 0.1524)
				(type default)
			)
			(layer "F.SilkS")
		)
		(fp_line
			(start -1.651 1.778)
			(end 1.651 1.778)
			(stroke
				(width 0.1524)
				(type default)
			)
			(layer "F.SilkS")
		)
		(fp_line
			(start 1.651 -1.778)
			(end -1.651 -1.778)
			(stroke
				(width 0.1524)
				(type default)
			)
			(layer "F.SilkS")
		)
		(fp_line
			(start 1.651 1.778)
			(end 1.651 -1.778)
			(stroke
				(width 0.1524)
				(type default)
			)
			(layer "F.SilkS")
		)
		(fp_poly
			(pts
				(xy -1.778 1.8796) (xy -1.778 -1.8796) (xy 1.778 -1.8796) (xy 1.778 1.8796)
			)
			(stroke
				(width 0)
				(type default)
			)
			(fill no)
			(layer "F.CrtYd")
		)
		(fp_poly
			(pts
				(xy -1.778 1.8796) (xy -1.778 -1.8796) (xy 1.778 -1.8796) (xy 1.778 1.8796)
			)
			(stroke
				(width 0)
				(type default)
			)
			(fill no)
			(layer "F.Fab")
		)
		(pad "D" smd custom
			(at 0 -0.9525)
			(size 0.1905 0.1905)
			(layers "F.Cu" "F.Mask" "F.Paste")
			(net "DRV_ACT_25_N")
			(options
				(clearance outline)
				(anchor circle)
			)
			(primitives
				(gr_poly
					(pts
						(arc
							(start -0.1778 0.5715)
							(mid -0.321484 0.511984)
							(end -0.381 0.3683)
						)
						(arc
							(start -0.381 -0.3683)
							(mid -0.321484 -0.511984)
							(end -0.1778 -0.5715)
						)
						(arc
							(start 0.1778 -0.5715)
							(mid 0.321484 -0.511984)
							(end 0.381 -0.3683)
						)
						(arc
							(start 0.381 0.3683)
							(mid 0.321484 0.511984)
							(end 0.1778 0.5715)
						)
					)
					(width 0)
					(fill yes)
				)
			)
		)
		(pad "G" smd custom
			(at -0.98425 0.9525)
			(size 0.1905 0.1905)
			(layers "F.Cu" "F.Mask" "F.Paste")
			(net "DRIVE_B_25_ACT")
			(options
				(clearance outline)
				(anchor circle)
			)
			(primitives
				(gr_poly
					(pts
						(arc
							(start -0.1778 0.5715)
							(mid -0.321484 0.511984)
							(end -0.381 0.3683)
						)
						(arc
							(start -0.381 -0.3683)
							(mid -0.321484 -0.511984)
							(end -0.1778 -0.5715)
						)
						(arc
							(start 0.1778 -0.5715)
							(mid 0.321484 -0.511984)
							(end 0.381 -0.3683)
						)
						(arc
							(start 0.381 0.3683)
							(mid 0.321484 0.511984)
							(end 0.1778 0.5715)
						)
					)
					(width 0)
					(fill yes)
				)
			)
		)
		(pad "S" smd custom
			(at 0.98425 0.9525)
			(size 0.1905 0.1905)
			(layers "F.Cu" "F.Mask" "F.Paste")
			(net "GND")
			(options
				(clearance outline)
				(anchor circle)
			)
			(primitives
				(gr_poly
					(pts
						(arc
							(start -0.1778 0.5715)
							(mid -0.321484 0.511984)
							(end -0.381 0.3683)
						)
						(arc
							(start -0.381 -0.3683)
							(mid -0.321484 -0.511984)
							(end -0.1778 -0.5715)
						)
						(arc
							(start 0.1778 -0.5715)
							(mid 0.321484 -0.511984)
							(end 0.381 -0.3683)
						)
						(arc
							(start 0.381 0.3683)
							(mid 0.321484 0.511984)
							(end 0.1778 0.5715)
						)
					)
					(width 0)
					(fill yes)
				)
			)
		)
	)
	(footprint ""
		(layer "F.Cu")
		(at 267.174726 -134.995666 -90)
		(property "Reference" "TP201"
			(at 0 0 270)
			(layer "F.SilkS")
			(hide yes)
			(effects
				(font
					(size 1.27 1.27)
				)
			)
		)
		(property "Value" "TPAD32-GP"
			(at -0.0508 -1.6764 270)
			(unlocked yes)
			(layer "F.Fab")
			(hide yes)
			(effects
				(font
					(size 1.016 1.016)
					(thickness 0.1524)
				)
			)
		)
		(property "Device Type" "TPAD32"
			(at -0.0508 -3.2004 270)
			(unlocked yes)
			(layer "F.Fab")
			(hide yes)
			(effects
				(font
					(size 1.016 1.016)
					(thickness 0.1524)
				)
			)
		)
		(duplicate_pad_numbers_are_jumpers no)
		(fp_poly
			(pts
				(arc
					(start 0 -0.4064)
					(mid 0 0.4064)
					(end 0 -0.4064)
				)
			)
			(stroke
				(width 0)
				(type default)
			)
			(fill no)
			(layer "F.CrtYd")
		)
		(fp_poly
			(pts
				(arc
					(start 0 -0.7112)
					(mid 0 0.7112)
					(end 0 -0.7112)
				)
			)
			(stroke
				(width 0)
				(type default)
			)
			(fill no)
			(layer "F.Fab")
		)
		(pad "1" smd circle
			(at 0 0 270)
			(size 0.8128 0.8128)
			(layers "F.Cu" "F.Mask" "F.Paste")
			(net "TP_PCIE_COMP_B_CLK_1_DN")
		)
	)
	(footprint ""
		(layer "F.Cu")
		(at 14.842998 -53.482494 -90)
		(property "Reference" "R697"
			(at 0 0 270)
			(layer "F.SilkS")
			(hide yes)
			(effects
				(font
					(size 1.27 1.27)
				)
			)
		)
		(property "Value" "300KR2F-GP"
			(at 0.064008 -3.993896 270)
			(unlocked yes)
			(layer "F.Fab")
			(hide yes)
			(effects
				(font
					(size 1.016 1.016)
					(thickness 0.1524)
				)
			)
		)
		(property "Device Type" "R402H16"
			(at 0.064008 -5.517896 270)
			(unlocked yes)
			(layer "F.Fab")
			(hide yes)
			(effects
				(font
					(size 1.016 1.016)
					(thickness 0.1524)
				)
			)
		)
		(duplicate_pad_numbers_are_jumpers no)
		(fp_line
			(start -0.508 -0.9398)
			(end -0.508 0.9398)
			(stroke
				(width 0.1524)
				(type default)
			)
			(layer "F.SilkS")
		)
		(fp_line
			(start 0.508 -0.9398)
			(end -0.508 -0.9398)
			(stroke
				(width 0.1524)
				(type default)
			)
			(layer "F.SilkS")
		)
		(fp_rect
			(start -0.508 0.9398)
			(end 0.508 -0.9398)
			(stroke
				(width 0)
				(type default)
			)
			(fill no)
			(layer "F.CrtYd")
		)
		(fp_rect
			(start -0.508 0.9398)
			(end 0.508 -0.9398)
			(stroke
				(width 0)
				(type default)
			)
			(fill no)
			(layer "F.Fab")
		)
		(pad "1" smd custom
			(at 0 -0.4445 270)
			(size 0.1397 0.1397)
			(layers "F.Cu" "F.Mask" "F.Paste")
			(net "SW_HDD_N24")
			(options
				(clearance outline)
				(anchor circle)
			)
			(primitives
				(gr_poly
					(pts
						(arc
							(start -0.1778 -0.2794)
							(mid -0.249642 -0.249642)
							(end -0.2794 -0.1778)
						)
						(arc
							(start -0.2794 0.1778)
							(mid -0.249642 0.249642)
							(end -0.1778 0.2794)
						)
						(arc
							(start 0.1778 0.2794)
							(mid 0.249642 0.249642)
							(end 0.2794 0.1778)
						)
						(arc
							(start 0.2794 -0.1778)
							(mid 0.249642 -0.249642)
							(end 0.1778 -0.2794)
						)
					)
					(width 0)
					(fill yes)
				)
			)
		)
		(pad "2" smd custom
			(at 0 0.4445 270)
			(size 0.1397 0.1397)
			(layers "F.Cu" "F.Mask" "F.Paste")
			(net "P12V_A")
			(options
				(clearance outline)
				(anchor circle)
			)
			(primitives
				(gr_poly
					(pts
						(arc
							(start -0.1778 -0.2794)
							(mid -0.249642 -0.249642)
							(end -0.2794 -0.1778)
						)
						(arc
							(start -0.2794 0.1778)
							(mid -0.249642 0.249642)
							(end -0.1778 0.2794)
						)
						(arc
							(start 0.1778 0.2794)
							(mid 0.249642 0.249642)
							(end 0.2794 0.1778)
						)
						(arc
							(start 0.2794 -0.1778)
							(mid 0.249642 -0.249642)
							(end 0.1778 -0.2794)
						)
					)
					(width 0)
					(fill yes)
				)
			)
		)
	)
	(footprint ""
		(layer "F.Cu")
		(at 105.740962 -127.78867 180)
		(property "Reference" "Q278"
			(at 0 0 180)
			(layer "F.SilkS")
			(hide yes)
			(effects
				(font
					(size 1.27 1.27)
				)
			)
		)
		(property "Value" "SSM3K324R-GP"
			(at 0.127 -8.9662 180)
			(unlocked yes)
			(layer "F.Fab")
			(hide yes)
			(effects
				(font
					(size 1.016 1.016)
					(thickness 0.1524)
				)
			)
		)
		(property "Device Type" "SOT23DGS2D4H35"
			(at 0.127 -10.4902 180)
			(unlocked yes)
			(layer "F.Fab")
			(hide yes)
			(effects
				(font
					(size 1.016 1.016)
					(thickness 0.1524)
				)
			)
		)
		(duplicate_pad_numbers_are_jumpers no)
		(fp_line
			(start 1.651 1.778)
			(end 1.651 -1.778)
			(stroke
				(width 0.1524)
				(type default)
			)
			(layer "F.SilkS")
		)
		(fp_line
			(start 1.651 -1.778)
			(end -1.651 -1.778)
			(stroke
				(width 0.1524)
				(type default)
			)
			(layer "F.SilkS")
		)
		(fp_line
			(start -1.651 1.778)
			(end 1.651 1.778)
			(stroke
				(width 0.1524)
				(type default)
			)
			(layer "F.SilkS")
		)
		(fp_line
			(start -1.651 -1.778)
			(end -1.651 1.778)
			(stroke
				(width 0.1524)
				(type default)
			)
			(layer "F.SilkS")
		)
		(fp_poly
			(pts
				(xy -1.778 1.8796) (xy -1.778 -1.8796) (xy 1.778 -1.8796) (xy 1.778 1.8796)
			)
			(stroke
				(width 0)
				(type default)
			)
			(fill no)
			(layer "F.CrtYd")
		)
		(fp_poly
			(pts
				(xy -1.778 1.8796) (xy -1.778 -1.8796) (xy 1.778 -1.8796) (xy 1.778 1.8796)
			)
			(stroke
				(width 0)
				(type default)
			)
			(fill no)
			(layer "F.Fab")
		)
		(pad "D" smd custom
			(at 0 -0.9525 180)
			(size 0.1905 0.1905)
			(layers "F.Cu" "F.Mask" "F.Paste")
			(net "DRV_ACT_15_N")
			(options
				(clearance outline)
				(anchor circle)
			)
			(primitives
				(gr_poly
					(pts
						(arc
							(start -0.1778 0.5715)
							(mid -0.321484 0.511984)
							(end -0.381 0.3683)
						)
						(arc
							(start -0.381 -0.3683)
							(mid -0.321484 -0.511984)
							(end -0.1778 -0.5715)
						)
						(arc
							(start 0.1778 -0.5715)
							(mid 0.321484 -0.511984)
							(end 0.381 -0.3683)
						)
						(arc
							(start 0.381 0.3683)
							(mid 0.321484 0.511984)
							(end 0.1778 0.5715)
						)
					)
					(width 0)
					(fill yes)
				)
			)
		)
		(pad "G" smd custom
			(at -0.98425 0.9525 180)
			(size 0.1905 0.1905)
			(layers "F.Cu" "F.Mask" "F.Paste")
			(net "DRIVE_A_15_ACT")
			(options
				(clearance outline)
				(anchor circle)
			)
			(primitives
				(gr_poly
					(pts
						(arc
							(start -0.1778 0.5715)
							(mid -0.321484 0.511984)
							(end -0.381 0.3683)
						)
						(arc
							(start -0.381 -0.3683)
							(mid -0.321484 -0.511984)
							(end -0.1778 -0.5715)
						)
						(arc
							(start 0.1778 -0.5715)
							(mid 0.321484 -0.511984)
							(end 0.381 -0.3683)
						)
						(arc
							(start 0.381 0.3683)
							(mid 0.321484 0.511984)
							(end 0.1778 0.5715)
						)
					)
					(width 0)
					(fill yes)
				)
			)
		)
		(pad "S" smd custom
			(at 0.98425 0.9525 180)
			(size 0.1905 0.1905)
			(layers "F.Cu" "F.Mask" "F.Paste")
			(net "GND")
			(options
				(clearance outline)
				(anchor circle)
			)
			(primitives
				(gr_poly
					(pts
						(arc
							(start -0.1778 0.5715)
							(mid -0.321484 0.511984)
							(end -0.381 0.3683)
						)
						(arc
							(start -0.381 -0.3683)
							(mid -0.321484 -0.511984)
							(end -0.1778 -0.5715)
						)
						(arc
							(start 0.1778 -0.5715)
							(mid 0.321484 -0.511984)
							(end 0.381 -0.3683)
						)
						(arc
							(start 0.381 0.3683)
							(mid 0.321484 0.511984)
							(end 0.1778 0.5715)
						)
					)
					(width 0)
					(fill yes)
				)
			)
		)
	)
	(footprint ""
		(layer "F.Cu")
		(at 468.329518 -46.01845 -90)
		(property "Reference" "R952"
			(at 0 0 270)
			(layer "F.SilkS")
			(hide yes)
			(effects
				(font
					(size 1.27 1.27)
				)
			)
		)
		(property "Value" "0R2J-2-GP"
			(at 0.064008 -3.993896 270)
			(unlocked yes)
			(layer "F.Fab")
			(hide yes)
			(effects
				(font
					(size 1.016 1.016)
					(thickness 0.1524)
				)
			)
		)
		(property "Device Type" "R402H16"
			(at 0.064008 -5.517896 270)
			(unlocked yes)
			(layer "F.Fab")
			(hide yes)
			(effects
				(font
					(size 1.016 1.016)
					(thickness 0.1524)
				)
			)
		)
		(duplicate_pad_numbers_are_jumpers no)
		(fp_line
			(start -0.508 -0.9398)
			(end -0.508 0.9398)
			(stroke
				(width 0.1524)
				(type default)
			)
			(layer "F.SilkS")
		)
		(fp_line
			(start 0.508 -0.9398)
			(end -0.508 -0.9398)
			(stroke
				(width 0.1524)
				(type default)
			)
			(layer "F.SilkS")
		)
		(fp_rect
			(start -0.508 0.9398)
			(end 0.508 -0.9398)
			(stroke
				(width 0)
				(type default)
			)
			(fill no)
			(layer "F.CrtYd")
		)
		(fp_rect
			(start -0.508 0.9398)
			(end 0.508 -0.9398)
			(stroke
				(width 0)
				(type default)
			)
			(fill no)
			(layer "F.Fab")
		)
		(pad "1" smd custom
			(at 0 -0.4445 270)
			(size 0.1397 0.1397)
			(layers "F.Cu" "F.Mask" "F.Paste")
			(net "SW_HDD_G35")
			(options
				(clearance outline)
				(anchor circle)
			)
			(primitives
				(gr_poly
					(pts
						(arc
							(start -0.1778 -0.2794)
							(mid -0.249642 -0.249642)
							(end -0.2794 -0.1778)
						)
						(arc
							(start -0.2794 0.1778)
							(mid -0.249642 0.249642)
							(end -0.1778 0.2794)
						)
						(arc
							(start 0.1778 0.2794)
							(mid 0.249642 0.249642)
							(end 0.2794 0.1778)
						)
						(arc
							(start 0.2794 -0.1778)
							(mid 0.249642 -0.249642)
							(end 0.1778 -0.2794)
						)
					)
					(width 0)
					(fill yes)
				)
			)
		)
		(pad "2" smd custom
			(at 0 0.4445 270)
			(size 0.1397 0.1397)
			(layers "F.Cu" "F.Mask" "F.Paste")
			(net "SW_HDD_R35")
			(options
				(clearance outline)
				(anchor circle)
			)
			(primitives
				(gr_poly
					(pts
						(arc
							(start -0.1778 -0.2794)
							(mid -0.249642 -0.249642)
							(end -0.2794 -0.1778)
						)
						(arc
							(start -0.2794 0.1778)
							(mid -0.249642 0.249642)
							(end -0.1778 0.2794)
						)
						(arc
							(start 0.1778 0.2794)
							(mid 0.249642 0.249642)
							(end 0.2794 0.1778)
						)
						(arc
							(start 0.2794 -0.1778)
							(mid 0.249642 -0.249642)
							(end 0.1778 -0.2794)
						)
					)
					(width 0)
					(fill yes)
				)
			)
		)
	)
	(footprint ""
		(layer "F.Cu")
		(at 51.980846 -292.778942 -90)
		(property "Reference" "C53"
			(at 0 0 270)
			(layer "F.SilkS")
			(hide yes)
			(effects
				(font
					(size 1.27 1.27)
				)
			)
		)
		(property "Value" "SC1U16V3KX-5GP"
			(at 0 -2.8194 270)
			(unlocked yes)
			(layer "F.Fab")
			(hide yes)
			(effects
				(font
					(size 1.016 1.016)
					(thickness 0.1524)
				)
			)
		)
		(property "Device Type" "C603H36"
			(at 0 -4.3434 270)
			(unlocked yes)
			(layer "F.Fab")
			(hide yes)
			(effects
				(font
					(size 1.016 1.016)
					(thickness 0.1524)
				)
			)
		)
		(duplicate_pad_numbers_are_jumpers no)
		(fp_line
			(start 0.508 0)
			(end -0.508 0)
			(stroke
				(width 0.2032)
				(type default)
			)
			(layer "F.SilkS")
		)
		(fp_rect
			(start -0.5842 1.3335)
			(end 0.5842 -1.3335)
			(stroke
				(width 0)
				(type default)
			)
			(fill no)
			(layer "F.CrtYd")
		)
		(fp_rect
			(start -0.5842 1.3335)
			(end 0.5842 -1.3335)
			(stroke
				(width 0)
				(type default)
			)
			(fill no)
			(layer "F.Fab")
		)
		(pad "1" smd custom
			(at 0 -0.762 270)
			(size 0.2159 0.2159)
			(layers "F.Cu" "F.Mask" "F.Paste")
			(net "P5V_HDD1")
			(options
				(clearance outline)
				(anchor circle)
			)
			(primitives
				(gr_poly
					(pts
						(arc
							(start -0.3302 -0.4318)
							(mid -0.402042 -0.402042)
							(end -0.4318 -0.3302)
						)
						(arc
							(start -0.4318 0.3302)
							(mid -0.402042 0.402042)
							(end -0.3302 0.4318)
						)
						(arc
							(start 0.3302 0.4318)
							(mid 0.402042 0.402042)
							(end 0.4318 0.3302)
						)
						(arc
							(start 0.4318 -0.3302)
							(mid 0.402042 -0.402042)
							(end 0.3302 -0.4318)
						)
					)
					(width 0)
					(fill yes)
				)
			)
		)
		(pad "2" smd custom
			(at 0 0.762 270)
			(size 0.2159 0.2159)
			(layers "F.Cu" "F.Mask" "F.Paste")
			(net "GND")
			(options
				(clearance outline)
				(anchor circle)
			)
			(primitives
				(gr_poly
					(pts
						(arc
							(start -0.3302 -0.4318)
							(mid -0.402042 -0.402042)
							(end -0.4318 -0.3302)
						)
						(arc
							(start -0.4318 0.3302)
							(mid -0.402042 0.402042)
							(end -0.3302 0.4318)
						)
						(arc
							(start 0.3302 0.4318)
							(mid 0.402042 0.402042)
							(end 0.4318 0.3302)
						)
						(arc
							(start 0.4318 -0.3302)
							(mid 0.402042 -0.402042)
							(end 0.3302 -0.4318)
						)
					)
					(width 0)
					(fill yes)
				)
			)
		)
	)
	(footprint ""
		(layer "F.Cu")
		(at 46.342046 -45.633894 90)
		(property "Reference" "R719"
			(at 0 0 90)
			(layer "F.SilkS")
			(hide yes)
			(effects
				(font
					(size 1.27 1.27)
				)
			)
		)
		(property "Value" "4K7R2J-2-GP"
			(at 0.064008 -3.993896 90)
			(unlocked yes)
			(layer "F.Fab")
			(hide yes)
			(effects
				(font
					(size 1.016 1.016)
					(thickness 0.1524)
				)
			)
		)
		(property "Device Type" "R402H16"
			(at 0.064008 -5.517896 90)
			(unlocked yes)
			(layer "F.Fab")
			(hide yes)
			(effects
				(font
					(size 1.016 1.016)
					(thickness 0.1524)
				)
			)
		)
		(duplicate_pad_numbers_are_jumpers no)
		(fp_line
			(start 0.508 -0.9398)
			(end -0.508 -0.9398)
			(stroke
				(width 0.1524)
				(type default)
			)
			(layer "F.SilkS")
		)
		(fp_line
			(start -0.508 -0.9398)
			(end -0.508 0.9398)
			(stroke
				(width 0.1524)
				(type default)
			)
			(layer "F.SilkS")
		)
		(fp_rect
			(start -0.508 0.9398)
			(end 0.508 -0.9398)
			(stroke
				(width 0)
				(type default)
			)
			(fill no)
			(layer "F.CrtYd")
		)
		(fp_rect
			(start -0.508 0.9398)
			(end 0.508 -0.9398)
			(stroke
				(width 0)
				(type default)
			)
			(fill no)
			(layer "F.Fab")
		)
		(pad "1" smd custom
			(at 0 -0.4445 90)
			(size 0.1397 0.1397)
			(layers "F.Cu" "F.Mask" "F.Paste")
			(net "P12V_A")
			(options
				(clearance outline)
				(anchor circle)
			)
			(primitives
				(gr_poly
					(pts
						(arc
							(start -0.1778 -0.2794)
							(mid -0.249642 -0.249642)
							(end -0.2794 -0.1778)
						)
						(arc
							(start -0.2794 0.1778)
							(mid -0.249642 0.249642)
							(end -0.1778 0.2794)
						)
						(arc
							(start 0.1778 0.2794)
							(mid 0.249642 0.249642)
							(end 0.2794 0.1778)
						)
						(arc
							(start 0.2794 -0.1778)
							(mid 0.249642 -0.249642)
							(end 0.1778 -0.2794)
						)
					)
					(width 0)
					(fill yes)
				)
			)
		)
		(pad "2" smd custom
			(at 0 0.4445 90)
			(size 0.1397 0.1397)
			(layers "F.Cu" "F.Mask" "F.Paste")
			(net "SW_HDD_R25")
			(options
				(clearance outline)
				(anchor circle)
			)
			(primitives
				(gr_poly
					(pts
						(arc
							(start -0.1778 -0.2794)
							(mid -0.249642 -0.249642)
							(end -0.2794 -0.1778)
						)
						(arc
							(start -0.2794 0.1778)
							(mid -0.249642 0.249642)
							(end -0.1778 0.2794)
						)
						(arc
							(start 0.1778 0.2794)
							(mid 0.249642 0.249642)
							(end 0.2794 0.1778)
						)
						(arc
							(start 0.2794 -0.1778)
							(mid 0.249642 -0.249642)
							(end 0.1778 -0.2794)
						)
					)
					(width 0)
					(fill yes)
				)
			)
		)
	)
	(footprint ""
		(layer "F.Cu")
		(at 466.453474 -291.124386)
		(property "Reference" "R596"
			(at 0 0 0)
			(layer "F.SilkS")
			(hide yes)
			(effects
				(font
					(size 1.27 1.27)
				)
			)
		)
		(property "Value" "4K7R2J-2-GP"
			(at 0.064008 -3.993896 0)
			(unlocked yes)
			(layer "F.Fab")
			(hide yes)
			(effects
				(font
					(size 1.016 1.016)
					(thickness 0.1524)
				)
			)
		)
		(property "Device Type" "R402H16"
			(at 0.064008 -5.517896 0)
			(unlocked yes)
			(layer "F.Fab")
			(hide yes)
			(effects
				(font
					(size 1.016 1.016)
					(thickness 0.1524)
				)
			)
		)
		(duplicate_pad_numbers_are_jumpers no)
		(fp_line
			(start -0.508 -0.9398)
			(end -0.508 0.9398)
			(stroke
				(width 0.1524)
				(type default)
			)
			(layer "F.SilkS")
		)
		(fp_line
			(start 0.508 -0.9398)
			(end -0.508 -0.9398)
			(stroke
				(width 0.1524)
				(type default)
			)
			(layer "F.SilkS")
		)
		(fp_rect
			(start -0.508 0.9398)
			(end 0.508 -0.9398)
			(stroke
				(width 0)
				(type default)
			)
			(fill no)
			(layer "F.CrtYd")
		)
		(fp_rect
			(start -0.508 0.9398)
			(end 0.508 -0.9398)
			(stroke
				(width 0)
				(type default)
			)
			(fill no)
			(layer "F.Fab")
		)
		(pad "1" smd custom
			(at 0 -0.4445)
			(size 0.1397 0.1397)
			(layers "F.Cu" "F.Mask" "F.Paste")
			(net "DRIVE_B_35_FLT_LED")
			(options
				(clearance outline)
				(anchor circle)
			)
			(primitives
				(gr_poly
					(pts
						(arc
							(start -0.1778 -0.2794)
							(mid -0.249642 -0.249642)
							(end -0.2794 -0.1778)
						)
						(arc
							(start -0.2794 0.1778)
							(mid -0.249642 0.249642)
							(end -0.1778 0.2794)
						)
						(arc
							(start 0.1778 0.2794)
							(mid 0.249642 0.249642)
							(end 0.2794 0.1778)
						)
						(arc
							(start 0.2794 -0.1778)
							(mid 0.249642 -0.249642)
							(end 0.1778 -0.2794)
						)
					)
					(width 0)
					(fill yes)
				)
			)
		)
		(pad "2" smd custom
			(at 0 0.4445)
			(size 0.1397 0.1397)
			(layers "F.Cu" "F.Mask" "F.Paste")
			(net "GND")
			(options
				(clearance outline)
				(anchor circle)
			)
			(primitives
				(gr_poly
					(pts
						(arc
							(start -0.1778 -0.2794)
							(mid -0.249642 -0.249642)
							(end -0.2794 -0.1778)
						)
						(arc
							(start -0.2794 0.1778)
							(mid -0.249642 0.249642)
							(end -0.1778 0.2794)
						)
						(arc
							(start 0.1778 0.2794)
							(mid 0.249642 0.249642)
							(end 0.2794 0.1778)
						)
						(arc
							(start 0.2794 -0.1778)
							(mid 0.249642 -0.249642)
							(end 0.1778 -0.2794)
						)
					)
					(width 0)
					(fill yes)
				)
			)
		)
	)
	(footprint ""
		(layer "F.Cu")
		(at 286.7152 -284.5308)
		(property "Reference" "R119"
			(at 0 0 0)
			(layer "F.SilkS")
			(hide yes)
			(effects
				(font
					(size 1.27 1.27)
				)
			)
		)
		(property "Value" "4K7R2F-GP"
			(at 0.064008 -3.993896 0)
			(unlocked yes)
			(layer "F.Fab")
			(hide yes)
			(effects
				(font
					(size 1.016 1.016)
					(thickness 0.1524)
				)
			)
		)
		(property "Device Type" "R402H16"
			(at 0.064008 -5.517896 0)
			(unlocked yes)
			(layer "F.Fab")
			(hide yes)
			(effects
				(font
					(size 1.016 1.016)
					(thickness 0.1524)
				)
			)
		)
		(duplicate_pad_numbers_are_jumpers no)
		(fp_line
			(start -0.508 -0.9398)
			(end -0.508 0.9398)
			(stroke
				(width 0.1524)
				(type default)
			)
			(layer "F.SilkS")
		)
		(fp_line
			(start 0.508 -0.9398)
			(end -0.508 -0.9398)
			(stroke
				(width 0.1524)
				(type default)
			)
			(layer "F.SilkS")
		)
		(fp_rect
			(start -0.508 0.9398)
			(end 0.508 -0.9398)
			(stroke
				(width 0)
				(type default)
			)
			(fill no)
			(layer "F.CrtYd")
		)
		(fp_rect
			(start -0.508 0.9398)
			(end 0.508 -0.9398)
			(stroke
				(width 0)
				(type default)
			)
			(fill no)
			(layer "F.Fab")
		)
		(pad "1" smd custom
			(at 0 -0.4445)
			(size 0.1397 0.1397)
			(layers "F.Cu" "F.Mask" "F.Paste")
			(net "P3V3_STBY_A")
			(options
				(clearance outline)
				(anchor circle)
			)
			(primitives
				(gr_poly
					(pts
						(arc
							(start -0.1778 -0.2794)
							(mid -0.249642 -0.249642)
							(end -0.2794 -0.1778)
						)
						(arc
							(start -0.2794 0.1778)
							(mid -0.249642 0.249642)
							(end -0.1778 0.2794)
						)
						(arc
							(start 0.1778 0.2794)
							(mid 0.249642 0.249642)
							(end 0.2794 0.1778)
						)
						(arc
							(start 0.2794 -0.1778)
							(mid 0.249642 -0.249642)
							(end 0.1778 -0.2794)
						)
					)
					(width 0)
					(fill yes)
				)
			)
		)
		(pad "2" smd custom
			(at 0 0.4445)
			(size 0.1397 0.1397)
			(layers "F.Cu" "F.Mask" "F.Paste")
			(net "IO_EXP2_HDD_FAULT_A0")
			(options
				(clearance outline)
				(anchor circle)
			)
			(primitives
				(gr_poly
					(pts
						(arc
							(start -0.1778 -0.2794)
							(mid -0.249642 -0.249642)
							(end -0.2794 -0.1778)
						)
						(arc
							(start -0.2794 0.1778)
							(mid -0.249642 0.249642)
							(end -0.1778 0.2794)
						)
						(arc
							(start 0.1778 0.2794)
							(mid 0.249642 0.249642)
							(end 0.2794 0.1778)
						)
						(arc
							(start 0.2794 -0.1778)
							(mid 0.249642 -0.249642)
							(end 0.1778 -0.2794)
						)
					)
					(width 0)
					(fill yes)
				)
			)
		)
	)
	(footprint ""
		(layer "F.Cu")
		(at 113.200942 -277.196804 -90)
		(property "Reference" "R216"
			(at 0 0 270)
			(layer "F.SilkS")
			(hide yes)
			(effects
				(font
					(size 1.27 1.27)
				)
			)
		)
		(property "Value" "0R2J-2-GP"
			(at 0.064008 -3.993896 270)
			(unlocked yes)
			(layer "F.Fab")
			(hide yes)
			(effects
				(font
					(size 1.016 1.016)
					(thickness 0.1524)
				)
			)
		)
		(property "Device Type" "R402H16"
			(at 0.064008 -5.517896 270)
			(unlocked yes)
			(layer "F.Fab")
			(hide yes)
			(effects
				(font
					(size 1.016 1.016)
					(thickness 0.1524)
				)
			)
		)
		(duplicate_pad_numbers_are_jumpers no)
		(fp_line
			(start -0.508 -0.9398)
			(end -0.508 0.9398)
			(stroke
				(width 0.1524)
				(type default)
			)
			(layer "F.SilkS")
		)
		(fp_line
			(start 0.508 -0.9398)
			(end -0.508 -0.9398)
			(stroke
				(width 0.1524)
				(type default)
			)
			(layer "F.SilkS")
		)
		(fp_rect
			(start -0.508 0.9398)
			(end 0.508 -0.9398)
			(stroke
				(width 0)
				(type default)
			)
			(fill no)
			(layer "F.CrtYd")
		)
		(fp_rect
			(start -0.508 0.9398)
			(end 0.508 -0.9398)
			(stroke
				(width 0)
				(type default)
			)
			(fill no)
			(layer "F.Fab")
		)
		(pad "1" smd custom
			(at 0 -0.4445 270)
			(size 0.1397 0.1397)
			(layers "F.Cu" "F.Mask" "F.Paste")
			(net "SW_HDD_G3")
			(options
				(clearance outline)
				(anchor circle)
			)
			(primitives
				(gr_poly
					(pts
						(arc
							(start -0.1778 -0.2794)
							(mid -0.249642 -0.249642)
							(end -0.2794 -0.1778)
						)
						(arc
							(start -0.2794 0.1778)
							(mid -0.249642 0.249642)
							(end -0.1778 0.2794)
						)
						(arc
							(start 0.1778 0.2794)
							(mid 0.249642 0.249642)
							(end 0.2794 0.1778)
						)
						(arc
							(start 0.2794 -0.1778)
							(mid 0.249642 -0.249642)
							(end 0.1778 -0.2794)
						)
					)
					(width 0)
					(fill yes)
				)
			)
		)
		(pad "2" smd custom
			(at 0 0.4445 270)
			(size 0.1397 0.1397)
			(layers "F.Cu" "F.Mask" "F.Paste")
			(net "SW_HDD_R3")
			(options
				(clearance outline)
				(anchor circle)
			)
			(primitives
				(gr_poly
					(pts
						(arc
							(start -0.1778 -0.2794)
							(mid -0.249642 -0.249642)
							(end -0.2794 -0.1778)
						)
						(arc
							(start -0.2794 0.1778)
							(mid -0.249642 0.249642)
							(end -0.1778 0.2794)
						)
						(arc
							(start 0.1778 0.2794)
							(mid 0.249642 0.249642)
							(end 0.2794 0.1778)
						)
						(arc
							(start 0.2794 -0.1778)
							(mid 0.249642 -0.249642)
							(end 0.1778 -0.2794)
						)
					)
					(width 0)
					(fill yes)
				)
			)
		)
	)
	(footprint ""
		(layer "F.Cu")
		(at 109.873796 -47.183294 180)
		(property "Reference" "R767"
			(at 0 0 180)
			(layer "F.SilkS")
			(hide yes)
			(effects
				(font
					(size 1.27 1.27)
				)
			)
		)
		(property "Value" "200KR2F-L-GP"
			(at 0.064008 -3.993896 180)
			(unlocked yes)
			(layer "F.Fab")
			(hide yes)
			(effects
				(font
					(size 1.016 1.016)
					(thickness 0.1524)
				)
			)
		)
		(property "Device Type" "R402H16"
			(at 0.064008 -5.517896 180)
			(unlocked yes)
			(layer "F.Fab")
			(hide yes)
			(effects
				(font
					(size 1.016 1.016)
					(thickness 0.1524)
				)
			)
		)
		(duplicate_pad_numbers_are_jumpers no)
		(fp_line
			(start 0.508 -0.9398)
			(end -0.508 -0.9398)
			(stroke
				(width 0.1524)
				(type default)
			)
			(layer "F.SilkS")
		)
		(fp_line
			(start -0.508 -0.9398)
			(end -0.508 0.9398)
			(stroke
				(width 0.1524)
				(type default)
			)
			(layer "F.SilkS")
		)
		(fp_rect
			(start -0.508 0.9398)
			(end 0.508 -0.9398)
			(stroke
				(width 0)
				(type default)
			)
			(fill no)
			(layer "F.CrtYd")
		)
		(fp_rect
			(start -0.508 0.9398)
			(end 0.508 -0.9398)
			(stroke
				(width 0)
				(type default)
			)
			(fill no)
			(layer "F.Fab")
		)
		(pad "1" smd custom
			(at 0 -0.4445 180)
			(size 0.1397 0.1397)
			(layers "F.Cu" "F.Mask" "F.Paste")
			(net "SW_HDD_R27")
			(options
				(clearance outline)
				(anchor circle)
			)
			(primitives
				(gr_poly
					(pts
						(arc
							(start -0.1778 -0.2794)
							(mid -0.249642 -0.249642)
							(end -0.2794 -0.1778)
						)
						(arc
							(start -0.2794 0.1778)
							(mid -0.249642 0.249642)
							(end -0.1778 0.2794)
						)
						(arc
							(start 0.1778 0.2794)
							(mid 0.249642 0.249642)
							(end 0.2794 0.1778)
						)
						(arc
							(start 0.2794 -0.1778)
							(mid 0.249642 -0.249642)
							(end 0.1778 -0.2794)
						)
					)
					(width 0)
					(fill yes)
				)
			)
		)
		(pad "2" smd custom
			(at 0 0.4445 180)
			(size 0.1397 0.1397)
			(layers "F.Cu" "F.Mask" "F.Paste")
			(net "SW_HDD_N27")
			(options
				(clearance outline)
				(anchor circle)
			)
			(primitives
				(gr_poly
					(pts
						(arc
							(start -0.1778 -0.2794)
							(mid -0.249642 -0.249642)
							(end -0.2794 -0.1778)
						)
						(arc
							(start -0.2794 0.1778)
							(mid -0.249642 0.249642)
							(end -0.1778 0.2794)
						)
						(arc
							(start 0.1778 0.2794)
							(mid 0.249642 0.249642)
							(end 0.2794 0.1778)
						)
						(arc
							(start 0.2794 -0.1778)
							(mid 0.249642 -0.249642)
							(end 0.1778 -0.2794)
						)
					)
					(width 0)
					(fill yes)
				)
			)
		)
	)
	(footprint ""
		(layer "F.Cu")
		(at 303.267872 -19.600672 90)
		(property "Reference" "TC1"
			(at 0 0 90)
			(layer "F.SilkS")
			(hide yes)
			(effects
				(font
					(size 1.27 1.27)
				)
			)
		)
		(property "Value" "ST100U16VDM-3-GP"
			(at 0 -9.6012 90)
			(unlocked yes)
			(layer "F.Fab")
			(hide yes)
			(effects
				(font
					(size 1.016 1.016)
					(thickness 0.1524)
				)
			)
		)
		(property "Device Type" "CT7343H79"
			(at 0 -11.1252 90)
			(unlocked yes)
			(layer "F.Fab")
			(hide yes)
			(effects
				(font
					(size 1.016 1.016)
					(thickness 0.1524)
				)
			)
		)
		(duplicate_pad_numbers_are_jumpers no)
		(fp_line
			(start 2.286 -4.8768)
			(end -2.286 -4.8768)
			(stroke
				(width 0.1524)
				(type default)
			)
			(layer "F.SilkS")
		)
		(fp_line
			(start -2.286 -4.8768)
			(end -2.286 -2.032)
			(stroke
				(width 0.1524)
				(type default)
			)
			(layer "F.SilkS")
		)
		(fp_line
			(start 2.1082 -4.699)
			(end -2.1082 -4.699)
			(stroke
				(width 0.508)
				(type default)
			)
			(layer "F.SilkS")
		)
		(fp_line
			(start 2.286 -2.032)
			(end 2.286 -4.8768)
			(stroke
				(width 0.1524)
				(type default)
			)
			(layer "F.SilkS")
		)
		(fp_line
			(start 2.286 2.032)
			(end 2.286 4.8768)
			(stroke
				(width 0.1524)
				(type default)
			)
			(layer "F.SilkS")
		)
		(fp_line
			(start 2.286 4.8768)
			(end -2.286 4.8768)
			(stroke
				(width 0.1524)
				(type default)
			)
			(layer "F.SilkS")
		)
		(fp_line
			(start -2.286 4.8768)
			(end -2.286 2.032)
			(stroke
				(width 0.1524)
				(type default)
			)
			(layer "F.SilkS")
		)
		(fp_rect
			(start -2.1463 3.6449)
			(end 2.1463 -3.6449)
			(stroke
				(width 0)
				(type default)
			)
			(fill no)
			(layer "F.CrtYd")
		)
		(fp_poly
			(pts
				(xy -2.54 4.953) (xy -2.54 4.2926) (xy -3.81 4.2926) (xy -3.81 -4.2926) (xy -2.54 -4.2926) (xy -2.54 -4.953)
				(xy 2.54 -4.953) (xy 2.54 -4.2926) (xy 3.81 -4.2926) (xy 3.81 -1.6256) (xy 2.1463 -1.6256) (xy 2.1463 -3.6449)
				(xy -2.1463 -3.6449) (xy -2.1463 3.6449) (xy 2.1463 3.6449) (xy 2.1463 -1.6129) (xy 3.81 -1.6129)
				(xy 3.81 4.2926) (xy 2.54 4.2926) (xy 2.54 4.953)
			)
			(stroke
				(width 0)
				(type default)
			)
			(fill no)
			(layer "F.CrtYd")
		)
		(fp_rect
			(start 2.54 4.2926)
			(end 3.81 -4.2926)
			(stroke
				(width 0)
				(type default)
			)
			(fill no)
			(layer "F.Fab")
		)
		(fp_rect
			(start -3.81 4.2926)
			(end -2.54 -4.2926)
			(stroke
				(width 0)
				(type default)
			)
			(fill no)
			(layer "F.Fab")
		)
		(fp_rect
			(start -2.54 4.953)
			(end 2.54 -4.953)
			(stroke
				(width 0)
				(type default)
			)
			(fill no)
			(layer "F.Fab")
		)
		(pad "1" smd rect
			(at 0 -3.1496 90)
			(size 2.413 2.286)
			(layers "F.Cu" "F.Mask" "F.Paste")
			(net "P12V_B_COMP")
		)
		(pad "2" smd rect
			(at 0 3.1496 90)
			(size 2.413 2.286)
			(layers "F.Cu" "F.Mask" "F.Paste")
			(net "GND")
		)
		(zone
			(layer "F.Cu")
			(hatch none 0.5)
			(connect_pads
				(clearance 0)
			)
			(min_thickness 0.25)
			(keepout
				(tracks allowed)
				(vias not_allowed)
				(pads allowed)
				(copperpour not_allowed)
				(footprints allowed)
			)
			(placement
				(enabled no)
				(sheetname "")
			)
			(fill
				(thermal_gap 0.5)
				(thermal_bridge_width 0.5)
				(island_removal_mode 0)
			)
			(polygon
				(pts
					(xy 301.578772 -21.111972) (xy 298.670472 -21.111972) (xy 298.670472 -18.089372) (xy 301.566072 -18.089372)
					(xy 301.896272 -18.089372) (xy 301.896272 -21.111972)
				)
			)
		)
		(zone
			(layer "F.Cu")
			(hatch none 0.5)
			(connect_pads
				(clearance 0)
			)
			(min_thickness 0.25)
			(keepout
				(tracks allowed)
				(vias not_allowed)
				(pads allowed)
				(copperpour not_allowed)
				(footprints allowed)
			)
			(placement
				(enabled no)
				(sheetname "")
			)
			(fill
				(thermal_gap 0.5)
				(thermal_bridge_width 0.5)
				(island_removal_mode 0)
			)
			(polygon
				(pts
					(xy 307.865272 -18.089372) (xy 307.865272 -21.111972) (xy 304.969672 -21.111972) (xy 304.639472 -21.111972)
					(xy 304.639472 -18.089372) (xy 304.969672 -18.089372)
				)
			)
		)
	)
	(footprint ""
		(layer "F.Cu")
		(at 361.6198 -140.6144 90)
		(property "Reference" "R1106"
			(at 0 0 90)
			(layer "F.SilkS")
			(hide yes)
			(effects
				(font
					(size 1.27 1.27)
				)
			)
		)
		(property "Value" "10R2F-L-GP"
			(at 0.064008 -3.993896 90)
			(unlocked yes)
			(layer "F.Fab")
			(hide yes)
			(effects
				(font
					(size 1.016 1.016)
					(thickness 0.1524)
				)
			)
		)
		(property "Device Type" "R402H14"
			(at 0.064008 -5.517896 90)
			(unlocked yes)
			(layer "F.Fab")
			(hide yes)
			(effects
				(font
					(size 1.016 1.016)
					(thickness 0.1524)
				)
			)
		)
		(duplicate_pad_numbers_are_jumpers no)
		(fp_line
			(start 0.508 -0.9398)
			(end -0.508 -0.9398)
			(stroke
				(width 0.1524)
				(type default)
			)
			(layer "F.SilkS")
		)
		(fp_line
			(start -0.508 -0.9398)
			(end -0.508 0.9398)
			(stroke
				(width 0.1524)
				(type default)
			)
			(layer "F.SilkS")
		)
		(fp_rect
			(start -0.508 0.9398)
			(end 0.508 -0.9398)
			(stroke
				(width 0)
				(type default)
			)
			(fill no)
			(layer "F.CrtYd")
		)
		(fp_rect
			(start -0.508 0.9398)
			(end 0.508 -0.9398)
			(stroke
				(width 0)
				(type default)
			)
			(fill no)
			(layer "F.Fab")
		)
		(pad "1" smd custom
			(at 0 -0.4445 90)
			(size 0.1397 0.1397)
			(layers "F.Cu" "F.Mask" "F.Paste")
			(net "MB1_CM_SENSE_R1_N")
			(options
				(clearance outline)
				(anchor circle)
			)
			(primitives
				(gr_poly
					(pts
						(arc
							(start -0.1778 -0.2794)
							(mid -0.249642 -0.249642)
							(end -0.2794 -0.1778)
						)
						(arc
							(start -0.2794 0.1778)
							(mid -0.249642 0.249642)
							(end -0.1778 0.2794)
						)
						(arc
							(start 0.1778 0.2794)
							(mid 0.249642 0.249642)
							(end 0.2794 0.1778)
						)
						(arc
							(start 0.2794 -0.1778)
							(mid 0.249642 -0.249642)
							(end 0.1778 -0.2794)
						)
					)
					(width 0)
					(fill yes)
				)
			)
		)
		(pad "2" smd custom
			(at 0 0.4445 90)
			(size 0.1397 0.1397)
			(layers "F.Cu" "F.Mask" "F.Paste")
			(net "MB1_HS_SENSE_N")
			(options
				(clearance outline)
				(anchor circle)
			)
			(primitives
				(gr_poly
					(pts
						(arc
							(start -0.1778 -0.2794)
							(mid -0.249642 -0.249642)
							(end -0.2794 -0.1778)
						)
						(arc
							(start -0.2794 0.1778)
							(mid -0.249642 0.249642)
							(end -0.1778 0.2794)
						)
						(arc
							(start 0.1778 0.2794)
							(mid 0.249642 0.249642)
							(end 0.2794 0.1778)
						)
						(arc
							(start 0.2794 -0.1778)
							(mid 0.249642 -0.249642)
							(end 0.1778 -0.2794)
						)
					)
					(width 0)
					(fill yes)
				)
			)
		)
	)
	(footprint ""
		(layer "F.Cu")
		(at 87.036148 -186.287918)
		(property "Reference" "C227"
			(at 0 0 0)
			(layer "F.SilkS")
			(hide yes)
			(effects
				(font
					(size 1.27 1.27)
				)
			)
		)
		(property "Value" "SC4D7U25V5KX-1-GP"
			(at -0.0762 -6.1214 0)
			(unlocked yes)
			(layer "F.Fab")
			(hide yes)
			(effects
				(font
					(size 1.016 1.016)
					(thickness 0.1524)
				)
			)
		)
		(property "Device Type" "C805H58"
			(at -0.0762 -8.1534 0)
			(unlocked yes)
			(layer "F.Fab")
			(hide yes)
			(effects
				(font
					(size 1.016 1.016)
					(thickness 0.1524)
				)
			)
		)
		(duplicate_pad_numbers_are_jumpers no)
		(fp_line
			(start 0.635 0)
			(end -0.635 0)
			(stroke
				(width 0.508)
				(type default)
			)
			(layer "F.SilkS")
		)
		(fp_rect
			(start -0.9652 1.778)
			(end 0.9652 -1.778)
			(stroke
				(width 0)
				(type default)
			)
			(fill no)
			(layer "F.CrtYd")
		)
		(fp_poly
			(pts
				(xy -0.9652 -1.778) (xy 0.9652 -1.778) (xy 0.9652 1.778) (xy -0.9652 1.778)
			)
			(stroke
				(width 0)
				(type default)
			)
			(fill no)
			(layer "F.Fab")
		)
		(pad "1" smd rect
			(at 0 -0.9652)
			(size 1.397 1.143)
			(layers "F.Cu" "F.Mask" "F.Paste")
			(net "P12V_HDD14")
		)
		(pad "2" smd rect
			(at 0 0.9652)
			(size 1.397 1.143)
			(layers "F.Cu" "F.Mask" "F.Paste")
			(net "GND")
		)
	)
	(footprint ""
		(layer "F.Cu")
		(at 369.624102 -279.443942 90)
		(property "Reference" "R307"
			(at 0 0 90)
			(layer "F.SilkS")
			(hide yes)
			(effects
				(font
					(size 1.27 1.27)
				)
			)
		)
		(property "Value" "200KR2F-L-GP"
			(at 0.064008 -3.993896 90)
			(unlocked yes)
			(layer "F.Fab")
			(hide yes)
			(effects
				(font
					(size 1.016 1.016)
					(thickness 0.1524)
				)
			)
		)
		(property "Device Type" "R402H16"
			(at 0.064008 -5.517896 90)
			(unlocked yes)
			(layer "F.Fab")
			(hide yes)
			(effects
				(font
					(size 1.016 1.016)
					(thickness 0.1524)
				)
			)
		)
		(duplicate_pad_numbers_are_jumpers no)
		(fp_line
			(start 0.508 -0.9398)
			(end -0.508 -0.9398)
			(stroke
				(width 0.1524)
				(type default)
			)
			(layer "F.SilkS")
		)
		(fp_line
			(start -0.508 -0.9398)
			(end -0.508 0.9398)
			(stroke
				(width 0.1524)
				(type default)
			)
			(layer "F.SilkS")
		)
		(fp_rect
			(start -0.508 0.9398)
			(end 0.508 -0.9398)
			(stroke
				(width 0)
				(type default)
			)
			(fill no)
			(layer "F.CrtYd")
		)
		(fp_rect
			(start -0.508 0.9398)
			(end 0.508 -0.9398)
			(stroke
				(width 0)
				(type default)
			)
			(fill no)
			(layer "F.Fab")
		)
		(pad "1" smd custom
			(at 0 -0.4445 90)
			(size 0.1397 0.1397)
			(layers "F.Cu" "F.Mask" "F.Paste")
			(net "SW_HDD_R7")
			(options
				(clearance outline)
				(anchor circle)
			)
			(primitives
				(gr_poly
					(pts
						(arc
							(start -0.1778 -0.2794)
							(mid -0.249642 -0.249642)
							(end -0.2794 -0.1778)
						)
						(arc
							(start -0.2794 0.1778)
							(mid -0.249642 0.249642)
							(end -0.1778 0.2794)
						)
						(arc
							(start 0.1778 0.2794)
							(mid 0.249642 0.249642)
							(end 0.2794 0.1778)
						)
						(arc
							(start 0.2794 -0.1778)
							(mid 0.249642 -0.249642)
							(end 0.1778 -0.2794)
						)
					)
					(width 0)
					(fill yes)
				)
			)
		)
		(pad "2" smd custom
			(at 0 0.4445 90)
			(size 0.1397 0.1397)
			(layers "F.Cu" "F.Mask" "F.Paste")
			(net "SW_HDD_N7")
			(options
				(clearance outline)
				(anchor circle)
			)
			(primitives
				(gr_poly
					(pts
						(arc
							(start -0.1778 -0.2794)
							(mid -0.249642 -0.249642)
							(end -0.2794 -0.1778)
						)
						(arc
							(start -0.2794 0.1778)
							(mid -0.249642 0.249642)
							(end -0.1778 0.2794)
						)
						(arc
							(start 0.1778 0.2794)
							(mid 0.249642 0.249642)
							(end 0.2794 0.1778)
						)
						(arc
							(start 0.2794 -0.1778)
							(mid 0.249642 -0.249642)
							(end 0.1778 -0.2794)
						)
					)
					(width 0)
					(fill yes)
				)
			)
		)
	)
	(footprint ""
		(layer "F.Cu")
		(at 270.409416 -20.18411 -90)
		(property "Reference" "R1130"
			(at 0 0 270)
			(layer "F.SilkS")
			(hide yes)
			(effects
				(font
					(size 1.27 1.27)
				)
			)
		)
		(property "Value" "100KR2F-L1-GP"
			(at 0.064008 -3.993896 270)
			(unlocked yes)
			(layer "F.Fab")
			(hide yes)
			(effects
				(font
					(size 1.016 1.016)
					(thickness 0.1524)
				)
			)
		)
		(property "Device Type" "R402H16"
			(at 0.064008 -5.517896 270)
			(unlocked yes)
			(layer "F.Fab")
			(hide yes)
			(effects
				(font
					(size 1.016 1.016)
					(thickness 0.1524)
				)
			)
		)
		(duplicate_pad_numbers_are_jumpers no)
		(fp_line
			(start -0.508 -0.9398)
			(end -0.508 0.9398)
			(stroke
				(width 0.1524)
				(type default)
			)
			(layer "F.SilkS")
		)
		(fp_line
			(start 0.508 -0.9398)
			(end -0.508 -0.9398)
			(stroke
				(width 0.1524)
				(type default)
			)
			(layer "F.SilkS")
		)
		(fp_rect
			(start -0.508 0.9398)
			(end 0.508 -0.9398)
			(stroke
				(width 0)
				(type default)
			)
			(fill no)
			(layer "F.CrtYd")
		)
		(fp_rect
			(start -0.508 0.9398)
			(end 0.508 -0.9398)
			(stroke
				(width 0)
				(type default)
			)
			(fill no)
			(layer "F.Fab")
		)
		(pad "1" smd custom
			(at 0 -0.4445 270)
			(size 0.1397 0.1397)
			(layers "F.Cu" "F.Mask" "F.Paste")
			(net "PCIE_COMP_B_RST_5")
			(options
				(clearance outline)
				(anchor circle)
			)
			(primitives
				(gr_poly
					(pts
						(arc
							(start -0.1778 -0.2794)
							(mid -0.249642 -0.249642)
							(end -0.2794 -0.1778)
						)
						(arc
							(start -0.2794 0.1778)
							(mid -0.249642 0.249642)
							(end -0.1778 0.2794)
						)
						(arc
							(start 0.1778 0.2794)
							(mid 0.249642 0.249642)
							(end 0.2794 0.1778)
						)
						(arc
							(start 0.2794 -0.1778)
							(mid 0.249642 -0.249642)
							(end 0.1778 -0.2794)
						)
					)
					(width 0)
					(fill yes)
				)
			)
		)
		(pad "2" smd custom
			(at 0 0.4445 270)
			(size 0.1397 0.1397)
			(layers "F.Cu" "F.Mask" "F.Paste")
			(net "GND")
			(options
				(clearance outline)
				(anchor circle)
			)
			(primitives
				(gr_poly
					(pts
						(arc
							(start -0.1778 -0.2794)
							(mid -0.249642 -0.249642)
							(end -0.2794 -0.1778)
						)
						(arc
							(start -0.2794 0.1778)
							(mid -0.249642 0.249642)
							(end -0.1778 0.2794)
						)
						(arc
							(start 0.1778 0.2794)
							(mid 0.249642 0.249642)
							(end 0.2794 0.1778)
						)
						(arc
							(start 0.2794 -0.1778)
							(mid 0.249642 -0.249642)
							(end 0.1778 -0.2794)
						)
					)
					(width 0)
					(fill yes)
				)
			)
		)
	)
	(footprint ""
		(layer "F.Cu")
		(at 330.090526 -22.654514 180)
		(property "Reference" "R1010"
			(at 0 0 180)
			(layer "F.SilkS")
			(hide yes)
			(effects
				(font
					(size 1.27 1.27)
				)
			)
		)
		(property "Value" "0R2J-2-GP"
			(at 0.064008 -3.993896 180)
			(unlocked yes)
			(layer "F.Fab")
			(hide yes)
			(effects
				(font
					(size 1.016 1.016)
					(thickness 0.1524)
				)
			)
		)
		(property "Device Type" "R402H16"
			(at 0.064008 -5.517896 180)
			(unlocked yes)
			(layer "F.Fab")
			(hide yes)
			(effects
				(font
					(size 1.016 1.016)
					(thickness 0.1524)
				)
			)
		)
		(duplicate_pad_numbers_are_jumpers no)
		(fp_line
			(start 0.508 -0.9398)
			(end -0.508 -0.9398)
			(stroke
				(width 0.1524)
				(type default)
			)
			(layer "F.SilkS")
		)
		(fp_line
			(start -0.508 -0.9398)
			(end -0.508 0.9398)
			(stroke
				(width 0.1524)
				(type default)
			)
			(layer "F.SilkS")
		)
		(fp_rect
			(start -0.508 0.9398)
			(end 0.508 -0.9398)
			(stroke
				(width 0)
				(type default)
			)
			(fill no)
			(layer "F.CrtYd")
		)
		(fp_rect
			(start -0.508 0.9398)
			(end 0.508 -0.9398)
			(stroke
				(width 0)
				(type default)
			)
			(fill no)
			(layer "F.Fab")
		)
		(pad "1" smd custom
			(at 0 -0.4445 180)
			(size 0.1397 0.1397)
			(layers "F.Cu" "F.Mask" "F.Paste")
			(net "GND")
			(options
				(clearance outline)
				(anchor circle)
			)
			(primitives
				(gr_poly
					(pts
						(arc
							(start -0.1778 -0.2794)
							(mid -0.249642 -0.249642)
							(end -0.2794 -0.1778)
						)
						(arc
							(start -0.2794 0.1778)
							(mid -0.249642 0.249642)
							(end -0.1778 0.2794)
						)
						(arc
							(start 0.1778 0.2794)
							(mid 0.249642 0.249642)
							(end 0.2794 0.1778)
						)
						(arc
							(start 0.2794 -0.1778)
							(mid 0.249642 -0.249642)
							(end 0.1778 -0.2794)
						)
					)
					(width 0)
					(fill yes)
				)
			)
		)
		(pad "2" smd custom
			(at 0 0.4445 180)
			(size 0.1397 0.1397)
			(layers "F.Cu" "F.Mask" "F.Paste")
			(net "IOM_B_SLOT_ID_1")
			(options
				(clearance outline)
				(anchor circle)
			)
			(primitives
				(gr_poly
					(pts
						(arc
							(start -0.1778 -0.2794)
							(mid -0.249642 -0.249642)
							(end -0.2794 -0.1778)
						)
						(arc
							(start -0.2794 0.1778)
							(mid -0.249642 0.249642)
							(end -0.1778 0.2794)
						)
						(arc
							(start 0.1778 0.2794)
							(mid 0.249642 0.249642)
							(end 0.2794 0.1778)
						)
						(arc
							(start 0.2794 -0.1778)
							(mid 0.249642 -0.249642)
							(end 0.1778 -0.2794)
						)
					)
					(width 0)
					(fill yes)
				)
			)
		)
	)
	(footprint ""
		(layer "F.Cu")
		(at 246.992902 -395.012164 180)
		(property "Reference" "R1170"
			(at 0 0 180)
			(layer "F.SilkS")
			(hide yes)
			(effects
				(font
					(size 1.27 1.27)
				)
			)
		)
		(property "Value" "3K92R2F-GP"
			(at 0.064008 -3.993896 180)
			(unlocked yes)
			(layer "F.Fab")
			(hide yes)
			(effects
				(font
					(size 1.016 1.016)
					(thickness 0.1524)
				)
			)
		)
		(property "Device Type" "R402H16"
			(at 0.064008 -5.517896 180)
			(unlocked yes)
			(layer "F.Fab")
			(hide yes)
			(effects
				(font
					(size 1.016 1.016)
					(thickness 0.1524)
				)
			)
		)
		(duplicate_pad_numbers_are_jumpers no)
		(fp_line
			(start 0.508 -0.9398)
			(end -0.508 -0.9398)
			(stroke
				(width 0.1524)
				(type default)
			)
			(layer "F.SilkS")
		)
		(fp_line
			(start -0.508 -0.9398)
			(end -0.508 0.9398)
			(stroke
				(width 0.1524)
				(type default)
			)
			(layer "F.SilkS")
		)
		(fp_rect
			(start -0.508 0.9398)
			(end 0.508 -0.9398)
			(stroke
				(width 0)
				(type default)
			)
			(fill no)
			(layer "F.CrtYd")
		)
		(fp_rect
			(start -0.508 0.9398)
			(end 0.508 -0.9398)
			(stroke
				(width 0)
				(type default)
			)
			(fill no)
			(layer "F.Fab")
		)
		(pad "1" smd custom
			(at 0 -0.4445 180)
			(size 0.1397 0.1397)
			(layers "F.Cu" "F.Mask" "F.Paste")
			(net "MB3_CM_OV_R")
			(options
				(clearance outline)
				(anchor circle)
			)
			(primitives
				(gr_poly
					(pts
						(arc
							(start -0.1778 -0.2794)
							(mid -0.249642 -0.249642)
							(end -0.2794 -0.1778)
						)
						(arc
							(start -0.2794 0.1778)
							(mid -0.249642 0.249642)
							(end -0.1778 0.2794)
						)
						(arc
							(start 0.1778 0.2794)
							(mid 0.249642 0.249642)
							(end 0.2794 0.1778)
						)
						(arc
							(start 0.2794 -0.1778)
							(mid 0.249642 -0.249642)
							(end 0.1778 -0.2794)
						)
					)
					(width 0)
					(fill yes)
				)
			)
		)
		(pad "2" smd custom
			(at 0 0.4445 180)
			(size 0.1397 0.1397)
			(layers "F.Cu" "F.Mask" "F.Paste")
			(net "AGND_CURRENT_DPB")
			(options
				(clearance outline)
				(anchor circle)
			)
			(primitives
				(gr_poly
					(pts
						(arc
							(start -0.1778 -0.2794)
							(mid -0.249642 -0.249642)
							(end -0.2794 -0.1778)
						)
						(arc
							(start -0.2794 0.1778)
							(mid -0.249642 0.249642)
							(end -0.1778 0.2794)
						)
						(arc
							(start 0.1778 0.2794)
							(mid 0.249642 0.249642)
							(end 0.2794 0.1778)
						)
						(arc
							(start 0.2794 -0.1778)
							(mid 0.249642 -0.249642)
							(end 0.1778 -0.2794)
						)
					)
					(width 0)
					(fill yes)
				)
			)
		)
	)
	(footprint ""
		(layer "F.Cu")
		(at 158.503112 -127.71247 180)
		(property "Reference" "Q280"
			(at 0 0 180)
			(layer "F.SilkS")
			(hide yes)
			(effects
				(font
					(size 1.27 1.27)
				)
			)
		)
		(property "Value" "SSM3K324R-GP"
			(at 0.127 -8.9662 180)
			(unlocked yes)
			(layer "F.Fab")
			(hide yes)
			(effects
				(font
					(size 1.016 1.016)
					(thickness 0.1524)
				)
			)
		)
		(property "Device Type" "SOT23DGS2D4H35"
			(at 0.127 -10.4902 180)
			(unlocked yes)
			(layer "F.Fab")
			(hide yes)
			(effects
				(font
					(size 1.016 1.016)
					(thickness 0.1524)
				)
			)
		)
		(duplicate_pad_numbers_are_jumpers no)
		(fp_line
			(start 1.651 1.778)
			(end 1.651 -1.778)
			(stroke
				(width 0.1524)
				(type default)
			)
			(layer "F.SilkS")
		)
		(fp_line
			(start 1.651 -1.778)
			(end -1.651 -1.778)
			(stroke
				(width 0.1524)
				(type default)
			)
			(layer "F.SilkS")
		)
		(fp_line
			(start -1.651 1.778)
			(end 1.651 1.778)
			(stroke
				(width 0.1524)
				(type default)
			)
			(layer "F.SilkS")
		)
		(fp_line
			(start -1.651 -1.778)
			(end -1.651 1.778)
			(stroke
				(width 0.1524)
				(type default)
			)
			(layer "F.SilkS")
		)
		(fp_poly
			(pts
				(xy -1.778 1.8796) (xy -1.778 -1.8796) (xy 1.778 -1.8796) (xy 1.778 1.8796)
			)
			(stroke
				(width 0)
				(type default)
			)
			(fill no)
			(layer "F.CrtYd")
		)
		(fp_poly
			(pts
				(xy -1.778 1.8796) (xy -1.778 -1.8796) (xy 1.778 -1.8796) (xy 1.778 1.8796)
			)
			(stroke
				(width 0)
				(type default)
			)
			(fill no)
			(layer "F.Fab")
		)
		(pad "D" smd custom
			(at 0 -0.9525 180)
			(size 0.1905 0.1905)
			(layers "F.Cu" "F.Mask" "F.Paste")
			(net "DRV_ACT_17_N")
			(options
				(clearance outline)
				(anchor circle)
			)
			(primitives
				(gr_poly
					(pts
						(arc
							(start -0.1778 0.5715)
							(mid -0.321484 0.511984)
							(end -0.381 0.3683)
						)
						(arc
							(start -0.381 -0.3683)
							(mid -0.321484 -0.511984)
							(end -0.1778 -0.5715)
						)
						(arc
							(start 0.1778 -0.5715)
							(mid 0.321484 -0.511984)
							(end 0.381 -0.3683)
						)
						(arc
							(start 0.381 0.3683)
							(mid 0.321484 0.511984)
							(end 0.1778 0.5715)
						)
					)
					(width 0)
					(fill yes)
				)
			)
		)
		(pad "G" smd custom
			(at -0.98425 0.9525 180)
			(size 0.1905 0.1905)
			(layers "F.Cu" "F.Mask" "F.Paste")
			(net "DRIVE_A_17_ACT")
			(options
				(clearance outline)
				(anchor circle)
			)
			(primitives
				(gr_poly
					(pts
						(arc
							(start -0.1778 0.5715)
							(mid -0.321484 0.511984)
							(end -0.381 0.3683)
						)
						(arc
							(start -0.381 -0.3683)
							(mid -0.321484 -0.511984)
							(end -0.1778 -0.5715)
						)
						(arc
							(start 0.1778 -0.5715)
							(mid 0.321484 -0.511984)
							(end 0.381 -0.3683)
						)
						(arc
							(start 0.381 0.3683)
							(mid 0.321484 0.511984)
							(end 0.1778 0.5715)
						)
					)
					(width 0)
					(fill yes)
				)
			)
		)
		(pad "S" smd custom
			(at 0.98425 0.9525 180)
			(size 0.1905 0.1905)
			(layers "F.Cu" "F.Mask" "F.Paste")
			(net "GND")
			(options
				(clearance outline)
				(anchor circle)
			)
			(primitives
				(gr_poly
					(pts
						(arc
							(start -0.1778 0.5715)
							(mid -0.321484 0.511984)
							(end -0.381 0.3683)
						)
						(arc
							(start -0.381 -0.3683)
							(mid -0.321484 -0.511984)
							(end -0.1778 -0.5715)
						)
						(arc
							(start 0.1778 -0.5715)
							(mid 0.321484 -0.511984)
							(end 0.381 -0.3683)
						)
						(arc
							(start 0.381 0.3683)
							(mid 0.321484 0.511984)
							(end 0.1778 0.5715)
						)
					)
					(width 0)
					(fill yes)
				)
			)
		)
	)
	(footprint ""
		(layer "F.Cu")
		(at 140.915898 -294.683942 -90)
		(property "Reference" "C97"
			(at 0 0 270)
			(layer "F.SilkS")
			(hide yes)
			(effects
				(font
					(size 1.27 1.27)
				)
			)
		)
		(property "Value" "SC4D7U25V5KX-1-GP"
			(at -0.0762 -6.1214 270)
			(unlocked yes)
			(layer "F.Fab")
			(hide yes)
			(effects
				(font
					(size 1.016 1.016)
					(thickness 0.1524)
				)
			)
		)
		(property "Device Type" "C805H58"
			(at -0.0762 -8.1534 270)
			(unlocked yes)
			(layer "F.Fab")
			(hide yes)
			(effects
				(font
					(size 1.016 1.016)
					(thickness 0.1524)
				)
			)
		)
		(duplicate_pad_numbers_are_jumpers no)
		(fp_line
			(start 0.635 0)
			(end -0.635 0)
			(stroke
				(width 0.508)
				(type default)
			)
			(layer "F.SilkS")
		)
		(fp_rect
			(start -0.9652 1.778)
			(end 0.9652 -1.778)
			(stroke
				(width 0)
				(type default)
			)
			(fill no)
			(layer "F.CrtYd")
		)
		(fp_poly
			(pts
				(xy -0.9652 -1.778) (xy 0.9652 -1.778) (xy 0.9652 1.778) (xy -0.9652 1.778)
			)
			(stroke
				(width 0)
				(type default)
			)
			(fill no)
			(layer "F.Fab")
		)
		(pad "1" smd rect
			(at 0 -0.9652 270)
			(size 1.397 1.143)
			(layers "F.Cu" "F.Mask" "F.Paste")
			(net "P12V_HDD4")
		)
		(pad "2" smd rect
			(at 0 0.9652 270)
			(size 1.397 1.143)
			(layers "F.Cu" "F.Mask" "F.Paste")
			(net "GND")
		)
	)
	(footprint ""
		(layer "F.Cu")
		(at 222.593916 -113.147348 -90)
		(property "Reference" "R159"
			(at 0 0 270)
			(layer "F.SilkS")
			(hide yes)
			(effects
				(font
					(size 1.27 1.27)
				)
			)
		)
		(property "Value" "0R2J-2-GP"
			(at 0.064008 -3.993896 270)
			(unlocked yes)
			(layer "F.Fab")
			(hide yes)
			(effects
				(font
					(size 1.016 1.016)
					(thickness 0.1524)
				)
			)
		)
		(property "Device Type" "R402H16"
			(at 0.064008 -5.517896 270)
			(unlocked yes)
			(layer "F.Fab")
			(hide yes)
			(effects
				(font
					(size 1.016 1.016)
					(thickness 0.1524)
				)
			)
		)
		(duplicate_pad_numbers_are_jumpers no)
		(fp_line
			(start -0.508 -0.9398)
			(end -0.508 0.9398)
			(stroke
				(width 0.1524)
				(type default)
			)
			(layer "F.SilkS")
		)
		(fp_line
			(start 0.508 -0.9398)
			(end -0.508 -0.9398)
			(stroke
				(width 0.1524)
				(type default)
			)
			(layer "F.SilkS")
		)
		(fp_rect
			(start -0.508 0.9398)
			(end 0.508 -0.9398)
			(stroke
				(width 0)
				(type default)
			)
			(fill no)
			(layer "F.CrtYd")
		)
		(fp_rect
			(start -0.508 0.9398)
			(end 0.508 -0.9398)
			(stroke
				(width 0)
				(type default)
			)
			(fill no)
			(layer "F.Fab")
		)
		(pad "1" smd custom
			(at 0 -0.4445 270)
			(size 0.1397 0.1397)
			(layers "F.Cu" "F.Mask" "F.Paste")
			(net "SLOT3_SVR_ID0_GPIO0")
			(options
				(clearance outline)
				(anchor circle)
			)
			(primitives
				(gr_poly
					(pts
						(arc
							(start -0.1778 -0.2794)
							(mid -0.249642 -0.249642)
							(end -0.2794 -0.1778)
						)
						(arc
							(start -0.2794 0.1778)
							(mid -0.249642 0.249642)
							(end -0.1778 0.2794)
						)
						(arc
							(start 0.1778 0.2794)
							(mid 0.249642 0.249642)
							(end 0.2794 0.1778)
						)
						(arc
							(start 0.2794 -0.1778)
							(mid 0.249642 -0.249642)
							(end 0.1778 -0.2794)
						)
					)
					(width 0)
					(fill yes)
				)
			)
		)
		(pad "2" smd custom
			(at 0 0.4445 270)
			(size 0.1397 0.1397)
			(layers "F.Cu" "F.Mask" "F.Paste")
			(net "COMP_A_BMC_A_SPARE_0")
			(options
				(clearance outline)
				(anchor circle)
			)
			(primitives
				(gr_poly
					(pts
						(arc
							(start -0.1778 -0.2794)
							(mid -0.249642 -0.249642)
							(end -0.2794 -0.1778)
						)
						(arc
							(start -0.2794 0.1778)
							(mid -0.249642 0.249642)
							(end -0.1778 0.2794)
						)
						(arc
							(start 0.1778 0.2794)
							(mid 0.249642 0.249642)
							(end 0.2794 0.1778)
						)
						(arc
							(start 0.2794 -0.1778)
							(mid 0.249642 -0.249642)
							(end 0.1778 -0.2794)
						)
					)
					(width 0)
					(fill yes)
				)
			)
		)
	)
	(footprint ""
		(layer "F.Cu")
		(at 77.942948 -174.857918)
		(property "Reference" "Q86"
			(at 0 0 0)
			(layer "F.SilkS")
			(hide yes)
			(effects
				(font
					(size 1.27 1.27)
				)
			)
		)
		(property "Value" "AO4407AL-GP"
			(at -3.707384 -1.5367 0)
			(unlocked yes)
			(layer "F.Fab")
			(hide yes)
			(effects
				(font
					(size 1.016 1.016)
					(thickness 0.1524)
				)
			)
		)
		(property "Device Type" "SOIC8H69"
			(at -3.707384 -3.0607 0)
			(unlocked yes)
			(layer "F.Fab")
			(hide yes)
			(effects
				(font
					(size 1.016 1.016)
					(thickness 0.1524)
				)
			)
		)
		(duplicate_pad_numbers_are_jumpers no)
		(fp_line
			(start -2.7432 -1.4224)
			(end -2.7432 1.4224)
			(stroke
				(width 0.1524)
				(type default)
			)
			(layer "F.SilkS")
		)
		(fp_line
			(start -2.7432 1.4224)
			(end -2.6416 1.4224)
			(stroke
				(width 0.1524)
				(type default)
			)
			(layer "F.SilkS")
		)
		(fp_line
			(start -2.7432 1.4224)
			(end 2.1336 1.4224)
			(stroke
				(width 0.1524)
				(type default)
			)
			(layer "F.SilkS")
		)
		(fp_line
			(start -2.7178 -0.508)
			(end -2.1844 -0.0508)
			(stroke
				(width 0.1524)
				(type default)
			)
			(layer "F.SilkS")
		)
		(fp_line
			(start -2.6289 3.4417)
			(end -2.6289 1.4732)
			(stroke
				(width 0.381)
				(type default)
			)
			(layer "F.SilkS")
		)
		(fp_line
			(start -2.1844 -0.0508)
			(end -2.7178 0.508)
			(stroke
				(width 0.1524)
				(type default)
			)
			(layer "F.SilkS")
		)
		(fp_line
			(start 2.1336 -1.4224)
			(end -2.7432 -1.4224)
			(stroke
				(width 0.1524)
				(type default)
			)
			(layer "F.SilkS")
		)
		(fp_line
			(start 2.1336 1.4224)
			(end 2.1336 -1.4224)
			(stroke
				(width 0.1524)
				(type default)
			)
			(layer "F.SilkS")
		)
		(fp_poly
			(pts
				(xy -2.2098 -1.4224) (xy -2.2098 1.4224) (xy 2.2098 1.4224) (xy 2.2098 -1.4224)
			)
			(stroke
				(width 0)
				(type default)
			)
			(fill yes)
			(layer "F.SilkS")
		)
		(fp_rect
			(start -2.450084 2.999994)
			(end 2.450084 -2.999994)
			(stroke
				(width 0)
				(type default)
			)
			(fill no)
			(layer "F.CrtYd")
		)
		(fp_poly
			(pts
				(xy -2.8194 3.6322) (xy -2.8194 -3.6322) (xy 2.8194 -3.6322) (xy 2.8194 1.18364) (xy 2.450084 1.18364)
				(xy 2.450084 -2.999994) (xy -2.450084 -2.999994) (xy -2.450084 2.999994) (xy 2.450084 2.999994)
				(xy 2.450084 1.18618) (xy 2.8194 1.18618) (xy 2.8194 3.6322)
			)
			(stroke
				(width 0)
				(type default)
			)
			(fill no)
			(layer "F.CrtYd")
		)
		(fp_rect
			(start -2.8194 3.6322)
			(end 2.8194 -3.6322)
			(stroke
				(width 0)
				(type default)
			)
			(fill no)
			(layer "F.Fab")
		)
		(pad "1" smd rect
			(at -1.905 2.54)
			(size 0.635 1.651)
			(layers "F.Cu" "F.Mask" "F.Paste")
			(net "P12V_A")
		)
		(pad "2" smd rect
			(at -0.635 2.54)
			(size 0.635 1.651)
			(layers "F.Cu" "F.Mask" "F.Paste")
			(net "P12V_A")
		)
		(pad "3" smd rect
			(at 0.635 2.54)
			(size 0.635 1.651)
			(layers "F.Cu" "F.Mask" "F.Paste")
			(net "P12V_A")
		)
		(pad "4" smd rect
			(at 1.905 2.54)
			(size 0.635 1.651)
			(layers "F.Cu" "F.Mask" "F.Paste")
			(net "SW_HDD_N14")
		)
		(pad "5" smd rect
			(at 1.905 -2.54)
			(size 0.635 1.651)
			(layers "F.Cu" "F.Mask" "F.Paste")
			(net "P12V_HDD14")
		)
		(pad "6" smd rect
			(at 0.635 -2.54)
			(size 0.635 1.651)
			(layers "F.Cu" "F.Mask" "F.Paste")
			(net "P12V_HDD14")
		)
		(pad "7" smd rect
			(at -0.635 -2.54)
			(size 0.635 1.651)
			(layers "F.Cu" "F.Mask" "F.Paste")
			(net "P12V_HDD14")
		)
		(pad "8" smd rect
			(at -1.905 -2.54)
			(size 0.635 1.651)
			(layers "F.Cu" "F.Mask" "F.Paste")
			(net "P12V_HDD14")
		)
	)
	(footprint ""
		(layer "F.Cu")
		(at 221.402402 -377.73991 -90)
		(property "Reference" "C536"
			(at 0 0 270)
			(layer "F.SilkS")
			(hide yes)
			(effects
				(font
					(size 1.27 1.27)
				)
			)
		)
		(property "Value" "SCD1U16V2KX-3GP"
			(at 1.1811 -2.7051 270)
			(unlocked yes)
			(layer "F.Fab")
			(hide yes)
			(effects
				(font
					(size 1.016 1.016)
					(thickness 0.1524)
				)
			)
		)
		(property "Device Type" "C402H22"
			(at 1.1811 -4.2291 270)
			(unlocked yes)
			(layer "F.Fab")
			(hide yes)
			(effects
				(font
					(size 1.016 1.016)
					(thickness 0.1524)
				)
			)
		)
		(duplicate_pad_numbers_are_jumpers no)
		(fp_rect
			(start -0.4318 0.9525)
			(end 0.4318 -0.9525)
			(stroke
				(width 0)
				(type default)
			)
			(fill no)
			(layer "F.CrtYd")
		)
		(fp_rect
			(start -0.4318 0.9525)
			(end 0.4318 -0.9525)
			(stroke
				(width 0)
				(type default)
			)
			(fill no)
			(layer "F.Fab")
		)
		(pad "1" smd custom
			(at 0 -0.4445 270)
			(size 0.1524 0.1524)
			(layers "F.Cu" "F.Mask" "F.Paste")
			(net "P3V3_STBY_B")
			(options
				(clearance outline)
				(anchor circle)
			)
			(primitives
				(gr_poly
					(pts
						(arc
							(start 0.3048 -0.2032)
							(mid 0.275042 -0.275042)
							(end 0.2032 -0.3048)
						)
						(arc
							(start -0.2032 -0.3048)
							(mid -0.275042 -0.275042)
							(end -0.3048 -0.2032)
						)
						(arc
							(start -0.3048 0.2032)
							(mid -0.275042 0.275042)
							(end -0.2032 0.3048)
						)
						(arc
							(start 0.2032 0.3048)
							(mid 0.275042 0.275042)
							(end 0.3048 0.2032)
						)
					)
					(width 0)
					(fill yes)
				)
			)
		)
		(pad "2" smd custom
			(at 0 0.4445 270)
			(size 0.1524 0.1524)
			(layers "F.Cu" "F.Mask" "F.Paste")
			(net "GND")
			(options
				(clearance outline)
				(anchor circle)
			)
			(primitives
				(gr_poly
					(pts
						(arc
							(start 0.3048 -0.2032)
							(mid 0.275042 -0.275042)
							(end 0.2032 -0.3048)
						)
						(arc
							(start -0.2032 -0.3048)
							(mid -0.275042 -0.275042)
							(end -0.3048 -0.2032)
						)
						(arc
							(start -0.3048 0.2032)
							(mid -0.275042 0.275042)
							(end -0.2032 0.3048)
						)
						(arc
							(start 0.2032 0.3048)
							(mid 0.275042 0.275042)
							(end 0.3048 0.2032)
						)
					)
					(width 0)
					(fill yes)
				)
			)
		)
	)
	(footprint ""
		(layer "F.Cu")
		(at 83.530948 -278.554942 180)
		(property "Reference" "Q13"
			(at 0 0 180)
			(layer "F.SilkS")
			(hide yes)
			(effects
				(font
					(size 1.27 1.27)
				)
			)
		)
		(property "Value" "2N7002KDW-GP"
			(at -2.3622 -8.2042 180)
			(unlocked yes)
			(layer "F.Fab")
			(hide yes)
			(effects
				(font
					(size 1.016 1.016)
					(thickness 0.1524)
				)
			)
		)
		(property "Device Type" "SOT-363H44"
			(at -2.3622 -10.1092 180)
			(unlocked yes)
			(layer "F.Fab")
			(hide yes)
			(effects
				(font
					(size 1.016 1.016)
					(thickness 0.1524)
				)
			)
		)
		(duplicate_pad_numbers_are_jumpers no)
		(fp_line
			(start 1.4478 1.7018)
			(end 1.4478 -1.7018)
			(stroke
				(width 0.1524)
				(type default)
			)
			(layer "F.SilkS")
		)
		(fp_line
			(start 1.4478 -1.7018)
			(end -1.4478 -1.7018)
			(stroke
				(width 0.1524)
				(type default)
			)
			(layer "F.SilkS")
		)
		(fp_line
			(start -1.27 1.524)
			(end -1.27 0.6604)
			(stroke
				(width 0.4826)
				(type default)
			)
			(layer "F.SilkS")
		)
		(fp_line
			(start -1.4478 1.7018)
			(end 1.4478 1.7018)
			(stroke
				(width 0.1524)
				(type default)
			)
			(layer "F.SilkS")
		)
		(fp_line
			(start -1.4478 -1.7018)
			(end -1.4478 1.7018)
			(stroke
				(width 0.1524)
				(type default)
			)
			(layer "F.SilkS")
		)
		(fp_poly
			(pts
				(xy -1.524 -1.778) (xy 1.524 -1.778) (xy 1.524 1.778) (xy -1.524 1.778)
			)
			(stroke
				(width 0)
				(type default)
			)
			(fill no)
			(layer "F.CrtYd")
		)
		(fp_poly
			(pts
				(xy -1.524 -1.778) (xy 1.524 -1.778) (xy 1.524 1.778) (xy -1.524 1.778)
			)
			(stroke
				(width 0)
				(type default)
			)
			(fill no)
			(layer "F.Fab")
		)
		(pad "1" smd rect
			(at -0.65024 0.9398 180)
			(size 0.4064 1.016)
			(layers "F.Cu" "F.Mask" "F.Paste")
			(net "GND")
		)
		(pad "2" smd rect
			(at 0 0.9398 180)
			(size 0.4064 1.016)
			(layers "F.Cu" "F.Mask" "F.Paste")
			(net "SW_PWR_R_HDD2")
		)
		(pad "3" smd rect
			(at 0.65024 0.9398 180)
			(size 0.4064 1.016)
			(layers "F.Cu" "F.Mask" "F.Paste")
			(net "SW_HDD_P2")
		)
		(pad "4" smd rect
			(at 0.65024 -0.9398 180)
			(size 0.4064 1.016)
			(layers "F.Cu" "F.Mask" "F.Paste")
			(net "GND")
		)
		(pad "5" smd rect
			(at 0 -0.9398 180)
			(size 0.4064 1.016)
			(layers "F.Cu" "F.Mask" "F.Paste")
			(net "SW_HDD_G2")
		)
		(pad "6" smd rect
			(at -0.65024 -0.9398 180)
			(size 0.4064 1.016)
			(layers "F.Cu" "F.Mask" "F.Paste")
			(net "SW_HDD_R2")
		)
	)
	(footprint ""
		(layer "F.Cu")
		(at 222.921322 -137.77087 -90)
		(property "Reference" "R1002"
			(at 0 0 270)
			(layer "F.SilkS")
			(hide yes)
			(effects
				(font
					(size 1.27 1.27)
				)
			)
		)
		(property "Value" "100KR2F-L1-GP"
			(at 0.064008 -3.993896 270)
			(unlocked yes)
			(layer "F.Fab")
			(hide yes)
			(effects
				(font
					(size 1.016 1.016)
					(thickness 0.1524)
				)
			)
		)
		(property "Device Type" "R402H16"
			(at 0.064008 -5.517896 270)
			(unlocked yes)
			(layer "F.Fab")
			(hide yes)
			(effects
				(font
					(size 1.016 1.016)
					(thickness 0.1524)
				)
			)
		)
		(duplicate_pad_numbers_are_jumpers no)
		(fp_line
			(start -0.508 -0.9398)
			(end -0.508 0.9398)
			(stroke
				(width 0.1524)
				(type default)
			)
			(layer "F.SilkS")
		)
		(fp_line
			(start 0.508 -0.9398)
			(end -0.508 -0.9398)
			(stroke
				(width 0.1524)
				(type default)
			)
			(layer "F.SilkS")
		)
		(fp_rect
			(start -0.508 0.9398)
			(end 0.508 -0.9398)
			(stroke
				(width 0)
				(type default)
			)
			(fill no)
			(layer "F.CrtYd")
		)
		(fp_rect
			(start -0.508 0.9398)
			(end 0.508 -0.9398)
			(stroke
				(width 0)
				(type default)
			)
			(fill no)
			(layer "F.Fab")
		)
		(pad "1" smd custom
			(at 0 -0.4445 270)
			(size 0.1397 0.1397)
			(layers "F.Cu" "F.Mask" "F.Paste")
			(net "PCIE_COMP_A_PCIE_RST_1")
			(options
				(clearance outline)
				(anchor circle)
			)
			(primitives
				(gr_poly
					(pts
						(arc
							(start -0.1778 -0.2794)
							(mid -0.249642 -0.249642)
							(end -0.2794 -0.1778)
						)
						(arc
							(start -0.2794 0.1778)
							(mid -0.249642 0.249642)
							(end -0.1778 0.2794)
						)
						(arc
							(start 0.1778 0.2794)
							(mid 0.249642 0.249642)
							(end 0.2794 0.1778)
						)
						(arc
							(start 0.2794 -0.1778)
							(mid 0.249642 -0.249642)
							(end 0.1778 -0.2794)
						)
					)
					(width 0)
					(fill yes)
				)
			)
		)
		(pad "2" smd custom
			(at 0 0.4445 270)
			(size 0.1397 0.1397)
			(layers "F.Cu" "F.Mask" "F.Paste")
			(net "GND")
			(options
				(clearance outline)
				(anchor circle)
			)
			(primitives
				(gr_poly
					(pts
						(arc
							(start -0.1778 -0.2794)
							(mid -0.249642 -0.249642)
							(end -0.2794 -0.1778)
						)
						(arc
							(start -0.2794 0.1778)
							(mid -0.249642 0.249642)
							(end -0.1778 0.2794)
						)
						(arc
							(start 0.1778 0.2794)
							(mid 0.249642 0.249642)
							(end 0.2794 0.1778)
						)
						(arc
							(start 0.2794 -0.1778)
							(mid 0.249642 -0.249642)
							(end 0.1778 -0.2794)
						)
					)
					(width 0)
					(fill yes)
				)
			)
		)
	)
	(footprint ""
		(layer "F.Cu")
		(at 467.499954 -269.999968)
		(property "Reference" ""
			(at 0 0 0)
			(layer "F.SilkS")
			(hide yes)
			(effects
				(font
					(size 1.27 1.27)
				)
			)
		)
		(property "Value" "*"
			(at -6.3373 -0.4572 0)
			(unlocked yes)
			(layer "F.Fab")
			(hide yes)
			(effects
				(font
					(size 1.016 1.016)
					(thickness 0.1524)
				)
			)
		)
		(duplicate_pad_numbers_are_jumpers no)
		(fp_poly
			(pts
				(arc
					(start 5.0673 0)
					(mid -5.0673 0)
					(end 5.0673 0)
				)
			)
			(stroke
				(width 0)
				(type default)
			)
			(fill no)
			(layer "B.CrtYd")
		)
		(fp_poly
			(pts
				(arc
					(start 5.0673 0)
					(mid -5.0673 0)
					(end 5.0673 0)
				)
			)
			(stroke
				(width 0)
				(type default)
			)
			(fill no)
			(layer "F.CrtYd")
		)
		(fp_poly
			(pts
				(arc
					(start 5.0673 0)
					(mid -5.0673 0)
					(end 5.0673 0)
				)
			)
			(stroke
				(width 0)
				(type default)
			)
			(fill no)
			(layer "B.Fab")
		)
		(fp_poly
			(pts
				(arc
					(start 5.0673 0)
					(mid -5.0673 0)
					(end 5.0673 0)
				)
			)
			(stroke
				(width 0)
				(type default)
			)
			(fill no)
			(layer "F.Fab")
		)
		(pad "1" thru_hole circle
			(at 0 0)
			(size 9.525 9.525)
			(drill 3.556)
			(layers "*.Cu" "*.Mask")
			(remove_unused_layers no)
			(net "Net_95")
			(clearance -2.4765)
			(thermal_gap 0.3048)
			(padstack
				(mode front_inner_back)
				(layer "Inner"
					(shape circle)
					(size 3.9624 3.9624)
					(clearance 0.3048)
				)
				(layer "B.Cu"
					(shape circle)
					(size 9.525 9.525)
					(clearance -2.4765)
				)
			)
		)
		(zone
			(layers "F.Cu" "B.Cu" "In1.Cu" "In2.Cu" "In3.Cu" "In4.Cu" "In5.Cu" "In6.Cu"
				"In7.Cu" "In8.Cu" "In9.Cu" "In10.Cu"
			)
			(hatch none 0.5)
			(connect_pads
				(clearance 0)
			)
			(min_thickness 0.25)
			(keepout
				(tracks not_allowed)
				(vias allowed)
				(pads allowed)
				(copperpour not_allowed)
				(footprints allowed)
			)
			(placement
				(enabled no)
				(sheetname "")
			)
			(fill
				(thermal_gap 0.5)
				(thermal_bridge_width 0.5)
				(island_removal_mode 0)
			)
			(polygon
				(pts
					(arc
						(start 472.262454 -269.999968)
						(mid 462.737454 -269.999968)
						(end 472.262454 -269.999968)
					)
				)
			)
		)
	)
	(footprint ""
		(layer "F.Cu")
		(at 335.788 -157.585918 180)
		(property "Reference" "R555"
			(at 0 0 180)
			(layer "F.SilkS")
			(hide yes)
			(effects
				(font
					(size 1.27 1.27)
				)
			)
		)
		(property "Value" "0R2J-2-GP"
			(at 0.064008 -3.993896 180)
			(unlocked yes)
			(layer "F.Fab")
			(hide yes)
			(effects
				(font
					(size 1.016 1.016)
					(thickness 0.1524)
				)
			)
		)
		(property "Device Type" "R402H16"
			(at 0.064008 -5.517896 180)
			(unlocked yes)
			(layer "F.Fab")
			(hide yes)
			(effects
				(font
					(size 1.016 1.016)
					(thickness 0.1524)
				)
			)
		)
		(duplicate_pad_numbers_are_jumpers no)
		(fp_line
			(start 0.508 -0.9398)
			(end -0.508 -0.9398)
			(stroke
				(width 0.1524)
				(type default)
			)
			(layer "F.SilkS")
		)
		(fp_line
			(start -0.508 -0.9398)
			(end -0.508 0.9398)
			(stroke
				(width 0.1524)
				(type default)
			)
			(layer "F.SilkS")
		)
		(fp_rect
			(start -0.508 0.9398)
			(end 0.508 -0.9398)
			(stroke
				(width 0)
				(type default)
			)
			(fill no)
			(layer "F.CrtYd")
		)
		(fp_rect
			(start -0.508 0.9398)
			(end 0.508 -0.9398)
			(stroke
				(width 0)
				(type default)
			)
			(fill no)
			(layer "F.Fab")
		)
		(pad "1" smd custom
			(at 0 -0.4445 180)
			(size 0.1397 0.1397)
			(layers "F.Cu" "F.Mask" "F.Paste")
			(net "DRIVE_A_18_PWR")
			(options
				(clearance outline)
				(anchor circle)
			)
			(primitives
				(gr_poly
					(pts
						(arc
							(start -0.1778 -0.2794)
							(mid -0.249642 -0.249642)
							(end -0.2794 -0.1778)
						)
						(arc
							(start -0.2794 0.1778)
							(mid -0.249642 0.249642)
							(end -0.1778 0.2794)
						)
						(arc
							(start 0.1778 0.2794)
							(mid 0.249642 0.249642)
							(end 0.2794 0.1778)
						)
						(arc
							(start 0.2794 -0.1778)
							(mid 0.249642 -0.249642)
							(end 0.1778 -0.2794)
						)
					)
					(width 0)
					(fill yes)
				)
			)
		)
		(pad "2" smd custom
			(at 0 0.4445 180)
			(size 0.1397 0.1397)
			(layers "F.Cu" "F.Mask" "F.Paste")
			(net "SW_PWR_R_HDD18")
			(options
				(clearance outline)
				(anchor circle)
			)
			(primitives
				(gr_poly
					(pts
						(arc
							(start -0.1778 -0.2794)
							(mid -0.249642 -0.249642)
							(end -0.2794 -0.1778)
						)
						(arc
							(start -0.2794 0.1778)
							(mid -0.249642 0.249642)
							(end -0.1778 0.2794)
						)
						(arc
							(start 0.1778 0.2794)
							(mid 0.249642 0.249642)
							(end 0.2794 0.1778)
						)
						(arc
							(start 0.2794 -0.1778)
							(mid 0.249642 -0.249642)
							(end 0.1778 -0.2794)
						)
					)
					(width 0)
					(fill yes)
				)
			)
		)
	)
	(footprint ""
		(layer "F.Cu")
		(at 176.165002 -242.25377)
		(property "Reference" "R227"
			(at 0 0 0)
			(layer "F.SilkS")
			(hide yes)
			(effects
				(font
					(size 1.27 1.27)
				)
			)
		)
		(property "Value" "91R3F-1-GP"
			(at -0.0254 -2.5146 0)
			(unlocked yes)
			(layer "F.Fab")
			(hide yes)
			(effects
				(font
					(size 1.016 1.016)
					(thickness 0.1524)
				)
			)
		)
		(property "Device Type" "R603H22"
			(at -0.0254 -4.0386 0)
			(unlocked yes)
			(layer "F.Fab")
			(hide yes)
			(effects
				(font
					(size 1.016 1.016)
					(thickness 0.1524)
				)
			)
		)
		(duplicate_pad_numbers_are_jumpers no)
		(fp_line
			(start -0.4826 0)
			(end -0.2032 0)
			(stroke
				(width 0.2032)
				(type default)
			)
			(layer "F.SilkS")
		)
		(fp_line
			(start 0.2032 0)
			(end 0.4826 0)
			(stroke
				(width 0.2032)
				(type default)
			)
			(layer "F.SilkS")
		)
		(fp_rect
			(start -0.5842 1.3335)
			(end 0.5842 -1.3335)
			(stroke
				(width 0)
				(type default)
			)
			(fill no)
			(layer "F.CrtYd")
		)
		(fp_rect
			(start -0.5842 1.3335)
			(end 0.5842 -1.3335)
			(stroke
				(width 0)
				(type default)
			)
			(fill no)
			(layer "F.Fab")
		)
		(pad "1" smd custom
			(at 0 -0.762)
			(size 0.2159 0.2159)
			(layers "F.Cu" "F.Mask" "F.Paste")
			(net "P5V_A_1")
			(options
				(clearance outline)
				(anchor circle)
			)
			(primitives
				(gr_poly
					(pts
						(arc
							(start -0.3302 -0.4318)
							(mid -0.402042 -0.402042)
							(end -0.4318 -0.3302)
						)
						(arc
							(start -0.4318 0.3302)
							(mid -0.402042 0.402042)
							(end -0.3302 0.4318)
						)
						(arc
							(start 0.3302 0.4318)
							(mid 0.402042 0.402042)
							(end 0.4318 0.3302)
						)
						(arc
							(start 0.4318 -0.3302)
							(mid 0.402042 -0.402042)
							(end 0.3302 -0.4318)
						)
					)
					(width 0)
					(fill yes)
				)
			)
		)
		(pad "2" smd custom
			(at 0 0.762)
			(size 0.2159 0.2159)
			(layers "F.Cu" "F.Mask" "F.Paste")
			(net "DRV_ACT_5")
			(options
				(clearance outline)
				(anchor circle)
			)
			(primitives
				(gr_poly
					(pts
						(arc
							(start -0.3302 -0.4318)
							(mid -0.402042 -0.402042)
							(end -0.4318 -0.3302)
						)
						(arc
							(start -0.4318 0.3302)
							(mid -0.402042 0.402042)
							(end -0.3302 0.4318)
						)
						(arc
							(start 0.3302 0.4318)
							(mid 0.402042 0.402042)
							(end 0.4318 0.3302)
						)
						(arc
							(start 0.4318 -0.3302)
							(mid 0.402042 -0.402042)
							(end 0.3302 -0.4318)
						)
					)
					(width 0)
					(fill yes)
				)
			)
		)
	)
	(footprint ""
		(layer "F.Cu")
		(at 300.82236 -65.452752 -90)
		(property "Reference" "C6"
			(at 0 0 270)
			(layer "F.SilkS")
			(hide yes)
			(effects
				(font
					(size 1.27 1.27)
				)
			)
		)
		(property "Value" "SCD1U16V2KX-3GP"
			(at 1.1811 -2.7051 270)
			(unlocked yes)
			(layer "F.Fab")
			(hide yes)
			(effects
				(font
					(size 1.016 1.016)
					(thickness 0.1524)
				)
			)
		)
		(property "Device Type" "C402H22"
			(at 1.1811 -4.2291 270)
			(unlocked yes)
			(layer "F.Fab")
			(hide yes)
			(effects
				(font
					(size 1.016 1.016)
					(thickness 0.1524)
				)
			)
		)
		(duplicate_pad_numbers_are_jumpers no)
		(fp_rect
			(start -0.4318 0.9525)
			(end 0.4318 -0.9525)
			(stroke
				(width 0)
				(type default)
			)
			(fill no)
			(layer "F.CrtYd")
		)
		(fp_rect
			(start -0.4318 0.9525)
			(end 0.4318 -0.9525)
			(stroke
				(width 0)
				(type default)
			)
			(fill no)
			(layer "F.Fab")
		)
		(pad "1" smd custom
			(at 0 -0.4445 270)
			(size 0.1524 0.1524)
			(layers "F.Cu" "F.Mask" "F.Paste")
			(net "P3V3_STBY_B")
			(options
				(clearance outline)
				(anchor circle)
			)
			(primitives
				(gr_poly
					(pts
						(arc
							(start 0.3048 -0.2032)
							(mid 0.275042 -0.275042)
							(end 0.2032 -0.3048)
						)
						(arc
							(start -0.2032 -0.3048)
							(mid -0.275042 -0.275042)
							(end -0.3048 -0.2032)
						)
						(arc
							(start -0.3048 0.2032)
							(mid -0.275042 0.275042)
							(end -0.2032 0.3048)
						)
						(arc
							(start 0.2032 0.3048)
							(mid 0.275042 0.275042)
							(end 0.3048 0.2032)
						)
					)
					(width 0)
					(fill yes)
				)
			)
		)
		(pad "2" smd custom
			(at 0 0.4445 270)
			(size 0.1524 0.1524)
			(layers "F.Cu" "F.Mask" "F.Paste")
			(net "GND")
			(options
				(clearance outline)
				(anchor circle)
			)
			(primitives
				(gr_poly
					(pts
						(arc
							(start 0.3048 -0.2032)
							(mid 0.275042 -0.275042)
							(end 0.2032 -0.3048)
						)
						(arc
							(start -0.2032 -0.3048)
							(mid -0.275042 -0.275042)
							(end -0.3048 -0.2032)
						)
						(arc
							(start -0.3048 0.2032)
							(mid -0.275042 0.275042)
							(end -0.2032 0.3048)
						)
						(arc
							(start 0.2032 0.3048)
							(mid 0.275042 0.275042)
							(end 0.3048 0.2032)
						)
					)
					(width 0)
					(fill yes)
				)
			)
		)
	)
	(footprint ""
		(layer "F.Cu")
		(at 473.961968 -290.20262)
		(property "Reference" "C188"
			(at 0 0 0)
			(layer "F.SilkS")
			(hide yes)
			(effects
				(font
					(size 1.27 1.27)
				)
			)
		)
		(property "Value" "SC4D7U25V5KX-1-GP"
			(at -0.0762 -6.1214 0)
			(unlocked yes)
			(layer "F.Fab")
			(hide yes)
			(effects
				(font
					(size 1.016 1.016)
					(thickness 0.1524)
				)
			)
		)
		(property "Device Type" "C805H58"
			(at -0.0762 -8.1534 0)
			(unlocked yes)
			(layer "F.Fab")
			(hide yes)
			(effects
				(font
					(size 1.016 1.016)
					(thickness 0.1524)
				)
			)
		)
		(duplicate_pad_numbers_are_jumpers no)
		(fp_line
			(start 0.635 0)
			(end -0.635 0)
			(stroke
				(width 0.508)
				(type default)
			)
			(layer "F.SilkS")
		)
		(fp_rect
			(start -0.9652 1.778)
			(end 0.9652 -1.778)
			(stroke
				(width 0)
				(type default)
			)
			(fill no)
			(layer "F.CrtYd")
		)
		(fp_poly
			(pts
				(xy -0.9652 -1.778) (xy 0.9652 -1.778) (xy 0.9652 1.778) (xy -0.9652 1.778)
			)
			(stroke
				(width 0)
				(type default)
			)
			(fill no)
			(layer "F.Fab")
		)
		(pad "1" smd rect
			(at 0 -0.9652)
			(size 1.397 1.143)
			(layers "F.Cu" "F.Mask" "F.Paste")
			(net "P12V_HDD11")
		)
		(pad "2" smd rect
			(at 0 0.9652)
			(size 1.397 1.143)
			(layers "F.Cu" "F.Mask" "F.Paste")
			(net "GND")
		)
	)
	(footprint ""
		(layer "F.Cu")
		(at 447.421 -181.991 90)
		(property "Reference" "C331"
			(at 0 0 90)
			(layer "F.SilkS")
			(hide yes)
			(effects
				(font
					(size 1.27 1.27)
				)
			)
		)
		(property "Value" "SCD01U50V2KX-1GP"
			(at 1.1811 -2.7051 90)
			(unlocked yes)
			(layer "F.Fab")
			(hide yes)
			(effects
				(font
					(size 1.016 1.016)
					(thickness 0.1524)
				)
			)
		)
		(property "Device Type" "C402H22"
			(at 1.1811 -4.2291 90)
			(unlocked yes)
			(layer "F.Fab")
			(hide yes)
			(effects
				(font
					(size 1.016 1.016)
					(thickness 0.1524)
				)
			)
		)
		(duplicate_pad_numbers_are_jumpers no)
		(fp_rect
			(start -0.4318 0.9525)
			(end 0.4318 -0.9525)
			(stroke
				(width 0)
				(type default)
			)
			(fill no)
			(layer "F.CrtYd")
		)
		(fp_rect
			(start -0.4318 0.9525)
			(end 0.4318 -0.9525)
			(stroke
				(width 0)
				(type default)
			)
			(fill no)
			(layer "F.Fab")
		)
		(pad "1" smd custom
			(at 0 -0.4445 90)
			(size 0.1524 0.1524)
			(layers "F.Cu" "F.Mask" "F.Paste")
			(net "HDD_PRSNT_22")
			(options
				(clearance outline)
				(anchor circle)
			)
			(primitives
				(gr_poly
					(pts
						(arc
							(start 0.3048 -0.2032)
							(mid 0.275042 -0.275042)
							(end 0.2032 -0.3048)
						)
						(arc
							(start -0.2032 -0.3048)
							(mid -0.275042 -0.275042)
							(end -0.3048 -0.2032)
						)
						(arc
							(start -0.3048 0.2032)
							(mid -0.275042 0.275042)
							(end -0.2032 0.3048)
						)
						(arc
							(start 0.2032 0.3048)
							(mid 0.275042 0.275042)
							(end 0.3048 0.2032)
						)
					)
					(width 0)
					(fill yes)
				)
			)
		)
		(pad "2" smd custom
			(at 0 0.4445 90)
			(size 0.1524 0.1524)
			(layers "F.Cu" "F.Mask" "F.Paste")
			(net "GND")
			(options
				(clearance outline)
				(anchor circle)
			)
			(primitives
				(gr_poly
					(pts
						(arc
							(start 0.3048 -0.2032)
							(mid 0.275042 -0.275042)
							(end 0.2032 -0.3048)
						)
						(arc
							(start -0.2032 -0.3048)
							(mid -0.275042 -0.275042)
							(end -0.3048 -0.2032)
						)
						(arc
							(start -0.3048 0.2032)
							(mid -0.275042 0.275042)
							(end -0.2032 0.3048)
						)
						(arc
							(start 0.2032 0.3048)
							(mid 0.275042 0.275042)
							(end 0.3048 0.2032)
						)
					)
					(width 0)
					(fill yes)
				)
			)
		)
	)
	(footprint ""
		(layer "F.Cu")
		(at 175.909478 -27.240738 90)
		(property "Reference" "R392"
			(at 0 0 90)
			(layer "F.SilkS")
			(hide yes)
			(effects
				(font
					(size 1.27 1.27)
				)
			)
		)
		(property "Value" "10KR2F-2-GP"
			(at 0.064008 -3.993896 90)
			(unlocked yes)
			(layer "F.Fab")
			(hide yes)
			(effects
				(font
					(size 1.016 1.016)
					(thickness 0.1524)
				)
			)
		)
		(property "Device Type" "R402H16"
			(at 0.064008 -5.517896 90)
			(unlocked yes)
			(layer "F.Fab")
			(hide yes)
			(effects
				(font
					(size 1.016 1.016)
					(thickness 0.1524)
				)
			)
		)
		(duplicate_pad_numbers_are_jumpers no)
		(fp_line
			(start 0.508 -0.9398)
			(end -0.508 -0.9398)
			(stroke
				(width 0.1524)
				(type default)
			)
			(layer "F.SilkS")
		)
		(fp_line
			(start -0.508 -0.9398)
			(end -0.508 0.9398)
			(stroke
				(width 0.1524)
				(type default)
			)
			(layer "F.SilkS")
		)
		(fp_rect
			(start -0.508 0.9398)
			(end 0.508 -0.9398)
			(stroke
				(width 0)
				(type default)
			)
			(fill no)
			(layer "F.CrtYd")
		)
		(fp_rect
			(start -0.508 0.9398)
			(end 0.508 -0.9398)
			(stroke
				(width 0)
				(type default)
			)
			(fill no)
			(layer "F.Fab")
		)
		(pad "1" smd custom
			(at 0 -0.4445 90)
			(size 0.1397 0.1397)
			(layers "F.Cu" "F.Mask" "F.Paste")
			(net "SYS_A_RESET_BUFFER_N")
			(options
				(clearance outline)
				(anchor circle)
			)
			(primitives
				(gr_poly
					(pts
						(arc
							(start -0.1778 -0.2794)
							(mid -0.249642 -0.249642)
							(end -0.2794 -0.1778)
						)
						(arc
							(start -0.2794 0.1778)
							(mid -0.249642 0.249642)
							(end -0.1778 0.2794)
						)
						(arc
							(start 0.1778 0.2794)
							(mid 0.249642 0.249642)
							(end 0.2794 0.1778)
						)
						(arc
							(start 0.2794 -0.1778)
							(mid 0.249642 -0.249642)
							(end 0.1778 -0.2794)
						)
					)
					(width 0)
					(fill yes)
				)
			)
		)
		(pad "2" smd custom
			(at 0 0.4445 90)
			(size 0.1397 0.1397)
			(layers "F.Cu" "F.Mask" "F.Paste")
			(net "GND")
			(options
				(clearance outline)
				(anchor circle)
			)
			(primitives
				(gr_poly
					(pts
						(arc
							(start -0.1778 -0.2794)
							(mid -0.249642 -0.249642)
							(end -0.2794 -0.1778)
						)
						(arc
							(start -0.2794 0.1778)
							(mid -0.249642 0.249642)
							(end -0.1778 0.2794)
						)
						(arc
							(start 0.1778 0.2794)
							(mid 0.249642 0.249642)
							(end 0.2794 0.1778)
						)
						(arc
							(start 0.2794 -0.1778)
							(mid 0.249642 -0.249642)
							(end 0.1778 -0.2794)
						)
					)
					(width 0)
					(fill yes)
				)
			)
		)
	)
	(footprint ""
		(layer "F.Cu")
		(at 325.550022 -287.910016 -90)
		(property "Reference" "HDDSAS6"
			(at 0 0 270)
			(layer "F.SilkS")
			(hide yes)
			(effects
				(font
					(size 1.27 1.27)
				)
			)
		)
		(property "Value" "SKT-SAS15P-14P-45-GP"
			(at -20.7645 -8.9789 270)
			(unlocked yes)
			(layer "F.Fab")
			(hide yes)
			(effects
				(font
					(size 1.016 1.016)
					(thickness 0.1524)
				)
			)
		)
		(property "Device Type" "10120818-001C-TRLF"
			(at -20.7645 -10.5029 270)
			(unlocked yes)
			(layer "F.Fab")
			(hide yes)
			(effects
				(font
					(size 1.016 1.016)
					(thickness 0.1524)
				)
			)
		)
		(duplicate_pad_numbers_are_jumpers no)
		(fp_line
			(start 1.651 4.2926)
			(end 1.651 3.0099)
			(stroke
				(width 0.1524)
				(type default)
			)
			(layer "F.SilkS")
		)
		(fp_line
			(start 8.509 4.2926)
			(end 1.651 4.2926)
			(stroke
				(width 0.1524)
				(type default)
			)
			(layer "F.SilkS")
		)
		(fp_line
			(start -23.4188 3.0099)
			(end -23.4188 -3.2512)
			(stroke
				(width 0.1524)
				(type default)
			)
			(layer "F.SilkS")
		)
		(fp_line
			(start 1.651 3.0099)
			(end -23.4188 3.0099)
			(stroke
				(width 0.1524)
				(type default)
			)
			(layer "F.SilkS")
		)
		(fp_line
			(start 8.509 3.0099)
			(end 8.509 4.2926)
			(stroke
				(width 0.1524)
				(type default)
			)
			(layer "F.SilkS")
		)
		(fp_line
			(start 23.4188 3.0099)
			(end 8.509 3.0099)
			(stroke
				(width 0.1524)
				(type default)
			)
			(layer "F.SilkS")
		)
		(fp_line
			(start -23.4188 -3.2512)
			(end 23.4188 -3.2512)
			(stroke
				(width 0.1524)
				(type default)
			)
			(layer "F.SilkS")
		)
		(fp_line
			(start 23.4188 -3.2512)
			(end 23.4188 3.0099)
			(stroke
				(width 0.1524)
				(type default)
			)
			(layer "F.SilkS")
		)
		(fp_line
			(start 15.5067 -3.3401)
			(end 16.2687 -3.3401)
			(stroke
				(width 0.3302)
				(type default)
			)
			(layer "F.SilkS")
		)
		(fp_poly
			(pts
				(xy 15.868904 -3.230372) (xy 16.503904 -3.865372) (xy 15.233904 -3.865372)
			)
			(stroke
				(width 0)
				(type default)
			)
			(fill yes)
			(layer "F.SilkS")
		)
		(fp_poly
			(pts
				(xy -22.8727 -2.7559) (xy 22.8727 -2.7559) (xy 22.8727 2.7559) (xy 8.255 2.7559) (xy 8.255 3.5179)
				(xy 1.905 3.5179) (xy 1.905 2.7559) (xy -22.8727 2.7559)
			)
			(stroke
				(width 0)
				(type default)
			)
			(fill no)
			(layer "F.CrtYd")
		)
		(fp_poly
			(pts
				(xy 1.397 4.5466) (xy 1.397 3.2639) (xy -23.6728 3.2639) (xy -23.6728 -3.5052) (xy 23.6728 -3.5052)
				(xy 23.6728 -0.00635) (xy 22.8727 -0.00635) (xy 22.8727 -2.7559) (xy -22.8727 -2.7559) (xy -22.8727 2.7559)
				(xy 1.905 2.7559) (xy 1.905 3.5179) (xy 8.255 3.5179) (xy 8.255 2.7559) (xy 22.8727 2.7559) (xy 22.8727 0.00635)
				(xy 23.6728 0.00635) (xy 23.6728 3.2639) (xy 8.763 3.2639) (xy 8.763 4.5466)
			)
			(stroke
				(width 0)
				(type default)
			)
			(fill no)
			(layer "F.CrtYd")
		)
		(fp_poly
			(pts
				(xy 1.397 4.5466) (xy 1.397 3.2639) (xy -23.6728 3.2639) (xy -23.6728 -3.5052) (xy 23.6728 -3.5052)
				(xy 23.6728 3.2639) (xy 8.763 3.2639) (xy 8.763 4.5466)
			)
			(stroke
				(width 0)
				(type default)
			)
			(fill no)
			(layer "F.Fab")
		)
		(pad "" np_thru_hole circle
			(at -18.874994 0 270)
			(size 0.254 0.254)
			(drill 1.3462)
			(layers "*.Cu" "*.Mask")
			(clearance 0.9017)
			(thermal_gap 0.9017)
		)
		(pad "" np_thru_hole circle
			(at 18.874994 0 270)
			(size 0.254 0.254)
			(drill 0.9398)
			(layers "*.Cu" "*.Mask")
			(clearance 0.6985)
			(thermal_gap 0.6985)
		)
		(pad "G1" smd rect
			(at 21.874988 0 270)
			(size 2.5908 2.5908)
			(layers "F.Cu" "F.Mask" "F.Paste")
			(net "GND")
		)
		(pad "G2" smd rect
			(at -21.874988 0 270)
			(size 2.5908 2.5908)
			(layers "F.Cu" "F.Mask" "F.Paste")
			(net "GND")
		)
		(pad "P1" smd rect
			(at 1.905 -1.82499 270)
			(size 0.6096 2.3622)
			(layers "F.Cu" "F.Mask" "F.Paste")
			(net "Net_2011")
		)
		(pad "P2" smd rect
			(at 0.635 -1.82499 270)
			(size 0.6096 2.3622)
			(layers "F.Cu" "F.Mask" "F.Paste")
			(net "Net_2012")
		)
		(pad "P3" smd rect
			(at -0.635 -1.82499 270)
			(size 0.6096 2.3622)
			(layers "F.Cu" "F.Mask" "F.Paste")
			(net "Net_2013")
		)
		(pad "P4" smd rect
			(at -1.905 -1.82499 270)
			(size 0.6096 2.3622)
			(layers "F.Cu" "F.Mask" "F.Paste")
			(net "GND")
		)
		(pad "P5" smd rect
			(at -3.175 -1.82499 270)
			(size 0.6096 2.3622)
			(layers "F.Cu" "F.Mask" "F.Paste")
			(net "HDD_PRSNT_6")
		)
		(pad "P6" smd rect
			(at -4.445 -1.82499 270)
			(size 0.6096 2.3622)
			(layers "F.Cu" "F.Mask" "F.Paste")
			(net "GND")
		)
		(pad "P7" smd rect
			(at -5.715 -1.82499 270)
			(size 0.6096 2.3622)
			(layers "F.Cu" "F.Mask" "F.Paste")
			(net "5V_PRE_6")
		)
		(pad "P8" smd rect
			(at -6.985 -1.82499 270)
			(size 0.6096 2.3622)
			(layers "F.Cu" "F.Mask" "F.Paste")
			(net "P5V_HDD6")
		)
		(pad "P9" smd rect
			(at -8.255 -1.82499 270)
			(size 0.6096 2.3622)
			(layers "F.Cu" "F.Mask" "F.Paste")
			(net "P5V_HDD6")
		)
		(pad "P10" smd rect
			(at -9.525 -1.82499 270)
			(size 0.6096 2.3622)
			(layers "F.Cu" "F.Mask" "F.Paste")
			(net "GND")
		)
		(pad "P11" smd rect
			(at -10.795 -1.82499 270)
			(size 0.6096 2.3622)
			(layers "F.Cu" "F.Mask" "F.Paste")
			(net "ACT_HDD_6")
		)
		(pad "P12" smd rect
			(at -12.065 -1.82499 270)
			(size 0.6096 2.3622)
			(layers "F.Cu" "F.Mask" "F.Paste")
			(net "GND")
		)
		(pad "P13" smd rect
			(at -13.335 -1.82499 270)
			(size 0.6096 2.3622)
			(layers "F.Cu" "F.Mask" "F.Paste")
			(net "12V_PRE_6")
		)
		(pad "P14" smd rect
			(at -14.605 -1.82499 270)
			(size 0.6096 2.3622)
			(layers "F.Cu" "F.Mask" "F.Paste")
			(net "P12V_HDD6")
		)
		(pad "P15" smd rect
			(at -15.875 -1.82499 270)
			(size 0.6096 2.3622)
			(layers "F.Cu" "F.Mask" "F.Paste")
			(net "P12V_HDD6")
		)
		(pad "S1" smd rect
			(at 15.875 -1.82499 270)
			(size 0.6096 2.3622)
			(layers "F.Cu" "F.Mask" "F.Paste")
			(net "GND")
		)
		(pad "S2" smd rect
			(at 14.605 -1.82499 270)
			(size 0.6096 2.3622)
			(layers "F.Cu" "F.Mask" "F.Paste")
			(net "SAS_HDD_RX_P6")
		)
		(pad "S3" smd rect
			(at 13.335 -1.82499 270)
			(size 0.6096 2.3622)
			(layers "F.Cu" "F.Mask" "F.Paste")
			(net "SAS_HDD_RX_N6")
		)
		(pad "S4" smd rect
			(at 12.065 -1.82499 270)
			(size 0.6096 2.3622)
			(layers "F.Cu" "F.Mask" "F.Paste")
			(net "GND")
		)
		(pad "S5" smd rect
			(at 10.795 -1.82499 270)
			(size 0.6096 2.3622)
			(layers "F.Cu" "F.Mask" "F.Paste")
			(net "PHY_DRV_A_TO_SCC_A_6_DN")
		)
		(pad "S6" smd rect
			(at 9.525 -1.82499 270)
			(size 0.6096 2.3622)
			(layers "F.Cu" "F.Mask" "F.Paste")
			(net "PHY_DRV_A_TO_SCC_A_6_DP")
		)
		(pad "S7" smd rect
			(at 8.255 -1.82499 270)
			(size 0.6096 2.3622)
			(layers "F.Cu" "F.Mask" "F.Paste")
			(net "GND")
		)
		(pad "S8" smd rect
			(at 7.480046 2.845054 270)
			(size 0.508 2.3622)
			(layers "F.Cu" "F.Mask" "F.Paste")
			(net "GND")
		)
		(pad "S9" smd rect
			(at 6.679946 2.845054 270)
			(size 0.508 2.3622)
			(layers "F.Cu" "F.Mask" "F.Paste")
			(net "Net_478")
		)
		(pad "S10" smd rect
			(at 5.8801 2.845054 270)
			(size 0.508 2.3622)
			(layers "F.Cu" "F.Mask" "F.Paste")
			(net "Net_370")
		)
		(pad "S11" smd rect
			(at 5.08 2.845054 270)
			(size 0.508 2.3622)
			(layers "F.Cu" "F.Mask" "F.Paste")
			(net "GND")
		)
		(pad "S12" smd rect
			(at 4.2799 2.845054 270)
			(size 0.508 2.3622)
			(layers "F.Cu" "F.Mask" "F.Paste")
			(net "Net_406")
		)
		(pad "S13" smd rect
			(at 3.480054 2.845054 270)
			(size 0.508 2.3622)
			(layers "F.Cu" "F.Mask" "F.Paste")
			(net "Net_442")
		)
		(pad "S14" smd rect
			(at 2.679954 2.845054 270)
			(size 0.508 2.3622)
			(layers "F.Cu" "F.Mask" "F.Paste")
			(net "GND")
		)
		(zone
			(layer "F.Cu")
			(hatch none 0.5)
			(connect_pads
				(clearance 0)
			)
			(min_thickness 0.25)
			(keepout
				(tracks allowed)
				(vias not_allowed)
				(pads allowed)
				(copperpour not_allowed)
				(footprints allowed)
			)
			(placement
				(enabled no)
				(sheetname "")
			)
			(fill
				(thermal_gap 0.5)
				(thermal_bridge_width 0.5)
				(island_removal_mode 0)
			)
			(polygon
				(pts
					(xy 329.207622 -304.648616) (xy 322.133722 -304.648616) (xy 322.133722 -311.582816) (xy 323.238622 -311.582816)
					(xy 323.238622 -307.468016) (xy 327.861422 -307.468016) (xy 327.861422 -311.582816) (xy 329.207622 -311.582816)
				)
			)
		)
		(zone
			(layer "F.Cu")
			(hatch none 0.5)
			(connect_pads
				(clearance 0)
			)
			(min_thickness 0.25)
			(keepout
				(tracks not_allowed)
				(vias allowed)
				(pads allowed)
				(copperpour not_allowed)
				(footprints allowed)
			)
			(placement
				(enabled no)
				(sheetname "")
			)
			(fill
				(thermal_gap 0.5)
				(thermal_bridge_width 0.5)
				(island_removal_mode 0)
			)
			(polygon
				(pts
					(xy 329.207622 -304.648616) (xy 322.133722 -304.648616) (xy 322.133722 -311.582816) (xy 323.238622 -311.582816)
					(xy 323.238622 -307.468016) (xy 327.861422 -307.468016) (xy 327.861422 -311.582816) (xy 329.207622 -311.582816)
				)
			)
		)
		(zone
			(layer "F.Cu")
			(hatch none 0.5)
			(connect_pads
				(clearance 0)
			)
			(min_thickness 0.25)
			(keepout
				(tracks allowed)
				(vias not_allowed)
				(pads allowed)
				(copperpour not_allowed)
				(footprints allowed)
			)
			(placement
				(enabled no)
				(sheetname "")
			)
			(fill
				(thermal_gap 0.5)
				(thermal_bridge_width 0.5)
				(island_removal_mode 0)
			)
			(polygon
				(pts
					(xy 329.207622 -271.171416) (xy 322.133722 -271.171416) (xy 322.133722 -264.237216) (xy 323.238622 -264.237216)
					(xy 323.238622 -268.352016) (xy 327.861422 -268.352016) (xy 327.861422 -264.237216) (xy 329.207622 -264.237216)
				)
			)
		)
		(zone
			(layer "F.Cu")
			(hatch none 0.5)
			(connect_pads
				(clearance 0)
			)
			(min_thickness 0.25)
			(keepout
				(tracks not_allowed)
				(vias allowed)
				(pads allowed)
				(copperpour not_allowed)
				(footprints allowed)
			)
			(placement
				(enabled no)
				(sheetname "")
			)
			(fill
				(thermal_gap 0.5)
				(thermal_bridge_width 0.5)
				(island_removal_mode 0)
			)
			(polygon
				(pts
					(xy 329.207622 -271.171416) (xy 322.133722 -271.171416) (xy 322.133722 -264.237216) (xy 323.238622 -264.237216)
					(xy 323.238622 -268.352016) (xy 327.861422 -268.352016) (xy 327.861422 -264.237216) (xy 329.207622 -264.237216)
				)
			)
		)
		(zone
			(layers "F.Cu" "B.Cu" "In1.Cu" "In2.Cu" "In3.Cu" "In4.Cu" "In5.Cu" "In6.Cu"
				"In7.Cu" "In8.Cu" "In9.Cu" "In10.Cu"
			)
			(hatch none 0.5)
			(connect_pads
				(clearance 0)
			)
			(min_thickness 0.25)
			(keepout
				(tracks not_allowed)
				(vias allowed)
				(pads allowed)
				(copperpour not_allowed)
				(footprints allowed)
			)
			(placement
				(enabled no)
				(sheetname "")
			)
			(fill
				(thermal_gap 0.5)
				(thermal_bridge_width 0.5)
				(island_removal_mode 0)
			)
			(polygon
				(pts
					(arc
						(start 326.324722 -269.035022)
						(mid 324.775322 -269.035022)
						(end 326.324722 -269.035022)
					)
				)
			)
		)
		(zone
			(layers "F.Cu" "B.Cu" "In1.Cu" "In2.Cu" "In3.Cu" "In4.Cu" "In5.Cu" "In6.Cu"
				"In7.Cu" "In8.Cu" "In9.Cu" "In10.Cu"
			)
			(hatch none 0.5)
			(connect_pads
				(clearance 0)
			)
			(min_thickness 0.25)
			(keepout
				(tracks not_allowed)
				(vias allowed)
				(pads allowed)
				(copperpour not_allowed)
				(footprints allowed)
			)
			(placement
				(enabled no)
				(sheetname "")
			)
			(fill
				(thermal_gap 0.5)
				(thermal_bridge_width 0.5)
				(island_removal_mode 0)
			)
			(polygon
				(pts
					(arc
						(start 326.527922 -306.78501)
						(mid 324.572122 -306.78501)
						(end 326.527922 -306.78501)
					)
				)
			)
		)
	)
	(footprint ""
		(layer "F.Cu")
		(at 482.489002 -162.749992 -90)
		(property "Reference" "VIA23"
			(at 0 0 270)
			(layer "F.SilkS")
			(hide yes)
			(effects
				(font
					(size 1.27 1.27)
				)
			)
		)
		(property "Value" "100OHM-8L-1D6MM-L18L16-GP"
			(at -3.7211 -4.5085 270)
			(unlocked yes)
			(layer "F.Fab")
			(hide yes)
			(effects
				(font
					(size 1.016 1.016)
					(thickness 0.1524)
				)
			)
		)
		(property "Device Type" "VIA-PCIE-4P-394076"
			(at -3.7211 -6.0325 270)
			(unlocked yes)
			(layer "F.Fab")
			(hide yes)
			(effects
				(font
					(size 1.016 1.016)
					(thickness 0.1524)
				)
			)
		)
		(duplicate_pad_numbers_are_jumpers no)
		(fp_rect
			(start -1.9685 0.381)
			(end 1.9685 -0.381)
			(stroke
				(width 0)
				(type default)
			)
			(fill no)
			(layer "F.CrtYd")
		)
		(fp_rect
			(start -1.9685 0.381)
			(end 1.9685 -0.381)
			(stroke
				(width 0)
				(type default)
			)
			(fill no)
			(layer "F.Fab")
		)
		(pad "1" thru_hole circle
			(at -1.5875 0 270)
			(size 0.508 0.508)
			(drill 0.254)
			(layers "*.Cu" "*.Mask")
			(remove_unused_layers no)
			(net "GND")
			(clearance 0.127)
			(thermal_gap 0.127)
		)
		(pad "2" thru_hole circle
			(at -0.5715 0 270)
			(size 0.508 0.508)
			(drill 0.254)
			(layers "*.Cu" "*.Mask")
			(remove_unused_layers no)
			(net "PHY_DRV_A_TO_SCC_A_23_DP")
			(clearance 0.127)
			(thermal_gap 0.127)
		)
		(pad "3" thru_hole circle
			(at 0.5715 0 270)
			(size 0.508 0.508)
			(drill 0.254)
			(layers "*.Cu" "*.Mask")
			(remove_unused_layers no)
			(net "PHY_DRV_A_TO_SCC_A_23_DN")
			(clearance 0.127)
			(thermal_gap 0.127)
		)
		(pad "4" thru_hole circle
			(at 1.5875 0 270)
			(size 0.508 0.508)
			(drill 0.254)
			(layers "*.Cu" "*.Mask")
			(remove_unused_layers no)
			(net "GND")
			(clearance 0.127)
			(thermal_gap 0.127)
		)
	)
	(footprint ""
		(layer "F.Cu")
		(at 362.310426 -131.891278)
		(property "Reference" "C566"
			(at 0 0 0)
			(layer "F.SilkS")
			(hide yes)
			(effects
				(font
					(size 1.27 1.27)
				)
			)
		)
		(property "Value" "SC1U16V3KX-5GP"
			(at 0 -2.8194 0)
			(unlocked yes)
			(layer "F.Fab")
			(hide yes)
			(effects
				(font
					(size 1.016 1.016)
					(thickness 0.1524)
				)
			)
		)
		(property "Device Type" "C603H36"
			(at 0 -4.3434 0)
			(unlocked yes)
			(layer "F.Fab")
			(hide yes)
			(effects
				(font
					(size 1.016 1.016)
					(thickness 0.1524)
				)
			)
		)
		(duplicate_pad_numbers_are_jumpers no)
		(fp_line
			(start 0.508 0)
			(end -0.508 0)
			(stroke
				(width 0.2032)
				(type default)
			)
			(layer "F.SilkS")
		)
		(fp_rect
			(start -0.5842 1.3335)
			(end 0.5842 -1.3335)
			(stroke
				(width 0)
				(type default)
			)
			(fill no)
			(layer "F.CrtYd")
		)
		(fp_rect
			(start -0.5842 1.3335)
			(end 0.5842 -1.3335)
			(stroke
				(width 0)
				(type default)
			)
			(fill no)
			(layer "F.Fab")
		)
		(pad "1" smd custom
			(at 0 -0.762)
			(size 0.2159 0.2159)
			(layers "F.Cu" "F.Mask" "F.Paste")
			(net "MB1_CM_OV_R")
			(options
				(clearance outline)
				(anchor circle)
			)
			(primitives
				(gr_poly
					(pts
						(arc
							(start -0.3302 -0.4318)
							(mid -0.402042 -0.402042)
							(end -0.4318 -0.3302)
						)
						(arc
							(start -0.4318 0.3302)
							(mid -0.402042 0.402042)
							(end -0.3302 0.4318)
						)
						(arc
							(start 0.3302 0.4318)
							(mid 0.402042 0.402042)
							(end 0.4318 0.3302)
						)
						(arc
							(start 0.4318 -0.3302)
							(mid 0.402042 -0.402042)
							(end 0.3302 -0.4318)
						)
					)
					(width 0)
					(fill yes)
				)
			)
		)
		(pad "2" smd custom
			(at 0 0.762)
			(size 0.2159 0.2159)
			(layers "F.Cu" "F.Mask" "F.Paste")
			(net "AGND_CURRENT_MONOB")
			(options
				(clearance outline)
				(anchor circle)
			)
			(primitives
				(gr_poly
					(pts
						(arc
							(start -0.3302 -0.4318)
							(mid -0.402042 -0.402042)
							(end -0.4318 -0.3302)
						)
						(arc
							(start -0.4318 0.3302)
							(mid -0.402042 0.402042)
							(end -0.3302 0.4318)
						)
						(arc
							(start 0.3302 0.4318)
							(mid 0.402042 0.402042)
							(end 0.4318 0.3302)
						)
						(arc
							(start 0.4318 -0.3302)
							(mid 0.402042 -0.402042)
							(end 0.3302 -0.4318)
						)
					)
					(width 0)
					(fill yes)
				)
			)
		)
	)
	(footprint ""
		(layer "F.Cu")
		(at 333.248 -42.585894 180)
		(property "Reference" "R828"
			(at 0 0 180)
			(layer "F.SilkS")
			(hide yes)
			(effects
				(font
					(size 1.27 1.27)
				)
			)
		)
		(property "Value" "1KR2F-3-GP"
			(at 0.064008 -3.993896 180)
			(unlocked yes)
			(layer "F.Fab")
			(hide yes)
			(effects
				(font
					(size 1.016 1.016)
					(thickness 0.1524)
				)
			)
		)
		(property "Device Type" "R402H16"
			(at 0.064008 -5.517896 180)
			(unlocked yes)
			(layer "F.Fab")
			(hide yes)
			(effects
				(font
					(size 1.016 1.016)
					(thickness 0.1524)
				)
			)
		)
		(duplicate_pad_numbers_are_jumpers no)
		(fp_line
			(start 0.508 -0.9398)
			(end -0.508 -0.9398)
			(stroke
				(width 0.1524)
				(type default)
			)
			(layer "F.SilkS")
		)
		(fp_line
			(start -0.508 -0.9398)
			(end -0.508 0.9398)
			(stroke
				(width 0.1524)
				(type default)
			)
			(layer "F.SilkS")
		)
		(fp_rect
			(start -0.508 0.9398)
			(end 0.508 -0.9398)
			(stroke
				(width 0)
				(type default)
			)
			(fill no)
			(layer "F.CrtYd")
		)
		(fp_rect
			(start -0.508 0.9398)
			(end 0.508 -0.9398)
			(stroke
				(width 0)
				(type default)
			)
			(fill no)
			(layer "F.Fab")
		)
		(pad "1" smd custom
			(at 0 -0.4445 180)
			(size 0.1397 0.1397)
			(layers "F.Cu" "F.Mask" "F.Paste")
			(net "P3V3_STBY_A")
			(options
				(clearance outline)
				(anchor circle)
			)
			(primitives
				(gr_poly
					(pts
						(arc
							(start -0.1778 -0.2794)
							(mid -0.249642 -0.249642)
							(end -0.2794 -0.1778)
						)
						(arc
							(start -0.2794 0.1778)
							(mid -0.249642 0.249642)
							(end -0.1778 0.2794)
						)
						(arc
							(start 0.1778 0.2794)
							(mid 0.249642 0.249642)
							(end 0.2794 0.1778)
						)
						(arc
							(start 0.2794 -0.1778)
							(mid 0.249642 -0.249642)
							(end 0.1778 -0.2794)
						)
					)
					(width 0)
					(fill yes)
				)
			)
		)
		(pad "2" smd custom
			(at 0 0.4445 180)
			(size 0.1397 0.1397)
			(layers "F.Cu" "F.Mask" "F.Paste")
			(net "SW_PWR_R_HDD30")
			(options
				(clearance outline)
				(anchor circle)
			)
			(primitives
				(gr_poly
					(pts
						(arc
							(start -0.1778 -0.2794)
							(mid -0.249642 -0.249642)
							(end -0.2794 -0.1778)
						)
						(arc
							(start -0.2794 0.1778)
							(mid -0.249642 0.249642)
							(end -0.1778 0.2794)
						)
						(arc
							(start 0.1778 0.2794)
							(mid 0.249642 0.249642)
							(end 0.2794 0.1778)
						)
						(arc
							(start 0.2794 -0.1778)
							(mid 0.249642 -0.249642)
							(end 0.1778 -0.2794)
						)
					)
					(width 0)
					(fill yes)
				)
			)
		)
	)
	(footprint ""
		(layer "F.Cu")
		(at 353.184714 -159.219392 -90)
		(property "Reference" "C285"
			(at 0 0 270)
			(layer "F.SilkS")
			(hide yes)
			(effects
				(font
					(size 1.27 1.27)
				)
			)
		)
		(property "Value" "SCD01U16V1KX-GP"
			(at -2.8321 -1.7399 270)
			(unlocked yes)
			(layer "F.Fab")
			(hide yes)
			(effects
				(font
					(size 1.016 1.016)
					(thickness 0.1524)
				)
			)
		)
		(property "Device Type" "C0201H13"
			(at -2.8321 -3.2639 270)
			(unlocked yes)
			(layer "F.Fab")
			(hide yes)
			(effects
				(font
					(size 1.016 1.016)
					(thickness 0.1524)
				)
			)
		)
		(duplicate_pad_numbers_are_jumpers no)
		(fp_rect
			(start -0.2794 0.6477)
			(end 0.2794 -0.6477)
			(stroke
				(width 0)
				(type default)
			)
			(fill no)
			(layer "F.CrtYd")
		)
		(fp_rect
			(start -0.2794 0.6477)
			(end 0.2794 -0.6477)
			(stroke
				(width 0)
				(type default)
			)
			(fill no)
			(layer "F.Fab")
		)
		(pad "1" smd custom
			(at 0 -0.2794 270)
			(size 0.0762 0.0762)
			(layers "F.Cu" "F.Mask" "F.Paste")
			(net "SAS_HDD_RX_N19")
			(options
				(clearance outline)
				(anchor circle)
			)
			(primitives
				(gr_poly
					(pts
						(arc
							(start 0.1524 -0.127)
							(mid 0.137521 -0.162921)
							(end 0.1016 -0.1778)
						)
						(arc
							(start -0.1016 -0.1778)
							(mid -0.137521 -0.162921)
							(end -0.1524 -0.127)
						)
						(arc
							(start -0.1524 0.127)
							(mid -0.137521 0.162921)
							(end -0.1016 0.1778)
						)
						(arc
							(start 0.1016 0.1778)
							(mid 0.137521 0.162921)
							(end 0.1524 0.127)
						)
					)
					(width 0)
					(fill yes)
				)
			)
		)
		(pad "2" smd custom
			(at 0 0.2794 270)
			(size 0.0762 0.0762)
			(layers "F.Cu" "F.Mask" "F.Paste")
			(net "PHY_SCC_A_TO_DRV_A_19_DN")
			(options
				(clearance outline)
				(anchor circle)
			)
			(primitives
				(gr_poly
					(pts
						(arc
							(start 0.1524 -0.127)
							(mid 0.137521 -0.162921)
							(end 0.1016 -0.1778)
						)
						(arc
							(start -0.1016 -0.1778)
							(mid -0.137521 -0.162921)
							(end -0.1524 -0.127)
						)
						(arc
							(start -0.1524 0.127)
							(mid -0.137521 0.162921)
							(end -0.1016 0.1778)
						)
						(arc
							(start 0.1016 0.1778)
							(mid 0.137521 0.162921)
							(end 0.1524 0.127)
						)
					)
					(width 0)
					(fill yes)
				)
			)
		)
	)
	(footprint ""
		(layer "F.Cu")
		(at 424.469052 -296.842942 180)
		(property "Reference" "C157"
			(at 0 0 180)
			(layer "F.SilkS")
			(hide yes)
			(effects
				(font
					(size 1.27 1.27)
				)
			)
		)
		(property "Value" "SC1U16V3KX-5GP"
			(at 0 -2.8194 180)
			(unlocked yes)
			(layer "F.Fab")
			(hide yes)
			(effects
				(font
					(size 1.016 1.016)
					(thickness 0.1524)
				)
			)
		)
		(property "Device Type" "C603H36"
			(at 0 -4.3434 180)
			(unlocked yes)
			(layer "F.Fab")
			(hide yes)
			(effects
				(font
					(size 1.016 1.016)
					(thickness 0.1524)
				)
			)
		)
		(duplicate_pad_numbers_are_jumpers no)
		(fp_line
			(start 0.508 0)
			(end -0.508 0)
			(stroke
				(width 0.2032)
				(type default)
			)
			(layer "F.SilkS")
		)
		(fp_rect
			(start -0.5842 1.3335)
			(end 0.5842 -1.3335)
			(stroke
				(width 0)
				(type default)
			)
			(fill no)
			(layer "F.CrtYd")
		)
		(fp_rect
			(start -0.5842 1.3335)
			(end 0.5842 -1.3335)
			(stroke
				(width 0)
				(type default)
			)
			(fill no)
			(layer "F.Fab")
		)
		(pad "1" smd custom
			(at 0 -0.762 180)
			(size 0.2159 0.2159)
			(layers "F.Cu" "F.Mask" "F.Paste")
			(net "P5V_HDD9")
			(options
				(clearance outline)
				(anchor circle)
			)
			(primitives
				(gr_poly
					(pts
						(arc
							(start -0.3302 -0.4318)
							(mid -0.402042 -0.402042)
							(end -0.4318 -0.3302)
						)
						(arc
							(start -0.4318 0.3302)
							(mid -0.402042 0.402042)
							(end -0.3302 0.4318)
						)
						(arc
							(start 0.3302 0.4318)
							(mid 0.402042 0.402042)
							(end 0.4318 0.3302)
						)
						(arc
							(start 0.4318 -0.3302)
							(mid 0.402042 -0.402042)
							(end 0.3302 -0.4318)
						)
					)
					(width 0)
					(fill yes)
				)
			)
		)
		(pad "2" smd custom
			(at 0 0.762 180)
			(size 0.2159 0.2159)
			(layers "F.Cu" "F.Mask" "F.Paste")
			(net "GND")
			(options
				(clearance outline)
				(anchor circle)
			)
			(primitives
				(gr_poly
					(pts
						(arc
							(start -0.3302 -0.4318)
							(mid -0.402042 -0.402042)
							(end -0.4318 -0.3302)
						)
						(arc
							(start -0.4318 0.3302)
							(mid -0.402042 0.402042)
							(end -0.3302 0.4318)
						)
						(arc
							(start 0.3302 0.4318)
							(mid 0.402042 0.402042)
							(end 0.4318 0.3302)
						)
						(arc
							(start 0.4318 -0.3302)
							(mid 0.402042 -0.402042)
							(end 0.3302 -0.4318)
						)
					)
					(width 0)
					(fill yes)
				)
			)
		)
	)
	(footprint ""
		(layer "F.Cu")
		(at 353.184714 -43.660568 -90)
		(property "Reference" "C442"
			(at 0 0 270)
			(layer "F.SilkS")
			(hide yes)
			(effects
				(font
					(size 1.27 1.27)
				)
			)
		)
		(property "Value" "SCD01U16V1KX-GP"
			(at -2.8321 -1.7399 270)
			(unlocked yes)
			(layer "F.Fab")
			(hide yes)
			(effects
				(font
					(size 1.016 1.016)
					(thickness 0.1524)
				)
			)
		)
		(property "Device Type" "C0201H13"
			(at -2.8321 -3.2639 270)
			(unlocked yes)
			(layer "F.Fab")
			(hide yes)
			(effects
				(font
					(size 1.016 1.016)
					(thickness 0.1524)
				)
			)
		)
		(duplicate_pad_numbers_are_jumpers no)
		(fp_rect
			(start -0.2794 0.6477)
			(end 0.2794 -0.6477)
			(stroke
				(width 0)
				(type default)
			)
			(fill no)
			(layer "F.CrtYd")
		)
		(fp_rect
			(start -0.2794 0.6477)
			(end 0.2794 -0.6477)
			(stroke
				(width 0)
				(type default)
			)
			(fill no)
			(layer "F.Fab")
		)
		(pad "1" smd custom
			(at 0 -0.2794 270)
			(size 0.0762 0.0762)
			(layers "F.Cu" "F.Mask" "F.Paste")
			(net "SAS_HDD_RX_P31")
			(options
				(clearance outline)
				(anchor circle)
			)
			(primitives
				(gr_poly
					(pts
						(arc
							(start 0.1524 -0.127)
							(mid 0.137521 -0.162921)
							(end 0.1016 -0.1778)
						)
						(arc
							(start -0.1016 -0.1778)
							(mid -0.137521 -0.162921)
							(end -0.1524 -0.127)
						)
						(arc
							(start -0.1524 0.127)
							(mid -0.137521 0.162921)
							(end -0.1016 0.1778)
						)
						(arc
							(start 0.1016 0.1778)
							(mid 0.137521 0.162921)
							(end 0.1524 0.127)
						)
					)
					(width 0)
					(fill yes)
				)
			)
		)
		(pad "2" smd custom
			(at 0 0.2794 270)
			(size 0.0762 0.0762)
			(layers "F.Cu" "F.Mask" "F.Paste")
			(net "PHY_SCC_A_TO_DRV_A_31_DP")
			(options
				(clearance outline)
				(anchor circle)
			)
			(primitives
				(gr_poly
					(pts
						(arc
							(start 0.1524 -0.127)
							(mid 0.137521 -0.162921)
							(end 0.1016 -0.1778)
						)
						(arc
							(start -0.1016 -0.1778)
							(mid -0.137521 -0.162921)
							(end -0.1524 -0.127)
						)
						(arc
							(start -0.1524 0.127)
							(mid -0.137521 0.162921)
							(end -0.1016 0.1778)
						)
						(arc
							(start 0.1016 0.1778)
							(mid 0.137521 0.162921)
							(end 0.1524 0.127)
						)
					)
					(width 0)
					(fill yes)
				)
			)
		)
	)
	(footprint ""
		(layer "F.Cu")
		(at 236.869986 -346.782136)
		(property "Reference" "R162"
			(at 0 0 0)
			(layer "F.SilkS")
			(hide yes)
			(effects
				(font
					(size 1.27 1.27)
				)
			)
		)
		(property "Value" "10KR2F-2-GP"
			(at 0.064008 -3.993896 0)
			(unlocked yes)
			(layer "F.Fab")
			(hide yes)
			(effects
				(font
					(size 1.016 1.016)
					(thickness 0.1524)
				)
			)
		)
		(property "Device Type" "R402H16"
			(at 0.064008 -5.517896 0)
			(unlocked yes)
			(layer "F.Fab")
			(hide yes)
			(effects
				(font
					(size 1.016 1.016)
					(thickness 0.1524)
				)
			)
		)
		(duplicate_pad_numbers_are_jumpers no)
		(fp_line
			(start -0.508 -0.9398)
			(end -0.508 0.9398)
			(stroke
				(width 0.1524)
				(type default)
			)
			(layer "F.SilkS")
		)
		(fp_line
			(start 0.508 -0.9398)
			(end -0.508 -0.9398)
			(stroke
				(width 0.1524)
				(type default)
			)
			(layer "F.SilkS")
		)
		(fp_rect
			(start -0.508 0.9398)
			(end 0.508 -0.9398)
			(stroke
				(width 0)
				(type default)
			)
			(fill no)
			(layer "F.CrtYd")
		)
		(fp_rect
			(start -0.508 0.9398)
			(end 0.508 -0.9398)
			(stroke
				(width 0)
				(type default)
			)
			(fill no)
			(layer "F.Fab")
		)
		(pad "1" smd custom
			(at 0 -0.4445)
			(size 0.1397 0.1397)
			(layers "F.Cu" "F.Mask" "F.Paste")
			(net "P5V_A_2_SENSE")
			(options
				(clearance outline)
				(anchor circle)
			)
			(primitives
				(gr_poly
					(pts
						(arc
							(start -0.1778 -0.2794)
							(mid -0.249642 -0.249642)
							(end -0.2794 -0.1778)
						)
						(arc
							(start -0.2794 0.1778)
							(mid -0.249642 0.249642)
							(end -0.1778 0.2794)
						)
						(arc
							(start 0.1778 0.2794)
							(mid 0.249642 0.249642)
							(end 0.2794 0.1778)
						)
						(arc
							(start 0.2794 -0.1778)
							(mid 0.249642 -0.249642)
							(end 0.1778 -0.2794)
						)
					)
					(width 0)
					(fill yes)
				)
			)
		)
		(pad "2" smd custom
			(at 0 0.4445)
			(size 0.1397 0.1397)
			(layers "F.Cu" "F.Mask" "F.Paste")
			(net "GND")
			(options
				(clearance outline)
				(anchor circle)
			)
			(primitives
				(gr_poly
					(pts
						(arc
							(start -0.1778 -0.2794)
							(mid -0.249642 -0.249642)
							(end -0.2794 -0.1778)
						)
						(arc
							(start -0.2794 0.1778)
							(mid -0.249642 0.249642)
							(end -0.1778 0.2794)
						)
						(arc
							(start 0.1778 0.2794)
							(mid 0.249642 0.249642)
							(end 0.2794 0.1778)
						)
						(arc
							(start 0.2794 -0.1778)
							(mid 0.249642 -0.249642)
							(end 0.1778 -0.2794)
						)
					)
					(width 0)
					(fill yes)
				)
			)
		)
	)
	(footprint ""
		(layer "F.Cu")
		(at 115.080796 -62.778894 -90)
		(property "Reference" "C391"
			(at 0 0 270)
			(layer "F.SilkS")
			(hide yes)
			(effects
				(font
					(size 1.27 1.27)
				)
			)
		)
		(property "Value" "SC1U16V3KX-5GP"
			(at 0 -2.8194 270)
			(unlocked yes)
			(layer "F.Fab")
			(hide yes)
			(effects
				(font
					(size 1.016 1.016)
					(thickness 0.1524)
				)
			)
		)
		(property "Device Type" "C603H36"
			(at 0 -4.3434 270)
			(unlocked yes)
			(layer "F.Fab")
			(hide yes)
			(effects
				(font
					(size 1.016 1.016)
					(thickness 0.1524)
				)
			)
		)
		(duplicate_pad_numbers_are_jumpers no)
		(fp_line
			(start 0.508 0)
			(end -0.508 0)
			(stroke
				(width 0.2032)
				(type default)
			)
			(layer "F.SilkS")
		)
		(fp_rect
			(start -0.5842 1.3335)
			(end 0.5842 -1.3335)
			(stroke
				(width 0)
				(type default)
			)
			(fill no)
			(layer "F.CrtYd")
		)
		(fp_rect
			(start -0.5842 1.3335)
			(end 0.5842 -1.3335)
			(stroke
				(width 0)
				(type default)
			)
			(fill no)
			(layer "F.Fab")
		)
		(pad "1" smd custom
			(at 0 -0.762 270)
			(size 0.2159 0.2159)
			(layers "F.Cu" "F.Mask" "F.Paste")
			(net "P5V_HDD27")
			(options
				(clearance outline)
				(anchor circle)
			)
			(primitives
				(gr_poly
					(pts
						(arc
							(start -0.3302 -0.4318)
							(mid -0.402042 -0.402042)
							(end -0.4318 -0.3302)
						)
						(arc
							(start -0.4318 0.3302)
							(mid -0.402042 0.402042)
							(end -0.3302 0.4318)
						)
						(arc
							(start 0.3302 0.4318)
							(mid 0.402042 0.402042)
							(end 0.4318 0.3302)
						)
						(arc
							(start 0.4318 -0.3302)
							(mid 0.402042 -0.402042)
							(end 0.3302 -0.4318)
						)
					)
					(width 0)
					(fill yes)
				)
			)
		)
		(pad "2" smd custom
			(at 0 0.762 270)
			(size 0.2159 0.2159)
			(layers "F.Cu" "F.Mask" "F.Paste")
			(net "GND")
			(options
				(clearance outline)
				(anchor circle)
			)
			(primitives
				(gr_poly
					(pts
						(arc
							(start -0.3302 -0.4318)
							(mid -0.402042 -0.402042)
							(end -0.4318 -0.3302)
						)
						(arc
							(start -0.4318 0.3302)
							(mid -0.402042 0.402042)
							(end -0.3302 0.4318)
						)
						(arc
							(start 0.3302 0.4318)
							(mid 0.402042 0.402042)
							(end 0.4318 0.3302)
						)
						(arc
							(start 0.4318 -0.3302)
							(mid 0.402042 -0.402042)
							(end 0.3302 -0.4318)
						)
					)
					(width 0)
					(fill yes)
				)
			)
		)
	)
	(footprint ""
		(layer "F.Cu")
		(at 281.999944 -14.85011 90)
		(property "Reference" "MONO4"
			(at 0 0 90)
			(layer "F.SilkS")
			(hide yes)
			(effects
				(font
					(size 1.27 1.27)
				)
			)
		)
		(property "Value" "AMP-CONN164-4R-1-GP"
			(at -25.705054 -1.203706 90)
			(unlocked yes)
			(layer "F.Fab")
			(hide yes)
			(effects
				(font
					(size 1.016 1.016)
					(thickness 0.1524)
				)
			)
		)
		(property "Device Type" "PREFIT-164P-890091-1H441"
			(at -25.705054 -2.727706 90)
			(unlocked yes)
			(layer "F.Fab")
			(hide yes)
			(effects
				(font
					(size 1.016 1.016)
					(thickness 0.1524)
				)
			)
		)
		(duplicate_pad_numbers_are_jumpers no)
		(fp_line
			(start 74.5998 -4.1656)
			(end 74.5998 5.4102)
			(stroke
				(width 0.1524)
				(type default)
			)
			(layer "F.SilkS")
		)
		(fp_line
			(start -14.9098 -4.1656)
			(end 74.5998 -4.1656)
			(stroke
				(width 0.1524)
				(type default)
			)
			(layer "F.SilkS")
		)
		(fp_line
			(start 74.5998 5.4102)
			(end -14.9098 5.4102)
			(stroke
				(width 0.1524)
				(type default)
			)
			(layer "F.SilkS")
		)
		(fp_line
			(start -14.9098 5.4102)
			(end -14.9098 -4.1656)
			(stroke
				(width 0.1524)
				(type default)
			)
			(layer "F.SilkS")
		)
		(fp_poly
			(pts
				(xy -14.9098 5.4102) (xy -14.9098 -4.1656) (xy 74.5998 -4.1656) (xy 74.5998 -3.98653) (xy -13.5636 -3.98653)
				(xy -13.5636 3.98653) (xy 23.4442 3.98653) (xy 23.4442 5.3086) (xy 33.8074 5.3086) (xy 33.8074 3.98653)
				(xy 74.5998 3.98653) (xy 74.5998 5.4102)
			)
			(stroke
				(width 0)
				(type default)
			)
			(fill yes)
			(layer "F.SilkS")
		)
		(fp_poly
			(pts
				(arc
					(start -13.1826 -2.99593)
					(mid -13.4366 -3.24993)
					(end -13.1826 -3.50393)
				)
				(arc
					(start -12.6746 -3.50393)
					(mid -12.4206 -3.24993)
					(end -12.6746 -2.99593)
				)
			)
			(stroke
				(width 0)
				(type default)
			)
			(fill yes)
			(layer "F.SilkS")
		)
		(fp_poly
			(pts
				(arc
					(start -13.1826 -0.995934)
					(mid -13.4366 -1.249934)
					(end -13.1826 -1.503934)
				)
				(arc
					(start -12.6746 -1.503934)
					(mid -12.4206 -1.249934)
					(end -12.6746 -0.995934)
				)
			)
			(stroke
				(width 0)
				(type default)
			)
			(fill yes)
			(layer "F.SilkS")
		)
		(fp_poly
			(pts
				(arc
					(start -13.1826 1.503934)
					(mid -13.4366 1.249934)
					(end -13.1826 0.995934)
				)
				(arc
					(start -12.6746 0.995934)
					(mid -12.4206 1.249934)
					(end -12.6746 1.503934)
				)
			)
			(stroke
				(width 0)
				(type default)
			)
			(fill yes)
			(layer "F.SilkS")
		)
		(fp_poly
			(pts
				(arc
					(start -13.1826 3.50393)
					(mid -13.4366 3.24993)
					(end -13.1826 2.99593)
				)
				(arc
					(start -12.6746 2.99593)
					(mid -12.4206 3.24993)
					(end -12.6746 3.50393)
				)
			)
			(stroke
				(width 0)
				(type default)
			)
			(fill yes)
			(layer "F.SilkS")
		)
		(fp_rect
			(start -17.1958 8.7884)
			(end 76.8858 -8.7884)
			(stroke
				(width 0)
				(type default)
			)
			(fill no)
			(layer "B.CrtYd")
		)
		(fp_rect
			(start -14.6558 5.1562)
			(end 74.3458 -3.9116)
			(stroke
				(width 0)
				(type default)
			)
			(fill no)
			(layer "F.CrtYd")
		)
		(fp_poly
			(pts
				(xy -15.1638 5.6642) (xy -15.1638 -4.4196) (xy 74.8538 -4.4196) (xy 74.8538 -0.00635) (xy 74.3458 -0.00635)
				(xy 74.3458 -3.9116) (xy -14.6558 -3.9116) (xy -14.6558 5.1562) (xy 74.3458 5.1562) (xy 74.3458 0.00635)
				(xy 74.8538 0.00635) (xy 74.8538 5.6642)
			)
			(stroke
				(width 0)
				(type default)
			)
			(fill no)
			(layer "F.CrtYd")
		)
		(fp_poly
			(pts
				(xy -19.6596 10.16) (xy -19.6596 0.00635) (xy -15.1638 0.00635) (xy -15.1638 5.6642) (xy 74.8538 5.6642)
				(xy 74.8538 -4.4196) (xy -15.1638 -4.4196) (xy -15.1638 -0.00635) (xy -19.6596 -0.00635) (xy -19.6596 -8.9154)
				(xy 79.3496 -8.9154) (xy 79.3496 10.16)
			)
			(stroke
				(width 0)
				(type default)
			)
			(fill no)
			(layer "F.CrtYd")
		)
		(fp_rect
			(start -17.1958 8.7884)
			(end 76.8858 -8.7884)
			(stroke
				(width 0)
				(type default)
			)
			(fill no)
			(layer "B.Fab")
		)
		(fp_rect
			(start -22.1996 13.7922)
			(end 81.8896 -13.7922)
			(stroke
				(width 0)
				(type default)
			)
			(fill no)
			(layer "B.Fab")
		)
		(fp_rect
			(start -15.1638 5.6642)
			(end 74.8538 -4.4196)
			(stroke
				(width 0)
				(type default)
			)
			(fill no)
			(layer "F.Fab")
		)
		(fp_rect
			(start -19.6596 10.16)
			(end 79.3496 -8.9154)
			(stroke
				(width 0)
				(type default)
			)
			(fill no)
			(layer "F.Fab")
		)
		(fp_rect
			(start -24.6634 15.1638)
			(end 84.3534 -13.9192)
			(stroke
				(width 0)
				(type default)
			)
			(fill no)
			(layer "F.Fab")
		)
		(fp_text user "Press Fit"
			(at 23.495 4.6482 90)
			(unlocked yes)
			(layer "F.SilkS")
			(effects
				(font
					(size 1.016 1.016)
					(thickness 0.1524)
				)
				(justify left)
			)
		)
		(fp_text user "Can not place BGA,CSP,Wave Solder Component"
			(at 2.032 12.2428 90)
			(unlocked yes)
			(layer "B.Fab")
			(effects
				(font
					(size 1.016 1.016)
					(thickness 0.1524)
				)
				(justify left)
			)
		)
		(fp_text user "High Limit 2mm"
			(at 18.8214 9.025636 90)
			(unlocked yes)
			(layer "F.Fab")
			(effects
				(font
					(size 1.016 1.016)
					(thickness 0.1524)
				)
				(justify left)
			)
		)
		(fp_text user "Can not place BGA,CSP,Wave Solder Component"
			(at 10.58799 13.215874 90)
			(unlocked yes)
			(layer "F.Fab")
			(effects
				(font
					(size 1.016 1.016)
					(thickness 0.1524)
				)
				(justify left)
			)
		)
		(pad "" np_thru_hole circle
			(at 0 0 90)
			(size 0.254 0.254)
			(drill 2.3622)
			(layers "*.Cu" "*.Mask")
			(clearance 1.4097)
			(thermal_gap 1.4097)
		)
		(pad "" np_thru_hole circle
			(at 73.149968 0 90)
			(size 0.254 0.254)
			(drill 2.3622)
			(layers "*.Cu" "*.Mask")
			(clearance 1.4097)
			(thermal_gap 1.4097)
		)
		(pad "A1" thru_hole circle
			(at -11.649964 -1.249934 90)
			(size 1.0668 1.0668)
			(drill 0.719836)
			(layers "*.Cu" "*.Mask")
			(remove_unused_layers no)
			(net "COMP_B_SEC_INS_N")
			(clearance 0.1905)
			(thermal_gap 0.1905)
		)
		(pad "A2" thru_hole circle
			(at -10.649966 -3.24993 90)
			(size 1.0668 1.0668)
			(drill 0.719836)
			(layers "*.Cu" "*.Mask")
			(remove_unused_layers no)
			(net "P12V_B_COMP")
			(clearance 0.1905)
			(thermal_gap 0.1905)
		)
		(pad "A3" thru_hole circle
			(at -9.649968 -1.249934 90)
			(size 1.0668 1.0668)
			(drill 0.719836)
			(layers "*.Cu" "*.Mask")
			(remove_unused_layers no)
			(net "P12V_B_COMP")
			(clearance 0.1905)
			(thermal_gap 0.1905)
		)
		(pad "A4" thru_hole circle
			(at -8.64997 -3.24993 90)
			(size 1.0668 1.0668)
			(drill 0.719836)
			(layers "*.Cu" "*.Mask")
			(remove_unused_layers no)
			(net "GND")
			(clearance 0.1905)
			(thermal_gap 0.1905)
		)
		(pad "A5" thru_hole circle
			(at -7.649972 -1.249934 90)
			(size 1.0668 1.0668)
			(drill 0.719836)
			(layers "*.Cu" "*.Mask")
			(remove_unused_layers no)
			(net "TP_COMP_B_NCSI_RCLK")
			(clearance 0.1905)
			(thermal_gap 0.1905)
		)
		(pad "A6" thru_hole circle
			(at -6.649974 -3.24993 90)
			(size 1.0668 1.0668)
			(drill 0.719836)
			(layers "*.Cu" "*.Mask")
			(remove_unused_layers no)
			(net "TP_COMP_B_NCSI_RXD0")
			(clearance 0.1905)
			(thermal_gap 0.1905)
		)
		(pad "A7" thru_hole circle
			(at -5.649976 -1.249934 90)
			(size 1.0668 1.0668)
			(drill 0.719836)
			(layers "*.Cu" "*.Mask")
			(remove_unused_layers no)
			(net "TP_COMP_B_NCSI_RXD1")
			(clearance 0.1905)
			(thermal_gap 0.1905)
		)
		(pad "A8" thru_hole circle
			(at -4.649978 -3.24993 90)
			(size 1.0668 1.0668)
			(drill 0.719836)
			(layers "*.Cu" "*.Mask")
			(remove_unused_layers no)
			(net "GND")
			(clearance 0.1905)
			(thermal_gap 0.1905)
		)
		(pad "A9" thru_hole circle
			(at -3.64998 -1.249934 90)
			(size 1.0668 1.0668)
			(drill 0.719836)
			(layers "*.Cu" "*.Mask")
			(remove_unused_layers no)
			(net "PCIE_COMP_B_TO_IOM_B_CLK_4_DP")
			(clearance 0.1905)
			(thermal_gap 0.1905)
		)
		(pad "A10" thru_hole circle
			(at -2.649982 -3.24993 90)
			(size 1.0668 1.0668)
			(drill 0.719836)
			(layers "*.Cu" "*.Mask")
			(remove_unused_layers no)
			(net "PCIE_COMP_B_TO_IOM_B_CLK_4_DN")
			(clearance 0.1905)
			(thermal_gap 0.1905)
		)
		(pad "A11" thru_hole circle
			(at -1.649984 -1.249934 90)
			(size 1.0668 1.0668)
			(drill 0.719836)
			(layers "*.Cu" "*.Mask")
			(remove_unused_layers no)
			(net "GND")
			(clearance 0.1905)
			(thermal_gap 0.1905)
		)
		(pad "A12" thru_hole circle
			(at 1.35001 -3.24993 90)
			(size 1.0668 1.0668)
			(drill 0.719836)
			(layers "*.Cu" "*.Mask")
			(remove_unused_layers no)
			(net "GND")
			(clearance 0.1905)
			(thermal_gap 0.1905)
		)
		(pad "A13" thru_hole circle
			(at 2.350008 -1.249934 90)
			(size 1.0668 1.0668)
			(drill 0.719836)
			(layers "*.Cu" "*.Mask")
			(remove_unused_layers no)
			(net "PCIE_COMP_B_CLK_P5")
			(clearance 0.1905)
			(thermal_gap 0.1905)
		)
		(pad "A14" thru_hole circle
			(at 3.350006 -3.24993 90)
			(size 1.0668 1.0668)
			(drill 0.719836)
			(layers "*.Cu" "*.Mask")
			(remove_unused_layers no)
			(net "PCIE_COMP_B_CLK_N5")
			(clearance 0.1905)
			(thermal_gap 0.1905)
		)
		(pad "A15" thru_hole circle
			(at 4.350004 -1.249934 90)
			(size 1.0668 1.0668)
			(drill 0.719836)
			(layers "*.Cu" "*.Mask")
			(remove_unused_layers no)
			(net "GND")
			(clearance 0.1905)
			(thermal_gap 0.1905)
		)
		(pad "A16" thru_hole circle
			(at 5.350002 -3.24993 90)
			(size 1.0668 1.0668)
			(drill 0.719836)
			(layers "*.Cu" "*.Mask")
			(remove_unused_layers no)
			(net "GND")
			(clearance 0.1905)
			(thermal_gap 0.1905)
		)
		(pad "A17" thru_hole circle
			(at 6.35 -1.249934 90)
			(size 1.0668 1.0668)
			(drill 0.719836)
			(layers "*.Cu" "*.Mask")
			(remove_unused_layers no)
			(net "Net_1379")
			(clearance 0.1905)
			(thermal_gap 0.1905)
		)
		(pad "A18" thru_hole circle
			(at 7.349998 -3.24993 90)
			(size 1.0668 1.0668)
			(drill 0.719836)
			(layers "*.Cu" "*.Mask")
			(remove_unused_layers no)
			(net "Net_1376")
			(clearance 0.1905)
			(thermal_gap 0.1905)
		)
		(pad "A19" thru_hole circle
			(at 8.349996 -1.249934 90)
			(size 1.0668 1.0668)
			(drill 0.719836)
			(layers "*.Cu" "*.Mask")
			(remove_unused_layers no)
			(net "GND")
			(clearance 0.1905)
			(thermal_gap 0.1905)
		)
		(pad "A20" thru_hole circle
			(at 9.349994 -3.24993 90)
			(size 1.0668 1.0668)
			(drill 0.719836)
			(layers "*.Cu" "*.Mask")
			(remove_unused_layers no)
			(net "GND")
			(clearance 0.1905)
			(thermal_gap 0.1905)
		)
		(pad "A21" thru_hole circle
			(at 10.349992 -1.249934 90)
			(size 1.0668 1.0668)
			(drill 0.719836)
			(layers "*.Cu" "*.Mask")
			(remove_unused_layers no)
			(net "Net_1378")
			(clearance 0.1905)
			(thermal_gap 0.1905)
		)
		(pad "A22" thru_hole circle
			(at 11.34999 -3.24993 90)
			(size 1.0668 1.0668)
			(drill 0.719836)
			(layers "*.Cu" "*.Mask")
			(remove_unused_layers no)
			(net "Net_1371")
			(clearance 0.1905)
			(thermal_gap 0.1905)
		)
		(pad "A23" thru_hole circle
			(at 12.349988 -1.249934 90)
			(size 1.0668 1.0668)
			(drill 0.719836)
			(layers "*.Cu" "*.Mask")
			(remove_unused_layers no)
			(net "GND")
			(clearance 0.1905)
			(thermal_gap 0.1905)
		)
		(pad "A24" thru_hole circle
			(at 13.349986 -3.24993 90)
			(size 1.0668 1.0668)
			(drill 0.719836)
			(layers "*.Cu" "*.Mask")
			(remove_unused_layers no)
			(net "GND")
			(clearance 0.1905)
			(thermal_gap 0.1905)
		)
		(pad "A25" thru_hole circle
			(at 14.349984 -1.249934 90)
			(size 1.0668 1.0668)
			(drill 0.719836)
			(layers "*.Cu" "*.Mask")
			(remove_unused_layers no)
			(net "Net_1374")
			(clearance 0.1905)
			(thermal_gap 0.1905)
		)
		(pad "A26" thru_hole circle
			(at 15.349982 -3.24993 90)
			(size 1.0668 1.0668)
			(drill 0.719836)
			(layers "*.Cu" "*.Mask")
			(remove_unused_layers no)
			(net "Net_1370")
			(clearance 0.1905)
			(thermal_gap 0.1905)
		)
		(pad "A27" thru_hole circle
			(at 16.34998 -1.249934 90)
			(size 1.0668 1.0668)
			(drill 0.719836)
			(layers "*.Cu" "*.Mask")
			(remove_unused_layers no)
			(net "GND")
			(clearance 0.1905)
			(thermal_gap 0.1905)
		)
		(pad "A28" thru_hole circle
			(at 17.349978 -3.24993 90)
			(size 1.0668 1.0668)
			(drill 0.719836)
			(layers "*.Cu" "*.Mask")
			(remove_unused_layers no)
			(net "GND")
			(clearance 0.1905)
			(thermal_gap 0.1905)
		)
		(pad "A29" thru_hole circle
			(at 18.349976 -1.249934 90)
			(size 1.0668 1.0668)
			(drill 0.719836)
			(layers "*.Cu" "*.Mask")
			(remove_unused_layers no)
			(net "Net_1368")
			(clearance 0.1905)
			(thermal_gap 0.1905)
		)
		(pad "A30" thru_hole circle
			(at 19.349974 -3.24993 90)
			(size 1.0668 1.0668)
			(drill 0.719836)
			(layers "*.Cu" "*.Mask")
			(remove_unused_layers no)
			(net "Net_1367")
			(clearance 0.1905)
			(thermal_gap 0.1905)
		)
		(pad "A31" thru_hole circle
			(at 20.349972 -1.249934 90)
			(size 1.0668 1.0668)
			(drill 0.719836)
			(layers "*.Cu" "*.Mask")
			(remove_unused_layers no)
			(net "GND")
			(clearance 0.1905)
			(thermal_gap 0.1905)
		)
		(pad "A32" thru_hole circle
			(at 21.34997 -3.24993 90)
			(size 1.0668 1.0668)
			(drill 0.719836)
			(layers "*.Cu" "*.Mask")
			(remove_unused_layers no)
			(net "GND")
			(clearance 0.1905)
			(thermal_gap 0.1905)
		)
		(pad "A33" thru_hole circle
			(at 22.349968 -1.249934 90)
			(size 1.0668 1.0668)
			(drill 0.719836)
			(layers "*.Cu" "*.Mask")
			(remove_unused_layers no)
			(net "PCIE_IOM_B_TO_COMP_B_12_DP")
			(clearance 0.1905)
			(thermal_gap 0.1905)
		)
		(pad "A34" thru_hole circle
			(at 23.349966 -3.24993 90)
			(size 1.0668 1.0668)
			(drill 0.719836)
			(layers "*.Cu" "*.Mask")
			(remove_unused_layers no)
			(net "PCIE_IOM_B_TO_COMP_B_12_DN")
			(clearance 0.1905)
			(thermal_gap 0.1905)
		)
		(pad "A35" thru_hole circle
			(at 24.349964 -1.249934 90)
			(size 1.0668 1.0668)
			(drill 0.719836)
			(layers "*.Cu" "*.Mask")
			(remove_unused_layers no)
			(net "GND")
			(clearance 0.1905)
			(thermal_gap 0.1905)
		)
		(pad "A36" thru_hole circle
			(at 25.349962 -3.24993 90)
			(size 1.0668 1.0668)
			(drill 0.719836)
			(layers "*.Cu" "*.Mask")
			(remove_unused_layers no)
			(net "GND")
			(clearance 0.1905)
			(thermal_gap 0.1905)
		)
		(pad "A37" thru_hole circle
			(at 26.34996 -1.249934 90)
			(size 1.0668 1.0668)
			(drill 0.719836)
			(layers "*.Cu" "*.Mask")
			(remove_unused_layers no)
			(net "PCIE_IOM_B_TO_COMP_B_13_DP")
			(clearance 0.1905)
			(thermal_gap 0.1905)
		)
		(pad "A38" thru_hole circle
			(at 27.349958 -3.24993 90)
			(size 1.0668 1.0668)
			(drill 0.719836)
			(layers "*.Cu" "*.Mask")
			(remove_unused_layers no)
			(net "PCIE_IOM_B_TO_COMP_B_13_DN")
			(clearance 0.1905)
			(thermal_gap 0.1905)
		)
		(pad "A39" thru_hole circle
			(at 28.349956 -1.249934 90)
			(size 1.0668 1.0668)
			(drill 0.719836)
			(layers "*.Cu" "*.Mask")
			(remove_unused_layers no)
			(net "GND")
			(clearance 0.1905)
			(thermal_gap 0.1905)
		)
		(pad "A40" thru_hole circle
			(at 29.349954 -3.24993 90)
			(size 1.0668 1.0668)
			(drill 0.719836)
			(layers "*.Cu" "*.Mask")
			(remove_unused_layers no)
			(net "GND")
			(clearance 0.1905)
			(thermal_gap 0.1905)
		)
		(pad "A41" thru_hole circle
			(at 30.349952 -1.249934 90)
			(size 1.0668 1.0668)
			(drill 0.719836)
			(layers "*.Cu" "*.Mask")
			(remove_unused_layers no)
			(net "PCIE_IOM_B_TO_COMP_B_14_DP")
			(clearance 0.1905)
			(thermal_gap 0.1905)
		)
		(pad "A42" thru_hole circle
			(at 31.34995 -3.24993 90)
			(size 1.0668 1.0668)
			(drill 0.719836)
			(layers "*.Cu" "*.Mask")
			(remove_unused_layers no)
			(net "PCIE_IOM_B_TO_COMP_B_14_DN")
			(clearance 0.1905)
			(thermal_gap 0.1905)
		)
		(pad "A43" thru_hole circle
			(at 32.349948 -1.249934 90)
			(size 1.0668 1.0668)
			(drill 0.719836)
			(layers "*.Cu" "*.Mask")
			(remove_unused_layers no)
			(net "GND")
			(clearance 0.1905)
			(thermal_gap 0.1905)
		)
		(pad "A44" thru_hole circle
			(at 33.349946 -3.24993 90)
			(size 1.0668 1.0668)
			(drill 0.719836)
			(layers "*.Cu" "*.Mask")
			(remove_unused_layers no)
			(net "GND")
			(clearance 0.1905)
			(thermal_gap 0.1905)
		)
		(pad "A45" thru_hole circle
			(at 34.349944 -1.249934 90)
			(size 1.0668 1.0668)
			(drill 0.719836)
			(layers "*.Cu" "*.Mask")
			(remove_unused_layers no)
			(net "PCIE_IOM_B_TO_COMP_B_15_DP")
			(clearance 0.1905)
			(thermal_gap 0.1905)
		)
		(pad "A46" thru_hole circle
			(at 35.349942 -3.24993 90)
			(size 1.0668 1.0668)
			(drill 0.719836)
			(layers "*.Cu" "*.Mask")
			(remove_unused_layers no)
			(net "PCIE_IOM_B_TO_COMP_B_15_DN")
			(clearance 0.1905)
			(thermal_gap 0.1905)
		)
		(pad "A47" thru_hole circle
			(at 36.34994 -1.249934 90)
			(size 1.0668 1.0668)
			(drill 0.719836)
			(layers "*.Cu" "*.Mask")
			(remove_unused_layers no)
			(net "GND")
			(clearance 0.1905)
			(thermal_gap 0.1905)
		)
		(pad "A48" thru_hole circle
			(at 37.349938 -3.24993 90)
			(size 1.0668 1.0668)
			(drill 0.719836)
			(layers "*.Cu" "*.Mask")
			(remove_unused_layers no)
			(net "GND")
			(clearance 0.1905)
			(thermal_gap 0.1905)
		)
		(pad "A49" thru_hole circle
			(at 38.349936 -1.249934 90)
			(size 1.0668 1.0668)
			(drill 0.719836)
			(layers "*.Cu" "*.Mask")
			(remove_unused_layers no)
			(net "PCIE_IOM_B_TO_COMP_B_16_DP")
			(clearance 0.1905)
			(thermal_gap 0.1905)
		)
		(pad "A50" thru_hole circle
			(at 39.349934 -3.24993 90)
			(size 1.0668 1.0668)
			(drill 0.719836)
			(layers "*.Cu" "*.Mask")
			(remove_unused_layers no)
			(net "PCIE_IOM_B_TO_COMP_B_16_DN")
			(clearance 0.1905)
			(thermal_gap 0.1905)
		)
		(pad "A51" thru_hole circle
			(at 40.349932 -1.249934 90)
			(size 1.0668 1.0668)
			(drill 0.719836)
			(layers "*.Cu" "*.Mask")
			(remove_unused_layers no)
			(net "GND")
			(clearance 0.1905)
			(thermal_gap 0.1905)
		)
		(pad "A52" thru_hole circle
			(at 41.34993 -3.24993 90)
			(size 1.0668 1.0668)
			(drill 0.719836)
			(layers "*.Cu" "*.Mask")
			(remove_unused_layers no)
			(net "GND")
			(clearance 0.1905)
			(thermal_gap 0.1905)
		)
		(pad "A53" thru_hole circle
			(at 42.349928 -1.249934 90)
			(size 1.0668 1.0668)
			(drill 0.719836)
			(layers "*.Cu" "*.Mask")
			(remove_unused_layers no)
			(net "PCIE_IOM_B_TO_COMP_B_17_DP")
			(clearance 0.1905)
			(thermal_gap 0.1905)
		)
		(pad "A54" thru_hole circle
			(at 43.349926 -3.24993 90)
			(size 1.0668 1.0668)
			(drill 0.719836)
			(layers "*.Cu" "*.Mask")
			(remove_unused_layers no)
			(net "PCIE_IOM_B_TO_COMP_B_17_DN")
			(clearance 0.1905)
			(thermal_gap 0.1905)
		)
		(pad "A55" thru_hole circle
			(at 44.349924 -1.249934 90)
			(size 1.0668 1.0668)
			(drill 0.719836)
			(layers "*.Cu" "*.Mask")
			(remove_unused_layers no)
			(net "GND")
			(clearance 0.1905)
			(thermal_gap 0.1905)
		)
		(pad "A56" thru_hole circle
			(at 45.349922 -3.24993 90)
			(size 1.0668 1.0668)
			(drill 0.719836)
			(layers "*.Cu" "*.Mask")
			(remove_unused_layers no)
			(net "GND")
			(clearance 0.1905)
			(thermal_gap 0.1905)
		)
		(pad "A57" thru_hole circle
			(at 46.34992 -1.249934 90)
			(size 1.0668 1.0668)
			(drill 0.719836)
			(layers "*.Cu" "*.Mask")
			(remove_unused_layers no)
			(net "PCIE_IOM_B_TO_COMP_B_18_DP")
			(clearance 0.1905)
			(thermal_gap 0.1905)
		)
		(pad "A58" thru_hole circle
			(at 47.349918 -3.24993 90)
			(size 1.0668 1.0668)
			(drill 0.719836)
			(layers "*.Cu" "*.Mask")
			(remove_unused_layers no)
			(net "PCIE_IOM_B_TO_COMP_B_18_DN")
			(clearance 0.1905)
			(thermal_gap 0.1905)
		)
		(pad "A59" thru_hole circle
			(at 48.349916 -1.249934 90)
			(size 1.0668 1.0668)
			(drill 0.719836)
			(layers "*.Cu" "*.Mask")
			(remove_unused_layers no)
			(net "GND")
			(clearance 0.1905)
			(thermal_gap 0.1905)
		)
		(pad "A60" thru_hole circle
			(at 49.349914 -3.24993 90)
			(size 1.0668 1.0668)
			(drill 0.719836)
			(layers "*.Cu" "*.Mask")
			(remove_unused_layers no)
			(net "GND")
			(clearance 0.1905)
			(thermal_gap 0.1905)
		)
		(pad "A61" thru_hole circle
			(at 50.349912 -1.249934 90)
			(size 1.0668 1.0668)
			(drill 0.719836)
			(layers "*.Cu" "*.Mask")
			(remove_unused_layers no)
			(net "PCIE_IOM_B_TO_COMP_B_19_DP")
			(clearance 0.1905)
			(thermal_gap 0.1905)
		)
		(pad "A62" thru_hole circle
			(at 51.34991 -3.24993 90)
			(size 1.0668 1.0668)
			(drill 0.719836)
			(layers "*.Cu" "*.Mask")
			(remove_unused_layers no)
			(net "PCIE_IOM_B_TO_COMP_B_19_DN")
			(clearance 0.1905)
			(thermal_gap 0.1905)
		)
		(pad "A63" thru_hole circle
			(at 52.349908 -1.249934 90)
			(size 1.0668 1.0668)
			(drill 0.719836)
			(layers "*.Cu" "*.Mask")
			(remove_unused_layers no)
			(net "GND")
			(clearance 0.1905)
			(thermal_gap 0.1905)
		)
		(pad "A64" thru_hole circle
			(at 53.349906 -3.24993 90)
			(size 1.0668 1.0668)
			(drill 0.719836)
			(layers "*.Cu" "*.Mask")
			(remove_unused_layers no)
			(net "GND")
			(clearance 0.1905)
			(thermal_gap 0.1905)
		)
		(pad "A65" thru_hole circle
			(at 54.349904 -1.249934 90)
			(size 1.0668 1.0668)
			(drill 0.719836)
			(layers "*.Cu" "*.Mask")
			(remove_unused_layers no)
			(net "PCIE_IOM_B_TO_COMP_B_20_DP")
			(clearance 0.1905)
			(thermal_gap 0.1905)
		)
		(pad "A66" thru_hole circle
			(at 55.349902 -3.24993 90)
			(size 1.0668 1.0668)
			(drill 0.719836)
			(layers "*.Cu" "*.Mask")
			(remove_unused_layers no)
			(net "PCIE_IOM_B_TO_COMP_B_20_DN")
			(clearance 0.1905)
			(thermal_gap 0.1905)
		)
		(pad "A67" thru_hole circle
			(at 56.3499 -1.249934 90)
			(size 1.0668 1.0668)
			(drill 0.719836)
			(layers "*.Cu" "*.Mask")
			(remove_unused_layers no)
			(net "GND")
			(clearance 0.1905)
			(thermal_gap 0.1905)
		)
		(pad "A68" thru_hole circle
			(at 57.349898 -3.24993 90)
			(size 1.0668 1.0668)
			(drill 0.719836)
			(layers "*.Cu" "*.Mask")
			(remove_unused_layers no)
			(net "GND")
			(clearance 0.1905)
			(thermal_gap 0.1905)
		)
		(pad "A69" thru_hole circle
			(at 58.349896 -1.249934 90)
			(size 1.0668 1.0668)
			(drill 0.719836)
			(layers "*.Cu" "*.Mask")
			(remove_unused_layers no)
			(net "PCIE_IOM_B_TO_COMP_B_21_DP")
			(clearance 0.1905)
			(thermal_gap 0.1905)
		)
		(pad "A70" thru_hole circle
			(at 59.349894 -3.24993 90)
			(size 1.0668 1.0668)
			(drill 0.719836)
			(layers "*.Cu" "*.Mask")
			(remove_unused_layers no)
			(net "PCIE_IOM_B_TO_COMP_B_21_DN")
			(clearance 0.1905)
			(thermal_gap 0.1905)
		)
		(pad "A71" thru_hole circle
			(at 60.349892 -1.249934 90)
			(size 1.0668 1.0668)
			(drill 0.719836)
			(layers "*.Cu" "*.Mask")
			(remove_unused_layers no)
			(net "GND")
			(clearance 0.1905)
			(thermal_gap 0.1905)
		)
		(pad "A72" thru_hole circle
			(at 61.34989 -3.24993 90)
			(size 1.0668 1.0668)
			(drill 0.719836)
			(layers "*.Cu" "*.Mask")
			(remove_unused_layers no)
			(net "GND")
			(clearance 0.1905)
			(thermal_gap 0.1905)
		)
		(pad "A73" thru_hole circle
			(at 62.349888 -1.249934 90)
			(size 1.0668 1.0668)
			(drill 0.719836)
			(layers "*.Cu" "*.Mask")
			(remove_unused_layers no)
			(net "PCIE_IOM_B_TO_COMP_B_22_DP")
			(clearance 0.1905)
			(thermal_gap 0.1905)
		)
		(pad "A74" thru_hole circle
			(at 63.349886 -3.24993 90)
			(size 1.0668 1.0668)
			(drill 0.719836)
			(layers "*.Cu" "*.Mask")
			(remove_unused_layers no)
			(net "PCIE_IOM_B_TO_COMP_B_22_DN")
			(clearance 0.1905)
			(thermal_gap 0.1905)
		)
		(pad "A75" thru_hole circle
			(at 64.349884 -1.249934 90)
			(size 1.0668 1.0668)
			(drill 0.719836)
			(layers "*.Cu" "*.Mask")
			(remove_unused_layers no)
			(net "GND")
			(clearance 0.1905)
			(thermal_gap 0.1905)
		)
		(pad "A76" thru_hole circle
			(at 65.349882 -3.24993 90)
			(size 1.0668 1.0668)
			(drill 0.719836)
			(layers "*.Cu" "*.Mask")
			(remove_unused_layers no)
			(net "GND")
			(clearance 0.1905)
			(thermal_gap 0.1905)
		)
		(pad "A77" thru_hole circle
			(at 66.34988 -1.249934 90)
			(size 1.0668 1.0668)
			(drill 0.719836)
			(layers "*.Cu" "*.Mask")
			(remove_unused_layers no)
			(net "PCIE_IOM_B_TO_COMP_B_23_DP")
			(clearance 0.1905)
			(thermal_gap 0.1905)
		)
		(pad "A78" thru_hole circle
			(at 67.349878 -3.24993 90)
			(size 1.0668 1.0668)
			(drill 0.719836)
			(layers "*.Cu" "*.Mask")
			(remove_unused_layers no)
			(net "PCIE_IOM_B_TO_COMP_B_23_DN")
			(clearance 0.1905)
			(thermal_gap 0.1905)
		)
		(pad "A79" thru_hole circle
			(at 68.349876 -1.249934 90)
			(size 1.0668 1.0668)
			(drill 0.719836)
			(layers "*.Cu" "*.Mask")
			(remove_unused_layers no)
			(net "GND")
			(clearance 0.1905)
			(thermal_gap 0.1905)
		)
		(pad "A80" thru_hole circle
			(at 69.349874 -3.24993 90)
			(size 1.0668 1.0668)
			(drill 0.719836)
			(layers "*.Cu" "*.Mask")
			(remove_unused_layers no)
			(net "GND")
			(clearance 0.1905)
			(thermal_gap 0.1905)
		)
		(pad "A81" thru_hole circle
			(at 70.350126 -1.249934 90)
			(size 1.0668 1.0668)
			(drill 0.719836)
			(layers "*.Cu" "*.Mask")
			(remove_unused_layers no)
			(net "P12V_B_COMP")
			(clearance 0.1905)
			(thermal_gap 0.1905)
		)
		(pad "A82" thru_hole circle
			(at 71.350124 -3.24993 90)
			(size 1.0668 1.0668)
			(drill 0.719836)
			(layers "*.Cu" "*.Mask")
			(remove_unused_layers no)
			(net "P12V_B_COMP")
			(clearance 0.1905)
			(thermal_gap 0.1905)
		)
		(pad "B1" thru_hole circle
			(at -11.649964 1.249934 90)
			(size 1.0668 1.0668)
			(drill 0.719836)
			(layers "*.Cu" "*.Mask")
			(remove_unused_layers no)
			(net "P12V_B_COMP")
			(clearance 0.1905)
			(thermal_gap 0.1905)
		)
		(pad "B2" thru_hole circle
			(at -10.649966 3.24993 90)
			(size 1.0668 1.0668)
			(drill 0.719836)
			(layers "*.Cu" "*.Mask")
			(remove_unused_layers no)
			(net "P12V_B_COMP")
			(clearance 0.1905)
			(thermal_gap 0.1905)
		)
		(pad "B3" thru_hole circle
			(at -9.649968 1.249934 90)
			(size 1.0668 1.0668)
			(drill 0.719836)
			(layers "*.Cu" "*.Mask")
			(remove_unused_layers no)
			(net "P12V_B_COMP")
			(clearance 0.1905)
			(thermal_gap 0.1905)
		)
		(pad "B4" thru_hole circle
			(at -8.64997 3.24993 90)
			(size 1.0668 1.0668)
			(drill 0.719836)
			(layers "*.Cu" "*.Mask")
			(remove_unused_layers no)
			(net "GND")
			(clearance 0.1905)
			(thermal_gap 0.1905)
		)
		(pad "B5" thru_hole circle
			(at -7.649972 1.249934 90)
			(size 1.0668 1.0668)
			(drill 0.719836)
			(layers "*.Cu" "*.Mask")
			(remove_unused_layers no)
			(net "TP_COMP_B_NCSI_TXEN")
			(clearance 0.1905)
			(thermal_gap 0.1905)
		)
		(pad "B6" thru_hole circle
			(at -6.649974 3.24993 90)
			(size 1.0668 1.0668)
			(drill 0.719836)
			(layers "*.Cu" "*.Mask")
			(remove_unused_layers no)
			(net "TP_COMP_B_NCSI_TXD0")
			(clearance 0.1905)
			(thermal_gap 0.1905)
		)
		(pad "B7" thru_hole circle
			(at -5.649976 1.249934 90)
			(size 1.0668 1.0668)
			(drill 0.719836)
			(layers "*.Cu" "*.Mask")
			(remove_unused_layers no)
			(net "TP_COMP_B_NCSI_TXD1")
			(clearance 0.1905)
			(thermal_gap 0.1905)
		)
		(pad "B8" thru_hole circle
			(at -4.649978 3.24993 90)
			(size 1.0668 1.0668)
			(drill 0.719836)
			(layers "*.Cu" "*.Mask")
			(remove_unused_layers no)
			(net "TP_COMP_B_NCSI_CRSDV")
			(clearance 0.1905)
			(thermal_gap 0.1905)
		)
		(pad "B9" thru_hole circle
			(at -3.64998 1.249934 90)
			(size 1.0668 1.0668)
			(drill 0.719836)
			(layers "*.Cu" "*.Mask")
			(remove_unused_layers no)
			(net "TP_COMP_B_NCSI_RXER")
			(clearance 0.1905)
			(thermal_gap 0.1905)
		)
		(pad "B10" thru_hole circle
			(at -2.649982 3.24993 90)
			(size 1.0668 1.0668)
			(drill 0.719836)
			(layers "*.Cu" "*.Mask")
			(remove_unused_layers no)
			(net "GND")
			(clearance 0.1905)
			(thermal_gap 0.1905)
		)
		(pad "B11" thru_hole circle
			(at -1.649984 1.249934 90)
			(size 1.0668 1.0668)
			(drill 0.719836)
			(layers "*.Cu" "*.Mask")
			(remove_unused_layers no)
			(net "PCIE_COMP_B_TO_IOM_B_RST_3")
			(clearance 0.1905)
			(thermal_gap 0.1905)
		)
		(pad "B12" thru_hole circle
			(at 1.35001 3.24993 90)
			(size 1.0668 1.0668)
			(drill 0.719836)
			(layers "*.Cu" "*.Mask")
			(remove_unused_layers no)
			(net "PCIE_COMP_B_TO_IOM_B_RST_4")
			(clearance 0.1905)
			(thermal_gap 0.1905)
		)
		(pad "B13" thru_hole circle
			(at 2.350008 1.249934 90)
			(size 1.0668 1.0668)
			(drill 0.719836)
			(layers "*.Cu" "*.Mask")
			(remove_unused_layers no)
			(net "PCIE_COMP_B_RST_5")
			(clearance 0.1905)
			(thermal_gap 0.1905)
		)
		(pad "B14" thru_hole circle
			(at 3.350006 3.24993 90)
			(size 1.0668 1.0668)
			(drill 0.719836)
			(layers "*.Cu" "*.Mask")
			(remove_unused_layers no)
			(net "GND")
			(clearance 0.1905)
			(thermal_gap 0.1905)
		)
		(pad "B15" thru_hole circle
			(at 4.350004 1.249934 90)
			(size 1.0668 1.0668)
			(drill 0.719836)
			(layers "*.Cu" "*.Mask")
			(remove_unused_layers no)
			(net "Net_1382")
			(clearance 0.1905)
			(thermal_gap 0.1905)
		)
		(pad "B16" thru_hole circle
			(at 5.350002 3.24993 90)
			(size 1.0668 1.0668)
			(drill 0.719836)
			(layers "*.Cu" "*.Mask")
			(remove_unused_layers no)
			(net "Net_1381")
			(clearance 0.1905)
			(thermal_gap 0.1905)
		)
		(pad "B17" thru_hole circle
			(at 6.35 1.249934 90)
			(size 1.0668 1.0668)
			(drill 0.719836)
			(layers "*.Cu" "*.Mask")
			(remove_unused_layers no)
			(net "GND")
			(clearance 0.1905)
			(thermal_gap 0.1905)
		)
		(pad "B18" thru_hole circle
			(at 7.349998 3.24993 90)
			(size 1.0668 1.0668)
			(drill 0.719836)
			(layers "*.Cu" "*.Mask")
			(remove_unused_layers no)
			(net "GND")
			(clearance 0.1905)
			(thermal_gap 0.1905)
		)
		(pad "B19" thru_hole circle
			(at 8.349996 1.249934 90)
			(size 1.0668 1.0668)
			(drill 0.719836)
			(layers "*.Cu" "*.Mask")
			(remove_unused_layers no)
			(net "Net_1377")
			(clearance 0.1905)
			(thermal_gap 0.1905)
		)
		(pad "B20" thru_hole circle
			(at 9.349994 3.24993 90)
			(size 1.0668 1.0668)
			(drill 0.719836)
			(layers "*.Cu" "*.Mask")
			(remove_unused_layers no)
			(net "Net_1380")
			(clearance 0.1905)
			(thermal_gap 0.1905)
		)
		(pad "B21" thru_hole circle
			(at 10.349992 1.249934 90)
			(size 1.0668 1.0668)
			(drill 0.719836)
			(layers "*.Cu" "*.Mask")
			(remove_unused_layers no)
			(net "GND")
			(clearance 0.1905)
			(thermal_gap 0.1905)
		)
		(pad "B22" thru_hole circle
			(at 11.34999 3.24993 90)
			(size 1.0668 1.0668)
			(drill 0.719836)
			(layers "*.Cu" "*.Mask")
			(remove_unused_layers no)
			(net "GND")
			(clearance 0.1905)
			(thermal_gap 0.1905)
		)
		(pad "B23" thru_hole circle
			(at 12.349988 1.249934 90)
			(size 1.0668 1.0668)
			(drill 0.719836)
			(layers "*.Cu" "*.Mask")
			(remove_unused_layers no)
			(net "Net_1373")
			(clearance 0.1905)
			(thermal_gap 0.1905)
		)
		(pad "B24" thru_hole circle
			(at 13.349986 3.24993 90)
			(size 1.0668 1.0668)
			(drill 0.719836)
			(layers "*.Cu" "*.Mask")
			(remove_unused_layers no)
			(net "Net_1375")
			(clearance 0.1905)
			(thermal_gap 0.1905)
		)
		(pad "B25" thru_hole circle
			(at 14.349984 1.249934 90)
			(size 1.0668 1.0668)
			(drill 0.719836)
			(layers "*.Cu" "*.Mask")
			(remove_unused_layers no)
			(net "GND")
			(clearance 0.1905)
			(thermal_gap 0.1905)
		)
		(pad "B26" thru_hole circle
			(at 15.349982 3.24993 90)
			(size 1.0668 1.0668)
			(drill 0.719836)
			(layers "*.Cu" "*.Mask")
			(remove_unused_layers no)
			(net "GND")
			(clearance 0.1905)
			(thermal_gap 0.1905)
		)
		(pad "B27" thru_hole circle
			(at 16.34998 1.249934 90)
			(size 1.0668 1.0668)
			(drill 0.719836)
			(layers "*.Cu" "*.Mask")
			(remove_unused_layers no)
			(net "Net_1372")
			(clearance 0.1905)
			(thermal_gap 0.1905)
		)
		(pad "B28" thru_hole circle
			(at 17.349978 3.24993 90)
			(size 1.0668 1.0668)
			(drill 0.719836)
			(layers "*.Cu" "*.Mask")
			(remove_unused_layers no)
			(net "Net_1369")
			(clearance 0.1905)
			(thermal_gap 0.1905)
		)
		(pad "B29" thru_hole circle
			(at 18.349976 1.249934 90)
			(size 1.0668 1.0668)
			(drill 0.719836)
			(layers "*.Cu" "*.Mask")
			(remove_unused_layers no)
			(net "GND")
			(clearance 0.1905)
			(thermal_gap 0.1905)
		)
		(pad "B30" thru_hole circle
			(at 19.349974 3.24993 90)
			(size 1.0668 1.0668)
			(drill 0.719836)
			(layers "*.Cu" "*.Mask")
			(remove_unused_layers no)
			(net "GND")
			(clearance 0.1905)
			(thermal_gap 0.1905)
		)
		(pad "B31" thru_hole circle
			(at 20.349972 1.249934 90)
			(size 1.0668 1.0668)
			(drill 0.719836)
			(layers "*.Cu" "*.Mask")
			(remove_unused_layers no)
			(net "PCIE_COMP_B_TO_IOM_B_CLK_3_DP")
			(clearance 0.1905)
			(thermal_gap 0.1905)
		)
		(pad "B32" thru_hole circle
			(at 21.34997 3.24993 90)
			(size 1.0668 1.0668)
			(drill 0.719836)
			(layers "*.Cu" "*.Mask")
			(remove_unused_layers no)
			(net "PCIE_COMP_B_TO_IOM_B_CLK_3_DN")
			(clearance 0.1905)
			(thermal_gap 0.1905)
		)
		(pad "B33" thru_hole circle
			(at 22.349968 1.249934 90)
			(size 1.0668 1.0668)
			(drill 0.719836)
			(layers "*.Cu" "*.Mask")
			(remove_unused_layers no)
			(net "GND")
			(clearance 0.1905)
			(thermal_gap 0.1905)
		)
		(pad "B34" thru_hole circle
			(at 23.349966 3.24993 90)
			(size 1.0668 1.0668)
			(drill 0.719836)
			(layers "*.Cu" "*.Mask")
			(remove_unused_layers no)
			(net "GND")
			(clearance 0.1905)
			(thermal_gap 0.1905)
		)
		(pad "B35" thru_hole circle
			(at 24.349964 1.249934 90)
			(size 1.0668 1.0668)
			(drill 0.719836)
			(layers "*.Cu" "*.Mask")
			(remove_unused_layers no)
			(net "PCIE_COMP_B_TO_IOM_B_12_DP")
			(clearance 0.1905)
			(thermal_gap 0.1905)
		)
		(pad "B36" thru_hole circle
			(at 25.349962 3.24993 90)
			(size 1.0668 1.0668)
			(drill 0.719836)
			(layers "*.Cu" "*.Mask")
			(remove_unused_layers no)
			(net "PCIE_COMP_B_TO_IOM_B_12_DN")
			(clearance 0.1905)
			(thermal_gap 0.1905)
		)
		(pad "B37" thru_hole circle
			(at 26.34996 1.249934 90)
			(size 1.0668 1.0668)
			(drill 0.719836)
			(layers "*.Cu" "*.Mask")
			(remove_unused_layers no)
			(net "GND")
			(clearance 0.1905)
			(thermal_gap 0.1905)
		)
		(pad "B38" thru_hole circle
			(at 27.349958 3.24993 90)
			(size 1.0668 1.0668)
			(drill 0.719836)
			(layers "*.Cu" "*.Mask")
			(remove_unused_layers no)
			(net "GND")
			(clearance 0.1905)
			(thermal_gap 0.1905)
		)
		(pad "B39" thru_hole circle
			(at 28.349956 1.249934 90)
			(size 1.0668 1.0668)
			(drill 0.719836)
			(layers "*.Cu" "*.Mask")
			(remove_unused_layers no)
			(net "PCIE_COMP_B_TO_IOM_B_13_DP")
			(clearance 0.1905)
			(thermal_gap 0.1905)
		)
		(pad "B40" thru_hole circle
			(at 29.349954 3.24993 90)
			(size 1.0668 1.0668)
			(drill 0.719836)
			(layers "*.Cu" "*.Mask")
			(remove_unused_layers no)
			(net "PCIE_COMP_B_TO_IOM_B_13_DN")
			(clearance 0.1905)
			(thermal_gap 0.1905)
		)
		(pad "B41" thru_hole circle
			(at 30.349952 1.249934 90)
			(size 1.0668 1.0668)
			(drill 0.719836)
			(layers "*.Cu" "*.Mask")
			(remove_unused_layers no)
			(net "GND")
			(clearance 0.1905)
			(thermal_gap 0.1905)
		)
		(pad "B42" thru_hole circle
			(at 31.34995 3.24993 90)
			(size 1.0668 1.0668)
			(drill 0.719836)
			(layers "*.Cu" "*.Mask")
			(remove_unused_layers no)
			(net "GND")
			(clearance 0.1905)
			(thermal_gap 0.1905)
		)
		(pad "B43" thru_hole circle
			(at 32.349948 1.249934 90)
			(size 1.0668 1.0668)
			(drill 0.719836)
			(layers "*.Cu" "*.Mask")
			(remove_unused_layers no)
			(net "PCIE_COMP_B_TO_IOM_B_14_DP")
			(clearance 0.1905)
			(thermal_gap 0.1905)
		)
		(pad "B44" thru_hole circle
			(at 33.349946 3.24993 90)
			(size 1.0668 1.0668)
			(drill 0.719836)
			(layers "*.Cu" "*.Mask")
			(remove_unused_layers no)
			(net "PCIE_COMP_B_TO_IOM_B_14_DN")
			(clearance 0.1905)
			(thermal_gap 0.1905)
		)
		(pad "B45" thru_hole circle
			(at 34.349944 1.249934 90)
			(size 1.0668 1.0668)
			(drill 0.719836)
			(layers "*.Cu" "*.Mask")
			(remove_unused_layers no)
			(net "GND")
			(clearance 0.1905)
			(thermal_gap 0.1905)
		)
		(pad "B46" thru_hole circle
			(at 35.349942 3.24993 90)
			(size 1.0668 1.0668)
			(drill 0.719836)
			(layers "*.Cu" "*.Mask")
			(remove_unused_layers no)
			(net "GND")
			(clearance 0.1905)
			(thermal_gap 0.1905)
		)
		(pad "B47" thru_hole circle
			(at 36.34994 1.249934 90)
			(size 1.0668 1.0668)
			(drill 0.719836)
			(layers "*.Cu" "*.Mask")
			(remove_unused_layers no)
			(net "PCIE_COMP_B_TO_IOM_B_15_DP")
			(clearance 0.1905)
			(thermal_gap 0.1905)
		)
		(pad "B48" thru_hole circle
			(at 37.349938 3.24993 90)
			(size 1.0668 1.0668)
			(drill 0.719836)
			(layers "*.Cu" "*.Mask")
			(remove_unused_layers no)
			(net "PCIE_COMP_B_TO_IOM_B_15_DN")
			(clearance 0.1905)
			(thermal_gap 0.1905)
		)
		(pad "B49" thru_hole circle
			(at 38.349936 1.249934 90)
			(size 1.0668 1.0668)
			(drill 0.719836)
			(layers "*.Cu" "*.Mask")
			(remove_unused_layers no)
			(net "GND")
			(clearance 0.1905)
			(thermal_gap 0.1905)
		)
		(pad "B50" thru_hole circle
			(at 39.349934 3.24993 90)
			(size 1.0668 1.0668)
			(drill 0.719836)
			(layers "*.Cu" "*.Mask")
			(remove_unused_layers no)
			(net "GND")
			(clearance 0.1905)
			(thermal_gap 0.1905)
		)
		(pad "B51" thru_hole circle
			(at 40.349932 1.249934 90)
			(size 1.0668 1.0668)
			(drill 0.719836)
			(layers "*.Cu" "*.Mask")
			(remove_unused_layers no)
			(net "PCIE_COMP_B_TO_IOM_B_16_DP")
			(clearance 0.1905)
			(thermal_gap 0.1905)
		)
		(pad "B52" thru_hole circle
			(at 41.34993 3.24993 90)
			(size 1.0668 1.0668)
			(drill 0.719836)
			(layers "*.Cu" "*.Mask")
			(remove_unused_layers no)
			(net "PCIE_COMP_B_TO_IOM_B_16_DN")
			(clearance 0.1905)
			(thermal_gap 0.1905)
		)
		(pad "B53" thru_hole circle
			(at 42.349928 1.249934 90)
			(size 1.0668 1.0668)
			(drill 0.719836)
			(layers "*.Cu" "*.Mask")
			(remove_unused_layers no)
			(net "GND")
			(clearance 0.1905)
			(thermal_gap 0.1905)
		)
		(pad "B54" thru_hole circle
			(at 43.349926 3.24993 90)
			(size 1.0668 1.0668)
			(drill 0.719836)
			(layers "*.Cu" "*.Mask")
			(remove_unused_layers no)
			(net "GND")
			(clearance 0.1905)
			(thermal_gap 0.1905)
		)
		(pad "B55" thru_hole circle
			(at 44.349924 1.249934 90)
			(size 1.0668 1.0668)
			(drill 0.719836)
			(layers "*.Cu" "*.Mask")
			(remove_unused_layers no)
			(net "PCIE_COMP_B_TO_IOM_B_17_DP")
			(clearance 0.1905)
			(thermal_gap 0.1905)
		)
		(pad "B56" thru_hole circle
			(at 45.349922 3.24993 90)
			(size 1.0668 1.0668)
			(drill 0.719836)
			(layers "*.Cu" "*.Mask")
			(remove_unused_layers no)
			(net "PCIE_COMP_B_TO_IOM_B_17_DN")
			(clearance 0.1905)
			(thermal_gap 0.1905)
		)
		(pad "B57" thru_hole circle
			(at 46.34992 1.249934 90)
			(size 1.0668 1.0668)
			(drill 0.719836)
			(layers "*.Cu" "*.Mask")
			(remove_unused_layers no)
			(net "GND")
			(clearance 0.1905)
			(thermal_gap 0.1905)
		)
		(pad "B58" thru_hole circle
			(at 47.349918 3.24993 90)
			(size 1.0668 1.0668)
			(drill 0.719836)
			(layers "*.Cu" "*.Mask")
			(remove_unused_layers no)
			(net "GND")
			(clearance 0.1905)
			(thermal_gap 0.1905)
		)
		(pad "B59" thru_hole circle
			(at 48.349916 1.249934 90)
			(size 1.0668 1.0668)
			(drill 0.719836)
			(layers "*.Cu" "*.Mask")
			(remove_unused_layers no)
			(net "PCIE_COMP_B_TO_IOM_B_18_DP")
			(clearance 0.1905)
			(thermal_gap 0.1905)
		)
		(pad "B60" thru_hole circle
			(at 49.349914 3.24993 90)
			(size 1.0668 1.0668)
			(drill 0.719836)
			(layers "*.Cu" "*.Mask")
			(remove_unused_layers no)
			(net "PCIE_COMP_B_TO_IOM_B_18_DN")
			(clearance 0.1905)
			(thermal_gap 0.1905)
		)
		(pad "B61" thru_hole circle
			(at 50.349912 1.249934 90)
			(size 1.0668 1.0668)
			(drill 0.719836)
			(layers "*.Cu" "*.Mask")
			(remove_unused_layers no)
			(net "GND")
			(clearance 0.1905)
			(thermal_gap 0.1905)
		)
		(pad "B62" thru_hole circle
			(at 51.34991 3.24993 90)
			(size 1.0668 1.0668)
			(drill 0.719836)
			(layers "*.Cu" "*.Mask")
			(remove_unused_layers no)
			(net "GND")
			(clearance 0.1905)
			(thermal_gap 0.1905)
		)
		(pad "B63" thru_hole circle
			(at 52.349908 1.249934 90)
			(size 1.0668 1.0668)
			(drill 0.719836)
			(layers "*.Cu" "*.Mask")
			(remove_unused_layers no)
			(net "PCIE_COMP_B_TO_IOM_B_19_DP")
			(clearance 0.1905)
			(thermal_gap 0.1905)
		)
		(pad "B64" thru_hole circle
			(at 53.349906 3.24993 90)
			(size 1.0668 1.0668)
			(drill 0.719836)
			(layers "*.Cu" "*.Mask")
			(remove_unused_layers no)
			(net "PCIE_COMP_B_TO_IOM_B_19_DN")
			(clearance 0.1905)
			(thermal_gap 0.1905)
		)
		(pad "B65" thru_hole circle
			(at 54.349904 1.249934 90)
			(size 1.0668 1.0668)
			(drill 0.719836)
			(layers "*.Cu" "*.Mask")
			(remove_unused_layers no)
			(net "GND")
			(clearance 0.1905)
			(thermal_gap 0.1905)
		)
		(pad "B66" thru_hole circle
			(at 55.349902 3.24993 90)
			(size 1.0668 1.0668)
			(drill 0.719836)
			(layers "*.Cu" "*.Mask")
			(remove_unused_layers no)
			(net "GND")
			(clearance 0.1905)
			(thermal_gap 0.1905)
		)
		(pad "B67" thru_hole circle
			(at 56.3499 1.249934 90)
			(size 1.0668 1.0668)
			(drill 0.719836)
			(layers "*.Cu" "*.Mask")
			(remove_unused_layers no)
			(net "PCIE_COMP_B_TO_IOM_B_20_DP")
			(clearance 0.1905)
			(thermal_gap 0.1905)
		)
		(pad "B68" thru_hole circle
			(at 57.349898 3.24993 90)
			(size 1.0668 1.0668)
			(drill 0.719836)
			(layers "*.Cu" "*.Mask")
			(remove_unused_layers no)
			(net "PCIE_COMP_B_TO_IOM_B_20_DN")
			(clearance 0.1905)
			(thermal_gap 0.1905)
		)
		(pad "B69" thru_hole circle
			(at 58.349896 1.249934 90)
			(size 1.0668 1.0668)
			(drill 0.719836)
			(layers "*.Cu" "*.Mask")
			(remove_unused_layers no)
			(net "GND")
			(clearance 0.1905)
			(thermal_gap 0.1905)
		)
		(pad "B70" thru_hole circle
			(at 59.349894 3.24993 90)
			(size 1.0668 1.0668)
			(drill 0.719836)
			(layers "*.Cu" "*.Mask")
			(remove_unused_layers no)
			(net "GND")
			(clearance 0.1905)
			(thermal_gap 0.1905)
		)
		(pad "B71" thru_hole circle
			(at 60.349892 1.249934 90)
			(size 1.0668 1.0668)
			(drill 0.719836)
			(layers "*.Cu" "*.Mask")
			(remove_unused_layers no)
			(net "PCIE_COMP_B_TO_IOM_B_21_DP")
			(clearance 0.1905)
			(thermal_gap 0.1905)
		)
		(pad "B72" thru_hole circle
			(at 61.34989 3.24993 90)
			(size 1.0668 1.0668)
			(drill 0.719836)
			(layers "*.Cu" "*.Mask")
			(remove_unused_layers no)
			(net "PCIE_COMP_B_TO_IOM_B_21_DN")
			(clearance 0.1905)
			(thermal_gap 0.1905)
		)
		(pad "B73" thru_hole circle
			(at 62.349888 1.249934 90)
			(size 1.0668 1.0668)
			(drill 0.719836)
			(layers "*.Cu" "*.Mask")
			(remove_unused_layers no)
			(net "GND")
			(clearance 0.1905)
			(thermal_gap 0.1905)
		)
		(pad "B74" thru_hole circle
			(at 63.349886 3.24993 90)
			(size 1.0668 1.0668)
			(drill 0.719836)
			(layers "*.Cu" "*.Mask")
			(remove_unused_layers no)
			(net "GND")
			(clearance 0.1905)
			(thermal_gap 0.1905)
		)
		(pad "B75" thru_hole circle
			(at 64.349884 1.249934 90)
			(size 1.0668 1.0668)
			(drill 0.719836)
			(layers "*.Cu" "*.Mask")
			(remove_unused_layers no)
			(net "PCIE_COMP_B_TO_IOM_B_22_DP")
			(clearance 0.1905)
			(thermal_gap 0.1905)
		)
		(pad "B76" thru_hole circle
			(at 65.349882 3.24993 90)
			(size 1.0668 1.0668)
			(drill 0.719836)
			(layers "*.Cu" "*.Mask")
			(remove_unused_layers no)
			(net "PCIE_COMP_B_TO_IOM_B_22_DN")
			(clearance 0.1905)
			(thermal_gap 0.1905)
		)
		(pad "B77" thru_hole circle
			(at 66.34988 1.249934 90)
			(size 1.0668 1.0668)
			(drill 0.719836)
			(layers "*.Cu" "*.Mask")
			(remove_unused_layers no)
			(net "GND")
			(clearance 0.1905)
			(thermal_gap 0.1905)
		)
		(pad "B78" thru_hole circle
			(at 67.349878 3.24993 90)
			(size 1.0668 1.0668)
			(drill 0.719836)
			(layers "*.Cu" "*.Mask")
			(remove_unused_layers no)
			(net "GND")
			(clearance 0.1905)
			(thermal_gap 0.1905)
		)
		(pad "B79" thru_hole circle
			(at 68.349876 1.249934 90)
			(size 1.0668 1.0668)
			(drill 0.719836)
			(layers "*.Cu" "*.Mask")
			(remove_unused_layers no)
			(net "PCIE_COMP_B_TO_IOM_B_23_DP")
			(clearance 0.1905)
			(thermal_gap 0.1905)
		)
		(pad "B80" thru_hole circle
			(at 69.349874 3.24993 90)
			(size 1.0668 1.0668)
			(drill 0.719836)
			(layers "*.Cu" "*.Mask")
			(remove_unused_layers no)
			(net "PCIE_COMP_B_TO_IOM_B_23_DN")
			(clearance 0.1905)
			(thermal_gap 0.1905)
		)
		(pad "B81" thru_hole circle
			(at 70.350126 1.249934 90)
			(size 1.0668 1.0668)
			(drill 0.719836)
			(layers "*.Cu" "*.Mask")
			(remove_unused_layers no)
			(net "GND")
			(clearance 0.1905)
			(thermal_gap 0.1905)
		)
		(pad "B82" thru_hole circle
			(at 71.350124 3.24993 90)
			(size 1.0668 1.0668)
			(drill 0.719836)
			(layers "*.Cu" "*.Mask")
			(remove_unused_layers no)
			(net "COMP_B_POWER_FAIL_N")
			(clearance 0.1905)
			(thermal_gap 0.1905)
		)
		(zone
			(layers "F.Cu" "B.Cu" "In1.Cu" "In2.Cu" "In3.Cu" "In4.Cu" "In5.Cu" "In6.Cu"
				"In7.Cu" "In8.Cu" "In9.Cu" "In10.Cu"
			)
			(hatch none 0.5)
			(connect_pads
				(clearance 0)
			)
			(min_thickness 0.25)
			(keepout
				(tracks not_allowed)
				(vias allowed)
				(pads allowed)
				(copperpour not_allowed)
				(footprints allowed)
			)
			(placement
				(enabled no)
				(sheetname "")
			)
			(fill
				(thermal_gap 0.5)
				(thermal_bridge_width 0.5)
				(island_removal_mode 0)
			)
			(polygon
				(pts
					(arc
						(start 283.485844 -88.000078)
						(mid 280.514044 -88.000078)
						(end 283.485844 -88.000078)
					)
				)
			)
		)
		(zone
			(layers "F.Cu" "B.Cu" "In1.Cu" "In2.Cu" "In3.Cu" "In4.Cu" "In5.Cu" "In6.Cu"
				"In7.Cu" "In8.Cu" "In9.Cu" "In10.Cu"
			)
			(hatch none 0.5)
			(connect_pads
				(clearance 0)
			)
			(min_thickness 0.25)
			(keepout
				(tracks not_allowed)
				(vias allowed)
				(pads allowed)
				(copperpour not_allowed)
				(footprints allowed)
			)
			(placement
				(enabled no)
				(sheetname "")
			)
			(fill
				(thermal_gap 0.5)
				(thermal_bridge_width 0.5)
				(island_removal_mode 0)
			)
			(polygon
				(pts
					(arc
						(start 283.485844 -14.85011)
						(mid 280.514044 -14.85011)
						(end 283.485844 -14.85011)
					)
				)
			)
		)
	)
	(footprint ""
		(layer "F.Cu")
		(at 43.208194 -130.269996 -90)
		(property "Reference" "R504"
			(at 0 0 270)
			(layer "F.SilkS")
			(hide yes)
			(effects
				(font
					(size 1.27 1.27)
				)
			)
		)
		(property "Value" "4K7R2J-2-GP"
			(at 0.064008 -3.993896 270)
			(unlocked yes)
			(layer "F.Fab")
			(hide yes)
			(effects
				(font
					(size 1.016 1.016)
					(thickness 0.1524)
				)
			)
		)
		(property "Device Type" "R402H16"
			(at 0.064008 -5.517896 270)
			(unlocked yes)
			(layer "F.Fab")
			(hide yes)
			(effects
				(font
					(size 1.016 1.016)
					(thickness 0.1524)
				)
			)
		)
		(duplicate_pad_numbers_are_jumpers no)
		(fp_line
			(start -0.508 -0.9398)
			(end -0.508 0.9398)
			(stroke
				(width 0.1524)
				(type default)
			)
			(layer "F.SilkS")
		)
		(fp_line
			(start 0.508 -0.9398)
			(end -0.508 -0.9398)
			(stroke
				(width 0.1524)
				(type default)
			)
			(layer "F.SilkS")
		)
		(fp_rect
			(start -0.508 0.9398)
			(end 0.508 -0.9398)
			(stroke
				(width 0)
				(type default)
			)
			(fill no)
			(layer "F.CrtYd")
		)
		(fp_rect
			(start -0.508 0.9398)
			(end 0.508 -0.9398)
			(stroke
				(width 0)
				(type default)
			)
			(fill no)
			(layer "F.Fab")
		)
		(pad "1" smd custom
			(at 0 -0.4445 270)
			(size 0.1397 0.1397)
			(layers "F.Cu" "F.Mask" "F.Paste")
			(net "DRIVE_A_13_ACT")
			(options
				(clearance outline)
				(anchor circle)
			)
			(primitives
				(gr_poly
					(pts
						(arc
							(start -0.1778 -0.2794)
							(mid -0.249642 -0.249642)
							(end -0.2794 -0.1778)
						)
						(arc
							(start -0.2794 0.1778)
							(mid -0.249642 0.249642)
							(end -0.1778 0.2794)
						)
						(arc
							(start 0.1778 0.2794)
							(mid 0.249642 0.249642)
							(end 0.2794 0.1778)
						)
						(arc
							(start 0.2794 -0.1778)
							(mid 0.249642 -0.249642)
							(end 0.1778 -0.2794)
						)
					)
					(width 0)
					(fill yes)
				)
			)
		)
		(pad "2" smd custom
			(at 0 0.4445 270)
			(size 0.1397 0.1397)
			(layers "F.Cu" "F.Mask" "F.Paste")
			(net "GND")
			(options
				(clearance outline)
				(anchor circle)
			)
			(primitives
				(gr_poly
					(pts
						(arc
							(start -0.1778 -0.2794)
							(mid -0.249642 -0.249642)
							(end -0.2794 -0.1778)
						)
						(arc
							(start -0.2794 0.1778)
							(mid -0.249642 0.249642)
							(end -0.1778 0.2794)
						)
						(arc
							(start 0.1778 0.2794)
							(mid 0.249642 0.249642)
							(end 0.2794 0.1778)
						)
						(arc
							(start 0.2794 -0.1778)
							(mid 0.249642 -0.249642)
							(end 0.1778 -0.2794)
						)
					)
					(width 0)
					(fill yes)
				)
			)
		)
	)
	(footprint ""
		(layer "F.Cu")
		(at 471.301318 -41.52265)
		(property "Reference" "R947"
			(at 0 0 0)
			(layer "F.SilkS")
			(hide yes)
			(effects
				(font
					(size 1.27 1.27)
				)
			)
		)
		(property "Value" "4K7R2J-2-GP"
			(at 0.064008 -3.993896 0)
			(unlocked yes)
			(layer "F.Fab")
			(hide yes)
			(effects
				(font
					(size 1.016 1.016)
					(thickness 0.1524)
				)
			)
		)
		(property "Device Type" "R402H16"
			(at 0.064008 -5.517896 0)
			(unlocked yes)
			(layer "F.Fab")
			(hide yes)
			(effects
				(font
					(size 1.016 1.016)
					(thickness 0.1524)
				)
			)
		)
		(duplicate_pad_numbers_are_jumpers no)
		(fp_line
			(start -0.508 -0.9398)
			(end -0.508 0.9398)
			(stroke
				(width 0.1524)
				(type default)
			)
			(layer "F.SilkS")
		)
		(fp_line
			(start 0.508 -0.9398)
			(end -0.508 -0.9398)
			(stroke
				(width 0.1524)
				(type default)
			)
			(layer "F.SilkS")
		)
		(fp_rect
			(start -0.508 0.9398)
			(end 0.508 -0.9398)
			(stroke
				(width 0)
				(type default)
			)
			(fill no)
			(layer "F.CrtYd")
		)
		(fp_rect
			(start -0.508 0.9398)
			(end 0.508 -0.9398)
			(stroke
				(width 0)
				(type default)
			)
			(fill no)
			(layer "F.Fab")
		)
		(pad "1" smd custom
			(at 0 -0.4445)
			(size 0.1397 0.1397)
			(layers "F.Cu" "F.Mask" "F.Paste")
			(net "SW_PWR_R_HDD35")
			(options
				(clearance outline)
				(anchor circle)
			)
			(primitives
				(gr_poly
					(pts
						(arc
							(start -0.1778 -0.2794)
							(mid -0.249642 -0.249642)
							(end -0.2794 -0.1778)
						)
						(arc
							(start -0.2794 0.1778)
							(mid -0.249642 0.249642)
							(end -0.1778 0.2794)
						)
						(arc
							(start 0.1778 0.2794)
							(mid 0.249642 0.249642)
							(end 0.2794 0.1778)
						)
						(arc
							(start 0.2794 -0.1778)
							(mid 0.249642 -0.249642)
							(end 0.1778 -0.2794)
						)
					)
					(width 0)
					(fill yes)
				)
			)
		)
		(pad "2" smd custom
			(at 0 0.4445)
			(size 0.1397 0.1397)
			(layers "F.Cu" "F.Mask" "F.Paste")
			(net "GND")
			(options
				(clearance outline)
				(anchor circle)
			)
			(primitives
				(gr_poly
					(pts
						(arc
							(start -0.1778 -0.2794)
							(mid -0.249642 -0.249642)
							(end -0.2794 -0.1778)
						)
						(arc
							(start -0.2794 0.1778)
							(mid -0.249642 0.249642)
							(end -0.1778 0.2794)
						)
						(arc
							(start 0.1778 0.2794)
							(mid 0.249642 0.249642)
							(end 0.2794 0.1778)
						)
						(arc
							(start 0.2794 -0.1778)
							(mid 0.249642 -0.249642)
							(end 0.1778 -0.2794)
						)
					)
					(width 0)
					(fill yes)
				)
			)
		)
	)
	(footprint ""
		(layer "F.Cu")
		(at 30.935676 -245.38305 -90)
		(property "Reference" "R1214"
			(at 0 0 270)
			(layer "F.SilkS")
			(hide yes)
			(effects
				(font
					(size 1.27 1.27)
				)
			)
		)
		(property "Value" "3D01R5F-GP"
			(at 0 -8.9535 270)
			(unlocked yes)
			(layer "F.Fab")
			(hide yes)
			(effects
				(font
					(size 1.27 1.016)
					(thickness 0.1524)
				)
			)
		)
		(property "Device Type" "R805H24"
			(at 0 -10.6299 270)
			(unlocked yes)
			(layer "F.Fab")
			(hide yes)
			(effects
				(font
					(size 1.27 1.016)
					(thickness 0.1524)
				)
			)
		)
		(duplicate_pad_numbers_are_jumpers no)
		(fp_line
			(start -0.889 1.7018)
			(end 0.889 1.7018)
			(stroke
				(width 0.1524)
				(type default)
			)
			(layer "F.SilkS")
		)
		(fp_line
			(start 0.889 1.7018)
			(end 0.889 -0.508)
			(stroke
				(width 0.1524)
				(type default)
			)
			(layer "F.SilkS")
		)
		(fp_line
			(start -0.889 0.0762)
			(end -0.889 1.7018)
			(stroke
				(width 0.1524)
				(type default)
			)
			(layer "F.SilkS")
		)
		(fp_line
			(start -0.889 -1.7018)
			(end -0.889 0.2794)
			(stroke
				(width 0.1524)
				(type default)
			)
			(layer "F.SilkS")
		)
		(fp_line
			(start 0.889 -1.7018)
			(end 0.889 -0.381)
			(stroke
				(width 0.1524)
				(type default)
			)
			(layer "F.SilkS")
		)
		(fp_line
			(start 0.889 -1.7018)
			(end -0.889 -1.7018)
			(stroke
				(width 0.1524)
				(type default)
			)
			(layer "F.SilkS")
		)
		(fp_poly
			(pts
				(xy 0.9652 -1.778) (xy 0.9652 1.778) (xy -0.9652 1.778) (xy -0.9652 -1.778)
			)
			(stroke
				(width 0)
				(type default)
			)
			(fill no)
			(layer "F.CrtYd")
		)
		(fp_rect
			(start -0.9652 1.778)
			(end 0.9652 -1.778)
			(stroke
				(width 0)
				(type default)
			)
			(fill no)
			(layer "F.Fab")
		)
		(pad "1" smd rect
			(at 0 -0.9652 270)
			(size 1.397 1.143)
			(layers "F.Cu" "F.Mask" "F.Paste")
			(net "P5V_SNB")
		)
		(pad "2" smd rect
			(at 0 0.9652 270)
			(size 1.397 1.143)
			(layers "F.Cu" "F.Mask" "F.Paste")
			(net "GND")
		)
	)
	(footprint ""
		(layer "F.Cu")
		(at 339.37194 -127.767588 180)
		(property "Reference" "Q282"
			(at 0 0 180)
			(layer "F.SilkS")
			(hide yes)
			(effects
				(font
					(size 1.27 1.27)
				)
			)
		)
		(property "Value" "SSM3K324R-GP"
			(at 0.127 -8.9662 180)
			(unlocked yes)
			(layer "F.Fab")
			(hide yes)
			(effects
				(font
					(size 1.016 1.016)
					(thickness 0.1524)
				)
			)
		)
		(property "Device Type" "SOT23DGS2D4H35"
			(at 0.127 -10.4902 180)
			(unlocked yes)
			(layer "F.Fab")
			(hide yes)
			(effects
				(font
					(size 1.016 1.016)
					(thickness 0.1524)
				)
			)
		)
		(duplicate_pad_numbers_are_jumpers no)
		(fp_line
			(start 1.651 1.778)
			(end 1.651 -1.778)
			(stroke
				(width 0.1524)
				(type default)
			)
			(layer "F.SilkS")
		)
		(fp_line
			(start 1.651 -1.778)
			(end -1.651 -1.778)
			(stroke
				(width 0.1524)
				(type default)
			)
			(layer "F.SilkS")
		)
		(fp_line
			(start -1.651 1.778)
			(end 1.651 1.778)
			(stroke
				(width 0.1524)
				(type default)
			)
			(layer "F.SilkS")
		)
		(fp_line
			(start -1.651 -1.778)
			(end -1.651 1.778)
			(stroke
				(width 0.1524)
				(type default)
			)
			(layer "F.SilkS")
		)
		(fp_poly
			(pts
				(xy -1.778 1.8796) (xy -1.778 -1.8796) (xy 1.778 -1.8796) (xy 1.778 1.8796)
			)
			(stroke
				(width 0)
				(type default)
			)
			(fill no)
			(layer "F.CrtYd")
		)
		(fp_poly
			(pts
				(xy -1.778 1.8796) (xy -1.778 -1.8796) (xy 1.778 -1.8796) (xy 1.778 1.8796)
			)
			(stroke
				(width 0)
				(type default)
			)
			(fill no)
			(layer "F.Fab")
		)
		(pad "D" smd custom
			(at 0 -0.9525 180)
			(size 0.1905 0.1905)
			(layers "F.Cu" "F.Mask" "F.Paste")
			(net "DRV_ACT_19_N")
			(options
				(clearance outline)
				(anchor circle)
			)
			(primitives
				(gr_poly
					(pts
						(arc
							(start -0.1778 0.5715)
							(mid -0.321484 0.511984)
							(end -0.381 0.3683)
						)
						(arc
							(start -0.381 -0.3683)
							(mid -0.321484 -0.511984)
							(end -0.1778 -0.5715)
						)
						(arc
							(start 0.1778 -0.5715)
							(mid 0.321484 -0.511984)
							(end 0.381 -0.3683)
						)
						(arc
							(start 0.381 0.3683)
							(mid 0.321484 0.511984)
							(end 0.1778 0.5715)
						)
					)
					(width 0)
					(fill yes)
				)
			)
		)
		(pad "G" smd custom
			(at -0.98425 0.9525 180)
			(size 0.1905 0.1905)
			(layers "F.Cu" "F.Mask" "F.Paste")
			(net "DRIVE_A_19_ACT")
			(options
				(clearance outline)
				(anchor circle)
			)
			(primitives
				(gr_poly
					(pts
						(arc
							(start -0.1778 0.5715)
							(mid -0.321484 0.511984)
							(end -0.381 0.3683)
						)
						(arc
							(start -0.381 -0.3683)
							(mid -0.321484 -0.511984)
							(end -0.1778 -0.5715)
						)
						(arc
							(start 0.1778 -0.5715)
							(mid 0.321484 -0.511984)
							(end 0.381 -0.3683)
						)
						(arc
							(start 0.381 0.3683)
							(mid 0.321484 0.511984)
							(end 0.1778 0.5715)
						)
					)
					(width 0)
					(fill yes)
				)
			)
		)
		(pad "S" smd custom
			(at 0.98425 0.9525 180)
			(size 0.1905 0.1905)
			(layers "F.Cu" "F.Mask" "F.Paste")
			(net "GND")
			(options
				(clearance outline)
				(anchor circle)
			)
			(primitives
				(gr_poly
					(pts
						(arc
							(start -0.1778 0.5715)
							(mid -0.321484 0.511984)
							(end -0.381 0.3683)
						)
						(arc
							(start -0.381 -0.3683)
							(mid -0.321484 -0.511984)
							(end -0.1778 -0.5715)
						)
						(arc
							(start 0.1778 -0.5715)
							(mid 0.321484 -0.511984)
							(end 0.381 -0.3683)
						)
						(arc
							(start 0.381 0.3683)
							(mid 0.321484 0.511984)
							(end 0.1778 0.5715)
						)
					)
					(width 0)
					(fill yes)
				)
			)
		)
	)
	(footprint ""
		(layer "F.Cu")
		(at 83.784948 -170.285918 180)
		(property "Reference" "Q83"
			(at 0 0 180)
			(layer "F.SilkS")
			(hide yes)
			(effects
				(font
					(size 1.27 1.27)
				)
			)
		)
		(property "Value" "AO4406AL-GP"
			(at -3.707384 -1.5367 180)
			(unlocked yes)
			(layer "F.Fab")
			(hide yes)
			(effects
				(font
					(size 1.016 1.016)
					(thickness 0.1524)
				)
			)
		)
		(property "Device Type" "SOIC8H69"
			(at -3.707384 -3.0607 180)
			(unlocked yes)
			(layer "F.Fab")
			(hide yes)
			(effects
				(font
					(size 1.016 1.016)
					(thickness 0.1524)
				)
			)
		)
		(duplicate_pad_numbers_are_jumpers no)
		(fp_line
			(start 2.1336 1.4224)
			(end 2.1336 -1.4224)
			(stroke
				(width 0.1524)
				(type default)
			)
			(layer "F.SilkS")
		)
		(fp_line
			(start 2.1336 -1.4224)
			(end -2.7432 -1.4224)
			(stroke
				(width 0.1524)
				(type default)
			)
			(layer "F.SilkS")
		)
		(fp_line
			(start -2.1844 -0.0508)
			(end -2.7178 0.508)
			(stroke
				(width 0.1524)
				(type default)
			)
			(layer "F.SilkS")
		)
		(fp_line
			(start -2.6289 3.4417)
			(end -2.6289 1.4732)
			(stroke
				(width 0.381)
				(type default)
			)
			(layer "F.SilkS")
		)
		(fp_line
			(start -2.7178 -0.508)
			(end -2.1844 -0.0508)
			(stroke
				(width 0.1524)
				(type default)
			)
			(layer "F.SilkS")
		)
		(fp_line
			(start -2.7432 1.4224)
			(end 2.1336 1.4224)
			(stroke
				(width 0.1524)
				(type default)
			)
			(layer "F.SilkS")
		)
		(fp_line
			(start -2.7432 1.4224)
			(end -2.6416 1.4224)
			(stroke
				(width 0.1524)
				(type default)
			)
			(layer "F.SilkS")
		)
		(fp_line
			(start -2.7432 -1.4224)
			(end -2.7432 1.4224)
			(stroke
				(width 0.1524)
				(type default)
			)
			(layer "F.SilkS")
		)
		(fp_poly
			(pts
				(xy -2.2098 -1.4224) (xy -2.2098 1.4224) (xy 2.2098 1.4224) (xy 2.2098 -1.4224)
			)
			(stroke
				(width 0)
				(type default)
			)
			(fill yes)
			(layer "F.SilkS")
		)
		(fp_rect
			(start -2.450084 2.999994)
			(end 2.450084 -2.999994)
			(stroke
				(width 0)
				(type default)
			)
			(fill no)
			(layer "F.CrtYd")
		)
		(fp_poly
			(pts
				(xy -2.8194 3.6322) (xy -2.8194 -3.6322) (xy 2.8194 -3.6322) (xy 2.8194 1.18364) (xy 2.450084 1.18364)
				(xy 2.450084 -2.999994) (xy -2.450084 -2.999994) (xy -2.450084 2.999994) (xy 2.450084 2.999994)
				(xy 2.450084 1.18618) (xy 2.8194 1.18618) (xy 2.8194 3.6322)
			)
			(stroke
				(width 0)
				(type default)
			)
			(fill no)
			(layer "F.CrtYd")
		)
		(fp_rect
			(start -2.8194 3.6322)
			(end 2.8194 -3.6322)
			(stroke
				(width 0)
				(type default)
			)
			(fill no)
			(layer "F.Fab")
		)
		(pad "1" smd rect
			(at -1.905 2.54 180)
			(size 0.635 1.651)
			(layers "F.Cu" "F.Mask" "F.Paste")
			(net "P5V_HDD14")
		)
		(pad "2" smd rect
			(at -0.635 2.54 180)
			(size 0.635 1.651)
			(layers "F.Cu" "F.Mask" "F.Paste")
			(net "P5V_HDD14")
		)
		(pad "3" smd rect
			(at 0.635 2.54 180)
			(size 0.635 1.651)
			(layers "F.Cu" "F.Mask" "F.Paste")
			(net "P5V_HDD14")
		)
		(pad "4" smd rect
			(at 1.905 2.54 180)
			(size 0.635 1.651)
			(layers "F.Cu" "F.Mask" "F.Paste")
			(net "SW_HDD_P14")
		)
		(pad "5" smd rect
			(at 1.905 -2.54 180)
			(size 0.635 1.651)
			(layers "F.Cu" "F.Mask" "F.Paste")
			(net "P5V_A_1")
		)
		(pad "6" smd rect
			(at 0.635 -2.54 180)
			(size 0.635 1.651)
			(layers "F.Cu" "F.Mask" "F.Paste")
			(net "P5V_A_1")
		)
		(pad "7" smd rect
			(at -0.635 -2.54 180)
			(size 0.635 1.651)
			(layers "F.Cu" "F.Mask" "F.Paste")
			(net "P5V_A_1")
		)
		(pad "8" smd rect
			(at -1.905 -2.54 180)
			(size 0.635 1.651)
			(layers "F.Cu" "F.Mask" "F.Paste")
			(net "P5V_A_1")
		)
	)
	(footprint ""
		(layer "F.Cu")
		(at 479.384614 -273.660616 -90)
		(property "Reference" "C182"
			(at 0 0 270)
			(layer "F.SilkS")
			(hide yes)
			(effects
				(font
					(size 1.27 1.27)
				)
			)
		)
		(property "Value" "SCD01U16V1KX-GP"
			(at -2.8321 -1.7399 270)
			(unlocked yes)
			(layer "F.Fab")
			(hide yes)
			(effects
				(font
					(size 1.016 1.016)
					(thickness 0.1524)
				)
			)
		)
		(property "Device Type" "C0201H13"
			(at -2.8321 -3.2639 270)
			(unlocked yes)
			(layer "F.Fab")
			(hide yes)
			(effects
				(font
					(size 1.016 1.016)
					(thickness 0.1524)
				)
			)
		)
		(duplicate_pad_numbers_are_jumpers no)
		(fp_rect
			(start -0.2794 0.6477)
			(end 0.2794 -0.6477)
			(stroke
				(width 0)
				(type default)
			)
			(fill no)
			(layer "F.CrtYd")
		)
		(fp_rect
			(start -0.2794 0.6477)
			(end 0.2794 -0.6477)
			(stroke
				(width 0)
				(type default)
			)
			(fill no)
			(layer "F.Fab")
		)
		(pad "1" smd custom
			(at 0 -0.2794 270)
			(size 0.0762 0.0762)
			(layers "F.Cu" "F.Mask" "F.Paste")
			(net "SAS_HDD_RX_P11")
			(options
				(clearance outline)
				(anchor circle)
			)
			(primitives
				(gr_poly
					(pts
						(arc
							(start 0.1524 -0.127)
							(mid 0.137521 -0.162921)
							(end 0.1016 -0.1778)
						)
						(arc
							(start -0.1016 -0.1778)
							(mid -0.137521 -0.162921)
							(end -0.1524 -0.127)
						)
						(arc
							(start -0.1524 0.127)
							(mid -0.137521 0.162921)
							(end -0.1016 0.1778)
						)
						(arc
							(start 0.1016 0.1778)
							(mid 0.137521 0.162921)
							(end 0.1524 0.127)
						)
					)
					(width 0)
					(fill yes)
				)
			)
		)
		(pad "2" smd custom
			(at 0 0.2794 270)
			(size 0.0762 0.0762)
			(layers "F.Cu" "F.Mask" "F.Paste")
			(net "PHY_SCC_A_TO_DRV_A_11_DP")
			(options
				(clearance outline)
				(anchor circle)
			)
			(primitives
				(gr_poly
					(pts
						(arc
							(start 0.1524 -0.127)
							(mid 0.137521 -0.162921)
							(end 0.1016 -0.1778)
						)
						(arc
							(start -0.1016 -0.1778)
							(mid -0.137521 -0.162921)
							(end -0.1524 -0.127)
						)
						(arc
							(start -0.1524 0.127)
							(mid -0.137521 0.162921)
							(end -0.1016 0.1778)
						)
						(arc
							(start 0.1016 0.1778)
							(mid 0.137521 0.162921)
							(end 0.1524 0.127)
						)
					)
					(width 0)
					(fill yes)
				)
			)
		)
	)
	(footprint ""
		(layer "F.Cu")
		(at 20.684998 -170.285918 180)
		(property "Reference" "Q72"
			(at 0 0 180)
			(layer "F.SilkS")
			(hide yes)
			(effects
				(font
					(size 1.27 1.27)
				)
			)
		)
		(property "Value" "AO4406AL-GP"
			(at -3.707384 -1.5367 180)
			(unlocked yes)
			(layer "F.Fab")
			(hide yes)
			(effects
				(font
					(size 1.016 1.016)
					(thickness 0.1524)
				)
			)
		)
		(property "Device Type" "SOIC8H69"
			(at -3.707384 -3.0607 180)
			(unlocked yes)
			(layer "F.Fab")
			(hide yes)
			(effects
				(font
					(size 1.016 1.016)
					(thickness 0.1524)
				)
			)
		)
		(duplicate_pad_numbers_are_jumpers no)
		(fp_line
			(start 2.1336 1.4224)
			(end 2.1336 -1.4224)
			(stroke
				(width 0.1524)
				(type default)
			)
			(layer "F.SilkS")
		)
		(fp_line
			(start 2.1336 -1.4224)
			(end -2.7432 -1.4224)
			(stroke
				(width 0.1524)
				(type default)
			)
			(layer "F.SilkS")
		)
		(fp_line
			(start -2.1844 -0.0508)
			(end -2.7178 0.508)
			(stroke
				(width 0.1524)
				(type default)
			)
			(layer "F.SilkS")
		)
		(fp_line
			(start -2.6289 3.4417)
			(end -2.6289 1.4732)
			(stroke
				(width 0.381)
				(type default)
			)
			(layer "F.SilkS")
		)
		(fp_line
			(start -2.7178 -0.508)
			(end -2.1844 -0.0508)
			(stroke
				(width 0.1524)
				(type default)
			)
			(layer "F.SilkS")
		)
		(fp_line
			(start -2.7432 1.4224)
			(end 2.1336 1.4224)
			(stroke
				(width 0.1524)
				(type default)
			)
			(layer "F.SilkS")
		)
		(fp_line
			(start -2.7432 1.4224)
			(end -2.6416 1.4224)
			(stroke
				(width 0.1524)
				(type default)
			)
			(layer "F.SilkS")
		)
		(fp_line
			(start -2.7432 -1.4224)
			(end -2.7432 1.4224)
			(stroke
				(width 0.1524)
				(type default)
			)
			(layer "F.SilkS")
		)
		(fp_poly
			(pts
				(xy -2.2098 -1.4224) (xy -2.2098 1.4224) (xy 2.2098 1.4224) (xy 2.2098 -1.4224)
			)
			(stroke
				(width 0)
				(type default)
			)
			(fill yes)
			(layer "F.SilkS")
		)
		(fp_rect
			(start -2.450084 2.999994)
			(end 2.450084 -2.999994)
			(stroke
				(width 0)
				(type default)
			)
			(fill no)
			(layer "F.CrtYd")
		)
		(fp_poly
			(pts
				(xy -2.8194 3.6322) (xy -2.8194 -3.6322) (xy 2.8194 -3.6322) (xy 2.8194 1.18364) (xy 2.450084 1.18364)
				(xy 2.450084 -2.999994) (xy -2.450084 -2.999994) (xy -2.450084 2.999994) (xy 2.450084 2.999994)
				(xy 2.450084 1.18618) (xy 2.8194 1.18618) (xy 2.8194 3.6322)
			)
			(stroke
				(width 0)
				(type default)
			)
			(fill no)
			(layer "F.CrtYd")
		)
		(fp_rect
			(start -2.8194 3.6322)
			(end 2.8194 -3.6322)
			(stroke
				(width 0)
				(type default)
			)
			(fill no)
			(layer "F.Fab")
		)
		(pad "1" smd rect
			(at -1.905 2.54 180)
			(size 0.635 1.651)
			(layers "F.Cu" "F.Mask" "F.Paste")
			(net "P5V_HDD12")
		)
		(pad "2" smd rect
			(at -0.635 2.54 180)
			(size 0.635 1.651)
			(layers "F.Cu" "F.Mask" "F.Paste")
			(net "P5V_HDD12")
		)
		(pad "3" smd rect
			(at 0.635 2.54 180)
			(size 0.635 1.651)
			(layers "F.Cu" "F.Mask" "F.Paste")
			(net "P5V_HDD12")
		)
		(pad "4" smd rect
			(at 1.905 2.54 180)
			(size 0.635 1.651)
			(layers "F.Cu" "F.Mask" "F.Paste")
			(net "SW_HDD_P12")
		)
		(pad "5" smd rect
			(at 1.905 -2.54 180)
			(size 0.635 1.651)
			(layers "F.Cu" "F.Mask" "F.Paste")
			(net "P5V_A_1")
		)
		(pad "6" smd rect
			(at 0.635 -2.54 180)
			(size 0.635 1.651)
			(layers "F.Cu" "F.Mask" "F.Paste")
			(net "P5V_A_1")
		)
		(pad "7" smd rect
			(at -0.635 -2.54 180)
			(size 0.635 1.651)
			(layers "F.Cu" "F.Mask" "F.Paste")
			(net "P5V_A_1")
		)
		(pad "8" smd rect
			(at -1.905 -2.54 180)
			(size 0.635 1.651)
			(layers "F.Cu" "F.Mask" "F.Paste")
			(net "P5V_A_1")
		)
	)
	(footprint ""
		(layer "F.Cu")
		(at 473.514928 -127.254)
		(property "Reference" "R346"
			(at 0 0 0)
			(layer "F.SilkS")
			(hide yes)
			(effects
				(font
					(size 1.27 1.27)
				)
			)
		)
		(property "Value" "91R3F-1-GP"
			(at -0.0254 -2.5146 0)
			(unlocked yes)
			(layer "F.Fab")
			(hide yes)
			(effects
				(font
					(size 1.016 1.016)
					(thickness 0.1524)
				)
			)
		)
		(property "Device Type" "R603H22"
			(at -0.0254 -4.0386 0)
			(unlocked yes)
			(layer "F.Fab")
			(hide yes)
			(effects
				(font
					(size 1.016 1.016)
					(thickness 0.1524)
				)
			)
		)
		(duplicate_pad_numbers_are_jumpers no)
		(fp_line
			(start -0.4826 0)
			(end -0.2032 0)
			(stroke
				(width 0.2032)
				(type default)
			)
			(layer "F.SilkS")
		)
		(fp_line
			(start 0.2032 0)
			(end 0.4826 0)
			(stroke
				(width 0.2032)
				(type default)
			)
			(layer "F.SilkS")
		)
		(fp_rect
			(start -0.5842 1.3335)
			(end 0.5842 -1.3335)
			(stroke
				(width 0)
				(type default)
			)
			(fill no)
			(layer "F.CrtYd")
		)
		(fp_rect
			(start -0.5842 1.3335)
			(end 0.5842 -1.3335)
			(stroke
				(width 0)
				(type default)
			)
			(fill no)
			(layer "F.Fab")
		)
		(pad "1" smd custom
			(at 0 -0.762)
			(size 0.2159 0.2159)
			(layers "F.Cu" "F.Mask" "F.Paste")
			(net "P5V_A_4")
			(options
				(clearance outline)
				(anchor circle)
			)
			(primitives
				(gr_poly
					(pts
						(arc
							(start -0.3302 -0.4318)
							(mid -0.402042 -0.402042)
							(end -0.4318 -0.3302)
						)
						(arc
							(start -0.4318 0.3302)
							(mid -0.402042 0.402042)
							(end -0.3302 0.4318)
						)
						(arc
							(start 0.3302 0.4318)
							(mid 0.402042 0.402042)
							(end 0.4318 0.3302)
						)
						(arc
							(start 0.4318 -0.3302)
							(mid 0.402042 -0.402042)
							(end 0.3302 -0.4318)
						)
					)
					(width 0)
					(fill yes)
				)
			)
		)
		(pad "2" smd custom
			(at 0 0.762)
			(size 0.2159 0.2159)
			(layers "F.Cu" "F.Mask" "F.Paste")
			(net "DRV_ACT_23")
			(options
				(clearance outline)
				(anchor circle)
			)
			(primitives
				(gr_poly
					(pts
						(arc
							(start -0.3302 -0.4318)
							(mid -0.402042 -0.402042)
							(end -0.4318 -0.3302)
						)
						(arc
							(start -0.4318 0.3302)
							(mid -0.402042 0.402042)
							(end -0.3302 0.4318)
						)
						(arc
							(start 0.3302 0.4318)
							(mid 0.402042 0.402042)
							(end 0.4318 0.3302)
						)
						(arc
							(start 0.4318 -0.3302)
							(mid 0.402042 -0.402042)
							(end 0.3302 -0.4318)
						)
					)
					(width 0)
					(fill yes)
				)
			)
		)
	)
	(footprint ""
		(layer "F.Cu")
		(at 240.4618 -260.5532 180)
		(property "Reference" "R47"
			(at 0 0 180)
			(layer "F.SilkS")
			(hide yes)
			(effects
				(font
					(size 1.27 1.27)
				)
			)
		)
		(property "Value" "0R2J-2-GP"
			(at 0.064008 -3.993896 180)
			(unlocked yes)
			(layer "F.Fab")
			(hide yes)
			(effects
				(font
					(size 1.016 1.016)
					(thickness 0.1524)
				)
			)
		)
		(property "Device Type" "R402H16"
			(at 0.064008 -5.517896 180)
			(unlocked yes)
			(layer "F.Fab")
			(hide yes)
			(effects
				(font
					(size 1.016 1.016)
					(thickness 0.1524)
				)
			)
		)
		(duplicate_pad_numbers_are_jumpers no)
		(fp_line
			(start 0.508 -0.9398)
			(end -0.508 -0.9398)
			(stroke
				(width 0.1524)
				(type default)
			)
			(layer "F.SilkS")
		)
		(fp_line
			(start -0.508 -0.9398)
			(end -0.508 0.9398)
			(stroke
				(width 0.1524)
				(type default)
			)
			(layer "F.SilkS")
		)
		(fp_rect
			(start -0.508 0.9398)
			(end 0.508 -0.9398)
			(stroke
				(width 0)
				(type default)
			)
			(fill no)
			(layer "F.CrtYd")
		)
		(fp_rect
			(start -0.508 0.9398)
			(end 0.508 -0.9398)
			(stroke
				(width 0)
				(type default)
			)
			(fill no)
			(layer "F.Fab")
		)
		(pad "1" smd custom
			(at 0 -0.4445 180)
			(size 0.1397 0.1397)
			(layers "F.Cu" "F.Mask" "F.Paste")
			(net "IO_EXP5_SDA")
			(options
				(clearance outline)
				(anchor circle)
			)
			(primitives
				(gr_poly
					(pts
						(arc
							(start -0.1778 -0.2794)
							(mid -0.249642 -0.249642)
							(end -0.2794 -0.1778)
						)
						(arc
							(start -0.2794 0.1778)
							(mid -0.249642 0.249642)
							(end -0.1778 0.2794)
						)
						(arc
							(start 0.1778 0.2794)
							(mid 0.249642 0.249642)
							(end 0.2794 0.1778)
						)
						(arc
							(start 0.2794 -0.1778)
							(mid 0.249642 -0.249642)
							(end 0.1778 -0.2794)
						)
					)
					(width 0)
					(fill yes)
				)
			)
		)
		(pad "2" smd custom
			(at 0 0.4445 180)
			(size 0.1397 0.1397)
			(layers "F.Cu" "F.Mask" "F.Paste")
			(net "I2C_DRIVE_A_INS_SDA")
			(options
				(clearance outline)
				(anchor circle)
			)
			(primitives
				(gr_poly
					(pts
						(arc
							(start -0.1778 -0.2794)
							(mid -0.249642 -0.249642)
							(end -0.2794 -0.1778)
						)
						(arc
							(start -0.2794 0.1778)
							(mid -0.249642 0.249642)
							(end -0.1778 0.2794)
						)
						(arc
							(start 0.1778 0.2794)
							(mid 0.249642 0.249642)
							(end 0.2794 0.1778)
						)
						(arc
							(start 0.2794 -0.1778)
							(mid 0.249642 -0.249642)
							(end 0.1778 -0.2794)
						)
					)
					(width 0)
					(fill yes)
				)
			)
		)
	)
	(footprint ""
		(layer "F.Cu")
		(at 54.546246 -276.065742 -90)
		(property "Reference" "R161"
			(at 0 0 270)
			(layer "F.SilkS")
			(hide yes)
			(effects
				(font
					(size 1.27 1.27)
				)
			)
		)
		(property "Value" "1KR2F-3-GP"
			(at 0.064008 -3.993896 270)
			(unlocked yes)
			(layer "F.Fab")
			(hide yes)
			(effects
				(font
					(size 1.016 1.016)
					(thickness 0.1524)
				)
			)
		)
		(property "Device Type" "R402H16"
			(at 0.064008 -5.517896 270)
			(unlocked yes)
			(layer "F.Fab")
			(hide yes)
			(effects
				(font
					(size 1.016 1.016)
					(thickness 0.1524)
				)
			)
		)
		(duplicate_pad_numbers_are_jumpers no)
		(fp_line
			(start -0.508 -0.9398)
			(end -0.508 0.9398)
			(stroke
				(width 0.1524)
				(type default)
			)
			(layer "F.SilkS")
		)
		(fp_line
			(start 0.508 -0.9398)
			(end -0.508 -0.9398)
			(stroke
				(width 0.1524)
				(type default)
			)
			(layer "F.SilkS")
		)
		(fp_rect
			(start -0.508 0.9398)
			(end 0.508 -0.9398)
			(stroke
				(width 0)
				(type default)
			)
			(fill no)
			(layer "F.CrtYd")
		)
		(fp_rect
			(start -0.508 0.9398)
			(end 0.508 -0.9398)
			(stroke
				(width 0)
				(type default)
			)
			(fill no)
			(layer "F.Fab")
		)
		(pad "1" smd custom
			(at 0 -0.4445 270)
			(size 0.1397 0.1397)
			(layers "F.Cu" "F.Mask" "F.Paste")
			(net "P3V3_STBY_A")
			(options
				(clearance outline)
				(anchor circle)
			)
			(primitives
				(gr_poly
					(pts
						(arc
							(start -0.1778 -0.2794)
							(mid -0.249642 -0.249642)
							(end -0.2794 -0.1778)
						)
						(arc
							(start -0.2794 0.1778)
							(mid -0.249642 0.249642)
							(end -0.1778 0.2794)
						)
						(arc
							(start 0.1778 0.2794)
							(mid 0.249642 0.249642)
							(end 0.2794 0.1778)
						)
						(arc
							(start 0.2794 -0.1778)
							(mid 0.249642 -0.249642)
							(end 0.1778 -0.2794)
						)
					)
					(width 0)
					(fill yes)
				)
			)
		)
		(pad "2" smd custom
			(at 0 0.4445 270)
			(size 0.1397 0.1397)
			(layers "F.Cu" "F.Mask" "F.Paste")
			(net "SW_PWR_R_HDD1")
			(options
				(clearance outline)
				(anchor circle)
			)
			(primitives
				(gr_poly
					(pts
						(arc
							(start -0.1778 -0.2794)
							(mid -0.249642 -0.249642)
							(end -0.2794 -0.1778)
						)
						(arc
							(start -0.2794 0.1778)
							(mid -0.249642 0.249642)
							(end -0.1778 0.2794)
						)
						(arc
							(start 0.1778 0.2794)
							(mid 0.249642 0.249642)
							(end 0.2794 0.1778)
						)
						(arc
							(start 0.2794 -0.1778)
							(mid 0.249642 -0.249642)
							(end 0.1778 -0.2794)
						)
					)
					(width 0)
					(fill yes)
				)
			)
		)
	)
	(footprint ""
		(layer "F.Cu")
		(at 310.69534 -60.017914 -90)
		(property "Reference" "R396"
			(at 0 0 270)
			(layer "F.SilkS")
			(hide yes)
			(effects
				(font
					(size 1.27 1.27)
				)
			)
		)
		(property "Value" "10KR2F-2-GP"
			(at 0.064008 -3.993896 270)
			(unlocked yes)
			(layer "F.Fab")
			(hide yes)
			(effects
				(font
					(size 1.016 1.016)
					(thickness 0.1524)
				)
			)
		)
		(property "Device Type" "R402H16"
			(at 0.064008 -5.517896 270)
			(unlocked yes)
			(layer "F.Fab")
			(hide yes)
			(effects
				(font
					(size 1.016 1.016)
					(thickness 0.1524)
				)
			)
		)
		(duplicate_pad_numbers_are_jumpers no)
		(fp_line
			(start -0.508 -0.9398)
			(end -0.508 0.9398)
			(stroke
				(width 0.1524)
				(type default)
			)
			(layer "F.SilkS")
		)
		(fp_line
			(start 0.508 -0.9398)
			(end -0.508 -0.9398)
			(stroke
				(width 0.1524)
				(type default)
			)
			(layer "F.SilkS")
		)
		(fp_rect
			(start -0.508 0.9398)
			(end 0.508 -0.9398)
			(stroke
				(width 0)
				(type default)
			)
			(fill no)
			(layer "F.CrtYd")
		)
		(fp_rect
			(start -0.508 0.9398)
			(end 0.508 -0.9398)
			(stroke
				(width 0)
				(type default)
			)
			(fill no)
			(layer "F.Fab")
		)
		(pad "1" smd custom
			(at 0 -0.4445 270)
			(size 0.1397 0.1397)
			(layers "F.Cu" "F.Mask" "F.Paste")
			(net "SYS_B_RESET_BUFFER_N")
			(options
				(clearance outline)
				(anchor circle)
			)
			(primitives
				(gr_poly
					(pts
						(arc
							(start -0.1778 -0.2794)
							(mid -0.249642 -0.249642)
							(end -0.2794 -0.1778)
						)
						(arc
							(start -0.2794 0.1778)
							(mid -0.249642 0.249642)
							(end -0.1778 0.2794)
						)
						(arc
							(start 0.1778 0.2794)
							(mid 0.249642 0.249642)
							(end 0.2794 0.1778)
						)
						(arc
							(start 0.2794 -0.1778)
							(mid 0.249642 -0.249642)
							(end 0.1778 -0.2794)
						)
					)
					(width 0)
					(fill yes)
				)
			)
		)
		(pad "2" smd custom
			(at 0 0.4445 270)
			(size 0.1397 0.1397)
			(layers "F.Cu" "F.Mask" "F.Paste")
			(net "GND")
			(options
				(clearance outline)
				(anchor circle)
			)
			(primitives
				(gr_poly
					(pts
						(arc
							(start -0.1778 -0.2794)
							(mid -0.249642 -0.249642)
							(end -0.2794 -0.1778)
						)
						(arc
							(start -0.2794 0.1778)
							(mid -0.249642 0.249642)
							(end -0.1778 0.2794)
						)
						(arc
							(start 0.1778 0.2794)
							(mid 0.249642 0.249642)
							(end 0.2794 0.1778)
						)
						(arc
							(start 0.2794 -0.1778)
							(mid 0.249642 -0.249642)
							(end 0.1778 -0.2794)
						)
					)
					(width 0)
					(fill yes)
				)
			)
		)
	)
	(footprint ""
		(layer "F.Cu")
		(at 398.88795 -275.760942 180)
		(property "Reference" "R331"
			(at 0 0 180)
			(layer "F.SilkS")
			(hide yes)
			(effects
				(font
					(size 1.27 1.27)
				)
			)
		)
		(property "Value" "0R2J-2-GP"
			(at 0.064008 -3.993896 180)
			(unlocked yes)
			(layer "F.Fab")
			(hide yes)
			(effects
				(font
					(size 1.016 1.016)
					(thickness 0.1524)
				)
			)
		)
		(property "Device Type" "R402H16"
			(at 0.064008 -5.517896 180)
			(unlocked yes)
			(layer "F.Fab")
			(hide yes)
			(effects
				(font
					(size 1.016 1.016)
					(thickness 0.1524)
				)
			)
		)
		(duplicate_pad_numbers_are_jumpers no)
		(fp_line
			(start 0.508 -0.9398)
			(end -0.508 -0.9398)
			(stroke
				(width 0.1524)
				(type default)
			)
			(layer "F.SilkS")
		)
		(fp_line
			(start -0.508 -0.9398)
			(end -0.508 0.9398)
			(stroke
				(width 0.1524)
				(type default)
			)
			(layer "F.SilkS")
		)
		(fp_rect
			(start -0.508 0.9398)
			(end 0.508 -0.9398)
			(stroke
				(width 0)
				(type default)
			)
			(fill no)
			(layer "F.CrtYd")
		)
		(fp_rect
			(start -0.508 0.9398)
			(end 0.508 -0.9398)
			(stroke
				(width 0)
				(type default)
			)
			(fill no)
			(layer "F.Fab")
		)
		(pad "1" smd custom
			(at 0 -0.4445 180)
			(size 0.1397 0.1397)
			(layers "F.Cu" "F.Mask" "F.Paste")
			(net "SW_HDD_G8")
			(options
				(clearance outline)
				(anchor circle)
			)
			(primitives
				(gr_poly
					(pts
						(arc
							(start -0.1778 -0.2794)
							(mid -0.249642 -0.249642)
							(end -0.2794 -0.1778)
						)
						(arc
							(start -0.2794 0.1778)
							(mid -0.249642 0.249642)
							(end -0.1778 0.2794)
						)
						(arc
							(start 0.1778 0.2794)
							(mid 0.249642 0.249642)
							(end 0.2794 0.1778)
						)
						(arc
							(start 0.2794 -0.1778)
							(mid 0.249642 -0.249642)
							(end 0.1778 -0.2794)
						)
					)
					(width 0)
					(fill yes)
				)
			)
		)
		(pad "2" smd custom
			(at 0 0.4445 180)
			(size 0.1397 0.1397)
			(layers "F.Cu" "F.Mask" "F.Paste")
			(net "SW_HDD_R8")
			(options
				(clearance outline)
				(anchor circle)
			)
			(primitives
				(gr_poly
					(pts
						(arc
							(start -0.1778 -0.2794)
							(mid -0.249642 -0.249642)
							(end -0.2794 -0.1778)
						)
						(arc
							(start -0.2794 0.1778)
							(mid -0.249642 0.249642)
							(end -0.1778 0.2794)
						)
						(arc
							(start 0.1778 0.2794)
							(mid 0.249642 0.249642)
							(end 0.2794 0.1778)
						)
						(arc
							(start 0.2794 -0.1778)
							(mid 0.249642 -0.249642)
							(end 0.1778 -0.2794)
						)
					)
					(width 0)
					(fill yes)
				)
			)
		)
	)
	(footprint ""
		(layer "F.Cu")
		(at 457.699872 -188.999876 180)
		(property "Reference" "C330"
			(at 0 0 180)
			(layer "F.SilkS")
			(hide yes)
			(effects
				(font
					(size 1.27 1.27)
				)
			)
		)
		(property "Value" "SC4D7U25V5KX-1-GP"
			(at -0.0762 -6.1214 180)
			(unlocked yes)
			(layer "F.Fab")
			(hide yes)
			(effects
				(font
					(size 1.016 1.016)
					(thickness 0.1524)
				)
			)
		)
		(property "Device Type" "C805H58"
			(at -0.0762 -8.1534 180)
			(unlocked yes)
			(layer "F.Fab")
			(hide yes)
			(effects
				(font
					(size 1.016 1.016)
					(thickness 0.1524)
				)
			)
		)
		(duplicate_pad_numbers_are_jumpers no)
		(fp_line
			(start 0.635 0)
			(end -0.635 0)
			(stroke
				(width 0.508)
				(type default)
			)
			(layer "F.SilkS")
		)
		(fp_rect
			(start -0.9652 1.778)
			(end 0.9652 -1.778)
			(stroke
				(width 0)
				(type default)
			)
			(fill no)
			(layer "F.CrtYd")
		)
		(fp_poly
			(pts
				(xy -0.9652 -1.778) (xy 0.9652 -1.778) (xy 0.9652 1.778) (xy -0.9652 1.778)
			)
			(stroke
				(width 0)
				(type default)
			)
			(fill no)
			(layer "F.Fab")
		)
		(pad "1" smd rect
			(at 0 -0.9652 180)
			(size 1.397 1.143)
			(layers "F.Cu" "F.Mask" "F.Paste")
			(net "P12V_HDD22")
		)
		(pad "2" smd rect
			(at 0 0.9652 180)
			(size 1.397 1.143)
			(layers "F.Cu" "F.Mask" "F.Paste")
			(net "GND")
		)
	)
	(footprint ""
		(layer "F.Cu")
		(at 430.438052 -157.585918 180)
		(property "Reference" "R624"
			(at 0 0 180)
			(layer "F.SilkS")
			(hide yes)
			(effects
				(font
					(size 1.27 1.27)
				)
			)
		)
		(property "Value" "0R2J-2-GP"
			(at 0.064008 -3.993896 180)
			(unlocked yes)
			(layer "F.Fab")
			(hide yes)
			(effects
				(font
					(size 1.016 1.016)
					(thickness 0.1524)
				)
			)
		)
		(property "Device Type" "R402H16"
			(at 0.064008 -5.517896 180)
			(unlocked yes)
			(layer "F.Fab")
			(hide yes)
			(effects
				(font
					(size 1.016 1.016)
					(thickness 0.1524)
				)
			)
		)
		(duplicate_pad_numbers_are_jumpers no)
		(fp_line
			(start 0.508 -0.9398)
			(end -0.508 -0.9398)
			(stroke
				(width 0.1524)
				(type default)
			)
			(layer "F.SilkS")
		)
		(fp_line
			(start -0.508 -0.9398)
			(end -0.508 0.9398)
			(stroke
				(width 0.1524)
				(type default)
			)
			(layer "F.SilkS")
		)
		(fp_rect
			(start -0.508 0.9398)
			(end 0.508 -0.9398)
			(stroke
				(width 0)
				(type default)
			)
			(fill no)
			(layer "F.CrtYd")
		)
		(fp_rect
			(start -0.508 0.9398)
			(end 0.508 -0.9398)
			(stroke
				(width 0)
				(type default)
			)
			(fill no)
			(layer "F.Fab")
		)
		(pad "1" smd custom
			(at 0 -0.4445 180)
			(size 0.1397 0.1397)
			(layers "F.Cu" "F.Mask" "F.Paste")
			(net "DRIVE_A_21_PWR")
			(options
				(clearance outline)
				(anchor circle)
			)
			(primitives
				(gr_poly
					(pts
						(arc
							(start -0.1778 -0.2794)
							(mid -0.249642 -0.249642)
							(end -0.2794 -0.1778)
						)
						(arc
							(start -0.2794 0.1778)
							(mid -0.249642 0.249642)
							(end -0.1778 0.2794)
						)
						(arc
							(start 0.1778 0.2794)
							(mid 0.249642 0.249642)
							(end 0.2794 0.1778)
						)
						(arc
							(start 0.2794 -0.1778)
							(mid 0.249642 -0.249642)
							(end 0.1778 -0.2794)
						)
					)
					(width 0)
					(fill yes)
				)
			)
		)
		(pad "2" smd custom
			(at 0 0.4445 180)
			(size 0.1397 0.1397)
			(layers "F.Cu" "F.Mask" "F.Paste")
			(net "SW_PWR_R_HDD21")
			(options
				(clearance outline)
				(anchor circle)
			)
			(primitives
				(gr_poly
					(pts
						(arc
							(start -0.1778 -0.2794)
							(mid -0.249642 -0.249642)
							(end -0.2794 -0.1778)
						)
						(arc
							(start -0.2794 0.1778)
							(mid -0.249642 0.249642)
							(end -0.1778 0.2794)
						)
						(arc
							(start 0.1778 0.2794)
							(mid 0.249642 0.249642)
							(end 0.2794 0.1778)
						)
						(arc
							(start 0.2794 -0.1778)
							(mid 0.249642 -0.249642)
							(end 0.1778 -0.2794)
						)
					)
					(width 0)
					(fill yes)
				)
			)
		)
	)
	(footprint ""
		(layer "F.Cu")
		(at 315.149992 -94.400116)
		(property "Reference" "FLED19"
			(at 0 0 0)
			(layer "F.SilkS")
			(hide yes)
			(effects
				(font
					(size 1.27 1.27)
				)
			)
		)
		(property "Value" "LED-BY-19-GP"
			(at -2.132076 1.414018 0)
			(unlocked yes)
			(layer "F.Fab")
			(hide yes)
			(effects
				(font
					(size 1.016 1.016)
					(thickness 0.1524)
				)
			)
		)
		(property "Device Type" "LED-1615-4PH26"
			(at -2.132076 -0.109982 0)
			(unlocked yes)
			(layer "F.Fab")
			(hide yes)
			(effects
				(font
					(size 1.016 1.016)
					(thickness 0.1524)
				)
			)
		)
		(duplicate_pad_numbers_are_jumpers no)
		(fp_line
			(start -1.2954 0.254)
			(end -1.2954 1.6002)
			(stroke
				(width 0.508)
				(type default)
			)
			(layer "F.SilkS")
		)
		(fp_line
			(start -1.2954 1.6002)
			(end 1.2954 1.6002)
			(stroke
				(width 0.508)
				(type default)
			)
			(layer "F.SilkS")
		)
		(fp_line
			(start -1.1176 -1.4224)
			(end 1.1176 -1.4224)
			(stroke
				(width 0.1524)
				(type default)
			)
			(layer "F.SilkS")
		)
		(fp_line
			(start -1.1176 1.4224)
			(end -1.1176 -1.4224)
			(stroke
				(width 0.1524)
				(type default)
			)
			(layer "F.SilkS")
		)
		(fp_line
			(start 1.1176 -1.4224)
			(end 1.1176 1.4224)
			(stroke
				(width 0.1524)
				(type default)
			)
			(layer "F.SilkS")
		)
		(fp_line
			(start 1.1176 1.4224)
			(end -1.1176 1.4224)
			(stroke
				(width 0.1524)
				(type default)
			)
			(layer "F.SilkS")
		)
		(fp_line
			(start 1.2954 1.6002)
			(end 1.2954 0.254)
			(stroke
				(width 0.508)
				(type default)
			)
			(layer "F.SilkS")
		)
		(fp_rect
			(start -0.7493 0.8001)
			(end 0.7493 -0.8001)
			(stroke
				(width 0)
				(type default)
			)
			(fill no)
			(layer "F.CrtYd")
		)
		(fp_poly
			(pts
				(xy -1.3716 1.6764) (xy -1.3716 -1.6764) (xy 1.3716 -1.6764) (xy 1.3716 0.0635) (xy 0.7493 0.0635)
				(xy 0.7493 -0.8001) (xy -0.7493 -0.8001) (xy -0.7493 0.8001) (xy 0.7493 0.8001) (xy 0.7493 0.0762)
				(xy 1.3716 0.0762) (xy 1.3716 1.6764)
			)
			(stroke
				(width 0)
				(type default)
			)
			(fill no)
			(layer "F.CrtYd")
		)
		(fp_rect
			(start -1.3716 1.6764)
			(end 1.3716 -1.6764)
			(stroke
				(width 0)
				(type default)
			)
			(fill no)
			(layer "F.Fab")
		)
		(pad "1" smd rect
			(at 0.50038 -0.73025)
			(size 0.7112 0.8636)
			(layers "F.Cu" "F.Mask" "F.Paste")
			(net "DRV_ACT_18")
		)
		(pad "2" smd rect
			(at -0.50038 -0.73025)
			(size 0.7112 0.8636)
			(layers "F.Cu" "F.Mask" "F.Paste")
			(net "FLT_HDD18")
		)
		(pad "3" smd rect
			(at 0.50038 0.73025)
			(size 0.7112 0.8636)
			(layers "F.Cu" "F.Mask" "F.Paste")
			(net "DRV_ACT_18_N")
		)
		(pad "4" smd rect
			(at -0.50038 0.73025)
			(size 0.7112 0.8636)
			(layers "F.Cu" "F.Mask" "F.Paste")
			(net "FLT_HDD018_N")
		)
	)
	(footprint ""
		(layer "F.Cu")
		(at 141.042898 -289.857942)
		(property "Reference" "Q26"
			(at 0 0 0)
			(layer "F.SilkS")
			(hide yes)
			(effects
				(font
					(size 1.27 1.27)
				)
			)
		)
		(property "Value" "AO4407AL-GP"
			(at -3.707384 -1.5367 0)
			(unlocked yes)
			(layer "F.Fab")
			(hide yes)
			(effects
				(font
					(size 1.016 1.016)
					(thickness 0.1524)
				)
			)
		)
		(property "Device Type" "SOIC8H69"
			(at -3.707384 -3.0607 0)
			(unlocked yes)
			(layer "F.Fab")
			(hide yes)
			(effects
				(font
					(size 1.016 1.016)
					(thickness 0.1524)
				)
			)
		)
		(duplicate_pad_numbers_are_jumpers no)
		(fp_line
			(start -2.7432 -1.4224)
			(end -2.7432 1.4224)
			(stroke
				(width 0.1524)
				(type default)
			)
			(layer "F.SilkS")
		)
		(fp_line
			(start -2.7432 1.4224)
			(end -2.6416 1.4224)
			(stroke
				(width 0.1524)
				(type default)
			)
			(layer "F.SilkS")
		)
		(fp_line
			(start -2.7432 1.4224)
			(end 2.1336 1.4224)
			(stroke
				(width 0.1524)
				(type default)
			)
			(layer "F.SilkS")
		)
		(fp_line
			(start -2.7178 -0.508)
			(end -2.1844 -0.0508)
			(stroke
				(width 0.1524)
				(type default)
			)
			(layer "F.SilkS")
		)
		(fp_line
			(start -2.6289 3.4417)
			(end -2.6289 1.4732)
			(stroke
				(width 0.381)
				(type default)
			)
			(layer "F.SilkS")
		)
		(fp_line
			(start -2.1844 -0.0508)
			(end -2.7178 0.508)
			(stroke
				(width 0.1524)
				(type default)
			)
			(layer "F.SilkS")
		)
		(fp_line
			(start 2.1336 -1.4224)
			(end -2.7432 -1.4224)
			(stroke
				(width 0.1524)
				(type default)
			)
			(layer "F.SilkS")
		)
		(fp_line
			(start 2.1336 1.4224)
			(end 2.1336 -1.4224)
			(stroke
				(width 0.1524)
				(type default)
			)
			(layer "F.SilkS")
		)
		(fp_poly
			(pts
				(xy -2.2098 -1.4224) (xy -2.2098 1.4224) (xy 2.2098 1.4224) (xy 2.2098 -1.4224)
			)
			(stroke
				(width 0)
				(type default)
			)
			(fill yes)
			(layer "F.SilkS")
		)
		(fp_rect
			(start -2.450084 2.999994)
			(end 2.450084 -2.999994)
			(stroke
				(width 0)
				(type default)
			)
			(fill no)
			(layer "F.CrtYd")
		)
		(fp_poly
			(pts
				(xy -2.8194 3.6322) (xy -2.8194 -3.6322) (xy 2.8194 -3.6322) (xy 2.8194 1.18364) (xy 2.450084 1.18364)
				(xy 2.450084 -2.999994) (xy -2.450084 -2.999994) (xy -2.450084 2.999994) (xy 2.450084 2.999994)
				(xy 2.450084 1.18618) (xy 2.8194 1.18618) (xy 2.8194 3.6322)
			)
			(stroke
				(width 0)
				(type default)
			)
			(fill no)
			(layer "F.CrtYd")
		)
		(fp_rect
			(start -2.8194 3.6322)
			(end 2.8194 -3.6322)
			(stroke
				(width 0)
				(type default)
			)
			(fill no)
			(layer "F.Fab")
		)
		(pad "1" smd rect
			(at -1.905 2.54)
			(size 0.635 1.651)
			(layers "F.Cu" "F.Mask" "F.Paste")
			(net "P12V_A")
		)
		(pad "2" smd rect
			(at -0.635 2.54)
			(size 0.635 1.651)
			(layers "F.Cu" "F.Mask" "F.Paste")
			(net "P12V_A")
		)
		(pad "3" smd rect
			(at 0.635 2.54)
			(size 0.635 1.651)
			(layers "F.Cu" "F.Mask" "F.Paste")
			(net "P12V_A")
		)
		(pad "4" smd rect
			(at 1.905 2.54)
			(size 0.635 1.651)
			(layers "F.Cu" "F.Mask" "F.Paste")
			(net "SW_HDD_N4")
		)
		(pad "5" smd rect
			(at 1.905 -2.54)
			(size 0.635 1.651)
			(layers "F.Cu" "F.Mask" "F.Paste")
			(net "P12V_HDD4")
		)
		(pad "6" smd rect
			(at 0.635 -2.54)
			(size 0.635 1.651)
			(layers "F.Cu" "F.Mask" "F.Paste")
			(net "P12V_HDD4")
		)
		(pad "7" smd rect
			(at -0.635 -2.54)
			(size 0.635 1.651)
			(layers "F.Cu" "F.Mask" "F.Paste")
			(net "P12V_HDD4")
		)
		(pad "8" smd rect
			(at -1.905 -2.54)
			(size 0.635 1.651)
			(layers "F.Cu" "F.Mask" "F.Paste")
			(net "P12V_HDD4")
		)
	)
	(footprint ""
		(layer "F.Cu")
		(at 111.795052 -242.25377)
		(property "Reference" "R219"
			(at 0 0 0)
			(layer "F.SilkS")
			(hide yes)
			(effects
				(font
					(size 1.27 1.27)
				)
			)
		)
		(property "Value" "130R3F-GP"
			(at -0.0254 -2.5146 0)
			(unlocked yes)
			(layer "F.Fab")
			(hide yes)
			(effects
				(font
					(size 1.016 1.016)
					(thickness 0.1524)
				)
			)
		)
		(property "Device Type" "R603H22"
			(at -0.0254 -4.0386 0)
			(unlocked yes)
			(layer "F.Fab")
			(hide yes)
			(effects
				(font
					(size 1.016 1.016)
					(thickness 0.1524)
				)
			)
		)
		(duplicate_pad_numbers_are_jumpers no)
		(fp_line
			(start -0.4826 0)
			(end -0.2032 0)
			(stroke
				(width 0.2032)
				(type default)
			)
			(layer "F.SilkS")
		)
		(fp_line
			(start 0.2032 0)
			(end 0.4826 0)
			(stroke
				(width 0.2032)
				(type default)
			)
			(layer "F.SilkS")
		)
		(fp_rect
			(start -0.5842 1.3335)
			(end 0.5842 -1.3335)
			(stroke
				(width 0)
				(type default)
			)
			(fill no)
			(layer "F.CrtYd")
		)
		(fp_rect
			(start -0.5842 1.3335)
			(end 0.5842 -1.3335)
			(stroke
				(width 0)
				(type default)
			)
			(fill no)
			(layer "F.Fab")
		)
		(pad "1" smd custom
			(at 0 -0.762)
			(size 0.2159 0.2159)
			(layers "F.Cu" "F.Mask" "F.Paste")
			(net "P5V_A_1")
			(options
				(clearance outline)
				(anchor circle)
			)
			(primitives
				(gr_poly
					(pts
						(arc
							(start -0.3302 -0.4318)
							(mid -0.402042 -0.402042)
							(end -0.4318 -0.3302)
						)
						(arc
							(start -0.4318 0.3302)
							(mid -0.402042 0.402042)
							(end -0.3302 0.4318)
						)
						(arc
							(start 0.3302 0.4318)
							(mid 0.402042 0.402042)
							(end 0.4318 0.3302)
						)
						(arc
							(start 0.4318 -0.3302)
							(mid 0.402042 -0.402042)
							(end 0.3302 -0.4318)
						)
					)
					(width 0)
					(fill yes)
				)
			)
		)
		(pad "2" smd custom
			(at 0 0.762)
			(size 0.2159 0.2159)
			(layers "F.Cu" "F.Mask" "F.Paste")
			(net "FLT_HDD3")
			(options
				(clearance outline)
				(anchor circle)
			)
			(primitives
				(gr_poly
					(pts
						(arc
							(start -0.3302 -0.4318)
							(mid -0.402042 -0.402042)
							(end -0.4318 -0.3302)
						)
						(arc
							(start -0.4318 0.3302)
							(mid -0.402042 0.402042)
							(end -0.3302 0.4318)
						)
						(arc
							(start 0.3302 0.4318)
							(mid 0.402042 0.402042)
							(end 0.4318 0.3302)
						)
						(arc
							(start 0.4318 -0.3302)
							(mid 0.402042 -0.402042)
							(end 0.3302 -0.4318)
						)
					)
					(width 0)
					(fill yes)
				)
			)
		)
	)
	(footprint ""
		(layer "F.Cu")
		(at 237.470696 -262.22706 90)
		(property "Reference" "R424"
			(at 0 0 90)
			(layer "F.SilkS")
			(hide yes)
			(effects
				(font
					(size 1.27 1.27)
				)
			)
		)
		(property "Value" "10KR2F-2-GP"
			(at 0.064008 -3.993896 90)
			(unlocked yes)
			(layer "F.Fab")
			(hide yes)
			(effects
				(font
					(size 1.016 1.016)
					(thickness 0.1524)
				)
			)
		)
		(property "Device Type" "R402H16"
			(at 0.064008 -5.517896 90)
			(unlocked yes)
			(layer "F.Fab")
			(hide yes)
			(effects
				(font
					(size 1.016 1.016)
					(thickness 0.1524)
				)
			)
		)
		(duplicate_pad_numbers_are_jumpers no)
		(fp_line
			(start 0.508 -0.9398)
			(end -0.508 -0.9398)
			(stroke
				(width 0.1524)
				(type default)
			)
			(layer "F.SilkS")
		)
		(fp_line
			(start -0.508 -0.9398)
			(end -0.508 0.9398)
			(stroke
				(width 0.1524)
				(type default)
			)
			(layer "F.SilkS")
		)
		(fp_rect
			(start -0.508 0.9398)
			(end 0.508 -0.9398)
			(stroke
				(width 0)
				(type default)
			)
			(fill no)
			(layer "F.CrtYd")
		)
		(fp_rect
			(start -0.508 0.9398)
			(end 0.508 -0.9398)
			(stroke
				(width 0)
				(type default)
			)
			(fill no)
			(layer "F.Fab")
		)
		(pad "1" smd custom
			(at 0 -0.4445 90)
			(size 0.1397 0.1397)
			(layers "F.Cu" "F.Mask" "F.Paste")
			(net "P3V3_STBY_A")
			(options
				(clearance outline)
				(anchor circle)
			)
			(primitives
				(gr_poly
					(pts
						(arc
							(start -0.1778 -0.2794)
							(mid -0.249642 -0.249642)
							(end -0.2794 -0.1778)
						)
						(arc
							(start -0.2794 0.1778)
							(mid -0.249642 0.249642)
							(end -0.1778 0.2794)
						)
						(arc
							(start 0.1778 0.2794)
							(mid 0.249642 0.249642)
							(end 0.2794 0.1778)
						)
						(arc
							(start 0.2794 -0.1778)
							(mid 0.249642 -0.249642)
							(end 0.1778 -0.2794)
						)
					)
					(width 0)
					(fill yes)
				)
			)
		)
		(pad "2" smd custom
			(at 0 0.4445 90)
			(size 0.1397 0.1397)
			(layers "F.Cu" "F.Mask" "F.Paste")
			(net "DRIVE_INSERT_ALERT_A_N")
			(options
				(clearance outline)
				(anchor circle)
			)
			(primitives
				(gr_poly
					(pts
						(arc
							(start -0.1778 -0.2794)
							(mid -0.249642 -0.249642)
							(end -0.2794 -0.1778)
						)
						(arc
							(start -0.2794 0.1778)
							(mid -0.249642 0.249642)
							(end -0.1778 0.2794)
						)
						(arc
							(start 0.1778 0.2794)
							(mid 0.249642 0.249642)
							(end 0.2794 0.1778)
						)
						(arc
							(start 0.2794 -0.1778)
							(mid 0.249642 -0.249642)
							(end 0.1778 -0.2794)
						)
					)
					(width 0)
					(fill yes)
				)
			)
		)
	)
	(footprint ""
		(layer "F.Cu")
		(at 464.2739 -49.443894 90)
		(property "Reference" "R928"
			(at 0 0 90)
			(layer "F.SilkS")
			(hide yes)
			(effects
				(font
					(size 1.27 1.27)
				)
			)
		)
		(property "Value" "200KR2F-L-GP"
			(at 0.064008 -3.993896 90)
			(unlocked yes)
			(layer "F.Fab")
			(hide yes)
			(effects
				(font
					(size 1.016 1.016)
					(thickness 0.1524)
				)
			)
		)
		(property "Device Type" "R402H16"
			(at 0.064008 -5.517896 90)
			(unlocked yes)
			(layer "F.Fab")
			(hide yes)
			(effects
				(font
					(size 1.016 1.016)
					(thickness 0.1524)
				)
			)
		)
		(duplicate_pad_numbers_are_jumpers no)
		(fp_line
			(start 0.508 -0.9398)
			(end -0.508 -0.9398)
			(stroke
				(width 0.1524)
				(type default)
			)
			(layer "F.SilkS")
		)
		(fp_line
			(start -0.508 -0.9398)
			(end -0.508 0.9398)
			(stroke
				(width 0.1524)
				(type default)
			)
			(layer "F.SilkS")
		)
		(fp_rect
			(start -0.508 0.9398)
			(end 0.508 -0.9398)
			(stroke
				(width 0)
				(type default)
			)
			(fill no)
			(layer "F.CrtYd")
		)
		(fp_rect
			(start -0.508 0.9398)
			(end 0.508 -0.9398)
			(stroke
				(width 0)
				(type default)
			)
			(fill no)
			(layer "F.Fab")
		)
		(pad "1" smd custom
			(at 0 -0.4445 90)
			(size 0.1397 0.1397)
			(layers "F.Cu" "F.Mask" "F.Paste")
			(net "SW_HDD_R34")
			(options
				(clearance outline)
				(anchor circle)
			)
			(primitives
				(gr_poly
					(pts
						(arc
							(start -0.1778 -0.2794)
							(mid -0.249642 -0.249642)
							(end -0.2794 -0.1778)
						)
						(arc
							(start -0.2794 0.1778)
							(mid -0.249642 0.249642)
							(end -0.1778 0.2794)
						)
						(arc
							(start 0.1778 0.2794)
							(mid 0.249642 0.249642)
							(end 0.2794 0.1778)
						)
						(arc
							(start 0.2794 -0.1778)
							(mid 0.249642 -0.249642)
							(end 0.1778 -0.2794)
						)
					)
					(width 0)
					(fill yes)
				)
			)
		)
		(pad "2" smd custom
			(at 0 0.4445 90)
			(size 0.1397 0.1397)
			(layers "F.Cu" "F.Mask" "F.Paste")
			(net "SW_HDD_N34")
			(options
				(clearance outline)
				(anchor circle)
			)
			(primitives
				(gr_poly
					(pts
						(arc
							(start -0.1778 -0.2794)
							(mid -0.249642 -0.249642)
							(end -0.2794 -0.1778)
						)
						(arc
							(start -0.2794 0.1778)
							(mid -0.249642 0.249642)
							(end -0.1778 0.2794)
						)
						(arc
							(start 0.1778 0.2794)
							(mid 0.249642 0.249642)
							(end 0.2794 0.1778)
						)
						(arc
							(start 0.2794 -0.1778)
							(mid 0.249642 -0.249642)
							(end 0.1778 -0.2794)
						)
					)
					(width 0)
					(fill yes)
				)
			)
		)
	)
	(footprint ""
		(layer "F.Cu")
		(at 476.8596 -67.3608)
		(property "Reference" "TP177"
			(at 0 0 0)
			(layer "F.SilkS")
			(hide yes)
			(effects
				(font
					(size 1.27 1.27)
				)
			)
		)
		(property "Value" "TPAD32-GP"
			(at -0.0508 -1.6764 0)
			(unlocked yes)
			(layer "F.Fab")
			(hide yes)
			(effects
				(font
					(size 1.016 1.016)
					(thickness 0.1524)
				)
			)
		)
		(property "Device Type" "TPAD32"
			(at -0.0508 -3.2004 0)
			(unlocked yes)
			(layer "F.Fab")
			(hide yes)
			(effects
				(font
					(size 1.016 1.016)
					(thickness 0.1524)
				)
			)
		)
		(duplicate_pad_numbers_are_jumpers no)
		(fp_poly
			(pts
				(arc
					(start 0.4064 0)
					(mid -0.4064 0)
					(end 0.4064 0)
				)
			)
			(stroke
				(width 0)
				(type default)
			)
			(fill no)
			(layer "F.CrtYd")
		)
		(fp_poly
			(pts
				(arc
					(start 0.7112 0)
					(mid -0.7112 0)
					(end 0.7112 0)
				)
			)
			(stroke
				(width 0)
				(type default)
			)
			(fill no)
			(layer "F.Fab")
		)
		(pad "1" smd circle
			(at 0 0)
			(size 0.8128 0.8128)
			(layers "F.Cu" "F.Mask" "F.Paste")
			(net "ACT_HDD_35")
		)
	)
	(footprint ""
		(layer "F.Cu")
		(at 458.3049 -275.252942 -90)
		(property "Reference" "Q61"
			(at 0 0 270)
			(layer "F.SilkS")
			(hide yes)
			(effects
				(font
					(size 1.27 1.27)
				)
			)
		)
		(property "Value" "2N7002KDW-GP"
			(at -2.3622 -8.2042 270)
			(unlocked yes)
			(layer "F.Fab")
			(hide yes)
			(effects
				(font
					(size 1.016 1.016)
					(thickness 0.1524)
				)
			)
		)
		(property "Device Type" "SOT-363H44"
			(at -2.3622 -10.1092 270)
			(unlocked yes)
			(layer "F.Fab")
			(hide yes)
			(effects
				(font
					(size 1.016 1.016)
					(thickness 0.1524)
				)
			)
		)
		(duplicate_pad_numbers_are_jumpers no)
		(fp_line
			(start -1.4478 1.7018)
			(end 1.4478 1.7018)
			(stroke
				(width 0.1524)
				(type default)
			)
			(layer "F.SilkS")
		)
		(fp_line
			(start 1.4478 1.7018)
			(end 1.4478 -1.7018)
			(stroke
				(width 0.1524)
				(type default)
			)
			(layer "F.SilkS")
		)
		(fp_line
			(start -1.27 1.524)
			(end -1.27 0.6604)
			(stroke
				(width 0.4826)
				(type default)
			)
			(layer "F.SilkS")
		)
		(fp_line
			(start -1.4478 -1.7018)
			(end -1.4478 1.7018)
			(stroke
				(width 0.1524)
				(type default)
			)
			(layer "F.SilkS")
		)
		(fp_line
			(start 1.4478 -1.7018)
			(end -1.4478 -1.7018)
			(stroke
				(width 0.1524)
				(type default)
			)
			(layer "F.SilkS")
		)
		(fp_poly
			(pts
				(xy -1.524 -1.778) (xy 1.524 -1.778) (xy 1.524 1.778) (xy -1.524 1.778)
			)
			(stroke
				(width 0)
				(type default)
			)
			(fill no)
			(layer "F.CrtYd")
		)
		(fp_poly
			(pts
				(xy -1.524 -1.778) (xy 1.524 -1.778) (xy 1.524 1.778) (xy -1.524 1.778)
			)
			(stroke
				(width 0)
				(type default)
			)
			(fill no)
			(layer "F.Fab")
		)
		(pad "1" smd rect
			(at -0.65024 0.9398 270)
			(size 0.4064 1.016)
			(layers "F.Cu" "F.Mask" "F.Paste")
			(net "GND")
		)
		(pad "2" smd rect
			(at 0 0.9398 270)
			(size 0.4064 1.016)
			(layers "F.Cu" "F.Mask" "F.Paste")
			(net "SW_PWR_R_HDD10")
		)
		(pad "3" smd rect
			(at 0.65024 0.9398 270)
			(size 0.4064 1.016)
			(layers "F.Cu" "F.Mask" "F.Paste")
			(net "SW_HDD_P10")
		)
		(pad "4" smd rect
			(at 0.65024 -0.9398 270)
			(size 0.4064 1.016)
			(layers "F.Cu" "F.Mask" "F.Paste")
			(net "GND")
		)
		(pad "5" smd rect
			(at 0 -0.9398 270)
			(size 0.4064 1.016)
			(layers "F.Cu" "F.Mask" "F.Paste")
			(net "SW_HDD_G10")
		)
		(pad "6" smd rect
			(at -0.65024 -0.9398 270)
			(size 0.4064 1.016)
			(layers "F.Cu" "F.Mask" "F.Paste")
			(net "SW_HDD_R10")
		)
	)
	(footprint ""
		(layer "F.Cu")
		(at 14.842998 -174.857918)
		(property "Reference" "Q74"
			(at 0 0 0)
			(layer "F.SilkS")
			(hide yes)
			(effects
				(font
					(size 1.27 1.27)
				)
			)
		)
		(property "Value" "AO4407AL-GP"
			(at -3.707384 -1.5367 0)
			(unlocked yes)
			(layer "F.Fab")
			(hide yes)
			(effects
				(font
					(size 1.016 1.016)
					(thickness 0.1524)
				)
			)
		)
		(property "Device Type" "SOIC8H69"
			(at -3.707384 -3.0607 0)
			(unlocked yes)
			(layer "F.Fab")
			(hide yes)
			(effects
				(font
					(size 1.016 1.016)
					(thickness 0.1524)
				)
			)
		)
		(duplicate_pad_numbers_are_jumpers no)
		(fp_line
			(start -2.7432 -1.4224)
			(end -2.7432 1.4224)
			(stroke
				(width 0.1524)
				(type default)
			)
			(layer "F.SilkS")
		)
		(fp_line
			(start -2.7432 1.4224)
			(end -2.6416 1.4224)
			(stroke
				(width 0.1524)
				(type default)
			)
			(layer "F.SilkS")
		)
		(fp_line
			(start -2.7432 1.4224)
			(end 2.1336 1.4224)
			(stroke
				(width 0.1524)
				(type default)
			)
			(layer "F.SilkS")
		)
		(fp_line
			(start -2.7178 -0.508)
			(end -2.1844 -0.0508)
			(stroke
				(width 0.1524)
				(type default)
			)
			(layer "F.SilkS")
		)
		(fp_line
			(start -2.6289 3.4417)
			(end -2.6289 1.4732)
			(stroke
				(width 0.381)
				(type default)
			)
			(layer "F.SilkS")
		)
		(fp_line
			(start -2.1844 -0.0508)
			(end -2.7178 0.508)
			(stroke
				(width 0.1524)
				(type default)
			)
			(layer "F.SilkS")
		)
		(fp_line
			(start 2.1336 -1.4224)
			(end -2.7432 -1.4224)
			(stroke
				(width 0.1524)
				(type default)
			)
			(layer "F.SilkS")
		)
		(fp_line
			(start 2.1336 1.4224)
			(end 2.1336 -1.4224)
			(stroke
				(width 0.1524)
				(type default)
			)
			(layer "F.SilkS")
		)
		(fp_poly
			(pts
				(xy -2.2098 -1.4224) (xy -2.2098 1.4224) (xy 2.2098 1.4224) (xy 2.2098 -1.4224)
			)
			(stroke
				(width 0)
				(type default)
			)
			(fill yes)
			(layer "F.SilkS")
		)
		(fp_rect
			(start -2.450084 2.999994)
			(end 2.450084 -2.999994)
			(stroke
				(width 0)
				(type default)
			)
			(fill no)
			(layer "F.CrtYd")
		)
		(fp_poly
			(pts
				(xy -2.8194 3.6322) (xy -2.8194 -3.6322) (xy 2.8194 -3.6322) (xy 2.8194 1.18364) (xy 2.450084 1.18364)
				(xy 2.450084 -2.999994) (xy -2.450084 -2.999994) (xy -2.450084 2.999994) (xy 2.450084 2.999994)
				(xy 2.450084 1.18618) (xy 2.8194 1.18618) (xy 2.8194 3.6322)
			)
			(stroke
				(width 0)
				(type default)
			)
			(fill no)
			(layer "F.CrtYd")
		)
		(fp_rect
			(start -2.8194 3.6322)
			(end 2.8194 -3.6322)
			(stroke
				(width 0)
				(type default)
			)
			(fill no)
			(layer "F.Fab")
		)
		(pad "1" smd rect
			(at -1.905 2.54)
			(size 0.635 1.651)
			(layers "F.Cu" "F.Mask" "F.Paste")
			(net "P12V_A")
		)
		(pad "2" smd rect
			(at -0.635 2.54)
			(size 0.635 1.651)
			(layers "F.Cu" "F.Mask" "F.Paste")
			(net "P12V_A")
		)
		(pad "3" smd rect
			(at 0.635 2.54)
			(size 0.635 1.651)
			(layers "F.Cu" "F.Mask" "F.Paste")
			(net "P12V_A")
		)
		(pad "4" smd rect
			(at 1.905 2.54)
			(size 0.635 1.651)
			(layers "F.Cu" "F.Mask" "F.Paste")
			(net "SW_HDD_N12")
		)
		(pad "5" smd rect
			(at 1.905 -2.54)
			(size 0.635 1.651)
			(layers "F.Cu" "F.Mask" "F.Paste")
			(net "P12V_HDD12")
		)
		(pad "6" smd rect
			(at 0.635 -2.54)
			(size 0.635 1.651)
			(layers "F.Cu" "F.Mask" "F.Paste")
			(net "P12V_HDD12")
		)
		(pad "7" smd rect
			(at -0.635 -2.54)
			(size 0.635 1.651)
			(layers "F.Cu" "F.Mask" "F.Paste")
			(net "P12V_HDD12")
		)
		(pad "8" smd rect
			(at -1.905 -2.54)
			(size 0.635 1.651)
			(layers "F.Cu" "F.Mask" "F.Paste")
			(net "P12V_HDD12")
		)
	)
	(footprint ""
		(layer "F.Cu")
		(at 447.834512 -43.660568 -90)
		(property "Reference" "C481"
			(at 0 0 270)
			(layer "F.SilkS")
			(hide yes)
			(effects
				(font
					(size 1.27 1.27)
				)
			)
		)
		(property "Value" "SCD01U16V1KX-GP"
			(at -2.8321 -1.7399 270)
			(unlocked yes)
			(layer "F.Fab")
			(hide yes)
			(effects
				(font
					(size 1.016 1.016)
					(thickness 0.1524)
				)
			)
		)
		(property "Device Type" "C0201H13"
			(at -2.8321 -3.2639 270)
			(unlocked yes)
			(layer "F.Fab")
			(hide yes)
			(effects
				(font
					(size 1.016 1.016)
					(thickness 0.1524)
				)
			)
		)
		(duplicate_pad_numbers_are_jumpers no)
		(fp_rect
			(start -0.2794 0.6477)
			(end 0.2794 -0.6477)
			(stroke
				(width 0)
				(type default)
			)
			(fill no)
			(layer "F.CrtYd")
		)
		(fp_rect
			(start -0.2794 0.6477)
			(end 0.2794 -0.6477)
			(stroke
				(width 0)
				(type default)
			)
			(fill no)
			(layer "F.Fab")
		)
		(pad "1" smd custom
			(at 0 -0.2794 270)
			(size 0.0762 0.0762)
			(layers "F.Cu" "F.Mask" "F.Paste")
			(net "SAS_HDD_RX_P34")
			(options
				(clearance outline)
				(anchor circle)
			)
			(primitives
				(gr_poly
					(pts
						(arc
							(start 0.1524 -0.127)
							(mid 0.137521 -0.162921)
							(end 0.1016 -0.1778)
						)
						(arc
							(start -0.1016 -0.1778)
							(mid -0.137521 -0.162921)
							(end -0.1524 -0.127)
						)
						(arc
							(start -0.1524 0.127)
							(mid -0.137521 0.162921)
							(end -0.1016 0.1778)
						)
						(arc
							(start 0.1016 0.1778)
							(mid 0.137521 0.162921)
							(end 0.1524 0.127)
						)
					)
					(width 0)
					(fill yes)
				)
			)
		)
		(pad "2" smd custom
			(at 0 0.2794 270)
			(size 0.0762 0.0762)
			(layers "F.Cu" "F.Mask" "F.Paste")
			(net "PHY_SCC_A_TO_DRV_A_34_DP")
			(options
				(clearance outline)
				(anchor circle)
			)
			(primitives
				(gr_poly
					(pts
						(arc
							(start 0.1524 -0.127)
							(mid 0.137521 -0.162921)
							(end 0.1016 -0.1778)
						)
						(arc
							(start -0.1016 -0.1778)
							(mid -0.137521 -0.162921)
							(end -0.1524 -0.127)
						)
						(arc
							(start -0.1524 0.127)
							(mid -0.137521 0.162921)
							(end -0.1016 0.1778)
						)
						(arc
							(start 0.1016 0.1778)
							(mid 0.137521 0.162921)
							(end 0.1524 0.127)
						)
					)
					(width 0)
					(fill yes)
				)
			)
		)
	)
	(footprint ""
		(layer "F.Cu")
		(at 282.3464 22.7584 -90)
		(property "Reference" "R16"
			(at 0 0 270)
			(layer "F.SilkS")
			(hide yes)
			(effects
				(font
					(size 1.27 1.27)
				)
			)
		)
		(property "Value" "0R2J-2-GP"
			(at 0.064008 -3.993896 270)
			(unlocked yes)
			(layer "F.Fab")
			(hide yes)
			(effects
				(font
					(size 1.016 1.016)
					(thickness 0.1524)
				)
			)
		)
		(property "Device Type" "R402H16"
			(at 0.064008 -5.517896 270)
			(unlocked yes)
			(layer "F.Fab")
			(hide yes)
			(effects
				(font
					(size 1.016 1.016)
					(thickness 0.1524)
				)
			)
		)
		(duplicate_pad_numbers_are_jumpers no)
		(fp_line
			(start -0.508 -0.9398)
			(end -0.508 0.9398)
			(stroke
				(width 0.1524)
				(type default)
			)
			(layer "F.SilkS")
		)
		(fp_line
			(start 0.508 -0.9398)
			(end -0.508 -0.9398)
			(stroke
				(width 0.1524)
				(type default)
			)
			(layer "F.SilkS")
		)
		(fp_rect
			(start -0.508 0.9398)
			(end 0.508 -0.9398)
			(stroke
				(width 0)
				(type default)
			)
			(fill no)
			(layer "F.CrtYd")
		)
		(fp_rect
			(start -0.508 0.9398)
			(end 0.508 -0.9398)
			(stroke
				(width 0)
				(type default)
			)
			(fill no)
			(layer "F.Fab")
		)
		(pad "1" smd custom
			(at 0 -0.4445 270)
			(size 0.1397 0.1397)
			(layers "F.Cu" "F.Mask" "F.Paste")
			(net "DPB_PWR_BTN_BUF_B")
			(options
				(clearance outline)
				(anchor circle)
			)
			(primitives
				(gr_poly
					(pts
						(arc
							(start -0.1778 -0.2794)
							(mid -0.249642 -0.249642)
							(end -0.2794 -0.1778)
						)
						(arc
							(start -0.2794 0.1778)
							(mid -0.249642 0.249642)
							(end -0.1778 0.2794)
						)
						(arc
							(start 0.1778 0.2794)
							(mid 0.249642 0.249642)
							(end 0.2794 0.1778)
						)
						(arc
							(start 0.2794 -0.1778)
							(mid 0.249642 -0.249642)
							(end 0.1778 -0.2794)
						)
					)
					(width 0)
					(fill yes)
				)
			)
		)
		(pad "2" smd custom
			(at 0 0.4445 270)
			(size 0.1397 0.1397)
			(layers "F.Cu" "F.Mask" "F.Paste")
			(net "DPB_PWR_BTN_B")
			(options
				(clearance outline)
				(anchor circle)
			)
			(primitives
				(gr_poly
					(pts
						(arc
							(start -0.1778 -0.2794)
							(mid -0.249642 -0.249642)
							(end -0.2794 -0.1778)
						)
						(arc
							(start -0.2794 0.1778)
							(mid -0.249642 0.249642)
							(end -0.1778 0.2794)
						)
						(arc
							(start 0.1778 0.2794)
							(mid 0.249642 0.249642)
							(end 0.2794 0.1778)
						)
						(arc
							(start 0.2794 -0.1778)
							(mid 0.249642 -0.249642)
							(end 0.1778 -0.2794)
						)
					)
					(width 0)
					(fill yes)
				)
			)
		)
	)
	(footprint ""
		(layer "F.Cu")
		(at 458.3049 -157.585918)
		(property "Reference" "R649"
			(at 0 0 0)
			(layer "F.SilkS")
			(hide yes)
			(effects
				(font
					(size 1.27 1.27)
				)
			)
		)
		(property "Value" "4K7R2J-2-GP"
			(at 0.064008 -3.993896 0)
			(unlocked yes)
			(layer "F.Fab")
			(hide yes)
			(effects
				(font
					(size 1.016 1.016)
					(thickness 0.1524)
				)
			)
		)
		(property "Device Type" "R402H16"
			(at 0.064008 -5.517896 0)
			(unlocked yes)
			(layer "F.Fab")
			(hide yes)
			(effects
				(font
					(size 1.016 1.016)
					(thickness 0.1524)
				)
			)
		)
		(duplicate_pad_numbers_are_jumpers no)
		(fp_line
			(start -0.508 -0.9398)
			(end -0.508 0.9398)
			(stroke
				(width 0.1524)
				(type default)
			)
			(layer "F.SilkS")
		)
		(fp_line
			(start 0.508 -0.9398)
			(end -0.508 -0.9398)
			(stroke
				(width 0.1524)
				(type default)
			)
			(layer "F.SilkS")
		)
		(fp_rect
			(start -0.508 0.9398)
			(end 0.508 -0.9398)
			(stroke
				(width 0)
				(type default)
			)
			(fill no)
			(layer "F.CrtYd")
		)
		(fp_rect
			(start -0.508 0.9398)
			(end 0.508 -0.9398)
			(stroke
				(width 0)
				(type default)
			)
			(fill no)
			(layer "F.Fab")
		)
		(pad "1" smd custom
			(at 0 -0.4445)
			(size 0.1397 0.1397)
			(layers "F.Cu" "F.Mask" "F.Paste")
			(net "SW_PWR_R_HDD22")
			(options
				(clearance outline)
				(anchor circle)
			)
			(primitives
				(gr_poly
					(pts
						(arc
							(start -0.1778 -0.2794)
							(mid -0.249642 -0.249642)
							(end -0.2794 -0.1778)
						)
						(arc
							(start -0.2794 0.1778)
							(mid -0.249642 0.249642)
							(end -0.1778 0.2794)
						)
						(arc
							(start 0.1778 0.2794)
							(mid 0.249642 0.249642)
							(end 0.2794 0.1778)
						)
						(arc
							(start 0.2794 -0.1778)
							(mid 0.249642 -0.249642)
							(end 0.1778 -0.2794)
						)
					)
					(width 0)
					(fill yes)
				)
			)
		)
		(pad "2" smd custom
			(at 0 0.4445)
			(size 0.1397 0.1397)
			(layers "F.Cu" "F.Mask" "F.Paste")
			(net "GND")
			(options
				(clearance outline)
				(anchor circle)
			)
			(primitives
				(gr_poly
					(pts
						(arc
							(start -0.1778 -0.2794)
							(mid -0.249642 -0.249642)
							(end -0.2794 -0.1778)
						)
						(arc
							(start -0.2794 0.1778)
							(mid -0.249642 0.249642)
							(end -0.1778 0.2794)
						)
						(arc
							(start 0.1778 0.2794)
							(mid 0.249642 0.249642)
							(end 0.2794 0.1778)
						)
						(arc
							(start 0.2794 -0.1778)
							(mid 0.249642 -0.249642)
							(end 0.1778 -0.2794)
						)
					)
					(width 0)
					(fill yes)
				)
			)
		)
	)
	(footprint ""
		(layer "F.Cu")
		(at 27.524202 -253.29515 180)
		(property "Reference" "R1222"
			(at 0 0 180)
			(layer "F.SilkS")
			(hide yes)
			(effects
				(font
					(size 1.27 1.27)
				)
			)
		)
		(property "Value" "619KR2F-GP"
			(at 0.064008 -3.993896 180)
			(unlocked yes)
			(layer "F.Fab")
			(hide yes)
			(effects
				(font
					(size 1.016 1.016)
					(thickness 0.1524)
				)
			)
		)
		(property "Device Type" "R402H16"
			(at 0.064008 -5.517896 180)
			(unlocked yes)
			(layer "F.Fab")
			(hide yes)
			(effects
				(font
					(size 1.016 1.016)
					(thickness 0.1524)
				)
			)
		)
		(duplicate_pad_numbers_are_jumpers no)
		(fp_line
			(start 0.508 -0.9398)
			(end -0.508 -0.9398)
			(stroke
				(width 0.1524)
				(type default)
			)
			(layer "F.SilkS")
		)
		(fp_line
			(start -0.508 -0.9398)
			(end -0.508 0.9398)
			(stroke
				(width 0.1524)
				(type default)
			)
			(layer "F.SilkS")
		)
		(fp_rect
			(start -0.508 0.9398)
			(end 0.508 -0.9398)
			(stroke
				(width 0)
				(type default)
			)
			(fill no)
			(layer "F.CrtYd")
		)
		(fp_rect
			(start -0.508 0.9398)
			(end 0.508 -0.9398)
			(stroke
				(width 0)
				(type default)
			)
			(fill no)
			(layer "F.Fab")
		)
		(pad "1" smd custom
			(at 0 -0.4445 180)
			(size 0.1397 0.1397)
			(layers "F.Cu" "F.Mask" "F.Paste")
			(net "P5V_A_RF")
			(options
				(clearance outline)
				(anchor circle)
			)
			(primitives
				(gr_poly
					(pts
						(arc
							(start -0.1778 -0.2794)
							(mid -0.249642 -0.249642)
							(end -0.2794 -0.1778)
						)
						(arc
							(start -0.2794 0.1778)
							(mid -0.249642 0.249642)
							(end -0.1778 0.2794)
						)
						(arc
							(start 0.1778 0.2794)
							(mid 0.249642 0.249642)
							(end 0.2794 0.1778)
						)
						(arc
							(start 0.2794 -0.1778)
							(mid 0.249642 -0.249642)
							(end 0.1778 -0.2794)
						)
					)
					(width 0)
					(fill yes)
				)
			)
		)
		(pad "2" smd custom
			(at 0 0.4445 180)
			(size 0.1397 0.1397)
			(layers "F.Cu" "F.Mask" "F.Paste")
			(net "AGND_P5V_A")
			(options
				(clearance outline)
				(anchor circle)
			)
			(primitives
				(gr_poly
					(pts
						(arc
							(start -0.1778 -0.2794)
							(mid -0.249642 -0.249642)
							(end -0.2794 -0.1778)
						)
						(arc
							(start -0.2794 0.1778)
							(mid -0.249642 0.249642)
							(end -0.1778 0.2794)
						)
						(arc
							(start 0.1778 0.2794)
							(mid 0.249642 0.249642)
							(end 0.2794 0.1778)
						)
						(arc
							(start 0.2794 -0.1778)
							(mid 0.249642 -0.249642)
							(end 0.1778 -0.2794)
						)
					)
					(width 0)
					(fill yes)
				)
			)
		)
	)
	(footprint ""
		(layer "F.Cu")
		(at 369.624102 -164.443918 90)
		(property "Reference" "R583"
			(at 0 0 90)
			(layer "F.SilkS")
			(hide yes)
			(effects
				(font
					(size 1.27 1.27)
				)
			)
		)
		(property "Value" "200KR2F-L-GP"
			(at 0.064008 -3.993896 90)
			(unlocked yes)
			(layer "F.Fab")
			(hide yes)
			(effects
				(font
					(size 1.016 1.016)
					(thickness 0.1524)
				)
			)
		)
		(property "Device Type" "R402H16"
			(at 0.064008 -5.517896 90)
			(unlocked yes)
			(layer "F.Fab")
			(hide yes)
			(effects
				(font
					(size 1.016 1.016)
					(thickness 0.1524)
				)
			)
		)
		(duplicate_pad_numbers_are_jumpers no)
		(fp_line
			(start 0.508 -0.9398)
			(end -0.508 -0.9398)
			(stroke
				(width 0.1524)
				(type default)
			)
			(layer "F.SilkS")
		)
		(fp_line
			(start -0.508 -0.9398)
			(end -0.508 0.9398)
			(stroke
				(width 0.1524)
				(type default)
			)
			(layer "F.SilkS")
		)
		(fp_rect
			(start -0.508 0.9398)
			(end 0.508 -0.9398)
			(stroke
				(width 0)
				(type default)
			)
			(fill no)
			(layer "F.CrtYd")
		)
		(fp_rect
			(start -0.508 0.9398)
			(end 0.508 -0.9398)
			(stroke
				(width 0)
				(type default)
			)
			(fill no)
			(layer "F.Fab")
		)
		(pad "1" smd custom
			(at 0 -0.4445 90)
			(size 0.1397 0.1397)
			(layers "F.Cu" "F.Mask" "F.Paste")
			(net "SW_HDD_R19")
			(options
				(clearance outline)
				(anchor circle)
			)
			(primitives
				(gr_poly
					(pts
						(arc
							(start -0.1778 -0.2794)
							(mid -0.249642 -0.249642)
							(end -0.2794 -0.1778)
						)
						(arc
							(start -0.2794 0.1778)
							(mid -0.249642 0.249642)
							(end -0.1778 0.2794)
						)
						(arc
							(start 0.1778 0.2794)
							(mid 0.249642 0.249642)
							(end 0.2794 0.1778)
						)
						(arc
							(start 0.2794 -0.1778)
							(mid 0.249642 -0.249642)
							(end 0.1778 -0.2794)
						)
					)
					(width 0)
					(fill yes)
				)
			)
		)
		(pad "2" smd custom
			(at 0 0.4445 90)
			(size 0.1397 0.1397)
			(layers "F.Cu" "F.Mask" "F.Paste")
			(net "SW_HDD_N19")
			(options
				(clearance outline)
				(anchor circle)
			)
			(primitives
				(gr_poly
					(pts
						(arc
							(start -0.1778 -0.2794)
							(mid -0.249642 -0.249642)
							(end -0.2794 -0.1778)
						)
						(arc
							(start -0.2794 0.1778)
							(mid -0.249642 0.249642)
							(end -0.1778 0.2794)
						)
						(arc
							(start 0.1778 0.2794)
							(mid 0.249642 0.249642)
							(end 0.2794 0.1778)
						)
						(arc
							(start 0.2794 -0.1778)
							(mid 0.249642 -0.249642)
							(end 0.1778 -0.2794)
						)
					)
					(width 0)
					(fill yes)
				)
			)
		)
	)
	(footprint ""
		(layer "F.Cu")
		(at 381.4318 -295.0718 -90)
		(property "Reference" "R318"
			(at 0 0 270)
			(layer "F.SilkS")
			(hide yes)
			(effects
				(font
					(size 1.27 1.27)
				)
			)
		)
		(property "Value" "220R3F-1-GP"
			(at -0.0254 -2.5146 270)
			(unlocked yes)
			(layer "F.Fab")
			(hide yes)
			(effects
				(font
					(size 1.016 1.016)
					(thickness 0.1524)
				)
			)
		)
		(property "Device Type" "R603H22"
			(at -0.0254 -4.0386 270)
			(unlocked yes)
			(layer "F.Fab")
			(hide yes)
			(effects
				(font
					(size 1.016 1.016)
					(thickness 0.1524)
				)
			)
		)
		(duplicate_pad_numbers_are_jumpers no)
		(fp_line
			(start -0.4826 0)
			(end -0.2032 0)
			(stroke
				(width 0.2032)
				(type default)
			)
			(layer "F.SilkS")
		)
		(fp_line
			(start 0.2032 0)
			(end 0.4826 0)
			(stroke
				(width 0.2032)
				(type default)
			)
			(layer "F.SilkS")
		)
		(fp_rect
			(start -0.5842 1.3335)
			(end 0.5842 -1.3335)
			(stroke
				(width 0)
				(type default)
			)
			(fill no)
			(layer "F.CrtYd")
		)
		(fp_rect
			(start -0.5842 1.3335)
			(end 0.5842 -1.3335)
			(stroke
				(width 0)
				(type default)
			)
			(fill no)
			(layer "F.Fab")
		)
		(pad "1" smd custom
			(at 0 -0.762 270)
			(size 0.2159 0.2159)
			(layers "F.Cu" "F.Mask" "F.Paste")
			(net "HDD_PRSNT_8")
			(options
				(clearance outline)
				(anchor circle)
			)
			(primitives
				(gr_poly
					(pts
						(arc
							(start -0.3302 -0.4318)
							(mid -0.402042 -0.402042)
							(end -0.4318 -0.3302)
						)
						(arc
							(start -0.4318 0.3302)
							(mid -0.402042 0.402042)
							(end -0.3302 0.4318)
						)
						(arc
							(start 0.3302 0.4318)
							(mid 0.402042 0.402042)
							(end 0.4318 0.3302)
						)
						(arc
							(start 0.4318 -0.3302)
							(mid 0.402042 -0.402042)
							(end 0.3302 -0.4318)
						)
					)
					(width 0)
					(fill yes)
				)
			)
		)
		(pad "2" smd custom
			(at 0 0.762 270)
			(size 0.2159 0.2159)
			(layers "F.Cu" "F.Mask" "F.Paste")
			(net "DRIVE_A_8_INS")
			(options
				(clearance outline)
				(anchor circle)
			)
			(primitives
				(gr_poly
					(pts
						(arc
							(start -0.3302 -0.4318)
							(mid -0.402042 -0.402042)
							(end -0.4318 -0.3302)
						)
						(arc
							(start -0.4318 0.3302)
							(mid -0.402042 0.402042)
							(end -0.3302 0.4318)
						)
						(arc
							(start 0.3302 0.4318)
							(mid 0.402042 0.402042)
							(end 0.4318 0.3302)
						)
						(arc
							(start 0.4318 -0.3302)
							(mid 0.402042 -0.402042)
							(end 0.3302 -0.4318)
						)
					)
					(width 0)
					(fill yes)
				)
			)
		)
	)
	(footprint ""
		(layer "F.Cu")
		(at 14.842998 -59.857894)
		(property "Reference" "Q146"
			(at 0 0 0)
			(layer "F.SilkS")
			(hide yes)
			(effects
				(font
					(size 1.27 1.27)
				)
			)
		)
		(property "Value" "AO4407AL-GP"
			(at -3.707384 -1.5367 0)
			(unlocked yes)
			(layer "F.Fab")
			(hide yes)
			(effects
				(font
					(size 1.016 1.016)
					(thickness 0.1524)
				)
			)
		)
		(property "Device Type" "SOIC8H69"
			(at -3.707384 -3.0607 0)
			(unlocked yes)
			(layer "F.Fab")
			(hide yes)
			(effects
				(font
					(size 1.016 1.016)
					(thickness 0.1524)
				)
			)
		)
		(duplicate_pad_numbers_are_jumpers no)
		(fp_line
			(start -2.7432 -1.4224)
			(end -2.7432 1.4224)
			(stroke
				(width 0.1524)
				(type default)
			)
			(layer "F.SilkS")
		)
		(fp_line
			(start -2.7432 1.4224)
			(end -2.6416 1.4224)
			(stroke
				(width 0.1524)
				(type default)
			)
			(layer "F.SilkS")
		)
		(fp_line
			(start -2.7432 1.4224)
			(end 2.1336 1.4224)
			(stroke
				(width 0.1524)
				(type default)
			)
			(layer "F.SilkS")
		)
		(fp_line
			(start -2.7178 -0.508)
			(end -2.1844 -0.0508)
			(stroke
				(width 0.1524)
				(type default)
			)
			(layer "F.SilkS")
		)
		(fp_line
			(start -2.6289 3.4417)
			(end -2.6289 1.4732)
			(stroke
				(width 0.381)
				(type default)
			)
			(layer "F.SilkS")
		)
		(fp_line
			(start -2.1844 -0.0508)
			(end -2.7178 0.508)
			(stroke
				(width 0.1524)
				(type default)
			)
			(layer "F.SilkS")
		)
		(fp_line
			(start 2.1336 -1.4224)
			(end -2.7432 -1.4224)
			(stroke
				(width 0.1524)
				(type default)
			)
			(layer "F.SilkS")
		)
		(fp_line
			(start 2.1336 1.4224)
			(end 2.1336 -1.4224)
			(stroke
				(width 0.1524)
				(type default)
			)
			(layer "F.SilkS")
		)
		(fp_poly
			(pts
				(xy -2.2098 -1.4224) (xy -2.2098 1.4224) (xy 2.2098 1.4224) (xy 2.2098 -1.4224)
			)
			(stroke
				(width 0)
				(type default)
			)
			(fill yes)
			(layer "F.SilkS")
		)
		(fp_rect
			(start -2.450084 2.999994)
			(end 2.450084 -2.999994)
			(stroke
				(width 0)
				(type default)
			)
			(fill no)
			(layer "F.CrtYd")
		)
		(fp_poly
			(pts
				(xy -2.8194 3.6322) (xy -2.8194 -3.6322) (xy 2.8194 -3.6322) (xy 2.8194 1.18364) (xy 2.450084 1.18364)
				(xy 2.450084 -2.999994) (xy -2.450084 -2.999994) (xy -2.450084 2.999994) (xy 2.450084 2.999994)
				(xy 2.450084 1.18618) (xy 2.8194 1.18618) (xy 2.8194 3.6322)
			)
			(stroke
				(width 0)
				(type default)
			)
			(fill no)
			(layer "F.CrtYd")
		)
		(fp_rect
			(start -2.8194 3.6322)
			(end 2.8194 -3.6322)
			(stroke
				(width 0)
				(type default)
			)
			(fill no)
			(layer "F.Fab")
		)
		(pad "1" smd rect
			(at -1.905 2.54)
			(size 0.635 1.651)
			(layers "F.Cu" "F.Mask" "F.Paste")
			(net "P12V_A")
		)
		(pad "2" smd rect
			(at -0.635 2.54)
			(size 0.635 1.651)
			(layers "F.Cu" "F.Mask" "F.Paste")
			(net "P12V_A")
		)
		(pad "3" smd rect
			(at 0.635 2.54)
			(size 0.635 1.651)
			(layers "F.Cu" "F.Mask" "F.Paste")
			(net "P12V_A")
		)
		(pad "4" smd rect
			(at 1.905 2.54)
			(size 0.635 1.651)
			(layers "F.Cu" "F.Mask" "F.Paste")
			(net "SW_HDD_N24")
		)
		(pad "5" smd rect
			(at 1.905 -2.54)
			(size 0.635 1.651)
			(layers "F.Cu" "F.Mask" "F.Paste")
			(net "P12V_HDD24")
		)
		(pad "6" smd rect
			(at 0.635 -2.54)
			(size 0.635 1.651)
			(layers "F.Cu" "F.Mask" "F.Paste")
			(net "P12V_HDD24")
		)
		(pad "7" smd rect
			(at -0.635 -2.54)
			(size 0.635 1.651)
			(layers "F.Cu" "F.Mask" "F.Paste")
			(net "P12V_HDD24")
		)
		(pad "8" smd rect
			(at -1.905 -2.54)
			(size 0.635 1.651)
			(layers "F.Cu" "F.Mask" "F.Paste")
			(net "P12V_HDD24")
		)
	)
	(footprint ""
		(layer "F.Cu")
		(at 243.84 -394.3858 90)
		(property "Reference" "R1160"
			(at 0 0 90)
			(layer "F.SilkS")
			(hide yes)
			(effects
				(font
					(size 1.27 1.27)
				)
			)
		)
		(property "Value" "100KR2F-L1-GP"
			(at 0.064008 -3.993896 90)
			(unlocked yes)
			(layer "F.Fab")
			(hide yes)
			(effects
				(font
					(size 1.016 1.016)
					(thickness 0.1524)
				)
			)
		)
		(property "Device Type" "R402H16"
			(at 0.064008 -5.517896 90)
			(unlocked yes)
			(layer "F.Fab")
			(hide yes)
			(effects
				(font
					(size 1.016 1.016)
					(thickness 0.1524)
				)
			)
		)
		(duplicate_pad_numbers_are_jumpers no)
		(fp_line
			(start 0.508 -0.9398)
			(end -0.508 -0.9398)
			(stroke
				(width 0.1524)
				(type default)
			)
			(layer "F.SilkS")
		)
		(fp_line
			(start -0.508 -0.9398)
			(end -0.508 0.9398)
			(stroke
				(width 0.1524)
				(type default)
			)
			(layer "F.SilkS")
		)
		(fp_rect
			(start -0.508 0.9398)
			(end 0.508 -0.9398)
			(stroke
				(width 0)
				(type default)
			)
			(fill no)
			(layer "F.CrtYd")
		)
		(fp_rect
			(start -0.508 0.9398)
			(end 0.508 -0.9398)
			(stroke
				(width 0)
				(type default)
			)
			(fill no)
			(layer "F.Fab")
		)
		(pad "1" smd custom
			(at 0 -0.4445 90)
			(size 0.1397 0.1397)
			(layers "F.Cu" "F.Mask" "F.Paste")
			(net "MB3_VCAP_R")
			(options
				(clearance outline)
				(anchor circle)
			)
			(primitives
				(gr_poly
					(pts
						(arc
							(start -0.1778 -0.2794)
							(mid -0.249642 -0.249642)
							(end -0.2794 -0.1778)
						)
						(arc
							(start -0.2794 0.1778)
							(mid -0.249642 0.249642)
							(end -0.1778 0.2794)
						)
						(arc
							(start 0.1778 0.2794)
							(mid 0.249642 0.249642)
							(end 0.2794 0.1778)
						)
						(arc
							(start 0.2794 -0.1778)
							(mid 0.249642 -0.249642)
							(end 0.1778 -0.2794)
						)
					)
					(width 0)
					(fill yes)
				)
			)
		)
		(pad "2" smd custom
			(at 0 0.4445 90)
			(size 0.1397 0.1397)
			(layers "F.Cu" "F.Mask" "F.Paste")
			(net "MB3_PSET_R")
			(options
				(clearance outline)
				(anchor circle)
			)
			(primitives
				(gr_poly
					(pts
						(arc
							(start -0.1778 -0.2794)
							(mid -0.249642 -0.249642)
							(end -0.2794 -0.1778)
						)
						(arc
							(start -0.2794 0.1778)
							(mid -0.249642 0.249642)
							(end -0.1778 0.2794)
						)
						(arc
							(start 0.1778 0.2794)
							(mid 0.249642 0.249642)
							(end 0.2794 0.1778)
						)
						(arc
							(start 0.2794 -0.1778)
							(mid 0.249642 -0.249642)
							(end 0.1778 -0.2794)
						)
					)
					(width 0)
					(fill yes)
				)
			)
		)
	)
	(footprint ""
		(layer "F.Cu")
		(at 300.702472 -182.0418 90)
		(property "Reference" "C120"
			(at 0 0 90)
			(layer "F.SilkS")
			(hide yes)
			(effects
				(font
					(size 1.27 1.27)
				)
			)
		)
		(property "Value" "SC2D2U25V5KX-2-GP"
			(at -0.0762 -6.1214 90)
			(unlocked yes)
			(layer "F.Fab")
			(hide yes)
			(effects
				(font
					(size 1.016 1.016)
					(thickness 0.1524)
				)
			)
		)
		(property "Device Type" "C805H54"
			(at -0.0762 -8.1534 90)
			(unlocked yes)
			(layer "F.Fab")
			(hide yes)
			(effects
				(font
					(size 1.016 1.016)
					(thickness 0.1524)
				)
			)
		)
		(duplicate_pad_numbers_are_jumpers no)
		(fp_line
			(start 0.635 0)
			(end -0.635 0)
			(stroke
				(width 0.508)
				(type default)
			)
			(layer "F.SilkS")
		)
		(fp_rect
			(start -0.9652 1.778)
			(end 0.9652 -1.778)
			(stroke
				(width 0)
				(type default)
			)
			(fill no)
			(layer "F.CrtYd")
		)
		(fp_poly
			(pts
				(xy -0.9652 -1.778) (xy 0.9652 -1.778) (xy 0.9652 1.778) (xy -0.9652 1.778)
			)
			(stroke
				(width 0)
				(type default)
			)
			(fill no)
			(layer "F.Fab")
		)
		(pad "1" smd rect
			(at 0 -0.9652 90)
			(size 1.397 1.143)
			(layers "F.Cu" "F.Mask" "F.Paste")
			(net "P12V_B_COMP")
		)
		(pad "2" smd rect
			(at 0 0.9652 90)
			(size 1.397 1.143)
			(layers "F.Cu" "F.Mask" "F.Paste")
			(net "GND")
		)
	)
	(footprint ""
		(layer "F.Cu")
		(at 414.639252 -273.940016 90)
		(property "Reference" "VIA4"
			(at 0 0 90)
			(layer "F.SilkS")
			(hide yes)
			(effects
				(font
					(size 1.27 1.27)
				)
			)
		)
		(property "Value" "100OHM-8L-1D6MM-L18L16-GP"
			(at -3.7211 -4.5085 90)
			(unlocked yes)
			(layer "F.Fab")
			(hide yes)
			(effects
				(font
					(size 1.016 1.016)
					(thickness 0.1524)
				)
			)
		)
		(property "Device Type" "VIA-PCIE-4P-394076"
			(at -3.7211 -6.0325 90)
			(unlocked yes)
			(layer "F.Fab")
			(hide yes)
			(effects
				(font
					(size 1.016 1.016)
					(thickness 0.1524)
				)
			)
		)
		(duplicate_pad_numbers_are_jumpers no)
		(fp_rect
			(start -1.9685 0.381)
			(end 1.9685 -0.381)
			(stroke
				(width 0)
				(type default)
			)
			(fill no)
			(layer "F.CrtYd")
		)
		(fp_rect
			(start -1.9685 0.381)
			(end 1.9685 -0.381)
			(stroke
				(width 0)
				(type default)
			)
			(fill no)
			(layer "F.Fab")
		)
		(pad "1" thru_hole circle
			(at -1.5875 0 90)
			(size 0.508 0.508)
			(drill 0.254)
			(layers "*.Cu" "*.Mask")
			(remove_unused_layers no)
			(net "GND")
			(clearance 0.127)
			(thermal_gap 0.127)
		)
		(pad "2" thru_hole circle
			(at -0.5715 0 90)
			(size 0.508 0.508)
			(drill 0.254)
			(layers "*.Cu" "*.Mask")
			(remove_unused_layers no)
			(net "PHY_SCC_A_TO_DRV_A_9_DP")
			(clearance 0.127)
			(thermal_gap 0.127)
		)
		(pad "3" thru_hole circle
			(at 0.5715 0 90)
			(size 0.508 0.508)
			(drill 0.254)
			(layers "*.Cu" "*.Mask")
			(remove_unused_layers no)
			(net "PHY_SCC_A_TO_DRV_A_9_DN")
			(clearance 0.127)
			(thermal_gap 0.127)
		)
		(pad "4" thru_hole circle
			(at 1.5875 0 90)
			(size 0.508 0.508)
			(drill 0.254)
			(layers "*.Cu" "*.Mask")
			(remove_unused_layers no)
			(net "GND")
			(clearance 0.127)
			(thermal_gap 0.127)
		)
	)
	(footprint ""
		(layer "F.Cu")
		(at 223.360742 -217.653362 90)
		(property "Reference" "R418"
			(at 0 0 90)
			(layer "F.SilkS")
			(hide yes)
			(effects
				(font
					(size 1.27 1.27)
				)
			)
		)
		(property "Value" "0R2J-2-GP"
			(at 0.064008 -3.993896 90)
			(unlocked yes)
			(layer "F.Fab")
			(hide yes)
			(effects
				(font
					(size 1.016 1.016)
					(thickness 0.1524)
				)
			)
		)
		(property "Device Type" "R402H16"
			(at 0.064008 -5.517896 90)
			(unlocked yes)
			(layer "F.Fab")
			(hide yes)
			(effects
				(font
					(size 1.016 1.016)
					(thickness 0.1524)
				)
			)
		)
		(duplicate_pad_numbers_are_jumpers no)
		(fp_line
			(start 0.508 -0.9398)
			(end -0.508 -0.9398)
			(stroke
				(width 0.1524)
				(type default)
			)
			(layer "F.SilkS")
		)
		(fp_line
			(start -0.508 -0.9398)
			(end -0.508 0.9398)
			(stroke
				(width 0.1524)
				(type default)
			)
			(layer "F.SilkS")
		)
		(fp_rect
			(start -0.508 0.9398)
			(end 0.508 -0.9398)
			(stroke
				(width 0)
				(type default)
			)
			(fill no)
			(layer "F.CrtYd")
		)
		(fp_rect
			(start -0.508 0.9398)
			(end 0.508 -0.9398)
			(stroke
				(width 0)
				(type default)
			)
			(fill no)
			(layer "F.Fab")
		)
		(pad "1" smd custom
			(at 0 -0.4445 90)
			(size 0.1397 0.1397)
			(layers "F.Cu" "F.Mask" "F.Paste")
			(net "I2C_SCC_A_SDA_BUF")
			(options
				(clearance outline)
				(anchor circle)
			)
			(primitives
				(gr_poly
					(pts
						(arc
							(start -0.1778 -0.2794)
							(mid -0.249642 -0.249642)
							(end -0.2794 -0.1778)
						)
						(arc
							(start -0.2794 0.1778)
							(mid -0.249642 0.249642)
							(end -0.1778 0.2794)
						)
						(arc
							(start 0.1778 0.2794)
							(mid 0.249642 0.249642)
							(end 0.2794 0.1778)
						)
						(arc
							(start 0.2794 -0.1778)
							(mid 0.249642 -0.249642)
							(end 0.1778 -0.2794)
						)
					)
					(width 0)
					(fill yes)
				)
			)
		)
		(pad "2" smd custom
			(at 0 0.4445 90)
			(size 0.1397 0.1397)
			(layers "F.Cu" "F.Mask" "F.Paste")
			(net "I2C_SCC_A_SDA")
			(options
				(clearance outline)
				(anchor circle)
			)
			(primitives
				(gr_poly
					(pts
						(arc
							(start -0.1778 -0.2794)
							(mid -0.249642 -0.249642)
							(end -0.2794 -0.1778)
						)
						(arc
							(start -0.2794 0.1778)
							(mid -0.249642 0.249642)
							(end -0.1778 0.2794)
						)
						(arc
							(start 0.1778 0.2794)
							(mid 0.249642 0.249642)
							(end 0.2794 0.1778)
						)
						(arc
							(start 0.2794 -0.1778)
							(mid 0.249642 -0.249642)
							(end 0.1778 -0.2794)
						)
					)
					(width 0)
					(fill yes)
				)
			)
		)
	)
	(footprint ""
		(layer "F.Cu")
		(at 445.5922 -256.35712 180)
		(property "Reference" "R1261"
			(at 0 0 180)
			(layer "F.SilkS")
			(hide yes)
			(effects
				(font
					(size 1.27 1.27)
				)
			)
		)
		(property "Value" "0R2J-2-GP"
			(at 0.064008 -3.993896 180)
			(unlocked yes)
			(layer "F.Fab")
			(hide yes)
			(effects
				(font
					(size 1.016 1.016)
					(thickness 0.1524)
				)
			)
		)
		(property "Device Type" "R402H16"
			(at 0.064008 -5.517896 180)
			(unlocked yes)
			(layer "F.Fab")
			(hide yes)
			(effects
				(font
					(size 1.016 1.016)
					(thickness 0.1524)
				)
			)
		)
		(duplicate_pad_numbers_are_jumpers no)
		(fp_line
			(start 0.508 -0.9398)
			(end -0.508 -0.9398)
			(stroke
				(width 0.1524)
				(type default)
			)
			(layer "F.SilkS")
		)
		(fp_line
			(start -0.508 -0.9398)
			(end -0.508 0.9398)
			(stroke
				(width 0.1524)
				(type default)
			)
			(layer "F.SilkS")
		)
		(fp_rect
			(start -0.508 0.9398)
			(end 0.508 -0.9398)
			(stroke
				(width 0)
				(type default)
			)
			(fill no)
			(layer "F.CrtYd")
		)
		(fp_rect
			(start -0.508 0.9398)
			(end 0.508 -0.9398)
			(stroke
				(width 0)
				(type default)
			)
			(fill no)
			(layer "F.Fab")
		)
		(pad "1" smd custom
			(at 0 -0.4445 180)
			(size 0.1397 0.1397)
			(layers "F.Cu" "F.Mask" "F.Paste")
			(net "P5V_C_ROVP")
			(options
				(clearance outline)
				(anchor circle)
			)
			(primitives
				(gr_poly
					(pts
						(arc
							(start -0.1778 -0.2794)
							(mid -0.249642 -0.249642)
							(end -0.2794 -0.1778)
						)
						(arc
							(start -0.2794 0.1778)
							(mid -0.249642 0.249642)
							(end -0.1778 0.2794)
						)
						(arc
							(start 0.1778 0.2794)
							(mid 0.249642 0.249642)
							(end 0.2794 0.1778)
						)
						(arc
							(start 0.2794 -0.1778)
							(mid 0.249642 -0.249642)
							(end 0.1778 -0.2794)
						)
					)
					(width 0)
					(fill yes)
				)
			)
		)
		(pad "2" smd custom
			(at 0 0.4445 180)
			(size 0.1397 0.1397)
			(layers "F.Cu" "F.Mask" "F.Paste")
			(net "AGND_P5V_C")
			(options
				(clearance outline)
				(anchor circle)
			)
			(primitives
				(gr_poly
					(pts
						(arc
							(start -0.1778 -0.2794)
							(mid -0.249642 -0.249642)
							(end -0.2794 -0.1778)
						)
						(arc
							(start -0.2794 0.1778)
							(mid -0.249642 0.249642)
							(end -0.1778 0.2794)
						)
						(arc
							(start 0.1778 0.2794)
							(mid 0.249642 0.249642)
							(end 0.2794 0.1778)
						)
						(arc
							(start 0.2794 -0.1778)
							(mid 0.249642 -0.249642)
							(end 0.1778 -0.2794)
						)
					)
					(width 0)
					(fill yes)
				)
			)
		)
	)
	(footprint ""
		(layer "F.Cu")
		(at 109.492796 -59.857894)
		(property "Reference" "Q164"
			(at 0 0 0)
			(layer "F.SilkS")
			(hide yes)
			(effects
				(font
					(size 1.27 1.27)
				)
			)
		)
		(property "Value" "AO4407AL-GP"
			(at -3.707384 -1.5367 0)
			(unlocked yes)
			(layer "F.Fab")
			(hide yes)
			(effects
				(font
					(size 1.016 1.016)
					(thickness 0.1524)
				)
			)
		)
		(property "Device Type" "SOIC8H69"
			(at -3.707384 -3.0607 0)
			(unlocked yes)
			(layer "F.Fab")
			(hide yes)
			(effects
				(font
					(size 1.016 1.016)
					(thickness 0.1524)
				)
			)
		)
		(duplicate_pad_numbers_are_jumpers no)
		(fp_line
			(start -2.7432 -1.4224)
			(end -2.7432 1.4224)
			(stroke
				(width 0.1524)
				(type default)
			)
			(layer "F.SilkS")
		)
		(fp_line
			(start -2.7432 1.4224)
			(end -2.6416 1.4224)
			(stroke
				(width 0.1524)
				(type default)
			)
			(layer "F.SilkS")
		)
		(fp_line
			(start -2.7432 1.4224)
			(end 2.1336 1.4224)
			(stroke
				(width 0.1524)
				(type default)
			)
			(layer "F.SilkS")
		)
		(fp_line
			(start -2.7178 -0.508)
			(end -2.1844 -0.0508)
			(stroke
				(width 0.1524)
				(type default)
			)
			(layer "F.SilkS")
		)
		(fp_line
			(start -2.6289 3.4417)
			(end -2.6289 1.4732)
			(stroke
				(width 0.381)
				(type default)
			)
			(layer "F.SilkS")
		)
		(fp_line
			(start -2.1844 -0.0508)
			(end -2.7178 0.508)
			(stroke
				(width 0.1524)
				(type default)
			)
			(layer "F.SilkS")
		)
		(fp_line
			(start 2.1336 -1.4224)
			(end -2.7432 -1.4224)
			(stroke
				(width 0.1524)
				(type default)
			)
			(layer "F.SilkS")
		)
		(fp_line
			(start 2.1336 1.4224)
			(end 2.1336 -1.4224)
			(stroke
				(width 0.1524)
				(type default)
			)
			(layer "F.SilkS")
		)
		(fp_poly
			(pts
				(xy -2.2098 -1.4224) (xy -2.2098 1.4224) (xy 2.2098 1.4224) (xy 2.2098 -1.4224)
			)
			(stroke
				(width 0)
				(type default)
			)
			(fill yes)
			(layer "F.SilkS")
		)
		(fp_rect
			(start -2.450084 2.999994)
			(end 2.450084 -2.999994)
			(stroke
				(width 0)
				(type default)
			)
			(fill no)
			(layer "F.CrtYd")
		)
		(fp_poly
			(pts
				(xy -2.8194 3.6322) (xy -2.8194 -3.6322) (xy 2.8194 -3.6322) (xy 2.8194 1.18364) (xy 2.450084 1.18364)
				(xy 2.450084 -2.999994) (xy -2.450084 -2.999994) (xy -2.450084 2.999994) (xy 2.450084 2.999994)
				(xy 2.450084 1.18618) (xy 2.8194 1.18618) (xy 2.8194 3.6322)
			)
			(stroke
				(width 0)
				(type default)
			)
			(fill no)
			(layer "F.CrtYd")
		)
		(fp_rect
			(start -2.8194 3.6322)
			(end 2.8194 -3.6322)
			(stroke
				(width 0)
				(type default)
			)
			(fill no)
			(layer "F.Fab")
		)
		(pad "1" smd rect
			(at -1.905 2.54)
			(size 0.635 1.651)
			(layers "F.Cu" "F.Mask" "F.Paste")
			(net "P12V_A")
		)
		(pad "2" smd rect
			(at -0.635 2.54)
			(size 0.635 1.651)
			(layers "F.Cu" "F.Mask" "F.Paste")
			(net "P12V_A")
		)
		(pad "3" smd rect
			(at 0.635 2.54)
			(size 0.635 1.651)
			(layers "F.Cu" "F.Mask" "F.Paste")
			(net "P12V_A")
		)
		(pad "4" smd rect
			(at 1.905 2.54)
			(size 0.635 1.651)
			(layers "F.Cu" "F.Mask" "F.Paste")
			(net "SW_HDD_N27")
		)
		(pad "5" smd rect
			(at 1.905 -2.54)
			(size 0.635 1.651)
			(layers "F.Cu" "F.Mask" "F.Paste")
			(net "P12V_HDD27")
		)
		(pad "6" smd rect
			(at 0.635 -2.54)
			(size 0.635 1.651)
			(layers "F.Cu" "F.Mask" "F.Paste")
			(net "P12V_HDD27")
		)
		(pad "7" smd rect
			(at -0.635 -2.54)
			(size 0.635 1.651)
			(layers "F.Cu" "F.Mask" "F.Paste")
			(net "P12V_HDD27")
		)
		(pad "8" smd rect
			(at -1.905 -2.54)
			(size 0.635 1.651)
			(layers "F.Cu" "F.Mask" "F.Paste")
			(net "P12V_HDD27")
		)
	)
	(footprint ""
		(layer "F.Cu")
		(at 451.749922 -287.910016 -90)
		(property "Reference" "HDDSAS10"
			(at 0 0 270)
			(layer "F.SilkS")
			(hide yes)
			(effects
				(font
					(size 1.27 1.27)
				)
			)
		)
		(property "Value" "SKT-SAS15P-14P-45-GP"
			(at -20.7645 -8.9789 270)
			(unlocked yes)
			(layer "F.Fab")
			(hide yes)
			(effects
				(font
					(size 1.016 1.016)
					(thickness 0.1524)
				)
			)
		)
		(property "Device Type" "10120818-001C-TRLF"
			(at -20.7645 -10.5029 270)
			(unlocked yes)
			(layer "F.Fab")
			(hide yes)
			(effects
				(font
					(size 1.016 1.016)
					(thickness 0.1524)
				)
			)
		)
		(duplicate_pad_numbers_are_jumpers no)
		(fp_line
			(start 1.651 4.2926)
			(end 1.651 3.0099)
			(stroke
				(width 0.1524)
				(type default)
			)
			(layer "F.SilkS")
		)
		(fp_line
			(start 8.509 4.2926)
			(end 1.651 4.2926)
			(stroke
				(width 0.1524)
				(type default)
			)
			(layer "F.SilkS")
		)
		(fp_line
			(start -23.4188 3.0099)
			(end -23.4188 -3.2512)
			(stroke
				(width 0.1524)
				(type default)
			)
			(layer "F.SilkS")
		)
		(fp_line
			(start 1.651 3.0099)
			(end -23.4188 3.0099)
			(stroke
				(width 0.1524)
				(type default)
			)
			(layer "F.SilkS")
		)
		(fp_line
			(start 8.509 3.0099)
			(end 8.509 4.2926)
			(stroke
				(width 0.1524)
				(type default)
			)
			(layer "F.SilkS")
		)
		(fp_line
			(start 23.4188 3.0099)
			(end 8.509 3.0099)
			(stroke
				(width 0.1524)
				(type default)
			)
			(layer "F.SilkS")
		)
		(fp_line
			(start -23.4188 -3.2512)
			(end 23.4188 -3.2512)
			(stroke
				(width 0.1524)
				(type default)
			)
			(layer "F.SilkS")
		)
		(fp_line
			(start 23.4188 -3.2512)
			(end 23.4188 3.0099)
			(stroke
				(width 0.1524)
				(type default)
			)
			(layer "F.SilkS")
		)
		(fp_line
			(start 15.5067 -3.3401)
			(end 16.2687 -3.3401)
			(stroke
				(width 0.3302)
				(type default)
			)
			(layer "F.SilkS")
		)
		(fp_poly
			(pts
				(xy 15.868904 -3.230372) (xy 16.503904 -3.865372) (xy 15.233904 -3.865372)
			)
			(stroke
				(width 0)
				(type default)
			)
			(fill yes)
			(layer "F.SilkS")
		)
		(fp_poly
			(pts
				(xy -22.8727 -2.7559) (xy 22.8727 -2.7559) (xy 22.8727 2.7559) (xy 8.255 2.7559) (xy 8.255 3.5179)
				(xy 1.905 3.5179) (xy 1.905 2.7559) (xy -22.8727 2.7559)
			)
			(stroke
				(width 0)
				(type default)
			)
			(fill no)
			(layer "F.CrtYd")
		)
		(fp_poly
			(pts
				(xy 1.397 4.5466) (xy 1.397 3.2639) (xy -23.6728 3.2639) (xy -23.6728 -3.5052) (xy 23.6728 -3.5052)
				(xy 23.6728 -0.00635) (xy 22.8727 -0.00635) (xy 22.8727 -2.7559) (xy -22.8727 -2.7559) (xy -22.8727 2.7559)
				(xy 1.905 2.7559) (xy 1.905 3.5179) (xy 8.255 3.5179) (xy 8.255 2.7559) (xy 22.8727 2.7559) (xy 22.8727 0.00635)
				(xy 23.6728 0.00635) (xy 23.6728 3.2639) (xy 8.763 3.2639) (xy 8.763 4.5466)
			)
			(stroke
				(width 0)
				(type default)
			)
			(fill no)
			(layer "F.CrtYd")
		)
		(fp_poly
			(pts
				(xy 1.397 4.5466) (xy 1.397 3.2639) (xy -23.6728 3.2639) (xy -23.6728 -3.5052) (xy 23.6728 -3.5052)
				(xy 23.6728 3.2639) (xy 8.763 3.2639) (xy 8.763 4.5466)
			)
			(stroke
				(width 0)
				(type default)
			)
			(fill no)
			(layer "F.Fab")
		)
		(pad "" np_thru_hole circle
			(at -18.874994 0 270)
			(size 0.254 0.254)
			(drill 1.3462)
			(layers "*.Cu" "*.Mask")
			(clearance 0.9017)
			(thermal_gap 0.9017)
		)
		(pad "" np_thru_hole circle
			(at 18.874994 0 270)
			(size 0.254 0.254)
			(drill 0.9398)
			(layers "*.Cu" "*.Mask")
			(clearance 0.6985)
			(thermal_gap 0.6985)
		)
		(pad "G1" smd rect
			(at 21.874988 0 270)
			(size 2.5908 2.5908)
			(layers "F.Cu" "F.Mask" "F.Paste")
			(net "GND")
		)
		(pad "G2" smd rect
			(at -21.874988 0 270)
			(size 2.5908 2.5908)
			(layers "F.Cu" "F.Mask" "F.Paste")
			(net "GND")
		)
		(pad "P1" smd rect
			(at 1.905 -1.82499 270)
			(size 0.6096 2.3622)
			(layers "F.Cu" "F.Mask" "F.Paste")
			(net "Net_2166")
		)
		(pad "P2" smd rect
			(at 0.635 -1.82499 270)
			(size 0.6096 2.3622)
			(layers "F.Cu" "F.Mask" "F.Paste")
			(net "Net_2167")
		)
		(pad "P3" smd rect
			(at -0.635 -1.82499 270)
			(size 0.6096 2.3622)
			(layers "F.Cu" "F.Mask" "F.Paste")
			(net "Net_2168")
		)
		(pad "P4" smd rect
			(at -1.905 -1.82499 270)
			(size 0.6096 2.3622)
			(layers "F.Cu" "F.Mask" "F.Paste")
			(net "GND")
		)
		(pad "P5" smd rect
			(at -3.175 -1.82499 270)
			(size 0.6096 2.3622)
			(layers "F.Cu" "F.Mask" "F.Paste")
			(net "HDD_PRSNT_10")
		)
		(pad "P6" smd rect
			(at -4.445 -1.82499 270)
			(size 0.6096 2.3622)
			(layers "F.Cu" "F.Mask" "F.Paste")
			(net "GND")
		)
		(pad "P7" smd rect
			(at -5.715 -1.82499 270)
			(size 0.6096 2.3622)
			(layers "F.Cu" "F.Mask" "F.Paste")
			(net "5V_PRE_10")
		)
		(pad "P8" smd rect
			(at -6.985 -1.82499 270)
			(size 0.6096 2.3622)
			(layers "F.Cu" "F.Mask" "F.Paste")
			(net "P5V_HDD10")
		)
		(pad "P9" smd rect
			(at -8.255 -1.82499 270)
			(size 0.6096 2.3622)
			(layers "F.Cu" "F.Mask" "F.Paste")
			(net "P5V_HDD10")
		)
		(pad "P10" smd rect
			(at -9.525 -1.82499 270)
			(size 0.6096 2.3622)
			(layers "F.Cu" "F.Mask" "F.Paste")
			(net "GND")
		)
		(pad "P11" smd rect
			(at -10.795 -1.82499 270)
			(size 0.6096 2.3622)
			(layers "F.Cu" "F.Mask" "F.Paste")
			(net "ACT_HDD_10")
		)
		(pad "P12" smd rect
			(at -12.065 -1.82499 270)
			(size 0.6096 2.3622)
			(layers "F.Cu" "F.Mask" "F.Paste")
			(net "GND")
		)
		(pad "P13" smd rect
			(at -13.335 -1.82499 270)
			(size 0.6096 2.3622)
			(layers "F.Cu" "F.Mask" "F.Paste")
			(net "12V_PRE_10")
		)
		(pad "P14" smd rect
			(at -14.605 -1.82499 270)
			(size 0.6096 2.3622)
			(layers "F.Cu" "F.Mask" "F.Paste")
			(net "P12V_HDD10")
		)
		(pad "P15" smd rect
			(at -15.875 -1.82499 270)
			(size 0.6096 2.3622)
			(layers "F.Cu" "F.Mask" "F.Paste")
			(net "P12V_HDD10")
		)
		(pad "S1" smd rect
			(at 15.875 -1.82499 270)
			(size 0.6096 2.3622)
			(layers "F.Cu" "F.Mask" "F.Paste")
			(net "GND")
		)
		(pad "S2" smd rect
			(at 14.605 -1.82499 270)
			(size 0.6096 2.3622)
			(layers "F.Cu" "F.Mask" "F.Paste")
			(net "SAS_HDD_RX_P10")
		)
		(pad "S3" smd rect
			(at 13.335 -1.82499 270)
			(size 0.6096 2.3622)
			(layers "F.Cu" "F.Mask" "F.Paste")
			(net "SAS_HDD_RX_N10")
		)
		(pad "S4" smd rect
			(at 12.065 -1.82499 270)
			(size 0.6096 2.3622)
			(layers "F.Cu" "F.Mask" "F.Paste")
			(net "GND")
		)
		(pad "S5" smd rect
			(at 10.795 -1.82499 270)
			(size 0.6096 2.3622)
			(layers "F.Cu" "F.Mask" "F.Paste")
			(net "PHY_DRV_A_TO_SCC_A_10_DN")
		)
		(pad "S6" smd rect
			(at 9.525 -1.82499 270)
			(size 0.6096 2.3622)
			(layers "F.Cu" "F.Mask" "F.Paste")
			(net "PHY_DRV_A_TO_SCC_A_10_DP")
		)
		(pad "S7" smd rect
			(at 8.255 -1.82499 270)
			(size 0.6096 2.3622)
			(layers "F.Cu" "F.Mask" "F.Paste")
			(net "GND")
		)
		(pad "S8" smd rect
			(at 7.480046 2.845054 270)
			(size 0.508 2.3622)
			(layers "F.Cu" "F.Mask" "F.Paste")
			(net "GND")
		)
		(pad "S9" smd rect
			(at 6.679946 2.845054 270)
			(size 0.508 2.3622)
			(layers "F.Cu" "F.Mask" "F.Paste")
			(net "Net_447")
		)
		(pad "S10" smd rect
			(at 5.8801 2.845054 270)
			(size 0.508 2.3622)
			(layers "F.Cu" "F.Mask" "F.Paste")
			(net "Net_339")
		)
		(pad "S11" smd rect
			(at 5.08 2.845054 270)
			(size 0.508 2.3622)
			(layers "F.Cu" "F.Mask" "F.Paste")
			(net "GND")
		)
		(pad "S12" smd rect
			(at 4.2799 2.845054 270)
			(size 0.508 2.3622)
			(layers "F.Cu" "F.Mask" "F.Paste")
			(net "Net_375")
		)
		(pad "S13" smd rect
			(at 3.480054 2.845054 270)
			(size 0.508 2.3622)
			(layers "F.Cu" "F.Mask" "F.Paste")
			(net "Net_411")
		)
		(pad "S14" smd rect
			(at 2.679954 2.845054 270)
			(size 0.508 2.3622)
			(layers "F.Cu" "F.Mask" "F.Paste")
			(net "GND")
		)
		(zone
			(layer "F.Cu")
			(hatch none 0.5)
			(connect_pads
				(clearance 0)
			)
			(min_thickness 0.25)
			(keepout
				(tracks allowed)
				(vias not_allowed)
				(pads allowed)
				(copperpour not_allowed)
				(footprints allowed)
			)
			(placement
				(enabled no)
				(sheetname "")
			)
			(fill
				(thermal_gap 0.5)
				(thermal_bridge_width 0.5)
				(island_removal_mode 0)
			)
			(polygon
				(pts
					(xy 455.407522 -304.648616) (xy 448.333622 -304.648616) (xy 448.333622 -311.582816) (xy 449.438522 -311.582816)
					(xy 449.438522 -307.468016) (xy 454.061322 -307.468016) (xy 454.061322 -311.582816) (xy 455.407522 -311.582816)
				)
			)
		)
		(zone
			(layer "F.Cu")
			(hatch none 0.5)
			(connect_pads
				(clearance 0)
			)
			(min_thickness 0.25)
			(keepout
				(tracks not_allowed)
				(vias allowed)
				(pads allowed)
				(copperpour not_allowed)
				(footprints allowed)
			)
			(placement
				(enabled no)
				(sheetname "")
			)
			(fill
				(thermal_gap 0.5)
				(thermal_bridge_width 0.5)
				(island_removal_mode 0)
			)
			(polygon
				(pts
					(xy 455.407522 -304.648616) (xy 448.333622 -304.648616) (xy 448.333622 -311.582816) (xy 449.438522 -311.582816)
					(xy 449.438522 -307.468016) (xy 454.061322 -307.468016) (xy 454.061322 -311.582816) (xy 455.407522 -311.582816)
				)
			)
		)
		(zone
			(layer "F.Cu")
			(hatch none 0.5)
			(connect_pads
				(clearance 0)
			)
			(min_thickness 0.25)
			(keepout
				(tracks not_allowed)
				(vias allowed)
				(pads allowed)
				(copperpour not_allowed)
				(footprints allowed)
			)
			(placement
				(enabled no)
				(sheetname "")
			)
			(fill
				(thermal_gap 0.5)
				(thermal_bridge_width 0.5)
				(island_removal_mode 0)
			)
			(polygon
				(pts
					(xy 455.407522 -271.171416) (xy 448.333622 -271.171416) (xy 448.333622 -264.237216) (xy 449.438522 -264.237216)
					(xy 449.438522 -268.352016) (xy 454.061322 -268.352016) (xy 454.061322 -264.237216) (xy 455.407522 -264.237216)
				)
			)
		)
		(zone
			(layer "F.Cu")
			(hatch none 0.5)
			(connect_pads
				(clearance 0)
			)
			(min_thickness 0.25)
			(keepout
				(tracks allowed)
				(vias not_allowed)
				(pads allowed)
				(copperpour not_allowed)
				(footprints allowed)
			)
			(placement
				(enabled no)
				(sheetname "")
			)
			(fill
				(thermal_gap 0.5)
				(thermal_bridge_width 0.5)
				(island_removal_mode 0)
			)
			(polygon
				(pts
					(xy 455.407522 -271.171416) (xy 448.333622 -271.171416) (xy 448.333622 -264.237216) (xy 449.438522 -264.237216)
					(xy 449.438522 -268.352016) (xy 454.061322 -268.352016) (xy 454.061322 -264.237216) (xy 455.407522 -264.237216)
				)
			)
		)
		(zone
			(layers "F.Cu" "B.Cu" "In1.Cu" "In2.Cu" "In3.Cu" "In4.Cu" "In5.Cu" "In6.Cu"
				"In7.Cu" "In8.Cu" "In9.Cu" "In10.Cu"
			)
			(hatch none 0.5)
			(connect_pads
				(clearance 0)
			)
			(min_thickness 0.25)
			(keepout
				(tracks not_allowed)
				(vias allowed)
				(pads allowed)
				(copperpour not_allowed)
				(footprints allowed)
			)
			(placement
				(enabled no)
				(sheetname "")
			)
			(fill
				(thermal_gap 0.5)
				(thermal_bridge_width 0.5)
				(island_removal_mode 0)
			)
			(polygon
				(pts
					(arc
						(start 452.524622 -269.035022)
						(mid 450.975222 -269.035022)
						(end 452.524622 -269.035022)
					)
				)
			)
		)
		(zone
			(layers "F.Cu" "B.Cu" "In1.Cu" "In2.Cu" "In3.Cu" "In4.Cu" "In5.Cu" "In6.Cu"
				"In7.Cu" "In8.Cu" "In9.Cu" "In10.Cu"
			)
			(hatch none 0.5)
			(connect_pads
				(clearance 0)
			)
			(min_thickness 0.25)
			(keepout
				(tracks not_allowed)
				(vias allowed)
				(pads allowed)
				(copperpour not_allowed)
				(footprints allowed)
			)
			(placement
				(enabled no)
				(sheetname "")
			)
			(fill
				(thermal_gap 0.5)
				(thermal_bridge_width 0.5)
				(island_removal_mode 0)
			)
			(polygon
				(pts
					(arc
						(start 452.727822 -306.78501)
						(mid 450.772022 -306.78501)
						(end 452.727822 -306.78501)
					)
				)
			)
		)
	)
	(footprint ""
		(layer "F.Cu")
		(at 357.100124 -57.909968 -90)
		(property "Reference" "HDDSAS31"
			(at 0 0 270)
			(layer "F.SilkS")
			(hide yes)
			(effects
				(font
					(size 1.27 1.27)
				)
			)
		)
		(property "Value" "SKT-SAS15P-14P-45-GP"
			(at -20.7645 -8.9789 270)
			(unlocked yes)
			(layer "F.Fab")
			(hide yes)
			(effects
				(font
					(size 1.016 1.016)
					(thickness 0.1524)
				)
			)
		)
		(property "Device Type" "10120818-001C-TRLF"
			(at -20.7645 -10.5029 270)
			(unlocked yes)
			(layer "F.Fab")
			(hide yes)
			(effects
				(font
					(size 1.016 1.016)
					(thickness 0.1524)
				)
			)
		)
		(duplicate_pad_numbers_are_jumpers no)
		(fp_line
			(start 1.651 4.2926)
			(end 1.651 3.0099)
			(stroke
				(width 0.1524)
				(type default)
			)
			(layer "F.SilkS")
		)
		(fp_line
			(start 8.509 4.2926)
			(end 1.651 4.2926)
			(stroke
				(width 0.1524)
				(type default)
			)
			(layer "F.SilkS")
		)
		(fp_line
			(start -23.4188 3.0099)
			(end -23.4188 -3.2512)
			(stroke
				(width 0.1524)
				(type default)
			)
			(layer "F.SilkS")
		)
		(fp_line
			(start 1.651 3.0099)
			(end -23.4188 3.0099)
			(stroke
				(width 0.1524)
				(type default)
			)
			(layer "F.SilkS")
		)
		(fp_line
			(start 8.509 3.0099)
			(end 8.509 4.2926)
			(stroke
				(width 0.1524)
				(type default)
			)
			(layer "F.SilkS")
		)
		(fp_line
			(start 23.4188 3.0099)
			(end 8.509 3.0099)
			(stroke
				(width 0.1524)
				(type default)
			)
			(layer "F.SilkS")
		)
		(fp_line
			(start -23.4188 -3.2512)
			(end 23.4188 -3.2512)
			(stroke
				(width 0.1524)
				(type default)
			)
			(layer "F.SilkS")
		)
		(fp_line
			(start 23.4188 -3.2512)
			(end 23.4188 3.0099)
			(stroke
				(width 0.1524)
				(type default)
			)
			(layer "F.SilkS")
		)
		(fp_line
			(start 15.5067 -3.3401)
			(end 16.2687 -3.3401)
			(stroke
				(width 0.3302)
				(type default)
			)
			(layer "F.SilkS")
		)
		(fp_poly
			(pts
				(xy 15.868904 -3.230372) (xy 16.503904 -3.865372) (xy 15.233904 -3.865372)
			)
			(stroke
				(width 0)
				(type default)
			)
			(fill yes)
			(layer "F.SilkS")
		)
		(fp_poly
			(pts
				(xy -22.8727 -2.7559) (xy 22.8727 -2.7559) (xy 22.8727 2.7559) (xy 8.255 2.7559) (xy 8.255 3.5179)
				(xy 1.905 3.5179) (xy 1.905 2.7559) (xy -22.8727 2.7559)
			)
			(stroke
				(width 0)
				(type default)
			)
			(fill no)
			(layer "F.CrtYd")
		)
		(fp_poly
			(pts
				(xy 1.397 4.5466) (xy 1.397 3.2639) (xy -23.6728 3.2639) (xy -23.6728 -3.5052) (xy 23.6728 -3.5052)
				(xy 23.6728 -0.00635) (xy 22.8727 -0.00635) (xy 22.8727 -2.7559) (xy -22.8727 -2.7559) (xy -22.8727 2.7559)
				(xy 1.905 2.7559) (xy 1.905 3.5179) (xy 8.255 3.5179) (xy 8.255 2.7559) (xy 22.8727 2.7559) (xy 22.8727 0.00635)
				(xy 23.6728 0.00635) (xy 23.6728 3.2639) (xy 8.763 3.2639) (xy 8.763 4.5466)
			)
			(stroke
				(width 0)
				(type default)
			)
			(fill no)
			(layer "F.CrtYd")
		)
		(fp_poly
			(pts
				(xy 1.397 4.5466) (xy 1.397 3.2639) (xy -23.6728 3.2639) (xy -23.6728 -3.5052) (xy 23.6728 -3.5052)
				(xy 23.6728 3.2639) (xy 8.763 3.2639) (xy 8.763 4.5466)
			)
			(stroke
				(width 0)
				(type default)
			)
			(fill no)
			(layer "F.Fab")
		)
		(pad "" np_thru_hole circle
			(at -18.874994 0 270)
			(size 0.254 0.254)
			(drill 1.3462)
			(layers "*.Cu" "*.Mask")
			(clearance 0.9017)
			(thermal_gap 0.9017)
		)
		(pad "" np_thru_hole circle
			(at 18.874994 0 270)
			(size 0.254 0.254)
			(drill 0.9398)
			(layers "*.Cu" "*.Mask")
			(clearance 0.6985)
			(thermal_gap 0.6985)
		)
		(pad "G1" smd rect
			(at 21.874988 0 270)
			(size 2.5908 2.5908)
			(layers "F.Cu" "F.Mask" "F.Paste")
			(net "GND")
		)
		(pad "G2" smd rect
			(at -21.874988 0 270)
			(size 2.5908 2.5908)
			(layers "F.Cu" "F.Mask" "F.Paste")
			(net "GND")
		)
		(pad "P1" smd rect
			(at 1.905 -1.82499 270)
			(size 0.6096 2.3622)
			(layers "F.Cu" "F.Mask" "F.Paste")
			(net "Net_2051")
		)
		(pad "P2" smd rect
			(at 0.635 -1.82499 270)
			(size 0.6096 2.3622)
			(layers "F.Cu" "F.Mask" "F.Paste")
			(net "Net_2052")
		)
		(pad "P3" smd rect
			(at -0.635 -1.82499 270)
			(size 0.6096 2.3622)
			(layers "F.Cu" "F.Mask" "F.Paste")
			(net "Net_2053")
		)
		(pad "P4" smd rect
			(at -1.905 -1.82499 270)
			(size 0.6096 2.3622)
			(layers "F.Cu" "F.Mask" "F.Paste")
			(net "GND")
		)
		(pad "P5" smd rect
			(at -3.175 -1.82499 270)
			(size 0.6096 2.3622)
			(layers "F.Cu" "F.Mask" "F.Paste")
			(net "HDD_PRSNT_31")
		)
		(pad "P6" smd rect
			(at -4.445 -1.82499 270)
			(size 0.6096 2.3622)
			(layers "F.Cu" "F.Mask" "F.Paste")
			(net "GND")
		)
		(pad "P7" smd rect
			(at -5.715 -1.82499 270)
			(size 0.6096 2.3622)
			(layers "F.Cu" "F.Mask" "F.Paste")
			(net "5V_PRE_31")
		)
		(pad "P8" smd rect
			(at -6.985 -1.82499 270)
			(size 0.6096 2.3622)
			(layers "F.Cu" "F.Mask" "F.Paste")
			(net "P5V_HDD31")
		)
		(pad "P9" smd rect
			(at -8.255 -1.82499 270)
			(size 0.6096 2.3622)
			(layers "F.Cu" "F.Mask" "F.Paste")
			(net "P5V_HDD31")
		)
		(pad "P10" smd rect
			(at -9.525 -1.82499 270)
			(size 0.6096 2.3622)
			(layers "F.Cu" "F.Mask" "F.Paste")
			(net "GND")
		)
		(pad "P11" smd rect
			(at -10.795 -1.82499 270)
			(size 0.6096 2.3622)
			(layers "F.Cu" "F.Mask" "F.Paste")
			(net "ACT_HDD_31")
		)
		(pad "P12" smd rect
			(at -12.065 -1.82499 270)
			(size 0.6096 2.3622)
			(layers "F.Cu" "F.Mask" "F.Paste")
			(net "GND")
		)
		(pad "P13" smd rect
			(at -13.335 -1.82499 270)
			(size 0.6096 2.3622)
			(layers "F.Cu" "F.Mask" "F.Paste")
			(net "12V_PRE_31")
		)
		(pad "P14" smd rect
			(at -14.605 -1.82499 270)
			(size 0.6096 2.3622)
			(layers "F.Cu" "F.Mask" "F.Paste")
			(net "P12V_HDD31")
		)
		(pad "P15" smd rect
			(at -15.875 -1.82499 270)
			(size 0.6096 2.3622)
			(layers "F.Cu" "F.Mask" "F.Paste")
			(net "P12V_HDD31")
		)
		(pad "S1" smd rect
			(at 15.875 -1.82499 270)
			(size 0.6096 2.3622)
			(layers "F.Cu" "F.Mask" "F.Paste")
			(net "GND")
		)
		(pad "S2" smd rect
			(at 14.605 -1.82499 270)
			(size 0.6096 2.3622)
			(layers "F.Cu" "F.Mask" "F.Paste")
			(net "SAS_HDD_RX_P31")
		)
		(pad "S3" smd rect
			(at 13.335 -1.82499 270)
			(size 0.6096 2.3622)
			(layers "F.Cu" "F.Mask" "F.Paste")
			(net "SAS_HDD_RX_N31")
		)
		(pad "S4" smd rect
			(at 12.065 -1.82499 270)
			(size 0.6096 2.3622)
			(layers "F.Cu" "F.Mask" "F.Paste")
			(net "GND")
		)
		(pad "S5" smd rect
			(at 10.795 -1.82499 270)
			(size 0.6096 2.3622)
			(layers "F.Cu" "F.Mask" "F.Paste")
			(net "PHY_DRV_A_TO_SCC_A_31_DN")
		)
		(pad "S6" smd rect
			(at 9.525 -1.82499 270)
			(size 0.6096 2.3622)
			(layers "F.Cu" "F.Mask" "F.Paste")
			(net "PHY_DRV_A_TO_SCC_A_31_DP")
		)
		(pad "S7" smd rect
			(at 8.255 -1.82499 270)
			(size 0.6096 2.3622)
			(layers "F.Cu" "F.Mask" "F.Paste")
			(net "GND")
		)
		(pad "S8" smd rect
			(at 7.480046 2.845054 270)
			(size 0.508 2.3622)
			(layers "F.Cu" "F.Mask" "F.Paste")
			(net "GND")
		)
		(pad "S9" smd rect
			(at 6.679946 2.845054 270)
			(size 0.508 2.3622)
			(layers "F.Cu" "F.Mask" "F.Paste")
			(net "Net_470")
		)
		(pad "S10" smd rect
			(at 5.8801 2.845054 270)
			(size 0.508 2.3622)
			(layers "F.Cu" "F.Mask" "F.Paste")
			(net "Net_362")
		)
		(pad "S11" smd rect
			(at 5.08 2.845054 270)
			(size 0.508 2.3622)
			(layers "F.Cu" "F.Mask" "F.Paste")
			(net "GND")
		)
		(pad "S12" smd rect
			(at 4.2799 2.845054 270)
			(size 0.508 2.3622)
			(layers "F.Cu" "F.Mask" "F.Paste")
			(net "Net_398")
		)
		(pad "S13" smd rect
			(at 3.480054 2.845054 270)
			(size 0.508 2.3622)
			(layers "F.Cu" "F.Mask" "F.Paste")
			(net "Net_434")
		)
		(pad "S14" smd rect
			(at 2.679954 2.845054 270)
			(size 0.508 2.3622)
			(layers "F.Cu" "F.Mask" "F.Paste")
			(net "GND")
		)
		(zone
			(layer "F.Cu")
			(hatch none 0.5)
			(connect_pads
				(clearance 0)
			)
			(min_thickness 0.25)
			(keepout
				(tracks not_allowed)
				(vias allowed)
				(pads allowed)
				(copperpour not_allowed)
				(footprints allowed)
			)
			(placement
				(enabled no)
				(sheetname "")
			)
			(fill
				(thermal_gap 0.5)
				(thermal_bridge_width 0.5)
				(island_removal_mode 0)
			)
			(polygon
				(pts
					(xy 360.757724 -74.648568) (xy 353.683824 -74.648568) (xy 353.683824 -81.582768) (xy 354.788724 -81.582768)
					(xy 354.788724 -77.467968) (xy 359.411524 -77.467968) (xy 359.411524 -81.582768) (xy 360.757724 -81.582768)
				)
			)
		)
		(zone
			(layer "F.Cu")
			(hatch none 0.5)
			(connect_pads
				(clearance 0)
			)
			(min_thickness 0.25)
			(keepout
				(tracks allowed)
				(vias not_allowed)
				(pads allowed)
				(copperpour not_allowed)
				(footprints allowed)
			)
			(placement
				(enabled no)
				(sheetname "")
			)
			(fill
				(thermal_gap 0.5)
				(thermal_bridge_width 0.5)
				(island_removal_mode 0)
			)
			(polygon
				(pts
					(xy 360.757724 -74.648568) (xy 353.683824 -74.648568) (xy 353.683824 -81.582768) (xy 354.788724 -81.582768)
					(xy 354.788724 -77.467968) (xy 359.411524 -77.467968) (xy 359.411524 -81.582768) (xy 360.757724 -81.582768)
				)
			)
		)
		(zone
			(layer "F.Cu")
			(hatch none 0.5)
			(connect_pads
				(clearance 0)
			)
			(min_thickness 0.25)
			(keepout
				(tracks not_allowed)
				(vias allowed)
				(pads allowed)
				(copperpour not_allowed)
				(footprints allowed)
			)
			(placement
				(enabled no)
				(sheetname "")
			)
			(fill
				(thermal_gap 0.5)
				(thermal_bridge_width 0.5)
				(island_removal_mode 0)
			)
			(polygon
				(pts
					(xy 360.757724 -41.171368) (xy 353.683824 -41.171368) (xy 353.683824 -34.237168) (xy 354.788724 -34.237168)
					(xy 354.788724 -38.351968) (xy 359.411524 -38.351968) (xy 359.411524 -34.237168) (xy 360.757724 -34.237168)
				)
			)
		)
		(zone
			(layer "F.Cu")
			(hatch none 0.5)
			(connect_pads
				(clearance 0)
			)
			(min_thickness 0.25)
			(keepout
				(tracks allowed)
				(vias not_allowed)
				(pads allowed)
				(copperpour not_allowed)
				(footprints allowed)
			)
			(placement
				(enabled no)
				(sheetname "")
			)
			(fill
				(thermal_gap 0.5)
				(thermal_bridge_width 0.5)
				(island_removal_mode 0)
			)
			(polygon
				(pts
					(xy 360.757724 -41.171368) (xy 353.683824 -41.171368) (xy 353.683824 -34.237168) (xy 354.788724 -34.237168)
					(xy 354.788724 -38.351968) (xy 359.411524 -38.351968) (xy 359.411524 -34.237168) (xy 360.757724 -34.237168)
				)
			)
		)
		(zone
			(layers "F.Cu" "B.Cu" "In1.Cu" "In2.Cu" "In3.Cu" "In4.Cu" "In5.Cu" "In6.Cu"
				"In7.Cu" "In8.Cu" "In9.Cu" "In10.Cu"
			)
			(hatch none 0.5)
			(connect_pads
				(clearance 0)
			)
			(min_thickness 0.25)
			(keepout
				(tracks not_allowed)
				(vias allowed)
				(pads allowed)
				(copperpour not_allowed)
				(footprints allowed)
			)
			(placement
				(enabled no)
				(sheetname "")
			)
			(fill
				(thermal_gap 0.5)
				(thermal_bridge_width 0.5)
				(island_removal_mode 0)
			)
			(polygon
				(pts
					(arc
						(start 357.874824 -39.034974)
						(mid 356.325424 -39.034974)
						(end 357.874824 -39.034974)
					)
				)
			)
		)
		(zone
			(layers "F.Cu" "B.Cu" "In1.Cu" "In2.Cu" "In3.Cu" "In4.Cu" "In5.Cu" "In6.Cu"
				"In7.Cu" "In8.Cu" "In9.Cu" "In10.Cu"
			)
			(hatch none 0.5)
			(connect_pads
				(clearance 0)
			)
			(min_thickness 0.25)
			(keepout
				(tracks not_allowed)
				(vias allowed)
				(pads allowed)
				(copperpour not_allowed)
				(footprints allowed)
			)
			(placement
				(enabled no)
				(sheetname "")
			)
			(fill
				(thermal_gap 0.5)
				(thermal_bridge_width 0.5)
				(island_removal_mode 0)
			)
			(polygon
				(pts
					(arc
						(start 358.078024 -76.784962)
						(mid 356.122224 -76.784962)
						(end 358.078024 -76.784962)
					)
				)
			)
		)
	)
	(footprint ""
		(layer "F.Cu")
		(at 153.712672 -131.18973 90)
		(property "Reference" "Q219"
			(at 0 0 90)
			(layer "F.SilkS")
			(hide yes)
			(effects
				(font
					(size 1.27 1.27)
				)
			)
		)
		(property "Value" "MMBT3904-3-GP"
			(at 0.10287 -10.29843 90)
			(unlocked yes)
			(layer "F.Fab")
			(hide yes)
			(effects
				(font
					(size 1.016 1.016)
					(thickness 0.1524)
				)
			)
		)
		(property "Device Type" "SOT23CBE2D4H44"
			(at 0.10287 -12.20343 90)
			(unlocked yes)
			(layer "F.Fab")
			(hide yes)
			(effects
				(font
					(size 1.016 1.016)
					(thickness 0.1524)
				)
			)
		)
		(duplicate_pad_numbers_are_jumpers no)
		(fp_line
			(start 1.651 -1.778)
			(end -1.651 -1.778)
			(stroke
				(width 0.1524)
				(type default)
			)
			(layer "F.SilkS")
		)
		(fp_line
			(start -1.651 -1.778)
			(end -1.651 1.778)
			(stroke
				(width 0.1524)
				(type default)
			)
			(layer "F.SilkS")
		)
		(fp_line
			(start 1.651 1.778)
			(end 1.651 -1.778)
			(stroke
				(width 0.1524)
				(type default)
			)
			(layer "F.SilkS")
		)
		(fp_line
			(start -1.651 1.778)
			(end 1.651 1.778)
			(stroke
				(width 0.1524)
				(type default)
			)
			(layer "F.SilkS")
		)
		(fp_poly
			(pts
				(xy -1.778 1.8796) (xy -1.778 -1.8796) (xy 1.778 -1.8796) (xy 1.778 1.8796)
			)
			(stroke
				(width 0)
				(type default)
			)
			(fill no)
			(layer "F.CrtYd")
		)
		(fp_poly
			(pts
				(xy -1.778 1.8796) (xy -1.778 -1.8796) (xy 1.778 -1.8796) (xy 1.778 1.8796)
			)
			(stroke
				(width 0)
				(type default)
			)
			(fill no)
			(layer "F.Fab")
		)
		(pad "B" smd custom
			(at -0.98425 0.9525 90)
			(size 0.1905 0.1905)
			(layers "F.Cu" "F.Mask" "F.Paste")
			(net "MB0_TEMP_B")
			(options
				(clearance outline)
				(anchor circle)
			)
			(primitives
				(gr_poly
					(pts
						(arc
							(start -0.1778 0.5715)
							(mid -0.321484 0.511984)
							(end -0.381 0.3683)
						)
						(arc
							(start -0.381 -0.3683)
							(mid -0.321484 -0.511984)
							(end -0.1778 -0.5715)
						)
						(arc
							(start 0.1778 -0.5715)
							(mid 0.321484 -0.511984)
							(end 0.381 -0.3683)
						)
						(arc
							(start 0.381 0.3683)
							(mid 0.321484 0.511984)
							(end 0.1778 0.5715)
						)
					)
					(width 0)
					(fill yes)
				)
			)
		)
		(pad "C" smd custom
			(at 0 -0.9525 90)
			(size 0.1905 0.1905)
			(layers "F.Cu" "F.Mask" "F.Paste")
			(net "MB0_TEMP_B")
			(options
				(clearance outline)
				(anchor circle)
			)
			(primitives
				(gr_poly
					(pts
						(arc
							(start -0.1778 0.5715)
							(mid -0.321484 0.511984)
							(end -0.381 0.3683)
						)
						(arc
							(start -0.381 -0.3683)
							(mid -0.321484 -0.511984)
							(end -0.1778 -0.5715)
						)
						(arc
							(start 0.1778 -0.5715)
							(mid 0.321484 -0.511984)
							(end 0.381 -0.3683)
						)
						(arc
							(start 0.381 0.3683)
							(mid 0.321484 0.511984)
							(end 0.1778 0.5715)
						)
					)
					(width 0)
					(fill yes)
				)
			)
		)
		(pad "E" smd custom
			(at 0.98425 0.9525 90)
			(size 0.1905 0.1905)
			(layers "F.Cu" "F.Mask" "F.Paste")
			(net "MB0_TEMP_E")
			(options
				(clearance outline)
				(anchor circle)
			)
			(primitives
				(gr_poly
					(pts
						(arc
							(start -0.1778 0.5715)
							(mid -0.321484 0.511984)
							(end -0.381 0.3683)
						)
						(arc
							(start -0.381 -0.3683)
							(mid -0.321484 -0.511984)
							(end -0.1778 -0.5715)
						)
						(arc
							(start 0.1778 -0.5715)
							(mid 0.321484 -0.511984)
							(end 0.381 -0.3683)
						)
						(arc
							(start 0.381 0.3683)
							(mid 0.321484 0.511984)
							(end 0.1778 0.5715)
						)
					)
					(width 0)
					(fill yes)
				)
			)
		)
	)
	(footprint ""
		(layer "F.Cu")
		(at 47.09033 -149.115018 90)
		(property "Reference" "R1234"
			(at 0 0 90)
			(layer "F.SilkS")
			(hide yes)
			(effects
				(font
					(size 1.27 1.27)
				)
			)
		)
		(property "Value" "100KR2F-L1-GP"
			(at 0.064008 -3.993896 90)
			(unlocked yes)
			(layer "F.Fab")
			(hide yes)
			(effects
				(font
					(size 1.016 1.016)
					(thickness 0.1524)
				)
			)
		)
		(property "Device Type" "R402H16"
			(at 0.064008 -5.517896 90)
			(unlocked yes)
			(layer "F.Fab")
			(hide yes)
			(effects
				(font
					(size 1.016 1.016)
					(thickness 0.1524)
				)
			)
		)
		(duplicate_pad_numbers_are_jumpers no)
		(fp_line
			(start 0.508 -0.9398)
			(end -0.508 -0.9398)
			(stroke
				(width 0.1524)
				(type default)
			)
			(layer "F.SilkS")
		)
		(fp_line
			(start -0.508 -0.9398)
			(end -0.508 0.9398)
			(stroke
				(width 0.1524)
				(type default)
			)
			(layer "F.SilkS")
		)
		(fp_rect
			(start -0.508 0.9398)
			(end 0.508 -0.9398)
			(stroke
				(width 0)
				(type default)
			)
			(fill no)
			(layer "F.CrtYd")
		)
		(fp_rect
			(start -0.508 0.9398)
			(end 0.508 -0.9398)
			(stroke
				(width 0)
				(type default)
			)
			(fill no)
			(layer "F.Fab")
		)
		(pad "1" smd custom
			(at 0 -0.4445 90)
			(size 0.1397 0.1397)
			(layers "F.Cu" "F.Mask" "F.Paste")
			(net "AGND_P5V_B")
			(options
				(clearance outline)
				(anchor circle)
			)
			(primitives
				(gr_poly
					(pts
						(arc
							(start -0.1778 -0.2794)
							(mid -0.249642 -0.249642)
							(end -0.2794 -0.1778)
						)
						(arc
							(start -0.2794 0.1778)
							(mid -0.249642 0.249642)
							(end -0.1778 0.2794)
						)
						(arc
							(start 0.1778 0.2794)
							(mid 0.249642 0.249642)
							(end 0.2794 0.1778)
						)
						(arc
							(start 0.2794 -0.1778)
							(mid 0.249642 -0.249642)
							(end 0.1778 -0.2794)
						)
					)
					(width 0)
					(fill yes)
				)
			)
		)
		(pad "2" smd custom
			(at 0 0.4445 90)
			(size 0.1397 0.1397)
			(layers "F.Cu" "F.Mask" "F.Paste")
			(net "P5V_B_MODE")
			(options
				(clearance outline)
				(anchor circle)
			)
			(primitives
				(gr_poly
					(pts
						(arc
							(start -0.1778 -0.2794)
							(mid -0.249642 -0.249642)
							(end -0.2794 -0.1778)
						)
						(arc
							(start -0.2794 0.1778)
							(mid -0.249642 0.249642)
							(end -0.1778 0.2794)
						)
						(arc
							(start 0.1778 0.2794)
							(mid 0.249642 0.249642)
							(end 0.2794 0.1778)
						)
						(arc
							(start 0.2794 -0.1778)
							(mid 0.249642 -0.249642)
							(end 0.1778 -0.2794)
						)
					)
					(width 0)
					(fill yes)
				)
			)
		)
	)
	(footprint ""
		(layer "F.Cu")
		(at 335.29397 -18.650966 180)
		(property "Reference" "C19"
			(at 0 0 180)
			(layer "F.SilkS")
			(hide yes)
			(effects
				(font
					(size 1.27 1.27)
				)
			)
		)
		(property "Value" "SCD1U16V2KX-3GP"
			(at 1.1811 -2.7051 180)
			(unlocked yes)
			(layer "F.Fab")
			(hide yes)
			(effects
				(font
					(size 1.016 1.016)
					(thickness 0.1524)
				)
			)
		)
		(property "Device Type" "C402H22"
			(at 1.1811 -4.2291 180)
			(unlocked yes)
			(layer "F.Fab")
			(hide yes)
			(effects
				(font
					(size 1.016 1.016)
					(thickness 0.1524)
				)
			)
		)
		(duplicate_pad_numbers_are_jumpers no)
		(fp_rect
			(start -0.4318 0.9525)
			(end 0.4318 -0.9525)
			(stroke
				(width 0)
				(type default)
			)
			(fill no)
			(layer "F.CrtYd")
		)
		(fp_rect
			(start -0.4318 0.9525)
			(end 0.4318 -0.9525)
			(stroke
				(width 0)
				(type default)
			)
			(fill no)
			(layer "F.Fab")
		)
		(pad "1" smd custom
			(at 0 -0.4445 180)
			(size 0.1524 0.1524)
			(layers "F.Cu" "F.Mask" "F.Paste")
			(net "P3V3_STBY_B")
			(options
				(clearance outline)
				(anchor circle)
			)
			(primitives
				(gr_poly
					(pts
						(arc
							(start 0.3048 -0.2032)
							(mid 0.275042 -0.275042)
							(end 0.2032 -0.3048)
						)
						(arc
							(start -0.2032 -0.3048)
							(mid -0.275042 -0.275042)
							(end -0.3048 -0.2032)
						)
						(arc
							(start -0.3048 0.2032)
							(mid -0.275042 0.275042)
							(end -0.2032 0.3048)
						)
						(arc
							(start 0.2032 0.3048)
							(mid 0.275042 0.275042)
							(end 0.3048 0.2032)
						)
					)
					(width 0)
					(fill yes)
				)
			)
		)
		(pad "2" smd custom
			(at 0 0.4445 180)
			(size 0.1524 0.1524)
			(layers "F.Cu" "F.Mask" "F.Paste")
			(net "GND")
			(options
				(clearance outline)
				(anchor circle)
			)
			(primitives
				(gr_poly
					(pts
						(arc
							(start 0.3048 -0.2032)
							(mid 0.275042 -0.275042)
							(end 0.2032 -0.3048)
						)
						(arc
							(start -0.2032 -0.3048)
							(mid -0.275042 -0.275042)
							(end -0.3048 -0.2032)
						)
						(arc
							(start -0.3048 0.2032)
							(mid -0.275042 0.275042)
							(end -0.2032 0.3048)
						)
						(arc
							(start 0.2032 0.3048)
							(mid 0.275042 0.275042)
							(end 0.3048 0.2032)
						)
					)
					(width 0)
					(fill yes)
				)
			)
		)
	)
	(footprint ""
		(layer "F.Cu")
		(at 242.522502 -379.837696 -90)
		(property "Reference" "C596"
			(at 0 0 270)
			(layer "F.SilkS")
			(hide yes)
			(effects
				(font
					(size 1.27 1.27)
				)
			)
		)
		(property "Value" "SCD033U50V3KX-1GP"
			(at 0 -2.8194 270)
			(unlocked yes)
			(layer "F.Fab")
			(hide yes)
			(effects
				(font
					(size 1.016 1.016)
					(thickness 0.1524)
				)
			)
		)
		(property "Device Type" "C603H36"
			(at 0 -4.3434 270)
			(unlocked yes)
			(layer "F.Fab")
			(hide yes)
			(effects
				(font
					(size 1.016 1.016)
					(thickness 0.1524)
				)
			)
		)
		(duplicate_pad_numbers_are_jumpers no)
		(fp_line
			(start 0.508 0)
			(end -0.508 0)
			(stroke
				(width 0.2032)
				(type default)
			)
			(layer "F.SilkS")
		)
		(fp_rect
			(start -0.5842 1.3335)
			(end 0.5842 -1.3335)
			(stroke
				(width 0)
				(type default)
			)
			(fill no)
			(layer "F.CrtYd")
		)
		(fp_rect
			(start -0.5842 1.3335)
			(end 0.5842 -1.3335)
			(stroke
				(width 0)
				(type default)
			)
			(fill no)
			(layer "F.Fab")
		)
		(pad "1" smd custom
			(at 0 -0.762 270)
			(size 0.2159 0.2159)
			(layers "F.Cu" "F.Mask" "F.Paste")
			(net "MB3_CM_GATE_C")
			(options
				(clearance outline)
				(anchor circle)
			)
			(primitives
				(gr_poly
					(pts
						(arc
							(start -0.3302 -0.4318)
							(mid -0.402042 -0.402042)
							(end -0.4318 -0.3302)
						)
						(arc
							(start -0.4318 0.3302)
							(mid -0.402042 0.402042)
							(end -0.3302 0.4318)
						)
						(arc
							(start 0.3302 0.4318)
							(mid 0.402042 0.402042)
							(end 0.4318 0.3302)
						)
						(arc
							(start 0.4318 -0.3302)
							(mid 0.402042 -0.402042)
							(end 0.3302 -0.4318)
						)
					)
					(width 0)
					(fill yes)
				)
			)
		)
		(pad "2" smd custom
			(at 0 0.762 270)
			(size 0.2159 0.2159)
			(layers "F.Cu" "F.Mask" "F.Paste")
			(net "GND")
			(options
				(clearance outline)
				(anchor circle)
			)
			(primitives
				(gr_poly
					(pts
						(arc
							(start -0.3302 -0.4318)
							(mid -0.402042 -0.402042)
							(end -0.4318 -0.3302)
						)
						(arc
							(start -0.4318 0.3302)
							(mid -0.402042 0.402042)
							(end -0.3302 0.4318)
						)
						(arc
							(start 0.3302 0.4318)
							(mid 0.402042 0.402042)
							(end 0.4318 0.3302)
						)
						(arc
							(start 0.4318 -0.3302)
							(mid 0.402042 -0.402042)
							(end 0.3302 -0.4318)
						)
					)
					(width 0)
					(fill yes)
				)
			)
		)
	)
	(footprint ""
		(layer "F.Cu")
		(at 233.4514 -231.3178)
		(property "Reference" "R72"
			(at 0 0 0)
			(layer "F.SilkS")
			(hide yes)
			(effects
				(font
					(size 1.27 1.27)
				)
			)
		)
		(property "Value" "4K7R2F-GP"
			(at 0.064008 -3.993896 0)
			(unlocked yes)
			(layer "F.Fab")
			(hide yes)
			(effects
				(font
					(size 1.016 1.016)
					(thickness 0.1524)
				)
			)
		)
		(property "Device Type" "R402H16"
			(at 0.064008 -5.517896 0)
			(unlocked yes)
			(layer "F.Fab")
			(hide yes)
			(effects
				(font
					(size 1.016 1.016)
					(thickness 0.1524)
				)
			)
		)
		(duplicate_pad_numbers_are_jumpers no)
		(fp_line
			(start -0.508 -0.9398)
			(end -0.508 0.9398)
			(stroke
				(width 0.1524)
				(type default)
			)
			(layer "F.SilkS")
		)
		(fp_line
			(start 0.508 -0.9398)
			(end -0.508 -0.9398)
			(stroke
				(width 0.1524)
				(type default)
			)
			(layer "F.SilkS")
		)
		(fp_rect
			(start -0.508 0.9398)
			(end 0.508 -0.9398)
			(stroke
				(width 0)
				(type default)
			)
			(fill no)
			(layer "F.CrtYd")
		)
		(fp_rect
			(start -0.508 0.9398)
			(end 0.508 -0.9398)
			(stroke
				(width 0)
				(type default)
			)
			(fill no)
			(layer "F.Fab")
		)
		(pad "1" smd custom
			(at 0 -0.4445)
			(size 0.1397 0.1397)
			(layers "F.Cu" "F.Mask" "F.Paste")
			(net "IO_EXP1_A0")
			(options
				(clearance outline)
				(anchor circle)
			)
			(primitives
				(gr_poly
					(pts
						(arc
							(start -0.1778 -0.2794)
							(mid -0.249642 -0.249642)
							(end -0.2794 -0.1778)
						)
						(arc
							(start -0.2794 0.1778)
							(mid -0.249642 0.249642)
							(end -0.1778 0.2794)
						)
						(arc
							(start 0.1778 0.2794)
							(mid 0.249642 0.249642)
							(end 0.2794 0.1778)
						)
						(arc
							(start 0.2794 -0.1778)
							(mid 0.249642 -0.249642)
							(end 0.1778 -0.2794)
						)
					)
					(width 0)
					(fill yes)
				)
			)
		)
		(pad "2" smd custom
			(at 0 0.4445)
			(size 0.1397 0.1397)
			(layers "F.Cu" "F.Mask" "F.Paste")
			(net "GND")
			(options
				(clearance outline)
				(anchor circle)
			)
			(primitives
				(gr_poly
					(pts
						(arc
							(start -0.1778 -0.2794)
							(mid -0.249642 -0.249642)
							(end -0.2794 -0.1778)
						)
						(arc
							(start -0.2794 0.1778)
							(mid -0.249642 0.249642)
							(end -0.1778 0.2794)
						)
						(arc
							(start 0.1778 0.2794)
							(mid 0.249642 0.249642)
							(end 0.2794 0.1778)
						)
						(arc
							(start 0.2794 -0.1778)
							(mid 0.249642 -0.249642)
							(end 0.1778 -0.2794)
						)
					)
					(width 0)
					(fill yes)
				)
			)
		)
	)
	(footprint ""
		(layer "F.Cu")
		(at 238.506 -394.3858 -90)
		(property "Reference" "R1164"
			(at 0 0 270)
			(layer "F.SilkS")
			(hide yes)
			(effects
				(font
					(size 1.27 1.27)
				)
			)
		)
		(property "Value" "100KR2F-L1-GP"
			(at 0.064008 -3.993896 270)
			(unlocked yes)
			(layer "F.Fab")
			(hide yes)
			(effects
				(font
					(size 1.016 1.016)
					(thickness 0.1524)
				)
			)
		)
		(property "Device Type" "R402H16"
			(at 0.064008 -5.517896 270)
			(unlocked yes)
			(layer "F.Fab")
			(hide yes)
			(effects
				(font
					(size 1.016 1.016)
					(thickness 0.1524)
				)
			)
		)
		(duplicate_pad_numbers_are_jumpers no)
		(fp_line
			(start -0.508 -0.9398)
			(end -0.508 0.9398)
			(stroke
				(width 0.1524)
				(type default)
			)
			(layer "F.SilkS")
		)
		(fp_line
			(start 0.508 -0.9398)
			(end -0.508 -0.9398)
			(stroke
				(width 0.1524)
				(type default)
			)
			(layer "F.SilkS")
		)
		(fp_rect
			(start -0.508 0.9398)
			(end 0.508 -0.9398)
			(stroke
				(width 0)
				(type default)
			)
			(fill no)
			(layer "F.CrtYd")
		)
		(fp_rect
			(start -0.508 0.9398)
			(end 0.508 -0.9398)
			(stroke
				(width 0)
				(type default)
			)
			(fill no)
			(layer "F.Fab")
		)
		(pad "1" smd custom
			(at 0 -0.4445 270)
			(size 0.1397 0.1397)
			(layers "F.Cu" "F.Mask" "F.Paste")
			(net "MB3_VCAP_R")
			(options
				(clearance outline)
				(anchor circle)
			)
			(primitives
				(gr_poly
					(pts
						(arc
							(start -0.1778 -0.2794)
							(mid -0.249642 -0.249642)
							(end -0.2794 -0.1778)
						)
						(arc
							(start -0.2794 0.1778)
							(mid -0.249642 0.249642)
							(end -0.1778 0.2794)
						)
						(arc
							(start 0.1778 0.2794)
							(mid 0.249642 0.249642)
							(end 0.2794 0.1778)
						)
						(arc
							(start 0.2794 -0.1778)
							(mid 0.249642 -0.249642)
							(end 0.1778 -0.2794)
						)
					)
					(width 0)
					(fill yes)
				)
			)
		)
		(pad "2" smd custom
			(at 0 0.4445 270)
			(size 0.1397 0.1397)
			(layers "F.Cu" "F.Mask" "F.Paste")
			(net "MB3_ISTART_R")
			(options
				(clearance outline)
				(anchor circle)
			)
			(primitives
				(gr_poly
					(pts
						(arc
							(start -0.1778 -0.2794)
							(mid -0.249642 -0.249642)
							(end -0.2794 -0.1778)
						)
						(arc
							(start -0.2794 0.1778)
							(mid -0.249642 0.249642)
							(end -0.1778 0.2794)
						)
						(arc
							(start 0.1778 0.2794)
							(mid 0.249642 0.249642)
							(end 0.2794 0.1778)
						)
						(arc
							(start 0.2794 -0.1778)
							(mid 0.249642 -0.249642)
							(end 0.1778 -0.2794)
						)
					)
					(width 0)
					(fill yes)
				)
			)
		)
	)
	(footprint ""
		(layer "F.Cu")
		(at 112.450118 -94.400116)
		(property "Reference" "FLED16"
			(at 0 0 0)
			(layer "F.SilkS")
			(hide yes)
			(effects
				(font
					(size 1.27 1.27)
				)
			)
		)
		(property "Value" "LED-BY-19-GP"
			(at -2.132076 1.414018 0)
			(unlocked yes)
			(layer "F.Fab")
			(hide yes)
			(effects
				(font
					(size 1.016 1.016)
					(thickness 0.1524)
				)
			)
		)
		(property "Device Type" "LED-1615-4PH26"
			(at -2.132076 -0.109982 0)
			(unlocked yes)
			(layer "F.Fab")
			(hide yes)
			(effects
				(font
					(size 1.016 1.016)
					(thickness 0.1524)
				)
			)
		)
		(duplicate_pad_numbers_are_jumpers no)
		(fp_line
			(start -1.2954 0.254)
			(end -1.2954 1.6002)
			(stroke
				(width 0.508)
				(type default)
			)
			(layer "F.SilkS")
		)
		(fp_line
			(start -1.2954 1.6002)
			(end 1.2954 1.6002)
			(stroke
				(width 0.508)
				(type default)
			)
			(layer "F.SilkS")
		)
		(fp_line
			(start -1.1176 -1.4224)
			(end 1.1176 -1.4224)
			(stroke
				(width 0.1524)
				(type default)
			)
			(layer "F.SilkS")
		)
		(fp_line
			(start -1.1176 1.4224)
			(end -1.1176 -1.4224)
			(stroke
				(width 0.1524)
				(type default)
			)
			(layer "F.SilkS")
		)
		(fp_line
			(start 1.1176 -1.4224)
			(end 1.1176 1.4224)
			(stroke
				(width 0.1524)
				(type default)
			)
			(layer "F.SilkS")
		)
		(fp_line
			(start 1.1176 1.4224)
			(end -1.1176 1.4224)
			(stroke
				(width 0.1524)
				(type default)
			)
			(layer "F.SilkS")
		)
		(fp_line
			(start 1.2954 1.6002)
			(end 1.2954 0.254)
			(stroke
				(width 0.508)
				(type default)
			)
			(layer "F.SilkS")
		)
		(fp_rect
			(start -0.7493 0.8001)
			(end 0.7493 -0.8001)
			(stroke
				(width 0)
				(type default)
			)
			(fill no)
			(layer "F.CrtYd")
		)
		(fp_poly
			(pts
				(xy -1.3716 1.6764) (xy -1.3716 -1.6764) (xy 1.3716 -1.6764) (xy 1.3716 0.0635) (xy 0.7493 0.0635)
				(xy 0.7493 -0.8001) (xy -0.7493 -0.8001) (xy -0.7493 0.8001) (xy 0.7493 0.8001) (xy 0.7493 0.0762)
				(xy 1.3716 0.0762) (xy 1.3716 1.6764)
			)
			(stroke
				(width 0)
				(type default)
			)
			(fill no)
			(layer "F.CrtYd")
		)
		(fp_rect
			(start -1.3716 1.6764)
			(end 1.3716 -1.6764)
			(stroke
				(width 0)
				(type default)
			)
			(fill no)
			(layer "F.Fab")
		)
		(pad "1" smd rect
			(at 0.50038 -0.73025)
			(size 0.7112 0.8636)
			(layers "F.Cu" "F.Mask" "F.Paste")
			(net "DRV_ACT_15")
		)
		(pad "2" smd rect
			(at -0.50038 -0.73025)
			(size 0.7112 0.8636)
			(layers "F.Cu" "F.Mask" "F.Paste")
			(net "FLT_HDD15")
		)
		(pad "3" smd rect
			(at 0.50038 0.73025)
			(size 0.7112 0.8636)
			(layers "F.Cu" "F.Mask" "F.Paste")
			(net "DRV_ACT_15_N")
		)
		(pad "4" smd rect
			(at -0.50038 0.73025)
			(size 0.7112 0.8636)
			(layers "F.Cu" "F.Mask" "F.Paste")
			(net "FLT_HDD15_N")
		)
	)
	(footprint ""
		(layer "F.Cu")
		(at 426.755052 -42.585894)
		(property "Reference" "R901"
			(at 0 0 0)
			(layer "F.SilkS")
			(hide yes)
			(effects
				(font
					(size 1.27 1.27)
				)
			)
		)
		(property "Value" "4K7R2J-2-GP"
			(at 0.064008 -3.993896 0)
			(unlocked yes)
			(layer "F.Fab")
			(hide yes)
			(effects
				(font
					(size 1.016 1.016)
					(thickness 0.1524)
				)
			)
		)
		(property "Device Type" "R402H16"
			(at 0.064008 -5.517896 0)
			(unlocked yes)
			(layer "F.Fab")
			(hide yes)
			(effects
				(font
					(size 1.016 1.016)
					(thickness 0.1524)
				)
			)
		)
		(duplicate_pad_numbers_are_jumpers no)
		(fp_line
			(start -0.508 -0.9398)
			(end -0.508 0.9398)
			(stroke
				(width 0.1524)
				(type default)
			)
			(layer "F.SilkS")
		)
		(fp_line
			(start 0.508 -0.9398)
			(end -0.508 -0.9398)
			(stroke
				(width 0.1524)
				(type default)
			)
			(layer "F.SilkS")
		)
		(fp_rect
			(start -0.508 0.9398)
			(end 0.508 -0.9398)
			(stroke
				(width 0)
				(type default)
			)
			(fill no)
			(layer "F.CrtYd")
		)
		(fp_rect
			(start -0.508 0.9398)
			(end 0.508 -0.9398)
			(stroke
				(width 0)
				(type default)
			)
			(fill no)
			(layer "F.Fab")
		)
		(pad "1" smd custom
			(at 0 -0.4445)
			(size 0.1397 0.1397)
			(layers "F.Cu" "F.Mask" "F.Paste")
			(net "SW_PWR_R_HDD33")
			(options
				(clearance outline)
				(anchor circle)
			)
			(primitives
				(gr_poly
					(pts
						(arc
							(start -0.1778 -0.2794)
							(mid -0.249642 -0.249642)
							(end -0.2794 -0.1778)
						)
						(arc
							(start -0.2794 0.1778)
							(mid -0.249642 0.249642)
							(end -0.1778 0.2794)
						)
						(arc
							(start 0.1778 0.2794)
							(mid 0.249642 0.249642)
							(end 0.2794 0.1778)
						)
						(arc
							(start 0.2794 -0.1778)
							(mid 0.249642 -0.249642)
							(end 0.1778 -0.2794)
						)
					)
					(width 0)
					(fill yes)
				)
			)
		)
		(pad "2" smd custom
			(at 0 0.4445)
			(size 0.1397 0.1397)
			(layers "F.Cu" "F.Mask" "F.Paste")
			(net "GND")
			(options
				(clearance outline)
				(anchor circle)
			)
			(primitives
				(gr_poly
					(pts
						(arc
							(start -0.1778 -0.2794)
							(mid -0.249642 -0.249642)
							(end -0.2794 -0.1778)
						)
						(arc
							(start -0.2794 0.1778)
							(mid -0.249642 0.249642)
							(end -0.1778 0.2794)
						)
						(arc
							(start 0.1778 0.2794)
							(mid 0.249642 0.249642)
							(end 0.2794 0.1778)
						)
						(arc
							(start 0.2794 -0.1778)
							(mid 0.249642 -0.249642)
							(end 0.1778 -0.2794)
						)
					)
					(width 0)
					(fill yes)
				)
			)
		)
	)
	(footprint ""
		(layer "F.Cu")
		(at 149.932898 -62.270894)
		(property "Reference" "R773"
			(at 0 0 0)
			(layer "F.SilkS")
			(hide yes)
			(effects
				(font
					(size 1.27 1.27)
				)
			)
		)
		(property "Value" "2R6F-GP"
			(at -0.0508 -4.8514 0)
			(unlocked yes)
			(layer "F.Fab")
			(hide yes)
			(effects
				(font
					(size 1.016 1.016)
					(thickness 0.1524)
				)
			)
		)
		(property "Device Type" "R1206H26"
			(at 0 -6.3754 0)
			(unlocked yes)
			(layer "F.Fab")
			(hide yes)
			(effects
				(font
					(size 1.016 1.016)
					(thickness 0.1524)
				)
			)
		)
		(duplicate_pad_numbers_are_jumpers no)
		(fp_line
			(start -1.016 -2.2352)
			(end 1.016 -2.2352)
			(stroke
				(width 0.1524)
				(type default)
			)
			(layer "F.SilkS")
		)
		(fp_line
			(start -1.016 2.2352)
			(end -1.016 -2.2352)
			(stroke
				(width 0.1524)
				(type default)
			)
			(layer "F.SilkS")
		)
		(fp_line
			(start 1.016 -2.2352)
			(end 1.016 2.2352)
			(stroke
				(width 0.1524)
				(type default)
			)
			(layer "F.SilkS")
		)
		(fp_line
			(start 1.016 2.2352)
			(end -1.016 2.2352)
			(stroke
				(width 0.1524)
				(type default)
			)
			(layer "F.SilkS")
		)
		(fp_rect
			(start -1.0922 2.3114)
			(end 1.0922 -2.3114)
			(stroke
				(width 0)
				(type default)
			)
			(fill no)
			(layer "F.CrtYd")
		)
		(fp_poly
			(pts
				(xy -1.0922 -2.3114) (xy 1.0922 -2.3114) (xy 1.0922 2.3114) (xy -1.0922 2.3114)
			)
			(stroke
				(width 0)
				(type default)
			)
			(fill no)
			(layer "F.Fab")
		)
		(pad "1" smd rect
			(at 0 -1.397)
			(size 1.651 1.27)
			(layers "F.Cu" "F.Mask" "F.Paste")
			(net "P5V_HDD28")
		)
		(pad "2" smd rect
			(at 0 1.397)
			(size 1.651 1.27)
			(layers "F.Cu" "F.Mask" "F.Paste")
			(net "5V_PRE_28")
		)
	)
	(footprint ""
		(layer "F.Cu")
		(at 336.174334 -21.45157)
		(property "Reference" "R66"
			(at 0 0 0)
			(layer "F.SilkS")
			(hide yes)
			(effects
				(font
					(size 1.27 1.27)
				)
			)
		)
		(property "Value" "4K7R2F-GP"
			(at 0.064008 -3.993896 0)
			(unlocked yes)
			(layer "F.Fab")
			(hide yes)
			(effects
				(font
					(size 1.016 1.016)
					(thickness 0.1524)
				)
			)
		)
		(property "Device Type" "R402H16"
			(at 0.064008 -5.517896 0)
			(unlocked yes)
			(layer "F.Fab")
			(hide yes)
			(effects
				(font
					(size 1.016 1.016)
					(thickness 0.1524)
				)
			)
		)
		(duplicate_pad_numbers_are_jumpers no)
		(fp_line
			(start -0.508 -0.9398)
			(end -0.508 0.9398)
			(stroke
				(width 0.1524)
				(type default)
			)
			(layer "F.SilkS")
		)
		(fp_line
			(start 0.508 -0.9398)
			(end -0.508 -0.9398)
			(stroke
				(width 0.1524)
				(type default)
			)
			(layer "F.SilkS")
		)
		(fp_rect
			(start -0.508 0.9398)
			(end 0.508 -0.9398)
			(stroke
				(width 0)
				(type default)
			)
			(fill no)
			(layer "F.CrtYd")
		)
		(fp_rect
			(start -0.508 0.9398)
			(end 0.508 -0.9398)
			(stroke
				(width 0)
				(type default)
			)
			(fill no)
			(layer "F.Fab")
		)
		(pad "1" smd custom
			(at 0 -0.4445)
			(size 0.1397 0.1397)
			(layers "F.Cu" "F.Mask" "F.Paste")
			(net "IO_EXP11_A2")
			(options
				(clearance outline)
				(anchor circle)
			)
			(primitives
				(gr_poly
					(pts
						(arc
							(start -0.1778 -0.2794)
							(mid -0.249642 -0.249642)
							(end -0.2794 -0.1778)
						)
						(arc
							(start -0.2794 0.1778)
							(mid -0.249642 0.249642)
							(end -0.1778 0.2794)
						)
						(arc
							(start 0.1778 0.2794)
							(mid 0.249642 0.249642)
							(end 0.2794 0.1778)
						)
						(arc
							(start 0.2794 -0.1778)
							(mid 0.249642 -0.249642)
							(end 0.1778 -0.2794)
						)
					)
					(width 0)
					(fill yes)
				)
			)
		)
		(pad "2" smd custom
			(at 0 0.4445)
			(size 0.1397 0.1397)
			(layers "F.Cu" "F.Mask" "F.Paste")
			(net "GND")
			(options
				(clearance outline)
				(anchor circle)
			)
			(primitives
				(gr_poly
					(pts
						(arc
							(start -0.1778 -0.2794)
							(mid -0.249642 -0.249642)
							(end -0.2794 -0.1778)
						)
						(arc
							(start -0.2794 0.1778)
							(mid -0.249642 0.249642)
							(end -0.1778 0.2794)
						)
						(arc
							(start 0.1778 0.2794)
							(mid 0.249642 0.249642)
							(end 0.2794 0.1778)
						)
						(arc
							(start 0.2794 -0.1778)
							(mid 0.249642 -0.249642)
							(end 0.1778 -0.2794)
						)
					)
					(width 0)
					(fill yes)
				)
			)
		)
	)
	(footprint ""
		(layer "F.Cu")
		(at 468.761318 -41.52265 180)
		(property "Reference" "R943"
			(at 0 0 180)
			(layer "F.SilkS")
			(hide yes)
			(effects
				(font
					(size 1.27 1.27)
				)
			)
		)
		(property "Value" "1KR2F-3-GP"
			(at 0.064008 -3.993896 180)
			(unlocked yes)
			(layer "F.Fab")
			(hide yes)
			(effects
				(font
					(size 1.016 1.016)
					(thickness 0.1524)
				)
			)
		)
		(property "Device Type" "R402H16"
			(at 0.064008 -5.517896 180)
			(unlocked yes)
			(layer "F.Fab")
			(hide yes)
			(effects
				(font
					(size 1.016 1.016)
					(thickness 0.1524)
				)
			)
		)
		(duplicate_pad_numbers_are_jumpers no)
		(fp_line
			(start 0.508 -0.9398)
			(end -0.508 -0.9398)
			(stroke
				(width 0.1524)
				(type default)
			)
			(layer "F.SilkS")
		)
		(fp_line
			(start -0.508 -0.9398)
			(end -0.508 0.9398)
			(stroke
				(width 0.1524)
				(type default)
			)
			(layer "F.SilkS")
		)
		(fp_rect
			(start -0.508 0.9398)
			(end 0.508 -0.9398)
			(stroke
				(width 0)
				(type default)
			)
			(fill no)
			(layer "F.CrtYd")
		)
		(fp_rect
			(start -0.508 0.9398)
			(end 0.508 -0.9398)
			(stroke
				(width 0)
				(type default)
			)
			(fill no)
			(layer "F.Fab")
		)
		(pad "1" smd custom
			(at 0 -0.4445 180)
			(size 0.1397 0.1397)
			(layers "F.Cu" "F.Mask" "F.Paste")
			(net "P3V3_STBY_A")
			(options
				(clearance outline)
				(anchor circle)
			)
			(primitives
				(gr_poly
					(pts
						(arc
							(start -0.1778 -0.2794)
							(mid -0.249642 -0.249642)
							(end -0.2794 -0.1778)
						)
						(arc
							(start -0.2794 0.1778)
							(mid -0.249642 0.249642)
							(end -0.1778 0.2794)
						)
						(arc
							(start 0.1778 0.2794)
							(mid 0.249642 0.249642)
							(end 0.2794 0.1778)
						)
						(arc
							(start 0.2794 -0.1778)
							(mid 0.249642 -0.249642)
							(end 0.1778 -0.2794)
						)
					)
					(width 0)
					(fill yes)
				)
			)
		)
		(pad "2" smd custom
			(at 0 0.4445 180)
			(size 0.1397 0.1397)
			(layers "F.Cu" "F.Mask" "F.Paste")
			(net "SW_PWR_R_HDD35")
			(options
				(clearance outline)
				(anchor circle)
			)
			(primitives
				(gr_poly
					(pts
						(arc
							(start -0.1778 -0.2794)
							(mid -0.249642 -0.249642)
							(end -0.2794 -0.1778)
						)
						(arc
							(start -0.2794 0.1778)
							(mid -0.249642 0.249642)
							(end -0.1778 0.2794)
						)
						(arc
							(start 0.1778 0.2794)
							(mid 0.249642 0.249642)
							(end 0.2794 0.1778)
						)
						(arc
							(start 0.2794 -0.1778)
							(mid 0.249642 -0.249642)
							(end 0.1778 -0.2794)
						)
					)
					(width 0)
					(fill yes)
				)
			)
		)
	)
	(footprint ""
		(layer "F.Cu")
		(at 35.797998 -61.127894 90)
		(property "Reference" "C358"
			(at 0 0 90)
			(layer "F.SilkS")
			(hide yes)
			(effects
				(font
					(size 1.27 1.27)
				)
			)
		)
		(property "Value" "SCD01U50V2KX-1GP"
			(at 1.1811 -2.7051 90)
			(unlocked yes)
			(layer "F.Fab")
			(hide yes)
			(effects
				(font
					(size 1.016 1.016)
					(thickness 0.1524)
				)
			)
		)
		(property "Device Type" "C402H22"
			(at 1.1811 -4.2291 90)
			(unlocked yes)
			(layer "F.Fab")
			(hide yes)
			(effects
				(font
					(size 1.016 1.016)
					(thickness 0.1524)
				)
			)
		)
		(duplicate_pad_numbers_are_jumpers no)
		(fp_rect
			(start -0.4318 0.9525)
			(end 0.4318 -0.9525)
			(stroke
				(width 0)
				(type default)
			)
			(fill no)
			(layer "F.CrtYd")
		)
		(fp_rect
			(start -0.4318 0.9525)
			(end 0.4318 -0.9525)
			(stroke
				(width 0)
				(type default)
			)
			(fill no)
			(layer "F.Fab")
		)
		(pad "1" smd custom
			(at 0 -0.4445 90)
			(size 0.1524 0.1524)
			(layers "F.Cu" "F.Mask" "F.Paste")
			(net "HDD_PRSNT_24")
			(options
				(clearance outline)
				(anchor circle)
			)
			(primitives
				(gr_poly
					(pts
						(arc
							(start 0.3048 -0.2032)
							(mid 0.275042 -0.275042)
							(end 0.2032 -0.3048)
						)
						(arc
							(start -0.2032 -0.3048)
							(mid -0.275042 -0.275042)
							(end -0.3048 -0.2032)
						)
						(arc
							(start -0.3048 0.2032)
							(mid -0.275042 0.275042)
							(end -0.2032 0.3048)
						)
						(arc
							(start 0.2032 0.3048)
							(mid 0.275042 0.275042)
							(end 0.3048 0.2032)
						)
					)
					(width 0)
					(fill yes)
				)
			)
		)
		(pad "2" smd custom
			(at 0 0.4445 90)
			(size 0.1524 0.1524)
			(layers "F.Cu" "F.Mask" "F.Paste")
			(net "GND")
			(options
				(clearance outline)
				(anchor circle)
			)
			(primitives
				(gr_poly
					(pts
						(arc
							(start 0.3048 -0.2032)
							(mid 0.275042 -0.275042)
							(end 0.2032 -0.3048)
						)
						(arc
							(start -0.2032 -0.3048)
							(mid -0.275042 -0.275042)
							(end -0.3048 -0.2032)
						)
						(arc
							(start -0.3048 0.2032)
							(mid -0.275042 0.275042)
							(end -0.2032 0.3048)
						)
						(arc
							(start 0.2032 0.3048)
							(mid 0.275042 0.275042)
							(end 0.3048 0.2032)
						)
					)
					(width 0)
					(fill yes)
				)
			)
		)
	)
	(footprint ""
		(layer "F.Cu")
		(at 470.097358 -288.357056)
		(property "Reference" "Q68"
			(at 0 0 0)
			(layer "F.SilkS")
			(hide yes)
			(effects
				(font
					(size 1.27 1.27)
				)
			)
		)
		(property "Value" "AO4407AL-GP"
			(at -3.707384 -1.5367 0)
			(unlocked yes)
			(layer "F.Fab")
			(hide yes)
			(effects
				(font
					(size 1.016 1.016)
					(thickness 0.1524)
				)
			)
		)
		(property "Device Type" "SOIC8H69"
			(at -3.707384 -3.0607 0)
			(unlocked yes)
			(layer "F.Fab")
			(hide yes)
			(effects
				(font
					(size 1.016 1.016)
					(thickness 0.1524)
				)
			)
		)
		(duplicate_pad_numbers_are_jumpers no)
		(fp_line
			(start -2.7432 -1.4224)
			(end -2.7432 1.4224)
			(stroke
				(width 0.1524)
				(type default)
			)
			(layer "F.SilkS")
		)
		(fp_line
			(start -2.7432 1.4224)
			(end -2.6416 1.4224)
			(stroke
				(width 0.1524)
				(type default)
			)
			(layer "F.SilkS")
		)
		(fp_line
			(start -2.7432 1.4224)
			(end 2.1336 1.4224)
			(stroke
				(width 0.1524)
				(type default)
			)
			(layer "F.SilkS")
		)
		(fp_line
			(start -2.7178 -0.508)
			(end -2.1844 -0.0508)
			(stroke
				(width 0.1524)
				(type default)
			)
			(layer "F.SilkS")
		)
		(fp_line
			(start -2.6289 3.4417)
			(end -2.6289 1.4732)
			(stroke
				(width 0.381)
				(type default)
			)
			(layer "F.SilkS")
		)
		(fp_line
			(start -2.1844 -0.0508)
			(end -2.7178 0.508)
			(stroke
				(width 0.1524)
				(type default)
			)
			(layer "F.SilkS")
		)
		(fp_line
			(start 2.1336 -1.4224)
			(end -2.7432 -1.4224)
			(stroke
				(width 0.1524)
				(type default)
			)
			(layer "F.SilkS")
		)
		(fp_line
			(start 2.1336 1.4224)
			(end 2.1336 -1.4224)
			(stroke
				(width 0.1524)
				(type default)
			)
			(layer "F.SilkS")
		)
		(fp_poly
			(pts
				(xy -2.2098 -1.4224) (xy -2.2098 1.4224) (xy 2.2098 1.4224) (xy 2.2098 -1.4224)
			)
			(stroke
				(width 0)
				(type default)
			)
			(fill yes)
			(layer "F.SilkS")
		)
		(fp_rect
			(start -2.450084 2.999994)
			(end 2.450084 -2.999994)
			(stroke
				(width 0)
				(type default)
			)
			(fill no)
			(layer "F.CrtYd")
		)
		(fp_poly
			(pts
				(xy -2.8194 3.6322) (xy -2.8194 -3.6322) (xy 2.8194 -3.6322) (xy 2.8194 1.18364) (xy 2.450084 1.18364)
				(xy 2.450084 -2.999994) (xy -2.450084 -2.999994) (xy -2.450084 2.999994) (xy 2.450084 2.999994)
				(xy 2.450084 1.18618) (xy 2.8194 1.18618) (xy 2.8194 3.6322)
			)
			(stroke
				(width 0)
				(type default)
			)
			(fill no)
			(layer "F.CrtYd")
		)
		(fp_rect
			(start -2.8194 3.6322)
			(end 2.8194 -3.6322)
			(stroke
				(width 0)
				(type default)
			)
			(fill no)
			(layer "F.Fab")
		)
		(pad "1" smd rect
			(at -1.905 2.54)
			(size 0.635 1.651)
			(layers "F.Cu" "F.Mask" "F.Paste")
			(net "P12V_A")
		)
		(pad "2" smd rect
			(at -0.635 2.54)
			(size 0.635 1.651)
			(layers "F.Cu" "F.Mask" "F.Paste")
			(net "P12V_A")
		)
		(pad "3" smd rect
			(at 0.635 2.54)
			(size 0.635 1.651)
			(layers "F.Cu" "F.Mask" "F.Paste")
			(net "P12V_A")
		)
		(pad "4" smd rect
			(at 1.905 2.54)
			(size 0.635 1.651)
			(layers "F.Cu" "F.Mask" "F.Paste")
			(net "SW_HDD_N11")
		)
		(pad "5" smd rect
			(at 1.905 -2.54)
			(size 0.635 1.651)
			(layers "F.Cu" "F.Mask" "F.Paste")
			(net "P12V_HDD11")
		)
		(pad "6" smd rect
			(at 0.635 -2.54)
			(size 0.635 1.651)
			(layers "F.Cu" "F.Mask" "F.Paste")
			(net "P12V_HDD11")
		)
		(pad "7" smd rect
			(at -0.635 -2.54)
			(size 0.635 1.651)
			(layers "F.Cu" "F.Mask" "F.Paste")
			(net "P12V_HDD11")
		)
		(pad "8" smd rect
			(at -1.905 -2.54)
			(size 0.635 1.651)
			(layers "F.Cu" "F.Mask" "F.Paste")
			(net "P12V_HDD11")
		)
	)
	(footprint ""
		(layer "F.Cu")
		(at 353.184714 -274.219416 -90)
		(property "Reference" "C129"
			(at 0 0 270)
			(layer "F.SilkS")
			(hide yes)
			(effects
				(font
					(size 1.27 1.27)
				)
			)
		)
		(property "Value" "SCD01U16V1KX-GP"
			(at -2.8321 -1.7399 270)
			(unlocked yes)
			(layer "F.Fab")
			(hide yes)
			(effects
				(font
					(size 1.016 1.016)
					(thickness 0.1524)
				)
			)
		)
		(property "Device Type" "C0201H13"
			(at -2.8321 -3.2639 270)
			(unlocked yes)
			(layer "F.Fab")
			(hide yes)
			(effects
				(font
					(size 1.016 1.016)
					(thickness 0.1524)
				)
			)
		)
		(duplicate_pad_numbers_are_jumpers no)
		(fp_rect
			(start -0.2794 0.6477)
			(end 0.2794 -0.6477)
			(stroke
				(width 0)
				(type default)
			)
			(fill no)
			(layer "F.CrtYd")
		)
		(fp_rect
			(start -0.2794 0.6477)
			(end 0.2794 -0.6477)
			(stroke
				(width 0)
				(type default)
			)
			(fill no)
			(layer "F.Fab")
		)
		(pad "1" smd custom
			(at 0 -0.2794 270)
			(size 0.0762 0.0762)
			(layers "F.Cu" "F.Mask" "F.Paste")
			(net "SAS_HDD_RX_N7")
			(options
				(clearance outline)
				(anchor circle)
			)
			(primitives
				(gr_poly
					(pts
						(arc
							(start 0.1524 -0.127)
							(mid 0.137521 -0.162921)
							(end 0.1016 -0.1778)
						)
						(arc
							(start -0.1016 -0.1778)
							(mid -0.137521 -0.162921)
							(end -0.1524 -0.127)
						)
						(arc
							(start -0.1524 0.127)
							(mid -0.137521 0.162921)
							(end -0.1016 0.1778)
						)
						(arc
							(start 0.1016 0.1778)
							(mid 0.137521 0.162921)
							(end 0.1524 0.127)
						)
					)
					(width 0)
					(fill yes)
				)
			)
		)
		(pad "2" smd custom
			(at 0 0.2794 270)
			(size 0.0762 0.0762)
			(layers "F.Cu" "F.Mask" "F.Paste")
			(net "PHY_SCC_A_TO_DRV_A_7_DN")
			(options
				(clearance outline)
				(anchor circle)
			)
			(primitives
				(gr_poly
					(pts
						(arc
							(start 0.1524 -0.127)
							(mid 0.137521 -0.162921)
							(end 0.1016 -0.1778)
						)
						(arc
							(start -0.1016 -0.1778)
							(mid -0.137521 -0.162921)
							(end -0.1524 -0.127)
						)
						(arc
							(start -0.1524 0.127)
							(mid -0.137521 0.162921)
							(end -0.1016 0.1778)
						)
						(arc
							(start 0.1016 0.1778)
							(mid 0.137521 0.162921)
							(end 0.1524 0.127)
						)
					)
					(width 0)
					(fill yes)
				)
			)
		)
	)
	(footprint ""
		(layer "F.Cu")
		(at 349.939102 -65.064894 -90)
		(property "Reference" "R847"
			(at 0 0 270)
			(layer "F.SilkS")
			(hide yes)
			(effects
				(font
					(size 1.27 1.27)
				)
			)
		)
		(property "Value" "220R3F-1-GP"
			(at -0.0254 -2.5146 270)
			(unlocked yes)
			(layer "F.Fab")
			(hide yes)
			(effects
				(font
					(size 1.016 1.016)
					(thickness 0.1524)
				)
			)
		)
		(property "Device Type" "R603H22"
			(at -0.0254 -4.0386 270)
			(unlocked yes)
			(layer "F.Fab")
			(hide yes)
			(effects
				(font
					(size 1.016 1.016)
					(thickness 0.1524)
				)
			)
		)
		(duplicate_pad_numbers_are_jumpers no)
		(fp_line
			(start -0.4826 0)
			(end -0.2032 0)
			(stroke
				(width 0.2032)
				(type default)
			)
			(layer "F.SilkS")
		)
		(fp_line
			(start 0.2032 0)
			(end 0.4826 0)
			(stroke
				(width 0.2032)
				(type default)
			)
			(layer "F.SilkS")
		)
		(fp_rect
			(start -0.5842 1.3335)
			(end 0.5842 -1.3335)
			(stroke
				(width 0)
				(type default)
			)
			(fill no)
			(layer "F.CrtYd")
		)
		(fp_rect
			(start -0.5842 1.3335)
			(end 0.5842 -1.3335)
			(stroke
				(width 0)
				(type default)
			)
			(fill no)
			(layer "F.Fab")
		)
		(pad "1" smd custom
			(at 0 -0.762 270)
			(size 0.2159 0.2159)
			(layers "F.Cu" "F.Mask" "F.Paste")
			(net "HDD_PRSNT_31")
			(options
				(clearance outline)
				(anchor circle)
			)
			(primitives
				(gr_poly
					(pts
						(arc
							(start -0.3302 -0.4318)
							(mid -0.402042 -0.402042)
							(end -0.4318 -0.3302)
						)
						(arc
							(start -0.4318 0.3302)
							(mid -0.402042 0.402042)
							(end -0.3302 0.4318)
						)
						(arc
							(start 0.3302 0.4318)
							(mid 0.402042 0.402042)
							(end 0.4318 0.3302)
						)
						(arc
							(start 0.4318 -0.3302)
							(mid 0.402042 -0.402042)
							(end 0.3302 -0.4318)
						)
					)
					(width 0)
					(fill yes)
				)
			)
		)
		(pad "2" smd custom
			(at 0 0.762 270)
			(size 0.2159 0.2159)
			(layers "F.Cu" "F.Mask" "F.Paste")
			(net "DRIVE_A_31_INS")
			(options
				(clearance outline)
				(anchor circle)
			)
			(primitives
				(gr_poly
					(pts
						(arc
							(start -0.3302 -0.4318)
							(mid -0.402042 -0.402042)
							(end -0.4318 -0.3302)
						)
						(arc
							(start -0.4318 0.3302)
							(mid -0.402042 0.402042)
							(end -0.3302 0.4318)
						)
						(arc
							(start 0.3302 0.4318)
							(mid 0.402042 0.402042)
							(end 0.4318 0.3302)
						)
						(arc
							(start 0.4318 -0.3302)
							(mid 0.402042 -0.402042)
							(end 0.3302 -0.4318)
						)
					)
					(width 0)
					(fill yes)
				)
			)
		)
	)
	(footprint ""
		(layer "F.Cu")
		(at 352.3488 -146.4564)
		(property "Reference" "R1096"
			(at 0 0 0)
			(layer "F.SilkS")
			(hide yes)
			(effects
				(font
					(size 1.27 1.27)
				)
			)
		)
		(property "Value" "D001FRL3115F-L-GP"
			(at 3.2766 1.3843 0)
			(unlocked yes)
			(layer "F.Fab")
			(hide yes)
			(effects
				(font
					(size 1.016 1.016)
					(thickness 0.1524)
				)
			)
		)
		(property "Device Type" "RL3115-4PH25"
			(at 3.2766 -0.1397 0)
			(unlocked yes)
			(layer "F.Fab")
			(hide yes)
			(effects
				(font
					(size 1.016 1.016)
					(thickness 0.1524)
				)
			)
		)
		(duplicate_pad_numbers_are_jumpers no)
		(fp_line
			(start -2.0828 -1.778)
			(end -2.0828 -0.4445)
			(stroke
				(width 0.3302)
				(type default)
			)
			(layer "F.SilkS")
		)
		(fp_line
			(start -1.9685 -1.651)
			(end 1.9685 -1.651)
			(stroke
				(width 0.1524)
				(type default)
			)
			(layer "F.SilkS")
		)
		(fp_line
			(start -1.9685 1.651)
			(end -1.9685 -1.651)
			(stroke
				(width 0.1524)
				(type default)
			)
			(layer "F.SilkS")
		)
		(fp_line
			(start -0.5461 -1.778)
			(end -2.0828 -1.778)
			(stroke
				(width 0.3302)
				(type default)
			)
			(layer "F.SilkS")
		)
		(fp_line
			(start 1.9685 -1.651)
			(end 1.9685 1.651)
			(stroke
				(width 0.1524)
				(type default)
			)
			(layer "F.SilkS")
		)
		(fp_line
			(start 1.9685 1.651)
			(end -1.9685 1.651)
			(stroke
				(width 0.1524)
				(type default)
			)
			(layer "F.SilkS")
		)
		(fp_poly
			(pts
				(xy -0.561594 -1.726946) (xy -0.053594 -2.234946) (xy -1.069594 -2.234946)
			)
			(stroke
				(width 0)
				(type default)
			)
			(fill yes)
			(layer "F.SilkS")
		)
		(fp_rect
			(start -1.524 0.7493)
			(end 1.524 -0.7493)
			(stroke
				(width 0)
				(type default)
			)
			(fill no)
			(layer "F.CrtYd")
		)
		(fp_poly
			(pts
				(xy -2.2225 1.905) (xy -2.2225 -1.905) (xy 2.2225 -1.905) (xy 2.2225 -0.7493) (xy -1.524 -0.7493)
				(xy -1.524 0.7493) (xy 1.524 0.7493) (xy 1.524 -0.7366) (xy 2.2225 -0.7366) (xy 2.2225 1.905)
			)
			(stroke
				(width 0)
				(type default)
			)
			(fill no)
			(layer "F.CrtYd")
		)
		(fp_rect
			(start -2.2225 1.905)
			(end 2.2225 -1.905)
			(stroke
				(width 0)
				(type default)
			)
			(fill no)
			(layer "F.Fab")
		)
		(pad "1" smd rect
			(at -0.5715 -0.813562)
			(size 2.286 1.143)
			(layers "F.Cu" "F.Mask" "F.Paste")
			(net "P12V_B")
		)
		(pad "2" smd rect
			(at -0.5715 0.813562)
			(size 2.286 1.143)
			(layers "F.Cu" "F.Mask" "F.Paste")
			(net "MB1_P12V_B_R")
		)
		(pad "3" smd rect
			(at 1.334008 -0.813562)
			(size 0.762 1.143)
			(layers "F.Cu" "F.Mask" "F.Paste")
			(net "MB1_CM_SENSE_R1_P")
		)
		(pad "4" smd rect
			(at 1.334008 0.813562)
			(size 0.762 1.143)
			(layers "F.Cu" "F.Mask" "F.Paste")
			(net "MB1_CM_SENSE_R1_N")
		)
		(zone
			(layer "F.Cu")
			(hatch none 0.5)
			(connect_pads
				(clearance 0)
			)
			(min_thickness 0.25)
			(keepout
				(tracks allowed)
				(vias not_allowed)
				(pads allowed)
				(copperpour not_allowed)
				(footprints allowed)
			)
			(placement
				(enabled no)
				(sheetname "")
			)
			(fill
				(thermal_gap 0.5)
				(thermal_bridge_width 0.5)
				(island_removal_mode 0)
			)
			(polygon
				(pts
					(xy 352.9203 -146.698462) (xy 353.301808 -146.698462) (xy 353.301808 -147.2057) (xy 352.9203 -147.2057)
				)
			)
		)
		(zone
			(layer "F.Cu")
			(hatch none 0.5)
			(connect_pads
				(clearance 0)
			)
			(min_thickness 0.25)
			(keepout
				(tracks not_allowed)
				(vias allowed)
				(pads allowed)
				(copperpour not_allowed)
				(footprints allowed)
			)
			(placement
				(enabled no)
				(sheetname "")
			)
			(fill
				(thermal_gap 0.5)
				(thermal_bridge_width 0.5)
				(island_removal_mode 0)
			)
			(polygon
				(pts
					(xy 352.9203 -146.698462) (xy 353.301808 -146.698462) (xy 353.301808 -147.2057) (xy 352.9203 -147.2057)
				)
			)
		)
		(zone
			(layer "F.Cu")
			(hatch none 0.5)
			(connect_pads
				(clearance 0)
			)
			(min_thickness 0.25)
			(keepout
				(tracks allowed)
				(vias not_allowed)
				(pads allowed)
				(copperpour not_allowed)
				(footprints allowed)
			)
			(placement
				(enabled no)
				(sheetname "")
			)
			(fill
				(thermal_gap 0.5)
				(thermal_bridge_width 0.5)
				(island_removal_mode 0)
			)
			(polygon
				(pts
					(xy 352.9203 -145.7071) (xy 353.301808 -145.7071) (xy 353.301808 -146.214338) (xy 352.9203 -146.214338)
				)
			)
		)
		(zone
			(layer "F.Cu")
			(hatch none 0.5)
			(connect_pads
				(clearance 0)
			)
			(min_thickness 0.25)
			(keepout
				(tracks not_allowed)
				(vias allowed)
				(pads allowed)
				(copperpour not_allowed)
				(footprints allowed)
			)
			(placement
				(enabled no)
				(sheetname "")
			)
			(fill
				(thermal_gap 0.5)
				(thermal_bridge_width 0.5)
				(island_removal_mode 0)
			)
			(polygon
				(pts
					(xy 352.9203 -145.7071) (xy 353.301808 -145.7071) (xy 353.301808 -146.214338) (xy 352.9203 -146.214338)
				)
			)
		)
	)
	(footprint ""
		(layer "F.Cu")
		(at 402.72335 -276.192742 90)
		(property "Reference" "D8"
			(at 0 0 90)
			(layer "F.SilkS")
			(hide yes)
			(effects
				(font
					(size 1.27 1.27)
				)
			)
		)
		(property "Value" "RB551V30-GP"
			(at 0 -6.7818 90)
			(unlocked yes)
			(layer "F.Fab")
			(hide yes)
			(effects
				(font
					(size 1.016 1.016)
					(thickness 0.1524)
				)
			)
		)
		(property "Device Type" "SOD323AKH38"
			(at 0 -8.6868 90)
			(unlocked yes)
			(layer "F.Fab")
			(hide yes)
			(effects
				(font
					(size 1.016 1.016)
					(thickness 0.1524)
				)
			)
		)
		(duplicate_pad_numbers_are_jumpers no)
		(fp_line
			(start 0.889 -1.9304)
			(end 0.889 2.159)
			(stroke
				(width 0.1524)
				(type default)
			)
			(layer "F.SilkS")
		)
		(fp_line
			(start -0.889 -1.9304)
			(end 0.889 -1.9304)
			(stroke
				(width 0.1524)
				(type default)
			)
			(layer "F.SilkS")
		)
		(fp_line
			(start 0.762 2.0574)
			(end -0.762 2.0574)
			(stroke
				(width 0.508)
				(type default)
			)
			(layer "F.SilkS")
		)
		(fp_line
			(start 0.889 2.159)
			(end -0.889 2.159)
			(stroke
				(width 0.1524)
				(type default)
			)
			(layer "F.SilkS")
		)
		(fp_line
			(start -0.889 2.159)
			(end -0.889 -1.9304)
			(stroke
				(width 0.1524)
				(type default)
			)
			(layer "F.SilkS")
		)
		(fp_rect
			(start -1.016 2.3114)
			(end 1.016 -2.0066)
			(stroke
				(width 0)
				(type default)
			)
			(fill no)
			(layer "F.CrtYd")
		)
		(fp_poly
			(pts
				(xy -1.016 -2.0066) (xy 1.016 -2.0066) (xy 1.016 2.3114) (xy -1.016 2.3114)
			)
			(stroke
				(width 0)
				(type default)
			)
			(fill no)
			(layer "F.Fab")
		)
		(pad "A" smd rect
			(at 0 -1.143 90)
			(size 0.5588 1.016)
			(layers "F.Cu" "F.Mask" "F.Paste")
			(net "SW_HDD_R8")
		)
		(pad "K" smd rect
			(at 0 1.143 90)
			(size 0.5588 1.016)
			(layers "F.Cu" "F.Mask" "F.Paste")
			(net "SW_HDD_N8")
		)
	)
	(footprint ""
		(layer "F.Cu")
		(at 441.484512 -158.660592 -90)
		(property "Reference" "C325"
			(at 0 0 270)
			(layer "F.SilkS")
			(hide yes)
			(effects
				(font
					(size 1.27 1.27)
				)
			)
		)
		(property "Value" "SCD01U16V1KX-GP"
			(at -2.8321 -1.7399 270)
			(unlocked yes)
			(layer "F.Fab")
			(hide yes)
			(effects
				(font
					(size 1.016 1.016)
					(thickness 0.1524)
				)
			)
		)
		(property "Device Type" "C0201H13"
			(at -2.8321 -3.2639 270)
			(unlocked yes)
			(layer "F.Fab")
			(hide yes)
			(effects
				(font
					(size 1.016 1.016)
					(thickness 0.1524)
				)
			)
		)
		(duplicate_pad_numbers_are_jumpers no)
		(fp_rect
			(start -0.2794 0.6477)
			(end 0.2794 -0.6477)
			(stroke
				(width 0)
				(type default)
			)
			(fill no)
			(layer "F.CrtYd")
		)
		(fp_rect
			(start -0.2794 0.6477)
			(end 0.2794 -0.6477)
			(stroke
				(width 0)
				(type default)
			)
			(fill no)
			(layer "F.Fab")
		)
		(pad "1" smd custom
			(at 0 -0.2794 270)
			(size 0.0762 0.0762)
			(layers "F.Cu" "F.Mask" "F.Paste")
			(net "SAS_HDD_RX_P22")
			(options
				(clearance outline)
				(anchor circle)
			)
			(primitives
				(gr_poly
					(pts
						(arc
							(start 0.1524 -0.127)
							(mid 0.137521 -0.162921)
							(end 0.1016 -0.1778)
						)
						(arc
							(start -0.1016 -0.1778)
							(mid -0.137521 -0.162921)
							(end -0.1524 -0.127)
						)
						(arc
							(start -0.1524 0.127)
							(mid -0.137521 0.162921)
							(end -0.1016 0.1778)
						)
						(arc
							(start 0.1016 0.1778)
							(mid 0.137521 0.162921)
							(end 0.1524 0.127)
						)
					)
					(width 0)
					(fill yes)
				)
			)
		)
		(pad "2" smd custom
			(at 0 0.2794 270)
			(size 0.0762 0.0762)
			(layers "F.Cu" "F.Mask" "F.Paste")
			(net "PHY_SCC_A_TO_DRV_A_22_DP")
			(options
				(clearance outline)
				(anchor circle)
			)
			(primitives
				(gr_poly
					(pts
						(arc
							(start 0.1524 -0.127)
							(mid 0.137521 -0.162921)
							(end 0.1016 -0.1778)
						)
						(arc
							(start -0.1016 -0.1778)
							(mid -0.137521 -0.162921)
							(end -0.1524 -0.127)
						)
						(arc
							(start -0.1524 0.127)
							(mid -0.137521 0.162921)
							(end -0.1016 0.1778)
						)
						(arc
							(start 0.1016 0.1778)
							(mid 0.137521 0.162921)
							(end 0.1524 0.127)
						)
					)
					(width 0)
					(fill yes)
				)
			)
		)
	)
	(footprint ""
		(layer "F.Cu")
		(at 335.788 -160.735518 180)
		(property "Reference" "R561"
			(at 0 0 180)
			(layer "F.SilkS")
			(hide yes)
			(effects
				(font
					(size 1.27 1.27)
				)
			)
		)
		(property "Value" "0R2J-2-GP"
			(at 0.064008 -3.993896 180)
			(unlocked yes)
			(layer "F.Fab")
			(hide yes)
			(effects
				(font
					(size 1.016 1.016)
					(thickness 0.1524)
				)
			)
		)
		(property "Device Type" "R402H16"
			(at 0.064008 -5.517896 180)
			(unlocked yes)
			(layer "F.Fab")
			(hide yes)
			(effects
				(font
					(size 1.016 1.016)
					(thickness 0.1524)
				)
			)
		)
		(duplicate_pad_numbers_are_jumpers no)
		(fp_line
			(start 0.508 -0.9398)
			(end -0.508 -0.9398)
			(stroke
				(width 0.1524)
				(type default)
			)
			(layer "F.SilkS")
		)
		(fp_line
			(start -0.508 -0.9398)
			(end -0.508 0.9398)
			(stroke
				(width 0.1524)
				(type default)
			)
			(layer "F.SilkS")
		)
		(fp_rect
			(start -0.508 0.9398)
			(end 0.508 -0.9398)
			(stroke
				(width 0)
				(type default)
			)
			(fill no)
			(layer "F.CrtYd")
		)
		(fp_rect
			(start -0.508 0.9398)
			(end 0.508 -0.9398)
			(stroke
				(width 0)
				(type default)
			)
			(fill no)
			(layer "F.Fab")
		)
		(pad "1" smd custom
			(at 0 -0.4445 180)
			(size 0.1397 0.1397)
			(layers "F.Cu" "F.Mask" "F.Paste")
			(net "SW_HDD_G18")
			(options
				(clearance outline)
				(anchor circle)
			)
			(primitives
				(gr_poly
					(pts
						(arc
							(start -0.1778 -0.2794)
							(mid -0.249642 -0.249642)
							(end -0.2794 -0.1778)
						)
						(arc
							(start -0.2794 0.1778)
							(mid -0.249642 0.249642)
							(end -0.1778 0.2794)
						)
						(arc
							(start 0.1778 0.2794)
							(mid 0.249642 0.249642)
							(end 0.2794 0.1778)
						)
						(arc
							(start 0.2794 -0.1778)
							(mid 0.249642 -0.249642)
							(end 0.1778 -0.2794)
						)
					)
					(width 0)
					(fill yes)
				)
			)
		)
		(pad "2" smd custom
			(at 0 0.4445 180)
			(size 0.1397 0.1397)
			(layers "F.Cu" "F.Mask" "F.Paste")
			(net "SW_HDD_R18")
			(options
				(clearance outline)
				(anchor circle)
			)
			(primitives
				(gr_poly
					(pts
						(arc
							(start -0.1778 -0.2794)
							(mid -0.249642 -0.249642)
							(end -0.2794 -0.1778)
						)
						(arc
							(start -0.2794 0.1778)
							(mid -0.249642 0.249642)
							(end -0.1778 0.2794)
						)
						(arc
							(start 0.1778 0.2794)
							(mid 0.249642 0.249642)
							(end 0.2794 0.1778)
						)
						(arc
							(start 0.2794 -0.1778)
							(mid 0.249642 -0.249642)
							(end 0.1778 -0.2794)
						)
					)
					(width 0)
					(fill yes)
				)
			)
		)
	)
	(footprint ""
		(layer "F.Cu")
		(at 339.759036 -33.550352)
		(property "Reference" "R92"
			(at 0 0 0)
			(layer "F.SilkS")
			(hide yes)
			(effects
				(font
					(size 1.27 1.27)
				)
			)
		)
		(property "Value" "4K7R2F-GP"
			(at 0.064008 -3.993896 0)
			(unlocked yes)
			(layer "F.Fab")
			(hide yes)
			(effects
				(font
					(size 1.016 1.016)
					(thickness 0.1524)
				)
			)
		)
		(property "Device Type" "R402H16"
			(at 0.064008 -5.517896 0)
			(unlocked yes)
			(layer "F.Fab")
			(hide yes)
			(effects
				(font
					(size 1.016 1.016)
					(thickness 0.1524)
				)
			)
		)
		(duplicate_pad_numbers_are_jumpers no)
		(fp_line
			(start -0.508 -0.9398)
			(end -0.508 0.9398)
			(stroke
				(width 0.1524)
				(type default)
			)
			(layer "F.SilkS")
		)
		(fp_line
			(start 0.508 -0.9398)
			(end -0.508 -0.9398)
			(stroke
				(width 0.1524)
				(type default)
			)
			(layer "F.SilkS")
		)
		(fp_rect
			(start -0.508 0.9398)
			(end 0.508 -0.9398)
			(stroke
				(width 0)
				(type default)
			)
			(fill no)
			(layer "F.CrtYd")
		)
		(fp_rect
			(start -0.508 0.9398)
			(end 0.508 -0.9398)
			(stroke
				(width 0)
				(type default)
			)
			(fill no)
			(layer "F.Fab")
		)
		(pad "1" smd custom
			(at 0 -0.4445)
			(size 0.1397 0.1397)
			(layers "F.Cu" "F.Mask" "F.Paste")
			(net "P3V3_STBY_B")
			(options
				(clearance outline)
				(anchor circle)
			)
			(primitives
				(gr_poly
					(pts
						(arc
							(start -0.1778 -0.2794)
							(mid -0.249642 -0.249642)
							(end -0.2794 -0.1778)
						)
						(arc
							(start -0.2794 0.1778)
							(mid -0.249642 0.249642)
							(end -0.1778 0.2794)
						)
						(arc
							(start 0.1778 0.2794)
							(mid 0.249642 0.249642)
							(end 0.2794 0.1778)
						)
						(arc
							(start 0.2794 -0.1778)
							(mid 0.249642 -0.249642)
							(end 0.1778 -0.2794)
						)
					)
					(width 0)
					(fill yes)
				)
			)
		)
		(pad "2" smd custom
			(at 0 0.4445)
			(size 0.1397 0.1397)
			(layers "F.Cu" "F.Mask" "F.Paste")
			(net "IO_EXP11_A0")
			(options
				(clearance outline)
				(anchor circle)
			)
			(primitives
				(gr_poly
					(pts
						(arc
							(start -0.1778 -0.2794)
							(mid -0.249642 -0.249642)
							(end -0.2794 -0.1778)
						)
						(arc
							(start -0.2794 0.1778)
							(mid -0.249642 0.249642)
							(end -0.1778 0.2794)
						)
						(arc
							(start 0.1778 0.2794)
							(mid 0.249642 0.249642)
							(end 0.2794 0.1778)
						)
						(arc
							(start 0.2794 -0.1778)
							(mid 0.249642 -0.249642)
							(end 0.1778 -0.2794)
						)
					)
					(width 0)
					(fill yes)
				)
			)
		)
	)
	(footprint ""
		(layer "F.Cu")
		(at 473.593668 -293.892732)
		(property "Reference" "Q299"
			(at 0 0 0)
			(layer "F.SilkS")
			(hide yes)
			(effects
				(font
					(size 1.27 1.27)
				)
			)
		)
		(property "Value" "SSM3K324R-GP"
			(at 0.127 -8.9662 0)
			(unlocked yes)
			(layer "F.Fab")
			(hide yes)
			(effects
				(font
					(size 1.016 1.016)
					(thickness 0.1524)
				)
			)
		)
		(property "Device Type" "SOT23DGS2D4H35"
			(at 0.127 -10.4902 0)
			(unlocked yes)
			(layer "F.Fab")
			(hide yes)
			(effects
				(font
					(size 1.016 1.016)
					(thickness 0.1524)
				)
			)
		)
		(duplicate_pad_numbers_are_jumpers no)
		(fp_line
			(start -1.651 -1.778)
			(end -1.651 1.778)
			(stroke
				(width 0.1524)
				(type default)
			)
			(layer "F.SilkS")
		)
		(fp_line
			(start -1.651 1.778)
			(end 1.651 1.778)
			(stroke
				(width 0.1524)
				(type default)
			)
			(layer "F.SilkS")
		)
		(fp_line
			(start 1.651 -1.778)
			(end -1.651 -1.778)
			(stroke
				(width 0.1524)
				(type default)
			)
			(layer "F.SilkS")
		)
		(fp_line
			(start 1.651 1.778)
			(end 1.651 -1.778)
			(stroke
				(width 0.1524)
				(type default)
			)
			(layer "F.SilkS")
		)
		(fp_poly
			(pts
				(xy -1.778 1.8796) (xy -1.778 -1.8796) (xy 1.778 -1.8796) (xy 1.778 1.8796)
			)
			(stroke
				(width 0)
				(type default)
			)
			(fill no)
			(layer "F.CrtYd")
		)
		(fp_poly
			(pts
				(xy -1.778 1.8796) (xy -1.778 -1.8796) (xy 1.778 -1.8796) (xy 1.778 1.8796)
			)
			(stroke
				(width 0)
				(type default)
			)
			(fill no)
			(layer "F.Fab")
		)
		(pad "D" smd custom
			(at 0 -0.9525)
			(size 0.1905 0.1905)
			(layers "F.Cu" "F.Mask" "F.Paste")
			(net "DRV_ACT_35_N")
			(options
				(clearance outline)
				(anchor circle)
			)
			(primitives
				(gr_poly
					(pts
						(arc
							(start -0.1778 0.5715)
							(mid -0.321484 0.511984)
							(end -0.381 0.3683)
						)
						(arc
							(start -0.381 -0.3683)
							(mid -0.321484 -0.511984)
							(end -0.1778 -0.5715)
						)
						(arc
							(start 0.1778 -0.5715)
							(mid 0.321484 -0.511984)
							(end 0.381 -0.3683)
						)
						(arc
							(start 0.381 0.3683)
							(mid 0.321484 0.511984)
							(end 0.1778 0.5715)
						)
					)
					(width 0)
					(fill yes)
				)
			)
		)
		(pad "G" smd custom
			(at -0.98425 0.9525)
			(size 0.1905 0.1905)
			(layers "F.Cu" "F.Mask" "F.Paste")
			(net "DRIVE_B_35_ACT")
			(options
				(clearance outline)
				(anchor circle)
			)
			(primitives
				(gr_poly
					(pts
						(arc
							(start -0.1778 0.5715)
							(mid -0.321484 0.511984)
							(end -0.381 0.3683)
						)
						(arc
							(start -0.381 -0.3683)
							(mid -0.321484 -0.511984)
							(end -0.1778 -0.5715)
						)
						(arc
							(start 0.1778 -0.5715)
							(mid 0.321484 -0.511984)
							(end 0.381 -0.3683)
						)
						(arc
							(start 0.381 0.3683)
							(mid 0.321484 0.511984)
							(end 0.1778 0.5715)
						)
					)
					(width 0)
					(fill yes)
				)
			)
		)
		(pad "S" smd custom
			(at 0.98425 0.9525)
			(size 0.1905 0.1905)
			(layers "F.Cu" "F.Mask" "F.Paste")
			(net "GND")
			(options
				(clearance outline)
				(anchor circle)
			)
			(primitives
				(gr_poly
					(pts
						(arc
							(start -0.1778 0.5715)
							(mid -0.321484 0.511984)
							(end -0.381 0.3683)
						)
						(arc
							(start -0.381 -0.3683)
							(mid -0.321484 -0.511984)
							(end -0.1778 -0.5715)
						)
						(arc
							(start 0.1778 -0.5715)
							(mid 0.321484 -0.511984)
							(end 0.381 -0.3683)
						)
						(arc
							(start 0.381 0.3683)
							(mid 0.321484 0.511984)
							(end 0.1778 0.5715)
						)
					)
					(width 0)
					(fill yes)
				)
			)
		)
	)
	(footprint ""
		(layer "F.Cu")
		(at 136.367266 -142.628874 -90)
		(property "Reference" "R1046"
			(at 0 0 270)
			(layer "F.SilkS")
			(hide yes)
			(effects
				(font
					(size 1.27 1.27)
				)
			)
		)
		(property "Value" "0R0603-PAD-2-GP-U"
			(at 2.1209 -0.1397 270)
			(unlocked yes)
			(layer "F.Fab")
			(hide yes)
			(effects
				(font
					(size 1.016 1.016)
					(thickness 0.1524)
				)
			)
		)
		(property "Device Type" "0R0603-PAD-1-U"
			(at 2.1209 -1.6637 270)
			(unlocked yes)
			(layer "F.Fab")
			(hide yes)
			(effects
				(font
					(size 1.016 1.016)
					(thickness 0.1524)
				)
			)
		)
		(duplicate_pad_numbers_are_jumpers no)
		(fp_rect
			(start -0.5842 1.3335)
			(end 0.5842 -1.3335)
			(stroke
				(width 0)
				(type default)
			)
			(fill no)
			(layer "F.CrtYd")
		)
		(fp_rect
			(start -0.5842 1.3335)
			(end 0.5842 -1.3335)
			(stroke
				(width 0)
				(type default)
			)
			(fill no)
			(layer "F.Fab")
		)
		(pad "1" smd custom
			(at 0 -0.762 270)
			(size 0.2159 0.2159)
			(layers "F.Cu" "F.Mask" "F.Paste")
			(net "AGND_CURRENT_MONOA")
			(options
				(clearance outline)
				(anchor circle)
			)
			(primitives
				(gr_poly
					(pts
						(arc
							(start -0.3302 -0.5842)
							(mid -0.402042 -0.554442)
							(end -0.4318 -0.4826)
						)
						(arc
							(start -0.4318 0.4826)
							(mid -0.402042 0.554442)
							(end -0.3302 0.5842)
						)
						(arc
							(start 0.3302 0.5842)
							(mid 0.402042 0.554442)
							(end 0.4318 0.4826)
						)
						(arc
							(start 0.4318 -0.4826)
							(mid 0.402042 -0.554442)
							(end 0.3302 -0.5842)
						)
					)
					(width 0)
					(fill yes)
				)
			)
		)
		(pad "2" smd custom
			(at 0 0.762 270)
			(size 0.2159 0.2159)
			(layers "F.Cu" "F.Mask" "F.Paste")
			(net "GND")
			(options
				(clearance outline)
				(anchor circle)
			)
			(primitives
				(gr_poly
					(pts
						(arc
							(start -0.4318 0.4826)
							(mid -0.402042 0.554442)
							(end -0.3302 0.5842)
						)
						(arc
							(start 0.3302 0.5842)
							(mid 0.402042 0.554442)
							(end 0.4318 0.4826)
						)
						(arc
							(start 0.4318 -0.4826)
							(mid 0.402042 -0.554442)
							(end 0.3302 -0.5842)
						)
						(arc
							(start -0.3302 -0.5842)
							(mid -0.402042 -0.554442)
							(end -0.4318 -0.4826)
						)
					)
					(width 0)
					(fill yes)
				)
			)
		)
	)
	(footprint ""
		(layer "F.Cu")
		(at 463.0039 -177.016918)
		(property "Reference" "Q134"
			(at 0 0 0)
			(layer "F.SilkS")
			(hide yes)
			(effects
				(font
					(size 1.27 1.27)
				)
			)
		)
		(property "Value" "AO4407AL-GP"
			(at -3.707384 -1.5367 0)
			(unlocked yes)
			(layer "F.Fab")
			(hide yes)
			(effects
				(font
					(size 1.016 1.016)
					(thickness 0.1524)
				)
			)
		)
		(property "Device Type" "SOIC8H69"
			(at -3.707384 -3.0607 0)
			(unlocked yes)
			(layer "F.Fab")
			(hide yes)
			(effects
				(font
					(size 1.016 1.016)
					(thickness 0.1524)
				)
			)
		)
		(duplicate_pad_numbers_are_jumpers no)
		(fp_line
			(start -2.7432 -1.4224)
			(end -2.7432 1.4224)
			(stroke
				(width 0.1524)
				(type default)
			)
			(layer "F.SilkS")
		)
		(fp_line
			(start -2.7432 1.4224)
			(end -2.6416 1.4224)
			(stroke
				(width 0.1524)
				(type default)
			)
			(layer "F.SilkS")
		)
		(fp_line
			(start -2.7432 1.4224)
			(end 2.1336 1.4224)
			(stroke
				(width 0.1524)
				(type default)
			)
			(layer "F.SilkS")
		)
		(fp_line
			(start -2.7178 -0.508)
			(end -2.1844 -0.0508)
			(stroke
				(width 0.1524)
				(type default)
			)
			(layer "F.SilkS")
		)
		(fp_line
			(start -2.6289 3.4417)
			(end -2.6289 1.4732)
			(stroke
				(width 0.381)
				(type default)
			)
			(layer "F.SilkS")
		)
		(fp_line
			(start -2.1844 -0.0508)
			(end -2.7178 0.508)
			(stroke
				(width 0.1524)
				(type default)
			)
			(layer "F.SilkS")
		)
		(fp_line
			(start 2.1336 -1.4224)
			(end -2.7432 -1.4224)
			(stroke
				(width 0.1524)
				(type default)
			)
			(layer "F.SilkS")
		)
		(fp_line
			(start 2.1336 1.4224)
			(end 2.1336 -1.4224)
			(stroke
				(width 0.1524)
				(type default)
			)
			(layer "F.SilkS")
		)
		(fp_poly
			(pts
				(xy -2.2098 -1.4224) (xy -2.2098 1.4224) (xy 2.2098 1.4224) (xy 2.2098 -1.4224)
			)
			(stroke
				(width 0)
				(type default)
			)
			(fill yes)
			(layer "F.SilkS")
		)
		(fp_rect
			(start -2.450084 2.999994)
			(end 2.450084 -2.999994)
			(stroke
				(width 0)
				(type default)
			)
			(fill no)
			(layer "F.CrtYd")
		)
		(fp_poly
			(pts
				(xy -2.8194 3.6322) (xy -2.8194 -3.6322) (xy 2.8194 -3.6322) (xy 2.8194 1.18364) (xy 2.450084 1.18364)
				(xy 2.450084 -2.999994) (xy -2.450084 -2.999994) (xy -2.450084 2.999994) (xy 2.450084 2.999994)
				(xy 2.450084 1.18618) (xy 2.8194 1.18618) (xy 2.8194 3.6322)
			)
			(stroke
				(width 0)
				(type default)
			)
			(fill no)
			(layer "F.CrtYd")
		)
		(fp_rect
			(start -2.8194 3.6322)
			(end 2.8194 -3.6322)
			(stroke
				(width 0)
				(type default)
			)
			(fill no)
			(layer "F.Fab")
		)
		(pad "1" smd rect
			(at -1.905 2.54)
			(size 0.635 1.651)
			(layers "F.Cu" "F.Mask" "F.Paste")
			(net "P12V_A")
		)
		(pad "2" smd rect
			(at -0.635 2.54)
			(size 0.635 1.651)
			(layers "F.Cu" "F.Mask" "F.Paste")
			(net "P12V_A")
		)
		(pad "3" smd rect
			(at 0.635 2.54)
			(size 0.635 1.651)
			(layers "F.Cu" "F.Mask" "F.Paste")
			(net "P12V_A")
		)
		(pad "4" smd rect
			(at 1.905 2.54)
			(size 0.635 1.651)
			(layers "F.Cu" "F.Mask" "F.Paste")
			(net "SW_HDD_N22")
		)
		(pad "5" smd rect
			(at 1.905 -2.54)
			(size 0.635 1.651)
			(layers "F.Cu" "F.Mask" "F.Paste")
			(net "P12V_HDD22")
		)
		(pad "6" smd rect
			(at 0.635 -2.54)
			(size 0.635 1.651)
			(layers "F.Cu" "F.Mask" "F.Paste")
			(net "P12V_HDD22")
		)
		(pad "7" smd rect
			(at -0.635 -2.54)
			(size 0.635 1.651)
			(layers "F.Cu" "F.Mask" "F.Paste")
			(net "P12V_HDD22")
		)
		(pad "8" smd rect
			(at -1.905 -2.54)
			(size 0.635 1.651)
			(layers "F.Cu" "F.Mask" "F.Paste")
			(net "P12V_HDD22")
		)
	)
	(footprint ""
		(layer "F.Cu")
		(at 469.747854 -127.756666 180)
		(property "Reference" "Q250"
			(at 0 0 180)
			(layer "F.SilkS")
			(hide yes)
			(effects
				(font
					(size 1.27 1.27)
				)
			)
		)
		(property "Value" "2N7002K-2-GP"
			(at 0.127 -8.9662 180)
			(unlocked yes)
			(layer "F.Fab")
			(hide yes)
			(effects
				(font
					(size 1.016 1.016)
					(thickness 0.1524)
				)
			)
		)
		(property "Device Type" "SOT23DGS2D4H44"
			(at 0.127 -10.4902 180)
			(unlocked yes)
			(layer "F.Fab")
			(hide yes)
			(effects
				(font
					(size 1.016 1.016)
					(thickness 0.1524)
				)
			)
		)
		(duplicate_pad_numbers_are_jumpers no)
		(fp_line
			(start 1.651 1.778)
			(end 1.651 -1.778)
			(stroke
				(width 0.1524)
				(type default)
			)
			(layer "F.SilkS")
		)
		(fp_line
			(start 1.651 -1.778)
			(end -1.651 -1.778)
			(stroke
				(width 0.1524)
				(type default)
			)
			(layer "F.SilkS")
		)
		(fp_line
			(start -1.651 1.778)
			(end 1.651 1.778)
			(stroke
				(width 0.1524)
				(type default)
			)
			(layer "F.SilkS")
		)
		(fp_line
			(start -1.651 -1.778)
			(end -1.651 1.778)
			(stroke
				(width 0.1524)
				(type default)
			)
			(layer "F.SilkS")
		)
		(fp_poly
			(pts
				(xy -1.778 1.8796) (xy -1.778 -1.8796) (xy 1.778 -1.8796) (xy 1.778 1.8796)
			)
			(stroke
				(width 0)
				(type default)
			)
			(fill no)
			(layer "F.CrtYd")
		)
		(fp_poly
			(pts
				(xy -1.778 1.8796) (xy -1.778 -1.8796) (xy 1.778 -1.8796) (xy 1.778 1.8796)
			)
			(stroke
				(width 0)
				(type default)
			)
			(fill no)
			(layer "F.Fab")
		)
		(pad "D" smd custom
			(at 0 -0.9525 180)
			(size 0.1905 0.1905)
			(layers "F.Cu" "F.Mask" "F.Paste")
			(net "FLT_HDD23_N")
			(options
				(clearance outline)
				(anchor circle)
			)
			(primitives
				(gr_poly
					(pts
						(arc
							(start -0.1778 0.5715)
							(mid -0.321484 0.511984)
							(end -0.381 0.3683)
						)
						(arc
							(start -0.381 -0.3683)
							(mid -0.321484 -0.511984)
							(end -0.1778 -0.5715)
						)
						(arc
							(start 0.1778 -0.5715)
							(mid 0.321484 -0.511984)
							(end 0.381 -0.3683)
						)
						(arc
							(start 0.381 0.3683)
							(mid 0.321484 0.511984)
							(end 0.1778 0.5715)
						)
					)
					(width 0)
					(fill yes)
				)
			)
		)
		(pad "G" smd custom
			(at -0.98425 0.9525 180)
			(size 0.1905 0.1905)
			(layers "F.Cu" "F.Mask" "F.Paste")
			(net "DRIVE_A_23_FLT_LED")
			(options
				(clearance outline)
				(anchor circle)
			)
			(primitives
				(gr_poly
					(pts
						(arc
							(start -0.1778 0.5715)
							(mid -0.321484 0.511984)
							(end -0.381 0.3683)
						)
						(arc
							(start -0.381 -0.3683)
							(mid -0.321484 -0.511984)
							(end -0.1778 -0.5715)
						)
						(arc
							(start 0.1778 -0.5715)
							(mid 0.321484 -0.511984)
							(end 0.381 -0.3683)
						)
						(arc
							(start 0.381 0.3683)
							(mid 0.321484 0.511984)
							(end 0.1778 0.5715)
						)
					)
					(width 0)
					(fill yes)
				)
			)
		)
		(pad "S" smd custom
			(at 0.98425 0.9525 180)
			(size 0.1905 0.1905)
			(layers "F.Cu" "F.Mask" "F.Paste")
			(net "GND")
			(options
				(clearance outline)
				(anchor circle)
			)
			(primitives
				(gr_poly
					(pts
						(arc
							(start -0.1778 0.5715)
							(mid -0.321484 0.511984)
							(end -0.381 0.3683)
						)
						(arc
							(start -0.381 -0.3683)
							(mid -0.321484 -0.511984)
							(end -0.1778 -0.5715)
						)
						(arc
							(start 0.1778 -0.5715)
							(mid 0.321484 -0.511984)
							(end 0.381 -0.3683)
						)
						(arc
							(start 0.381 0.3683)
							(mid 0.321484 0.511984)
							(end 0.1778 0.5715)
						)
					)
					(width 0)
					(fill yes)
				)
			)
		)
	)
	(footprint ""
		(layer "F.Cu")
		(at 255.411478 -12.667234 180)
		(property "Reference" "TP219"
			(at 0 0 180)
			(layer "F.SilkS")
			(hide yes)
			(effects
				(font
					(size 1.27 1.27)
				)
			)
		)
		(property "Value" "TPAD32-GP"
			(at -0.0508 -1.6764 180)
			(unlocked yes)
			(layer "F.Fab")
			(hide yes)
			(effects
				(font
					(size 1.016 1.016)
					(thickness 0.1524)
				)
			)
		)
		(property "Device Type" "TPAD32"
			(at -0.0508 -3.2004 180)
			(unlocked yes)
			(layer "F.Fab")
			(hide yes)
			(effects
				(font
					(size 1.016 1.016)
					(thickness 0.1524)
				)
			)
		)
		(duplicate_pad_numbers_are_jumpers no)
		(fp_poly
			(pts
				(arc
					(start -0.4064 0)
					(mid 0.4064 0)
					(end -0.4064 0)
				)
			)
			(stroke
				(width 0)
				(type default)
			)
			(fill no)
			(layer "F.CrtYd")
		)
		(fp_poly
			(pts
				(arc
					(start -0.7112 0)
					(mid 0.7112 0)
					(end -0.7112 0)
				)
			)
			(stroke
				(width 0)
				(type default)
			)
			(fill no)
			(layer "F.Fab")
		)
		(pad "1" smd circle
			(at 0 0 180)
			(size 0.8128 0.8128)
			(layers "F.Cu" "F.Mask" "F.Paste")
			(net "TP_COMP_A_NCSI_RXER")
		)
	)
	(footprint ""
		(layer "F.Cu")
		(at 458.9399 -48.554894 -90)
		(property "Reference" "R919"
			(at 0 0 270)
			(layer "F.SilkS")
			(hide yes)
			(effects
				(font
					(size 1.27 1.27)
				)
			)
		)
		(property "Value" "4K7R2J-2-GP"
			(at 0.064008 -3.993896 270)
			(unlocked yes)
			(layer "F.Fab")
			(hide yes)
			(effects
				(font
					(size 1.016 1.016)
					(thickness 0.1524)
				)
			)
		)
		(property "Device Type" "R402H16"
			(at 0.064008 -5.517896 270)
			(unlocked yes)
			(layer "F.Fab")
			(hide yes)
			(effects
				(font
					(size 1.016 1.016)
					(thickness 0.1524)
				)
			)
		)
		(duplicate_pad_numbers_are_jumpers no)
		(fp_line
			(start -0.508 -0.9398)
			(end -0.508 0.9398)
			(stroke
				(width 0.1524)
				(type default)
			)
			(layer "F.SilkS")
		)
		(fp_line
			(start 0.508 -0.9398)
			(end -0.508 -0.9398)
			(stroke
				(width 0.1524)
				(type default)
			)
			(layer "F.SilkS")
		)
		(fp_rect
			(start -0.508 0.9398)
			(end 0.508 -0.9398)
			(stroke
				(width 0)
				(type default)
			)
			(fill no)
			(layer "F.CrtYd")
		)
		(fp_rect
			(start -0.508 0.9398)
			(end 0.508 -0.9398)
			(stroke
				(width 0)
				(type default)
			)
			(fill no)
			(layer "F.Fab")
		)
		(pad "1" smd custom
			(at 0 -0.4445 270)
			(size 0.1397 0.1397)
			(layers "F.Cu" "F.Mask" "F.Paste")
			(net "P12V_A")
			(options
				(clearance outline)
				(anchor circle)
			)
			(primitives
				(gr_poly
					(pts
						(arc
							(start -0.1778 -0.2794)
							(mid -0.249642 -0.249642)
							(end -0.2794 -0.1778)
						)
						(arc
							(start -0.2794 0.1778)
							(mid -0.249642 0.249642)
							(end -0.1778 0.2794)
						)
						(arc
							(start 0.1778 0.2794)
							(mid 0.249642 0.249642)
							(end 0.2794 0.1778)
						)
						(arc
							(start 0.2794 -0.1778)
							(mid 0.249642 -0.249642)
							(end 0.1778 -0.2794)
						)
					)
					(width 0)
					(fill yes)
				)
			)
		)
		(pad "2" smd custom
			(at 0 0.4445 270)
			(size 0.1397 0.1397)
			(layers "F.Cu" "F.Mask" "F.Paste")
			(net "SW_HDD_P34")
			(options
				(clearance outline)
				(anchor circle)
			)
			(primitives
				(gr_poly
					(pts
						(arc
							(start -0.1778 -0.2794)
							(mid -0.249642 -0.249642)
							(end -0.2794 -0.1778)
						)
						(arc
							(start -0.2794 0.1778)
							(mid -0.249642 0.249642)
							(end -0.1778 0.2794)
						)
						(arc
							(start 0.1778 0.2794)
							(mid 0.249642 0.249642)
							(end 0.2794 0.1778)
						)
						(arc
							(start 0.2794 -0.1778)
							(mid 0.249642 -0.249642)
							(end 0.1778 -0.2794)
						)
					)
					(width 0)
					(fill yes)
				)
			)
		)
	)
	(footprint ""
		(layer "F.Cu")
		(at 272.321528 -16.425672 -90)
		(property "Reference" "TP249"
			(at 0 0 270)
			(layer "F.SilkS")
			(hide yes)
			(effects
				(font
					(size 1.27 1.27)
				)
			)
		)
		(property "Value" "TPAD32-GP"
			(at -0.0508 -1.6764 270)
			(unlocked yes)
			(layer "F.Fab")
			(hide yes)
			(effects
				(font
					(size 1.016 1.016)
					(thickness 0.1524)
				)
			)
		)
		(property "Device Type" "TPAD32"
			(at -0.0508 -3.2004 270)
			(unlocked yes)
			(layer "F.Fab")
			(hide yes)
			(effects
				(font
					(size 1.016 1.016)
					(thickness 0.1524)
				)
			)
		)
		(duplicate_pad_numbers_are_jumpers no)
		(fp_poly
			(pts
				(arc
					(start 0 -0.4064)
					(mid 0 0.4064)
					(end 0 -0.4064)
				)
			)
			(stroke
				(width 0)
				(type default)
			)
			(fill no)
			(layer "F.CrtYd")
		)
		(fp_poly
			(pts
				(arc
					(start 0 -0.7112)
					(mid 0 0.7112)
					(end 0 -0.7112)
				)
			)
			(stroke
				(width 0)
				(type default)
			)
			(fill no)
			(layer "F.Fab")
		)
		(pad "1" smd circle
			(at 0 0 270)
			(size 0.8128 0.8128)
			(layers "F.Cu" "F.Mask" "F.Paste")
			(net "PCIE_COMP_B_CLK_P5")
		)
	)
	(footprint ""
		(layer "F.Cu")
		(at 392.91895 -304.335942 180)
		(property "Reference" "C151"
			(at 0 0 180)
			(layer "F.SilkS")
			(hide yes)
			(effects
				(font
					(size 1.27 1.27)
				)
			)
		)
		(property "Value" "SC1U25V3KX-GP"
			(at 0 -2.8194 180)
			(unlocked yes)
			(layer "F.Fab")
			(hide yes)
			(effects
				(font
					(size 1.016 1.016)
					(thickness 0.1524)
				)
			)
		)
		(property "Device Type" "C603H36"
			(at 0 -4.3434 180)
			(unlocked yes)
			(layer "F.Fab")
			(hide yes)
			(effects
				(font
					(size 1.016 1.016)
					(thickness 0.1524)
				)
			)
		)
		(duplicate_pad_numbers_are_jumpers no)
		(fp_line
			(start 0.508 0)
			(end -0.508 0)
			(stroke
				(width 0.2032)
				(type default)
			)
			(layer "F.SilkS")
		)
		(fp_rect
			(start -0.5842 1.3335)
			(end 0.5842 -1.3335)
			(stroke
				(width 0)
				(type default)
			)
			(fill no)
			(layer "F.CrtYd")
		)
		(fp_rect
			(start -0.5842 1.3335)
			(end 0.5842 -1.3335)
			(stroke
				(width 0)
				(type default)
			)
			(fill no)
			(layer "F.Fab")
		)
		(pad "1" smd custom
			(at 0 -0.762 180)
			(size 0.2159 0.2159)
			(layers "F.Cu" "F.Mask" "F.Paste")
			(net "P12V_HDD8")
			(options
				(clearance outline)
				(anchor circle)
			)
			(primitives
				(gr_poly
					(pts
						(arc
							(start -0.3302 -0.4318)
							(mid -0.402042 -0.402042)
							(end -0.4318 -0.3302)
						)
						(arc
							(start -0.4318 0.3302)
							(mid -0.402042 0.402042)
							(end -0.3302 0.4318)
						)
						(arc
							(start 0.3302 0.4318)
							(mid 0.402042 0.402042)
							(end 0.4318 0.3302)
						)
						(arc
							(start 0.4318 -0.3302)
							(mid 0.402042 -0.402042)
							(end 0.3302 -0.4318)
						)
					)
					(width 0)
					(fill yes)
				)
			)
		)
		(pad "2" smd custom
			(at 0 0.762 180)
			(size 0.2159 0.2159)
			(layers "F.Cu" "F.Mask" "F.Paste")
			(net "GND")
			(options
				(clearance outline)
				(anchor circle)
			)
			(primitives
				(gr_poly
					(pts
						(arc
							(start -0.3302 -0.4318)
							(mid -0.402042 -0.402042)
							(end -0.4318 -0.3302)
						)
						(arc
							(start -0.4318 0.3302)
							(mid -0.402042 0.402042)
							(end -0.3302 0.4318)
						)
						(arc
							(start 0.3302 0.4318)
							(mid 0.402042 0.402042)
							(end 0.4318 0.3302)
						)
						(arc
							(start 0.4318 -0.3302)
							(mid 0.402042 -0.402042)
							(end 0.3302 -0.4318)
						)
					)
					(width 0)
					(fill yes)
				)
			)
		)
	)
	(footprint ""
		(layer "F.Cu")
		(at 337.312 -277.792942 90)
		(property "Reference" "D6"
			(at 0 0 90)
			(layer "F.SilkS")
			(hide yes)
			(effects
				(font
					(size 1.27 1.27)
				)
			)
		)
		(property "Value" "RB551V30-GP"
			(at 0 -6.7818 90)
			(unlocked yes)
			(layer "F.Fab")
			(hide yes)
			(effects
				(font
					(size 1.016 1.016)
					(thickness 0.1524)
				)
			)
		)
		(property "Device Type" "SOD323AKH38"
			(at 0 -8.6868 90)
			(unlocked yes)
			(layer "F.Fab")
			(hide yes)
			(effects
				(font
					(size 1.016 1.016)
					(thickness 0.1524)
				)
			)
		)
		(duplicate_pad_numbers_are_jumpers no)
		(fp_line
			(start 0.889 -1.9304)
			(end 0.889 2.159)
			(stroke
				(width 0.1524)
				(type default)
			)
			(layer "F.SilkS")
		)
		(fp_line
			(start -0.889 -1.9304)
			(end 0.889 -1.9304)
			(stroke
				(width 0.1524)
				(type default)
			)
			(layer "F.SilkS")
		)
		(fp_line
			(start 0.762 2.0574)
			(end -0.762 2.0574)
			(stroke
				(width 0.508)
				(type default)
			)
			(layer "F.SilkS")
		)
		(fp_line
			(start 0.889 2.159)
			(end -0.889 2.159)
			(stroke
				(width 0.1524)
				(type default)
			)
			(layer "F.SilkS")
		)
		(fp_line
			(start -0.889 2.159)
			(end -0.889 -1.9304)
			(stroke
				(width 0.1524)
				(type default)
			)
			(layer "F.SilkS")
		)
		(fp_rect
			(start -1.016 2.3114)
			(end 1.016 -2.0066)
			(stroke
				(width 0)
				(type default)
			)
			(fill no)
			(layer "F.CrtYd")
		)
		(fp_poly
			(pts
				(xy -1.016 -2.0066) (xy 1.016 -2.0066) (xy 1.016 2.3114) (xy -1.016 2.3114)
			)
			(stroke
				(width 0)
				(type default)
			)
			(fill no)
			(layer "F.Fab")
		)
		(pad "A" smd rect
			(at 0 -1.143 90)
			(size 0.5588 1.016)
			(layers "F.Cu" "F.Mask" "F.Paste")
			(net "SW_HDD_R6")
		)
		(pad "K" smd rect
			(at 0 1.143 90)
			(size 0.5588 1.016)
			(layers "F.Cu" "F.Mask" "F.Paste")
			(net "SW_HDD_N6")
		)
	)
	(footprint ""
		(layer "F.Cu")
		(at 259.8674 -243.2685)
		(property "Reference" "R94"
			(at 0 0 0)
			(layer "F.SilkS")
			(hide yes)
			(effects
				(font
					(size 1.27 1.27)
				)
			)
		)
		(property "Value" "4K7R2F-GP"
			(at 0.064008 -3.993896 0)
			(unlocked yes)
			(layer "F.Fab")
			(hide yes)
			(effects
				(font
					(size 1.016 1.016)
					(thickness 0.1524)
				)
			)
		)
		(property "Device Type" "R402H16"
			(at 0.064008 -5.517896 0)
			(unlocked yes)
			(layer "F.Fab")
			(hide yes)
			(effects
				(font
					(size 1.016 1.016)
					(thickness 0.1524)
				)
			)
		)
		(duplicate_pad_numbers_are_jumpers no)
		(fp_line
			(start -0.508 -0.9398)
			(end -0.508 0.9398)
			(stroke
				(width 0.1524)
				(type default)
			)
			(layer "F.SilkS")
		)
		(fp_line
			(start 0.508 -0.9398)
			(end -0.508 -0.9398)
			(stroke
				(width 0.1524)
				(type default)
			)
			(layer "F.SilkS")
		)
		(fp_rect
			(start -0.508 0.9398)
			(end 0.508 -0.9398)
			(stroke
				(width 0)
				(type default)
			)
			(fill no)
			(layer "F.CrtYd")
		)
		(fp_rect
			(start -0.508 0.9398)
			(end 0.508 -0.9398)
			(stroke
				(width 0)
				(type default)
			)
			(fill no)
			(layer "F.Fab")
		)
		(pad "1" smd custom
			(at 0 -0.4445)
			(size 0.1397 0.1397)
			(layers "F.Cu" "F.Mask" "F.Paste")
			(net "P3V3_STBY_A")
			(options
				(clearance outline)
				(anchor circle)
			)
			(primitives
				(gr_poly
					(pts
						(arc
							(start -0.1778 -0.2794)
							(mid -0.249642 -0.249642)
							(end -0.2794 -0.1778)
						)
						(arc
							(start -0.2794 0.1778)
							(mid -0.249642 0.249642)
							(end -0.1778 0.2794)
						)
						(arc
							(start 0.1778 0.2794)
							(mid 0.249642 0.249642)
							(end 0.2794 0.1778)
						)
						(arc
							(start 0.2794 -0.1778)
							(mid 0.249642 -0.249642)
							(end 0.1778 -0.2794)
						)
					)
					(width 0)
					(fill yes)
				)
			)
		)
		(pad "2" smd custom
			(at 0 0.4445)
			(size 0.1397 0.1397)
			(layers "F.Cu" "F.Mask" "F.Paste")
			(net "IO_EXP3_INT_N")
			(options
				(clearance outline)
				(anchor circle)
			)
			(primitives
				(gr_poly
					(pts
						(arc
							(start -0.1778 -0.2794)
							(mid -0.249642 -0.249642)
							(end -0.2794 -0.1778)
						)
						(arc
							(start -0.2794 0.1778)
							(mid -0.249642 0.249642)
							(end -0.1778 0.2794)
						)
						(arc
							(start 0.1778 0.2794)
							(mid 0.249642 0.249642)
							(end 0.2794 0.1778)
						)
						(arc
							(start 0.2794 -0.1778)
							(mid 0.249642 -0.249642)
							(end 0.1778 -0.2794)
						)
					)
					(width 0)
					(fill yes)
				)
			)
		)
	)
	(footprint ""
		(layer "F.Cu")
		(at 376.4534 -134.8486 90)
		(property "Reference" "R1082"
			(at 0 0 90)
			(layer "F.SilkS")
			(hide yes)
			(effects
				(font
					(size 1.27 1.27)
				)
			)
		)
		(property "Value" "0R2J-2-GP"
			(at 0.064008 -3.993896 90)
			(unlocked yes)
			(layer "F.Fab")
			(hide yes)
			(effects
				(font
					(size 1.016 1.016)
					(thickness 0.1524)
				)
			)
		)
		(property "Device Type" "R402H16"
			(at 0.064008 -5.517896 90)
			(unlocked yes)
			(layer "F.Fab")
			(hide yes)
			(effects
				(font
					(size 1.016 1.016)
					(thickness 0.1524)
				)
			)
		)
		(duplicate_pad_numbers_are_jumpers no)
		(fp_line
			(start 0.508 -0.9398)
			(end -0.508 -0.9398)
			(stroke
				(width 0.1524)
				(type default)
			)
			(layer "F.SilkS")
		)
		(fp_line
			(start -0.508 -0.9398)
			(end -0.508 0.9398)
			(stroke
				(width 0.1524)
				(type default)
			)
			(layer "F.SilkS")
		)
		(fp_rect
			(start -0.508 0.9398)
			(end 0.508 -0.9398)
			(stroke
				(width 0)
				(type default)
			)
			(fill no)
			(layer "F.CrtYd")
		)
		(fp_rect
			(start -0.508 0.9398)
			(end 0.508 -0.9398)
			(stroke
				(width 0)
				(type default)
			)
			(fill no)
			(layer "F.Fab")
		)
		(pad "1" smd custom
			(at 0 -0.4445 90)
			(size 0.1397 0.1397)
			(layers "F.Cu" "F.Mask" "F.Paste")
			(net "MB1_SPISS_PD")
			(options
				(clearance outline)
				(anchor circle)
			)
			(primitives
				(gr_poly
					(pts
						(arc
							(start -0.1778 -0.2794)
							(mid -0.249642 -0.249642)
							(end -0.2794 -0.1778)
						)
						(arc
							(start -0.2794 0.1778)
							(mid -0.249642 0.249642)
							(end -0.1778 0.2794)
						)
						(arc
							(start 0.1778 0.2794)
							(mid 0.249642 0.249642)
							(end 0.2794 0.1778)
						)
						(arc
							(start 0.2794 -0.1778)
							(mid 0.249642 -0.249642)
							(end 0.1778 -0.2794)
						)
					)
					(width 0)
					(fill yes)
				)
			)
		)
		(pad "2" smd custom
			(at 0 0.4445 90)
			(size 0.1397 0.1397)
			(layers "F.Cu" "F.Mask" "F.Paste")
			(net "AGND_CURRENT_MONOB")
			(options
				(clearance outline)
				(anchor circle)
			)
			(primitives
				(gr_poly
					(pts
						(arc
							(start -0.1778 -0.2794)
							(mid -0.249642 -0.249642)
							(end -0.2794 -0.1778)
						)
						(arc
							(start -0.2794 0.1778)
							(mid -0.249642 0.249642)
							(end -0.1778 0.2794)
						)
						(arc
							(start 0.1778 0.2794)
							(mid 0.249642 0.249642)
							(end 0.2794 0.1778)
						)
						(arc
							(start 0.2794 -0.1778)
							(mid 0.249642 -0.249642)
							(end 0.1778 -0.2794)
						)
					)
					(width 0)
					(fill yes)
				)
			)
		)
	)
	(footprint ""
		(layer "F.Cu")
		(at 317.627 -69.469)
		(property "Reference" "TP152"
			(at 0 0 0)
			(layer "F.SilkS")
			(hide yes)
			(effects
				(font
					(size 1.27 1.27)
				)
			)
		)
		(property "Value" "TPAD32-GP"
			(at -0.0508 -1.6764 0)
			(unlocked yes)
			(layer "F.Fab")
			(hide yes)
			(effects
				(font
					(size 1.016 1.016)
					(thickness 0.1524)
				)
			)
		)
		(property "Device Type" "TPAD32"
			(at -0.0508 -3.2004 0)
			(unlocked yes)
			(layer "F.Fab")
			(hide yes)
			(effects
				(font
					(size 1.016 1.016)
					(thickness 0.1524)
				)
			)
		)
		(duplicate_pad_numbers_are_jumpers no)
		(fp_poly
			(pts
				(arc
					(start 0.4064 0)
					(mid -0.4064 0)
					(end 0.4064 0)
				)
			)
			(stroke
				(width 0)
				(type default)
			)
			(fill no)
			(layer "F.CrtYd")
		)
		(fp_poly
			(pts
				(arc
					(start 0.7112 0)
					(mid -0.7112 0)
					(end 0.7112 0)
				)
			)
			(stroke
				(width 0)
				(type default)
			)
			(fill no)
			(layer "F.Fab")
		)
		(pad "1" smd circle
			(at 0 0)
			(size 0.8128 0.8128)
			(layers "F.Cu" "F.Mask" "F.Paste")
			(net "ACT_HDD_30")
		)
	)
	(footprint ""
		(layer "F.Cu")
		(at 22.996398 -163.554918 90)
		(property "Reference" "R419"
			(at 0 0 90)
			(layer "F.SilkS")
			(hide yes)
			(effects
				(font
					(size 1.27 1.27)
				)
			)
		)
		(property "Value" "4K7R2J-2-GP"
			(at 0.064008 -3.993896 90)
			(unlocked yes)
			(layer "F.Fab")
			(hide yes)
			(effects
				(font
					(size 1.016 1.016)
					(thickness 0.1524)
				)
			)
		)
		(property "Device Type" "R402H16"
			(at 0.064008 -5.517896 90)
			(unlocked yes)
			(layer "F.Fab")
			(hide yes)
			(effects
				(font
					(size 1.016 1.016)
					(thickness 0.1524)
				)
			)
		)
		(duplicate_pad_numbers_are_jumpers no)
		(fp_line
			(start 0.508 -0.9398)
			(end -0.508 -0.9398)
			(stroke
				(width 0.1524)
				(type default)
			)
			(layer "F.SilkS")
		)
		(fp_line
			(start -0.508 -0.9398)
			(end -0.508 0.9398)
			(stroke
				(width 0.1524)
				(type default)
			)
			(layer "F.SilkS")
		)
		(fp_rect
			(start -0.508 0.9398)
			(end 0.508 -0.9398)
			(stroke
				(width 0)
				(type default)
			)
			(fill no)
			(layer "F.CrtYd")
		)
		(fp_rect
			(start -0.508 0.9398)
			(end 0.508 -0.9398)
			(stroke
				(width 0)
				(type default)
			)
			(fill no)
			(layer "F.Fab")
		)
		(pad "1" smd custom
			(at 0 -0.4445 90)
			(size 0.1397 0.1397)
			(layers "F.Cu" "F.Mask" "F.Paste")
			(net "SW_PWR_R_HDD12")
			(options
				(clearance outline)
				(anchor circle)
			)
			(primitives
				(gr_poly
					(pts
						(arc
							(start -0.1778 -0.2794)
							(mid -0.249642 -0.249642)
							(end -0.2794 -0.1778)
						)
						(arc
							(start -0.2794 0.1778)
							(mid -0.249642 0.249642)
							(end -0.1778 0.2794)
						)
						(arc
							(start 0.1778 0.2794)
							(mid 0.249642 0.249642)
							(end 0.2794 0.1778)
						)
						(arc
							(start 0.2794 -0.1778)
							(mid 0.249642 -0.249642)
							(end 0.1778 -0.2794)
						)
					)
					(width 0)
					(fill yes)
				)
			)
		)
		(pad "2" smd custom
			(at 0 0.4445 90)
			(size 0.1397 0.1397)
			(layers "F.Cu" "F.Mask" "F.Paste")
			(net "GND")
			(options
				(clearance outline)
				(anchor circle)
			)
			(primitives
				(gr_poly
					(pts
						(arc
							(start -0.1778 -0.2794)
							(mid -0.249642 -0.249642)
							(end -0.2794 -0.1778)
						)
						(arc
							(start -0.2794 0.1778)
							(mid -0.249642 0.249642)
							(end -0.1778 0.2794)
						)
						(arc
							(start 0.1778 0.2794)
							(mid 0.249642 0.249642)
							(end 0.2794 0.1778)
						)
						(arc
							(start 0.2794 -0.1778)
							(mid 0.249642 -0.249642)
							(end 0.1778 -0.2794)
						)
					)
					(width 0)
					(fill yes)
				)
			)
		)
	)
	(footprint ""
		(layer "F.Cu")
		(at 346.700094 -94.400116)
		(property "Reference" "FLED20"
			(at 0 0 0)
			(layer "F.SilkS")
			(hide yes)
			(effects
				(font
					(size 1.27 1.27)
				)
			)
		)
		(property "Value" "LED-BY-19-GP"
			(at -2.132076 1.414018 0)
			(unlocked yes)
			(layer "F.Fab")
			(hide yes)
			(effects
				(font
					(size 1.016 1.016)
					(thickness 0.1524)
				)
			)
		)
		(property "Device Type" "LED-1615-4PH26"
			(at -2.132076 -0.109982 0)
			(unlocked yes)
			(layer "F.Fab")
			(hide yes)
			(effects
				(font
					(size 1.016 1.016)
					(thickness 0.1524)
				)
			)
		)
		(duplicate_pad_numbers_are_jumpers no)
		(fp_line
			(start -1.2954 0.254)
			(end -1.2954 1.6002)
			(stroke
				(width 0.508)
				(type default)
			)
			(layer "F.SilkS")
		)
		(fp_line
			(start -1.2954 1.6002)
			(end 1.2954 1.6002)
			(stroke
				(width 0.508)
				(type default)
			)
			(layer "F.SilkS")
		)
		(fp_line
			(start -1.1176 -1.4224)
			(end 1.1176 -1.4224)
			(stroke
				(width 0.1524)
				(type default)
			)
			(layer "F.SilkS")
		)
		(fp_line
			(start -1.1176 1.4224)
			(end -1.1176 -1.4224)
			(stroke
				(width 0.1524)
				(type default)
			)
			(layer "F.SilkS")
		)
		(fp_line
			(start 1.1176 -1.4224)
			(end 1.1176 1.4224)
			(stroke
				(width 0.1524)
				(type default)
			)
			(layer "F.SilkS")
		)
		(fp_line
			(start 1.1176 1.4224)
			(end -1.1176 1.4224)
			(stroke
				(width 0.1524)
				(type default)
			)
			(layer "F.SilkS")
		)
		(fp_line
			(start 1.2954 1.6002)
			(end 1.2954 0.254)
			(stroke
				(width 0.508)
				(type default)
			)
			(layer "F.SilkS")
		)
		(fp_rect
			(start -0.7493 0.8001)
			(end 0.7493 -0.8001)
			(stroke
				(width 0)
				(type default)
			)
			(fill no)
			(layer "F.CrtYd")
		)
		(fp_poly
			(pts
				(xy -1.3716 1.6764) (xy -1.3716 -1.6764) (xy 1.3716 -1.6764) (xy 1.3716 0.0635) (xy 0.7493 0.0635)
				(xy 0.7493 -0.8001) (xy -0.7493 -0.8001) (xy -0.7493 0.8001) (xy 0.7493 0.8001) (xy 0.7493 0.0762)
				(xy 1.3716 0.0762) (xy 1.3716 1.6764)
			)
			(stroke
				(width 0)
				(type default)
			)
			(fill no)
			(layer "F.CrtYd")
		)
		(fp_rect
			(start -1.3716 1.6764)
			(end 1.3716 -1.6764)
			(stroke
				(width 0)
				(type default)
			)
			(fill no)
			(layer "F.Fab")
		)
		(pad "1" smd rect
			(at 0.50038 -0.73025)
			(size 0.7112 0.8636)
			(layers "F.Cu" "F.Mask" "F.Paste")
			(net "DRV_ACT_19")
		)
		(pad "2" smd rect
			(at -0.50038 -0.73025)
			(size 0.7112 0.8636)
			(layers "F.Cu" "F.Mask" "F.Paste")
			(net "FLT_HDD19")
		)
		(pad "3" smd rect
			(at 0.50038 0.73025)
			(size 0.7112 0.8636)
			(layers "F.Cu" "F.Mask" "F.Paste")
			(net "DRV_ACT_19_N")
		)
		(pad "4" smd rect
			(at -0.50038 0.73025)
			(size 0.7112 0.8636)
			(layers "F.Cu" "F.Mask" "F.Paste")
			(net "FLT_HDD19_N")
		)
	)
	(footprint ""
		(layer "F.Cu")
		(at 387.83895 -47.749968 -90)
		(property "Reference" "VIA32"
			(at 0 0 270)
			(layer "F.SilkS")
			(hide yes)
			(effects
				(font
					(size 1.27 1.27)
				)
			)
		)
		(property "Value" "100OHM-8L-1D6MM-L18L16-GP"
			(at -3.7211 -4.5085 270)
			(unlocked yes)
			(layer "F.Fab")
			(hide yes)
			(effects
				(font
					(size 1.016 1.016)
					(thickness 0.1524)
				)
			)
		)
		(property "Device Type" "VIA-PCIE-4P-394076"
			(at -3.7211 -6.0325 270)
			(unlocked yes)
			(layer "F.Fab")
			(hide yes)
			(effects
				(font
					(size 1.016 1.016)
					(thickness 0.1524)
				)
			)
		)
		(duplicate_pad_numbers_are_jumpers no)
		(fp_rect
			(start -1.9685 0.381)
			(end 1.9685 -0.381)
			(stroke
				(width 0)
				(type default)
			)
			(fill no)
			(layer "F.CrtYd")
		)
		(fp_rect
			(start -1.9685 0.381)
			(end 1.9685 -0.381)
			(stroke
				(width 0)
				(type default)
			)
			(fill no)
			(layer "F.Fab")
		)
		(pad "1" thru_hole circle
			(at -1.5875 0 270)
			(size 0.508 0.508)
			(drill 0.254)
			(layers "*.Cu" "*.Mask")
			(remove_unused_layers no)
			(net "GND")
			(clearance 0.127)
			(thermal_gap 0.127)
		)
		(pad "2" thru_hole circle
			(at -0.5715 0 270)
			(size 0.508 0.508)
			(drill 0.254)
			(layers "*.Cu" "*.Mask")
			(remove_unused_layers no)
			(net "PHY_DRV_A_TO_SCC_A_32_DP")
			(clearance 0.127)
			(thermal_gap 0.127)
		)
		(pad "3" thru_hole circle
			(at 0.5715 0 270)
			(size 0.508 0.508)
			(drill 0.254)
			(layers "*.Cu" "*.Mask")
			(remove_unused_layers no)
			(net "PHY_DRV_A_TO_SCC_A_32_DN")
			(clearance 0.127)
			(thermal_gap 0.127)
		)
		(pad "4" thru_hole circle
			(at 1.5875 0 270)
			(size 0.508 0.508)
			(drill 0.254)
			(layers "*.Cu" "*.Mask")
			(remove_unused_layers no)
			(net "GND")
			(clearance 0.127)
			(thermal_gap 0.127)
		)
	)
	(footprint ""
		(layer "F.Cu")
		(at 46.392846 -54.523894 90)
		(property "Reference" "C374"
			(at 0 0 90)
			(layer "F.SilkS")
			(hide yes)
			(effects
				(font
					(size 1.27 1.27)
				)
			)
		)
		(property "Value" "SCD033U25V2KX-GP"
			(at 1.1811 -2.7051 90)
			(unlocked yes)
			(layer "F.Fab")
			(hide yes)
			(effects
				(font
					(size 1.016 1.016)
					(thickness 0.1524)
				)
			)
		)
		(property "Device Type" "C402H22"
			(at 1.1811 -4.2291 90)
			(unlocked yes)
			(layer "F.Fab")
			(hide yes)
			(effects
				(font
					(size 1.016 1.016)
					(thickness 0.1524)
				)
			)
		)
		(duplicate_pad_numbers_are_jumpers no)
		(fp_rect
			(start -0.4318 0.9525)
			(end 0.4318 -0.9525)
			(stroke
				(width 0)
				(type default)
			)
			(fill no)
			(layer "F.CrtYd")
		)
		(fp_rect
			(start -0.4318 0.9525)
			(end 0.4318 -0.9525)
			(stroke
				(width 0)
				(type default)
			)
			(fill no)
			(layer "F.Fab")
		)
		(pad "1" smd custom
			(at 0 -0.4445 90)
			(size 0.1524 0.1524)
			(layers "F.Cu" "F.Mask" "F.Paste")
			(net "P12V_A")
			(options
				(clearance outline)
				(anchor circle)
			)
			(primitives
				(gr_poly
					(pts
						(arc
							(start 0.3048 -0.2032)
							(mid 0.275042 -0.275042)
							(end 0.2032 -0.3048)
						)
						(arc
							(start -0.2032 -0.3048)
							(mid -0.275042 -0.275042)
							(end -0.3048 -0.2032)
						)
						(arc
							(start -0.3048 0.2032)
							(mid -0.275042 0.275042)
							(end -0.2032 0.3048)
						)
						(arc
							(start 0.2032 0.3048)
							(mid 0.275042 0.275042)
							(end 0.3048 0.2032)
						)
					)
					(width 0)
					(fill yes)
				)
			)
		)
		(pad "2" smd custom
			(at 0 0.4445 90)
			(size 0.1524 0.1524)
			(layers "F.Cu" "F.Mask" "F.Paste")
			(net "SW_HDD_N25")
			(options
				(clearance outline)
				(anchor circle)
			)
			(primitives
				(gr_poly
					(pts
						(arc
							(start 0.3048 -0.2032)
							(mid 0.275042 -0.275042)
							(end 0.2032 -0.3048)
						)
						(arc
							(start -0.2032 -0.3048)
							(mid -0.275042 -0.275042)
							(end -0.3048 -0.2032)
						)
						(arc
							(start -0.3048 0.2032)
							(mid -0.275042 0.275042)
							(end -0.2032 0.3048)
						)
						(arc
							(start 0.2032 0.3048)
							(mid 0.275042 0.275042)
							(end 0.3048 0.2032)
						)
					)
					(width 0)
					(fill yes)
				)
			)
		)
	)
	(footprint ""
		(layer "F.Cu")
		(at 52.031646 -161.268918 180)
		(property "Reference" "Q79"
			(at 0 0 180)
			(layer "F.SilkS")
			(hide yes)
			(effects
				(font
					(size 1.27 1.27)
				)
			)
		)
		(property "Value" "2N7002KDW-GP"
			(at -2.3622 -8.2042 180)
			(unlocked yes)
			(layer "F.Fab")
			(hide yes)
			(effects
				(font
					(size 1.016 1.016)
					(thickness 0.1524)
				)
			)
		)
		(property "Device Type" "SOT-363H44"
			(at -2.3622 -10.1092 180)
			(unlocked yes)
			(layer "F.Fab")
			(hide yes)
			(effects
				(font
					(size 1.016 1.016)
					(thickness 0.1524)
				)
			)
		)
		(duplicate_pad_numbers_are_jumpers no)
		(fp_line
			(start 1.4478 1.7018)
			(end 1.4478 -1.7018)
			(stroke
				(width 0.1524)
				(type default)
			)
			(layer "F.SilkS")
		)
		(fp_line
			(start 1.4478 -1.7018)
			(end -1.4478 -1.7018)
			(stroke
				(width 0.1524)
				(type default)
			)
			(layer "F.SilkS")
		)
		(fp_line
			(start -1.27 1.524)
			(end -1.27 0.6604)
			(stroke
				(width 0.4826)
				(type default)
			)
			(layer "F.SilkS")
		)
		(fp_line
			(start -1.4478 1.7018)
			(end 1.4478 1.7018)
			(stroke
				(width 0.1524)
				(type default)
			)
			(layer "F.SilkS")
		)
		(fp_line
			(start -1.4478 -1.7018)
			(end -1.4478 1.7018)
			(stroke
				(width 0.1524)
				(type default)
			)
			(layer "F.SilkS")
		)
		(fp_poly
			(pts
				(xy -1.524 -1.778) (xy 1.524 -1.778) (xy 1.524 1.778) (xy -1.524 1.778)
			)
			(stroke
				(width 0)
				(type default)
			)
			(fill no)
			(layer "F.CrtYd")
		)
		(fp_poly
			(pts
				(xy -1.524 -1.778) (xy 1.524 -1.778) (xy 1.524 1.778) (xy -1.524 1.778)
			)
			(stroke
				(width 0)
				(type default)
			)
			(fill no)
			(layer "F.Fab")
		)
		(pad "1" smd rect
			(at -0.65024 0.9398 180)
			(size 0.4064 1.016)
			(layers "F.Cu" "F.Mask" "F.Paste")
			(net "GND")
		)
		(pad "2" smd rect
			(at 0 0.9398 180)
			(size 0.4064 1.016)
			(layers "F.Cu" "F.Mask" "F.Paste")
			(net "SW_PWR_R_HDD13")
		)
		(pad "3" smd rect
			(at 0.65024 0.9398 180)
			(size 0.4064 1.016)
			(layers "F.Cu" "F.Mask" "F.Paste")
			(net "SW_HDD_P13")
		)
		(pad "4" smd rect
			(at 0.65024 -0.9398 180)
			(size 0.4064 1.016)
			(layers "F.Cu" "F.Mask" "F.Paste")
			(net "GND")
		)
		(pad "5" smd rect
			(at 0 -0.9398 180)
			(size 0.4064 1.016)
			(layers "F.Cu" "F.Mask" "F.Paste")
			(net "SW_HDD_G13")
		)
		(pad "6" smd rect
			(at -0.65024 -0.9398 180)
			(size 0.4064 1.016)
			(layers "F.Cu" "F.Mask" "F.Paste")
			(net "SW_HDD_R13")
		)
	)
	(footprint ""
		(layer "F.Cu")
		(at 272.321528 -17.873472 -90)
		(property "Reference" "TP250"
			(at 0 0 270)
			(layer "F.SilkS")
			(hide yes)
			(effects
				(font
					(size 1.27 1.27)
				)
			)
		)
		(property "Value" "TPAD32-GP"
			(at -0.0508 -1.6764 270)
			(unlocked yes)
			(layer "F.Fab")
			(hide yes)
			(effects
				(font
					(size 1.016 1.016)
					(thickness 0.1524)
				)
			)
		)
		(property "Device Type" "TPAD32"
			(at -0.0508 -3.2004 270)
			(unlocked yes)
			(layer "F.Fab")
			(hide yes)
			(effects
				(font
					(size 1.016 1.016)
					(thickness 0.1524)
				)
			)
		)
		(duplicate_pad_numbers_are_jumpers no)
		(fp_poly
			(pts
				(arc
					(start 0 -0.4064)
					(mid 0 0.4064)
					(end 0 -0.4064)
				)
			)
			(stroke
				(width 0)
				(type default)
			)
			(fill no)
			(layer "F.CrtYd")
		)
		(fp_poly
			(pts
				(arc
					(start 0 -0.7112)
					(mid 0 0.7112)
					(end 0 -0.7112)
				)
			)
			(stroke
				(width 0)
				(type default)
			)
			(fill no)
			(layer "F.Fab")
		)
		(pad "1" smd circle
			(at 0 0 270)
			(size 0.8128 0.8128)
			(layers "F.Cu" "F.Mask" "F.Paste")
			(net "PCIE_COMP_B_CLK_N5")
		)
	)
	(footprint ""
		(layer "F.Cu")
		(at 190.258954 -47.749968 -90)
		(property "Reference" "VIA62"
			(at 0 0 270)
			(layer "F.SilkS")
			(hide yes)
			(effects
				(font
					(size 1.27 1.27)
				)
			)
		)
		(property "Value" "100OHM-8L-1D6MM-L18L16-GP"
			(at -3.7211 -4.5085 270)
			(unlocked yes)
			(layer "F.Fab")
			(hide yes)
			(effects
				(font
					(size 1.016 1.016)
					(thickness 0.1524)
				)
			)
		)
		(property "Device Type" "VIA-PCIE-4P-394076"
			(at -3.7211 -6.0325 270)
			(unlocked yes)
			(layer "F.Fab")
			(hide yes)
			(effects
				(font
					(size 1.016 1.016)
					(thickness 0.1524)
				)
			)
		)
		(duplicate_pad_numbers_are_jumpers no)
		(fp_rect
			(start -1.9685 0.381)
			(end 1.9685 -0.381)
			(stroke
				(width 0)
				(type default)
			)
			(fill no)
			(layer "F.CrtYd")
		)
		(fp_rect
			(start -1.9685 0.381)
			(end 1.9685 -0.381)
			(stroke
				(width 0)
				(type default)
			)
			(fill no)
			(layer "F.Fab")
		)
		(pad "1" thru_hole circle
			(at -1.5875 0 270)
			(size 0.508 0.508)
			(drill 0.254)
			(layers "*.Cu" "*.Mask")
			(remove_unused_layers no)
			(net "GND")
			(clearance 0.127)
			(thermal_gap 0.127)
		)
		(pad "2" thru_hole circle
			(at -0.5715 0 270)
			(size 0.508 0.508)
			(drill 0.254)
			(layers "*.Cu" "*.Mask")
			(remove_unused_layers no)
			(net "PHY_DRV_A_TO_SCC_A_29_DP")
			(clearance 0.127)
			(thermal_gap 0.127)
		)
		(pad "3" thru_hole circle
			(at 0.5715 0 270)
			(size 0.508 0.508)
			(drill 0.254)
			(layers "*.Cu" "*.Mask")
			(remove_unused_layers no)
			(net "PHY_DRV_A_TO_SCC_A_29_DN")
			(clearance 0.127)
			(thermal_gap 0.127)
		)
		(pad "4" thru_hole circle
			(at 1.5875 0 270)
			(size 0.508 0.508)
			(drill 0.254)
			(layers "*.Cu" "*.Mask")
			(remove_unused_layers no)
			(net "GND")
			(clearance 0.127)
			(thermal_gap 0.127)
		)
	)
	(footprint ""
		(layer "F.Cu")
		(at 50.739802 -151.31415)
		(property "Reference" "R1224"
			(at 0 0 0)
			(layer "F.SilkS")
			(hide yes)
			(effects
				(font
					(size 1.27 1.27)
				)
			)
		)
		(property "Value" "49K9R2F-L-GP"
			(at 0.064008 -3.993896 0)
			(unlocked yes)
			(layer "F.Fab")
			(hide yes)
			(effects
				(font
					(size 1.016 1.016)
					(thickness 0.1524)
				)
			)
		)
		(property "Device Type" "R402H16"
			(at 0.064008 -5.517896 0)
			(unlocked yes)
			(layer "F.Fab")
			(hide yes)
			(effects
				(font
					(size 1.016 1.016)
					(thickness 0.1524)
				)
			)
		)
		(duplicate_pad_numbers_are_jumpers no)
		(fp_line
			(start -0.508 -0.9398)
			(end -0.508 0.9398)
			(stroke
				(width 0.1524)
				(type default)
			)
			(layer "F.SilkS")
		)
		(fp_line
			(start 0.508 -0.9398)
			(end -0.508 -0.9398)
			(stroke
				(width 0.1524)
				(type default)
			)
			(layer "F.SilkS")
		)
		(fp_rect
			(start -0.508 0.9398)
			(end 0.508 -0.9398)
			(stroke
				(width 0)
				(type default)
			)
			(fill no)
			(layer "F.CrtYd")
		)
		(fp_rect
			(start -0.508 0.9398)
			(end 0.508 -0.9398)
			(stroke
				(width 0)
				(type default)
			)
			(fill no)
			(layer "F.Fab")
		)
		(pad "1" smd custom
			(at 0 -0.4445)
			(size 0.1397 0.1397)
			(layers "F.Cu" "F.Mask" "F.Paste")
			(net "P12V_A")
			(options
				(clearance outline)
				(anchor circle)
			)
			(primitives
				(gr_poly
					(pts
						(arc
							(start -0.1778 -0.2794)
							(mid -0.249642 -0.249642)
							(end -0.2794 -0.1778)
						)
						(arc
							(start -0.2794 0.1778)
							(mid -0.249642 0.249642)
							(end -0.1778 0.2794)
						)
						(arc
							(start 0.1778 0.2794)
							(mid 0.249642 0.249642)
							(end 0.2794 0.1778)
						)
						(arc
							(start 0.2794 -0.1778)
							(mid 0.249642 -0.249642)
							(end 0.1778 -0.2794)
						)
					)
					(width 0)
					(fill yes)
				)
			)
		)
		(pad "2" smd custom
			(at 0 0.4445)
			(size 0.1397 0.1397)
			(layers "F.Cu" "F.Mask" "F.Paste")
			(net "P5V_B_EN_R")
			(options
				(clearance outline)
				(anchor circle)
			)
			(primitives
				(gr_poly
					(pts
						(arc
							(start -0.1778 -0.2794)
							(mid -0.249642 -0.249642)
							(end -0.2794 -0.1778)
						)
						(arc
							(start -0.2794 0.1778)
							(mid -0.249642 0.249642)
							(end -0.1778 0.2794)
						)
						(arc
							(start 0.1778 0.2794)
							(mid 0.249642 0.249642)
							(end 0.2794 0.1778)
						)
						(arc
							(start 0.2794 -0.1778)
							(mid 0.249642 -0.249642)
							(end 0.1778 -0.2794)
						)
					)
					(width 0)
					(fill yes)
				)
			)
		)
	)
	(footprint ""
		(layer "F.Cu")
		(at 143.024098 -282.060142 90)
		(property "Reference" "R229"
			(at 0 0 90)
			(layer "F.SilkS")
			(hide yes)
			(effects
				(font
					(size 1.27 1.27)
				)
			)
		)
		(property "Value" "4K7R2J-2-GP"
			(at 0.064008 -3.993896 90)
			(unlocked yes)
			(layer "F.Fab")
			(hide yes)
			(effects
				(font
					(size 1.016 1.016)
					(thickness 0.1524)
				)
			)
		)
		(property "Device Type" "R402H16"
			(at 0.064008 -5.517896 90)
			(unlocked yes)
			(layer "F.Fab")
			(hide yes)
			(effects
				(font
					(size 1.016 1.016)
					(thickness 0.1524)
				)
			)
		)
		(duplicate_pad_numbers_are_jumpers no)
		(fp_line
			(start 0.508 -0.9398)
			(end -0.508 -0.9398)
			(stroke
				(width 0.1524)
				(type default)
			)
			(layer "F.SilkS")
		)
		(fp_line
			(start -0.508 -0.9398)
			(end -0.508 0.9398)
			(stroke
				(width 0.1524)
				(type default)
			)
			(layer "F.SilkS")
		)
		(fp_rect
			(start -0.508 0.9398)
			(end 0.508 -0.9398)
			(stroke
				(width 0)
				(type default)
			)
			(fill no)
			(layer "F.CrtYd")
		)
		(fp_rect
			(start -0.508 0.9398)
			(end 0.508 -0.9398)
			(stroke
				(width 0)
				(type default)
			)
			(fill no)
			(layer "F.Fab")
		)
		(pad "1" smd custom
			(at 0 -0.4445 90)
			(size 0.1397 0.1397)
			(layers "F.Cu" "F.Mask" "F.Paste")
			(net "P12V_A")
			(options
				(clearance outline)
				(anchor circle)
			)
			(primitives
				(gr_poly
					(pts
						(arc
							(start -0.1778 -0.2794)
							(mid -0.249642 -0.249642)
							(end -0.2794 -0.1778)
						)
						(arc
							(start -0.2794 0.1778)
							(mid -0.249642 0.249642)
							(end -0.1778 0.2794)
						)
						(arc
							(start 0.1778 0.2794)
							(mid 0.249642 0.249642)
							(end 0.2794 0.1778)
						)
						(arc
							(start 0.2794 -0.1778)
							(mid 0.249642 -0.249642)
							(end 0.1778 -0.2794)
						)
					)
					(width 0)
					(fill yes)
				)
			)
		)
		(pad "2" smd custom
			(at 0 0.4445 90)
			(size 0.1397 0.1397)
			(layers "F.Cu" "F.Mask" "F.Paste")
			(net "SW_HDD_P4")
			(options
				(clearance outline)
				(anchor circle)
			)
			(primitives
				(gr_poly
					(pts
						(arc
							(start -0.1778 -0.2794)
							(mid -0.249642 -0.249642)
							(end -0.2794 -0.1778)
						)
						(arc
							(start -0.2794 0.1778)
							(mid -0.249642 0.249642)
							(end -0.1778 0.2794)
						)
						(arc
							(start 0.1778 0.2794)
							(mid 0.249642 0.249642)
							(end 0.2794 0.1778)
						)
						(arc
							(start 0.2794 -0.1778)
							(mid 0.249642 -0.249642)
							(end 0.1778 -0.2794)
						)
					)
					(width 0)
					(fill yes)
				)
			)
		)
	)
	(footprint ""
		(layer "F.Cu")
		(at 7.240524 -284.60319 90)
		(property "Reference" "R550"
			(at 0 0 90)
			(layer "F.SilkS")
			(hide yes)
			(effects
				(font
					(size 1.27 1.27)
				)
			)
		)
		(property "Value" "4K7R2J-2-GP"
			(at 0.064008 -3.993896 90)
			(unlocked yes)
			(layer "F.Fab")
			(hide yes)
			(effects
				(font
					(size 1.016 1.016)
					(thickness 0.1524)
				)
			)
		)
		(property "Device Type" "R402H16"
			(at 0.064008 -5.517896 90)
			(unlocked yes)
			(layer "F.Fab")
			(hide yes)
			(effects
				(font
					(size 1.016 1.016)
					(thickness 0.1524)
				)
			)
		)
		(duplicate_pad_numbers_are_jumpers no)
		(fp_line
			(start 0.508 -0.9398)
			(end -0.508 -0.9398)
			(stroke
				(width 0.1524)
				(type default)
			)
			(layer "F.SilkS")
		)
		(fp_line
			(start -0.508 -0.9398)
			(end -0.508 0.9398)
			(stroke
				(width 0.1524)
				(type default)
			)
			(layer "F.SilkS")
		)
		(fp_rect
			(start -0.508 0.9398)
			(end 0.508 -0.9398)
			(stroke
				(width 0)
				(type default)
			)
			(fill no)
			(layer "F.CrtYd")
		)
		(fp_rect
			(start -0.508 0.9398)
			(end 0.508 -0.9398)
			(stroke
				(width 0)
				(type default)
			)
			(fill no)
			(layer "F.Fab")
		)
		(pad "1" smd custom
			(at 0 -0.4445 90)
			(size 0.1397 0.1397)
			(layers "F.Cu" "F.Mask" "F.Paste")
			(net "DRIVE_B_24_ACT")
			(options
				(clearance outline)
				(anchor circle)
			)
			(primitives
				(gr_poly
					(pts
						(arc
							(start -0.1778 -0.2794)
							(mid -0.249642 -0.249642)
							(end -0.2794 -0.1778)
						)
						(arc
							(start -0.2794 0.1778)
							(mid -0.249642 0.249642)
							(end -0.1778 0.2794)
						)
						(arc
							(start 0.1778 0.2794)
							(mid 0.249642 0.249642)
							(end 0.2794 0.1778)
						)
						(arc
							(start 0.2794 -0.1778)
							(mid 0.249642 -0.249642)
							(end 0.1778 -0.2794)
						)
					)
					(width 0)
					(fill yes)
				)
			)
		)
		(pad "2" smd custom
			(at 0 0.4445 90)
			(size 0.1397 0.1397)
			(layers "F.Cu" "F.Mask" "F.Paste")
			(net "GND")
			(options
				(clearance outline)
				(anchor circle)
			)
			(primitives
				(gr_poly
					(pts
						(arc
							(start -0.1778 -0.2794)
							(mid -0.249642 -0.249642)
							(end -0.2794 -0.1778)
						)
						(arc
							(start -0.2794 0.1778)
							(mid -0.249642 0.249642)
							(end -0.1778 0.2794)
						)
						(arc
							(start 0.1778 0.2794)
							(mid 0.249642 0.249642)
							(end 0.2794 0.1778)
						)
						(arc
							(start 0.2794 -0.1778)
							(mid 0.249642 -0.249642)
							(end 0.1778 -0.2794)
						)
					)
					(width 0)
					(fill yes)
				)
			)
		)
	)
	(footprint ""
		(layer "F.Cu")
		(at 257.3401 -139.7 -90)
		(property "Reference" "R454"
			(at 0 0 270)
			(layer "F.SilkS")
			(hide yes)
			(effects
				(font
					(size 1.27 1.27)
				)
			)
		)
		(property "Value" "4K7R2F-GP"
			(at 0.064008 -3.993896 270)
			(unlocked yes)
			(layer "F.Fab")
			(hide yes)
			(effects
				(font
					(size 1.016 1.016)
					(thickness 0.1524)
				)
			)
		)
		(property "Device Type" "R402H16"
			(at 0.064008 -5.517896 270)
			(unlocked yes)
			(layer "F.Fab")
			(hide yes)
			(effects
				(font
					(size 1.016 1.016)
					(thickness 0.1524)
				)
			)
		)
		(duplicate_pad_numbers_are_jumpers no)
		(fp_line
			(start -0.508 -0.9398)
			(end -0.508 0.9398)
			(stroke
				(width 0.1524)
				(type default)
			)
			(layer "F.SilkS")
		)
		(fp_line
			(start 0.508 -0.9398)
			(end -0.508 -0.9398)
			(stroke
				(width 0.1524)
				(type default)
			)
			(layer "F.SilkS")
		)
		(fp_rect
			(start -0.508 0.9398)
			(end 0.508 -0.9398)
			(stroke
				(width 0)
				(type default)
			)
			(fill no)
			(layer "F.CrtYd")
		)
		(fp_rect
			(start -0.508 0.9398)
			(end 0.508 -0.9398)
			(stroke
				(width 0)
				(type default)
			)
			(fill no)
			(layer "F.Fab")
		)
		(pad "1" smd custom
			(at 0 -0.4445 270)
			(size 0.1397 0.1397)
			(layers "F.Cu" "F.Mask" "F.Paste")
			(net "GND")
			(options
				(clearance outline)
				(anchor circle)
			)
			(primitives
				(gr_poly
					(pts
						(arc
							(start -0.1778 -0.2794)
							(mid -0.249642 -0.249642)
							(end -0.2794 -0.1778)
						)
						(arc
							(start -0.2794 0.1778)
							(mid -0.249642 0.249642)
							(end -0.1778 0.2794)
						)
						(arc
							(start 0.1778 0.2794)
							(mid 0.249642 0.249642)
							(end 0.2794 0.1778)
						)
						(arc
							(start 0.2794 -0.1778)
							(mid 0.249642 -0.249642)
							(end 0.1778 -0.2794)
						)
					)
					(width 0)
					(fill yes)
				)
			)
		)
		(pad "2" smd custom
			(at 0 0.4445 270)
			(size 0.1397 0.1397)
			(layers "F.Cu" "F.Mask" "F.Paste")
			(net "COMP_A_FAST_THROTTLE_N")
			(options
				(clearance outline)
				(anchor circle)
			)
			(primitives
				(gr_poly
					(pts
						(arc
							(start -0.1778 -0.2794)
							(mid -0.249642 -0.249642)
							(end -0.2794 -0.1778)
						)
						(arc
							(start -0.2794 0.1778)
							(mid -0.249642 0.249642)
							(end -0.1778 0.2794)
						)
						(arc
							(start 0.1778 0.2794)
							(mid 0.249642 0.249642)
							(end 0.2794 0.1778)
						)
						(arc
							(start 0.2794 -0.1778)
							(mid 0.249642 -0.249642)
							(end 0.1778 -0.2794)
						)
					)
					(width 0)
					(fill yes)
				)
			)
		)
	)
	(footprint ""
		(layer "F.Cu")
		(at 364.290102 -49.596294 90)
		(property "Reference" "C451"
			(at 0 0 90)
			(layer "F.SilkS")
			(hide yes)
			(effects
				(font
					(size 1.27 1.27)
				)
			)
		)
		(property "Value" "SCD033U25V2KX-GP"
			(at 1.1811 -2.7051 90)
			(unlocked yes)
			(layer "F.Fab")
			(hide yes)
			(effects
				(font
					(size 1.016 1.016)
					(thickness 0.1524)
				)
			)
		)
		(property "Device Type" "C402H22"
			(at 1.1811 -4.2291 90)
			(unlocked yes)
			(layer "F.Fab")
			(hide yes)
			(effects
				(font
					(size 1.016 1.016)
					(thickness 0.1524)
				)
			)
		)
		(duplicate_pad_numbers_are_jumpers no)
		(fp_rect
			(start -0.4318 0.9525)
			(end 0.4318 -0.9525)
			(stroke
				(width 0)
				(type default)
			)
			(fill no)
			(layer "F.CrtYd")
		)
		(fp_rect
			(start -0.4318 0.9525)
			(end 0.4318 -0.9525)
			(stroke
				(width 0)
				(type default)
			)
			(fill no)
			(layer "F.Fab")
		)
		(pad "1" smd custom
			(at 0 -0.4445 90)
			(size 0.1524 0.1524)
			(layers "F.Cu" "F.Mask" "F.Paste")
			(net "SW_HDD_P31")
			(options
				(clearance outline)
				(anchor circle)
			)
			(primitives
				(gr_poly
					(pts
						(arc
							(start 0.3048 -0.2032)
							(mid 0.275042 -0.275042)
							(end 0.2032 -0.3048)
						)
						(arc
							(start -0.2032 -0.3048)
							(mid -0.275042 -0.275042)
							(end -0.3048 -0.2032)
						)
						(arc
							(start -0.3048 0.2032)
							(mid -0.275042 0.275042)
							(end -0.2032 0.3048)
						)
						(arc
							(start 0.2032 0.3048)
							(mid 0.275042 0.275042)
							(end 0.3048 0.2032)
						)
					)
					(width 0)
					(fill yes)
				)
			)
		)
		(pad "2" smd custom
			(at 0 0.4445 90)
			(size 0.1524 0.1524)
			(layers "F.Cu" "F.Mask" "F.Paste")
			(net "GND")
			(options
				(clearance outline)
				(anchor circle)
			)
			(primitives
				(gr_poly
					(pts
						(arc
							(start 0.3048 -0.2032)
							(mid 0.275042 -0.275042)
							(end 0.2032 -0.3048)
						)
						(arc
							(start -0.2032 -0.3048)
							(mid -0.275042 -0.275042)
							(end -0.3048 -0.2032)
						)
						(arc
							(start -0.3048 0.2032)
							(mid -0.275042 0.275042)
							(end -0.2032 0.3048)
						)
						(arc
							(start 0.2032 0.3048)
							(mid 0.275042 0.275042)
							(end 0.3048 0.2032)
						)
					)
					(width 0)
					(fill yes)
				)
			)
		)
	)
	(footprint ""
		(layer "F.Cu")
		(at 52.566824 -142.179548 90)
		(property "Reference" "C622"
			(at 0 0 90)
			(layer "F.SilkS")
			(hide yes)
			(effects
				(font
					(size 1.27 1.27)
				)
			)
		)
		(property "Value" "SCD1U16V2KX-3GP"
			(at 1.1811 -2.7051 90)
			(unlocked yes)
			(layer "F.Fab")
			(hide yes)
			(effects
				(font
					(size 1.016 1.016)
					(thickness 0.1524)
				)
			)
		)
		(property "Device Type" "C402H22"
			(at 1.1811 -4.2291 90)
			(unlocked yes)
			(layer "F.Fab")
			(hide yes)
			(effects
				(font
					(size 1.016 1.016)
					(thickness 0.1524)
				)
			)
		)
		(duplicate_pad_numbers_are_jumpers no)
		(fp_rect
			(start -0.4318 0.9525)
			(end 0.4318 -0.9525)
			(stroke
				(width 0)
				(type default)
			)
			(fill no)
			(layer "F.CrtYd")
		)
		(fp_rect
			(start -0.4318 0.9525)
			(end 0.4318 -0.9525)
			(stroke
				(width 0)
				(type default)
			)
			(fill no)
			(layer "F.Fab")
		)
		(pad "1" smd custom
			(at 0 -0.4445 90)
			(size 0.1524 0.1524)
			(layers "F.Cu" "F.Mask" "F.Paste")
			(net "P5V_B_VBST_RC")
			(options
				(clearance outline)
				(anchor circle)
			)
			(primitives
				(gr_poly
					(pts
						(arc
							(start 0.3048 -0.2032)
							(mid 0.275042 -0.275042)
							(end 0.2032 -0.3048)
						)
						(arc
							(start -0.2032 -0.3048)
							(mid -0.275042 -0.275042)
							(end -0.3048 -0.2032)
						)
						(arc
							(start -0.3048 0.2032)
							(mid -0.275042 0.275042)
							(end -0.2032 0.3048)
						)
						(arc
							(start 0.2032 0.3048)
							(mid 0.275042 0.275042)
							(end 0.3048 0.2032)
						)
					)
					(width 0)
					(fill yes)
				)
			)
		)
		(pad "2" smd custom
			(at 0 0.4445 90)
			(size 0.1524 0.1524)
			(layers "F.Cu" "F.Mask" "F.Paste")
			(net "P5V_B_LL")
			(options
				(clearance outline)
				(anchor circle)
			)
			(primitives
				(gr_poly
					(pts
						(arc
							(start 0.3048 -0.2032)
							(mid 0.275042 -0.275042)
							(end 0.2032 -0.3048)
						)
						(arc
							(start -0.2032 -0.3048)
							(mid -0.275042 -0.275042)
							(end -0.3048 -0.2032)
						)
						(arc
							(start -0.3048 0.2032)
							(mid -0.275042 0.275042)
							(end -0.2032 0.3048)
						)
						(arc
							(start 0.2032 0.3048)
							(mid 0.275042 0.275042)
							(end 0.3048 0.2032)
						)
					)
					(width 0)
					(fill yes)
				)
			)
		)
	)
	(footprint ""
		(layer "F.Cu")
		(at 118.585996 -301.287942)
		(property "Reference" "C83"
			(at 0 0 0)
			(layer "F.SilkS")
			(hide yes)
			(effects
				(font
					(size 1.27 1.27)
				)
			)
		)
		(property "Value" "SC4D7U25V5KX-1-GP"
			(at -0.0762 -6.1214 0)
			(unlocked yes)
			(layer "F.Fab")
			(hide yes)
			(effects
				(font
					(size 1.016 1.016)
					(thickness 0.1524)
				)
			)
		)
		(property "Device Type" "C805H58"
			(at -0.0762 -8.1534 0)
			(unlocked yes)
			(layer "F.Fab")
			(hide yes)
			(effects
				(font
					(size 1.016 1.016)
					(thickness 0.1524)
				)
			)
		)
		(duplicate_pad_numbers_are_jumpers no)
		(fp_line
			(start 0.635 0)
			(end -0.635 0)
			(stroke
				(width 0.508)
				(type default)
			)
			(layer "F.SilkS")
		)
		(fp_rect
			(start -0.9652 1.778)
			(end 0.9652 -1.778)
			(stroke
				(width 0)
				(type default)
			)
			(fill no)
			(layer "F.CrtYd")
		)
		(fp_poly
			(pts
				(xy -0.9652 -1.778) (xy 0.9652 -1.778) (xy 0.9652 1.778) (xy -0.9652 1.778)
			)
			(stroke
				(width 0)
				(type default)
			)
			(fill no)
			(layer "F.Fab")
		)
		(pad "1" smd rect
			(at 0 -0.9652)
			(size 1.397 1.143)
			(layers "F.Cu" "F.Mask" "F.Paste")
			(net "P12V_HDD3")
		)
		(pad "2" smd rect
			(at 0 0.9652)
			(size 1.397 1.143)
			(layers "F.Cu" "F.Mask" "F.Paste")
			(net "GND")
		)
	)
	(footprint ""
		(layer "F.Cu")
		(at 472.899994 -94.400116)
		(property "Reference" "FLED24"
			(at 0 0 0)
			(layer "F.SilkS")
			(hide yes)
			(effects
				(font
					(size 1.27 1.27)
				)
			)
		)
		(property "Value" "LED-BY-19-GP"
			(at -2.132076 1.414018 0)
			(unlocked yes)
			(layer "F.Fab")
			(hide yes)
			(effects
				(font
					(size 1.016 1.016)
					(thickness 0.1524)
				)
			)
		)
		(property "Device Type" "LED-1615-4PH26"
			(at -2.132076 -0.109982 0)
			(unlocked yes)
			(layer "F.Fab")
			(hide yes)
			(effects
				(font
					(size 1.016 1.016)
					(thickness 0.1524)
				)
			)
		)
		(duplicate_pad_numbers_are_jumpers no)
		(fp_line
			(start -1.2954 0.254)
			(end -1.2954 1.6002)
			(stroke
				(width 0.508)
				(type default)
			)
			(layer "F.SilkS")
		)
		(fp_line
			(start -1.2954 1.6002)
			(end 1.2954 1.6002)
			(stroke
				(width 0.508)
				(type default)
			)
			(layer "F.SilkS")
		)
		(fp_line
			(start -1.1176 -1.4224)
			(end 1.1176 -1.4224)
			(stroke
				(width 0.1524)
				(type default)
			)
			(layer "F.SilkS")
		)
		(fp_line
			(start -1.1176 1.4224)
			(end -1.1176 -1.4224)
			(stroke
				(width 0.1524)
				(type default)
			)
			(layer "F.SilkS")
		)
		(fp_line
			(start 1.1176 -1.4224)
			(end 1.1176 1.4224)
			(stroke
				(width 0.1524)
				(type default)
			)
			(layer "F.SilkS")
		)
		(fp_line
			(start 1.1176 1.4224)
			(end -1.1176 1.4224)
			(stroke
				(width 0.1524)
				(type default)
			)
			(layer "F.SilkS")
		)
		(fp_line
			(start 1.2954 1.6002)
			(end 1.2954 0.254)
			(stroke
				(width 0.508)
				(type default)
			)
			(layer "F.SilkS")
		)
		(fp_rect
			(start -0.7493 0.8001)
			(end 0.7493 -0.8001)
			(stroke
				(width 0)
				(type default)
			)
			(fill no)
			(layer "F.CrtYd")
		)
		(fp_poly
			(pts
				(xy -1.3716 1.6764) (xy -1.3716 -1.6764) (xy 1.3716 -1.6764) (xy 1.3716 0.0635) (xy 0.7493 0.0635)
				(xy 0.7493 -0.8001) (xy -0.7493 -0.8001) (xy -0.7493 0.8001) (xy 0.7493 0.8001) (xy 0.7493 0.0762)
				(xy 1.3716 0.0762) (xy 1.3716 1.6764)
			)
			(stroke
				(width 0)
				(type default)
			)
			(fill no)
			(layer "F.CrtYd")
		)
		(fp_rect
			(start -1.3716 1.6764)
			(end 1.3716 -1.6764)
			(stroke
				(width 0)
				(type default)
			)
			(fill no)
			(layer "F.Fab")
		)
		(pad "1" smd rect
			(at 0.50038 -0.73025)
			(size 0.7112 0.8636)
			(layers "F.Cu" "F.Mask" "F.Paste")
			(net "DRV_ACT_23")
		)
		(pad "2" smd rect
			(at -0.50038 -0.73025)
			(size 0.7112 0.8636)
			(layers "F.Cu" "F.Mask" "F.Paste")
			(net "FLT_HDD23")
		)
		(pad "3" smd rect
			(at 0.50038 0.73025)
			(size 0.7112 0.8636)
			(layers "F.Cu" "F.Mask" "F.Paste")
			(net "DRV_ACT_23_N")
		)
		(pad "4" smd rect
			(at -0.50038 0.73025)
			(size 0.7112 0.8636)
			(layers "F.Cu" "F.Mask" "F.Paste")
			(net "FLT_HDD23_N")
		)
	)
	(footprint ""
		(layer "F.Cu")
		(at 461.9879 -42.585894 180)
		(property "Reference" "R922"
			(at 0 0 180)
			(layer "F.SilkS")
			(hide yes)
			(effects
				(font
					(size 1.27 1.27)
				)
			)
		)
		(property "Value" "0R2J-2-GP"
			(at 0.064008 -3.993896 180)
			(unlocked yes)
			(layer "F.Fab")
			(hide yes)
			(effects
				(font
					(size 1.016 1.016)
					(thickness 0.1524)
				)
			)
		)
		(property "Device Type" "R402H16"
			(at 0.064008 -5.517896 180)
			(unlocked yes)
			(layer "F.Fab")
			(hide yes)
			(effects
				(font
					(size 1.016 1.016)
					(thickness 0.1524)
				)
			)
		)
		(duplicate_pad_numbers_are_jumpers no)
		(fp_line
			(start 0.508 -0.9398)
			(end -0.508 -0.9398)
			(stroke
				(width 0.1524)
				(type default)
			)
			(layer "F.SilkS")
		)
		(fp_line
			(start -0.508 -0.9398)
			(end -0.508 0.9398)
			(stroke
				(width 0.1524)
				(type default)
			)
			(layer "F.SilkS")
		)
		(fp_rect
			(start -0.508 0.9398)
			(end 0.508 -0.9398)
			(stroke
				(width 0)
				(type default)
			)
			(fill no)
			(layer "F.CrtYd")
		)
		(fp_rect
			(start -0.508 0.9398)
			(end 0.508 -0.9398)
			(stroke
				(width 0)
				(type default)
			)
			(fill no)
			(layer "F.Fab")
		)
		(pad "1" smd custom
			(at 0 -0.4445 180)
			(size 0.1397 0.1397)
			(layers "F.Cu" "F.Mask" "F.Paste")
			(net "DRIVE_A_34_PWR")
			(options
				(clearance outline)
				(anchor circle)
			)
			(primitives
				(gr_poly
					(pts
						(arc
							(start -0.1778 -0.2794)
							(mid -0.249642 -0.249642)
							(end -0.2794 -0.1778)
						)
						(arc
							(start -0.2794 0.1778)
							(mid -0.249642 0.249642)
							(end -0.1778 0.2794)
						)
						(arc
							(start 0.1778 0.2794)
							(mid 0.249642 0.249642)
							(end 0.2794 0.1778)
						)
						(arc
							(start 0.2794 -0.1778)
							(mid 0.249642 -0.249642)
							(end 0.1778 -0.2794)
						)
					)
					(width 0)
					(fill yes)
				)
			)
		)
		(pad "2" smd custom
			(at 0 0.4445 180)
			(size 0.1397 0.1397)
			(layers "F.Cu" "F.Mask" "F.Paste")
			(net "SW_PWR_R_HDD34")
			(options
				(clearance outline)
				(anchor circle)
			)
			(primitives
				(gr_poly
					(pts
						(arc
							(start -0.1778 -0.2794)
							(mid -0.249642 -0.249642)
							(end -0.2794 -0.1778)
						)
						(arc
							(start -0.2794 0.1778)
							(mid -0.249642 0.249642)
							(end -0.1778 0.2794)
						)
						(arc
							(start 0.1778 0.2794)
							(mid 0.249642 0.249642)
							(end 0.2794 0.1778)
						)
						(arc
							(start 0.2794 -0.1778)
							(mid 0.249642 -0.249642)
							(end 0.1778 -0.2794)
						)
					)
					(width 0)
					(fill yes)
				)
			)
		)
	)
	(footprint ""
		(layer "F.Cu")
		(at 271.251172 -5.69087 90)
		(property "Reference" "R995"
			(at 0 0 90)
			(layer "F.SilkS")
			(hide yes)
			(effects
				(font
					(size 1.27 1.27)
				)
			)
		)
		(property "Value" "100KR2F-L1-GP"
			(at 0.064008 -3.993896 90)
			(unlocked yes)
			(layer "F.Fab")
			(hide yes)
			(effects
				(font
					(size 1.016 1.016)
					(thickness 0.1524)
				)
			)
		)
		(property "Device Type" "R402H16"
			(at 0.064008 -5.517896 90)
			(unlocked yes)
			(layer "F.Fab")
			(hide yes)
			(effects
				(font
					(size 1.016 1.016)
					(thickness 0.1524)
				)
			)
		)
		(duplicate_pad_numbers_are_jumpers no)
		(fp_line
			(start 0.508 -0.9398)
			(end -0.508 -0.9398)
			(stroke
				(width 0.1524)
				(type default)
			)
			(layer "F.SilkS")
		)
		(fp_line
			(start -0.508 -0.9398)
			(end -0.508 0.9398)
			(stroke
				(width 0.1524)
				(type default)
			)
			(layer "F.SilkS")
		)
		(fp_rect
			(start -0.508 0.9398)
			(end 0.508 -0.9398)
			(stroke
				(width 0)
				(type default)
			)
			(fill no)
			(layer "F.CrtYd")
		)
		(fp_rect
			(start -0.508 0.9398)
			(end 0.508 -0.9398)
			(stroke
				(width 0)
				(type default)
			)
			(fill no)
			(layer "F.Fab")
		)
		(pad "1" smd custom
			(at 0 -0.4445 90)
			(size 0.1397 0.1397)
			(layers "F.Cu" "F.Mask" "F.Paste")
			(net "P3V3_STBY_B")
			(options
				(clearance outline)
				(anchor circle)
			)
			(primitives
				(gr_poly
					(pts
						(arc
							(start -0.1778 -0.2794)
							(mid -0.249642 -0.249642)
							(end -0.2794 -0.1778)
						)
						(arc
							(start -0.2794 0.1778)
							(mid -0.249642 0.249642)
							(end -0.1778 0.2794)
						)
						(arc
							(start 0.1778 0.2794)
							(mid 0.249642 0.249642)
							(end 0.2794 0.1778)
						)
						(arc
							(start 0.2794 -0.1778)
							(mid 0.249642 -0.249642)
							(end 0.1778 -0.2794)
						)
					)
					(width 0)
					(fill yes)
				)
			)
		)
		(pad "2" smd custom
			(at 0 0.4445 90)
			(size 0.1397 0.1397)
			(layers "F.Cu" "F.Mask" "F.Paste")
			(net "COMP_B_SEC_INS_N")
			(options
				(clearance outline)
				(anchor circle)
			)
			(primitives
				(gr_poly
					(pts
						(arc
							(start -0.1778 -0.2794)
							(mid -0.249642 -0.249642)
							(end -0.2794 -0.1778)
						)
						(arc
							(start -0.2794 0.1778)
							(mid -0.249642 0.249642)
							(end -0.1778 0.2794)
						)
						(arc
							(start 0.1778 0.2794)
							(mid 0.249642 0.249642)
							(end 0.2794 0.1778)
						)
						(arc
							(start 0.2794 -0.1778)
							(mid 0.249642 -0.249642)
							(end 0.1778 -0.2794)
						)
					)
					(width 0)
					(fill yes)
				)
			)
		)
	)
	(footprint ""
		(layer "F.Cu")
		(at 185.950098 -172.909992 -90)
		(property "Reference" "HDDSAS17"
			(at 0 0 270)
			(layer "F.SilkS")
			(hide yes)
			(effects
				(font
					(size 1.27 1.27)
				)
			)
		)
		(property "Value" "SKT-SAS15P-14P-45-GP"
			(at -20.7645 -8.9789 270)
			(unlocked yes)
			(layer "F.Fab")
			(hide yes)
			(effects
				(font
					(size 1.016 1.016)
					(thickness 0.1524)
				)
			)
		)
		(property "Device Type" "10120818-001C-TRLF"
			(at -20.7645 -10.5029 270)
			(unlocked yes)
			(layer "F.Fab")
			(hide yes)
			(effects
				(font
					(size 1.016 1.016)
					(thickness 0.1524)
				)
			)
		)
		(duplicate_pad_numbers_are_jumpers no)
		(fp_line
			(start 1.651 4.2926)
			(end 1.651 3.0099)
			(stroke
				(width 0.1524)
				(type default)
			)
			(layer "F.SilkS")
		)
		(fp_line
			(start 8.509 4.2926)
			(end 1.651 4.2926)
			(stroke
				(width 0.1524)
				(type default)
			)
			(layer "F.SilkS")
		)
		(fp_line
			(start -23.4188 3.0099)
			(end -23.4188 -3.2512)
			(stroke
				(width 0.1524)
				(type default)
			)
			(layer "F.SilkS")
		)
		(fp_line
			(start 1.651 3.0099)
			(end -23.4188 3.0099)
			(stroke
				(width 0.1524)
				(type default)
			)
			(layer "F.SilkS")
		)
		(fp_line
			(start 8.509 3.0099)
			(end 8.509 4.2926)
			(stroke
				(width 0.1524)
				(type default)
			)
			(layer "F.SilkS")
		)
		(fp_line
			(start 23.4188 3.0099)
			(end 8.509 3.0099)
			(stroke
				(width 0.1524)
				(type default)
			)
			(layer "F.SilkS")
		)
		(fp_line
			(start -23.4188 -3.2512)
			(end 23.4188 -3.2512)
			(stroke
				(width 0.1524)
				(type default)
			)
			(layer "F.SilkS")
		)
		(fp_line
			(start 23.4188 -3.2512)
			(end 23.4188 3.0099)
			(stroke
				(width 0.1524)
				(type default)
			)
			(layer "F.SilkS")
		)
		(fp_line
			(start 15.5067 -3.3401)
			(end 16.2687 -3.3401)
			(stroke
				(width 0.3302)
				(type default)
			)
			(layer "F.SilkS")
		)
		(fp_poly
			(pts
				(xy 15.868904 -3.230372) (xy 16.503904 -3.865372) (xy 15.233904 -3.865372)
			)
			(stroke
				(width 0)
				(type default)
			)
			(fill yes)
			(layer "F.SilkS")
		)
		(fp_poly
			(pts
				(xy -22.8727 -2.7559) (xy 22.8727 -2.7559) (xy 22.8727 2.7559) (xy 8.255 2.7559) (xy 8.255 3.5179)
				(xy 1.905 3.5179) (xy 1.905 2.7559) (xy -22.8727 2.7559)
			)
			(stroke
				(width 0)
				(type default)
			)
			(fill no)
			(layer "F.CrtYd")
		)
		(fp_poly
			(pts
				(xy 1.397 4.5466) (xy 1.397 3.2639) (xy -23.6728 3.2639) (xy -23.6728 -3.5052) (xy 23.6728 -3.5052)
				(xy 23.6728 -0.00635) (xy 22.8727 -0.00635) (xy 22.8727 -2.7559) (xy -22.8727 -2.7559) (xy -22.8727 2.7559)
				(xy 1.905 2.7559) (xy 1.905 3.5179) (xy 8.255 3.5179) (xy 8.255 2.7559) (xy 22.8727 2.7559) (xy 22.8727 0.00635)
				(xy 23.6728 0.00635) (xy 23.6728 3.2639) (xy 8.763 3.2639) (xy 8.763 4.5466)
			)
			(stroke
				(width 0)
				(type default)
			)
			(fill no)
			(layer "F.CrtYd")
		)
		(fp_poly
			(pts
				(xy 1.397 4.5466) (xy 1.397 3.2639) (xy -23.6728 3.2639) (xy -23.6728 -3.5052) (xy 23.6728 -3.5052)
				(xy 23.6728 3.2639) (xy 8.763 3.2639) (xy 8.763 4.5466)
			)
			(stroke
				(width 0)
				(type default)
			)
			(fill no)
			(layer "F.Fab")
		)
		(pad "" np_thru_hole circle
			(at -18.874994 0 270)
			(size 0.254 0.254)
			(drill 1.3462)
			(layers "*.Cu" "*.Mask")
			(clearance 0.9017)
			(thermal_gap 0.9017)
		)
		(pad "" np_thru_hole circle
			(at 18.874994 0 270)
			(size 0.254 0.254)
			(drill 0.9398)
			(layers "*.Cu" "*.Mask")
			(clearance 0.6985)
			(thermal_gap 0.6985)
		)
		(pad "G1" smd rect
			(at 21.874988 0 270)
			(size 2.5908 2.5908)
			(layers "F.Cu" "F.Mask" "F.Paste")
			(net "GND")
		)
		(pad "G2" smd rect
			(at -21.874988 0 270)
			(size 2.5908 2.5908)
			(layers "F.Cu" "F.Mask" "F.Paste")
			(net "GND")
		)
		(pad "P1" smd rect
			(at 1.905 -1.82499 270)
			(size 0.6096 2.3622)
			(layers "F.Cu" "F.Mask" "F.Paste")
			(net "Net_2131")
		)
		(pad "P2" smd rect
			(at 0.635 -1.82499 270)
			(size 0.6096 2.3622)
			(layers "F.Cu" "F.Mask" "F.Paste")
			(net "Net_2132")
		)
		(pad "P3" smd rect
			(at -0.635 -1.82499 270)
			(size 0.6096 2.3622)
			(layers "F.Cu" "F.Mask" "F.Paste")
			(net "Net_2133")
		)
		(pad "P4" smd rect
			(at -1.905 -1.82499 270)
			(size 0.6096 2.3622)
			(layers "F.Cu" "F.Mask" "F.Paste")
			(net "GND")
		)
		(pad "P5" smd rect
			(at -3.175 -1.82499 270)
			(size 0.6096 2.3622)
			(layers "F.Cu" "F.Mask" "F.Paste")
			(net "HDD_PRSNT_17")
		)
		(pad "P6" smd rect
			(at -4.445 -1.82499 270)
			(size 0.6096 2.3622)
			(layers "F.Cu" "F.Mask" "F.Paste")
			(net "GND")
		)
		(pad "P7" smd rect
			(at -5.715 -1.82499 270)
			(size 0.6096 2.3622)
			(layers "F.Cu" "F.Mask" "F.Paste")
			(net "5V_PRE_17")
		)
		(pad "P8" smd rect
			(at -6.985 -1.82499 270)
			(size 0.6096 2.3622)
			(layers "F.Cu" "F.Mask" "F.Paste")
			(net "P5V_HDD17")
		)
		(pad "P9" smd rect
			(at -8.255 -1.82499 270)
			(size 0.6096 2.3622)
			(layers "F.Cu" "F.Mask" "F.Paste")
			(net "P5V_HDD17")
		)
		(pad "P10" smd rect
			(at -9.525 -1.82499 270)
			(size 0.6096 2.3622)
			(layers "F.Cu" "F.Mask" "F.Paste")
			(net "GND")
		)
		(pad "P11" smd rect
			(at -10.795 -1.82499 270)
			(size 0.6096 2.3622)
			(layers "F.Cu" "F.Mask" "F.Paste")
			(net "ACT_HDD_17")
		)
		(pad "P12" smd rect
			(at -12.065 -1.82499 270)
			(size 0.6096 2.3622)
			(layers "F.Cu" "F.Mask" "F.Paste")
			(net "GND")
		)
		(pad "P13" smd rect
			(at -13.335 -1.82499 270)
			(size 0.6096 2.3622)
			(layers "F.Cu" "F.Mask" "F.Paste")
			(net "12V_PRE_17")
		)
		(pad "P14" smd rect
			(at -14.605 -1.82499 270)
			(size 0.6096 2.3622)
			(layers "F.Cu" "F.Mask" "F.Paste")
			(net "P12V_HDD17")
		)
		(pad "P15" smd rect
			(at -15.875 -1.82499 270)
			(size 0.6096 2.3622)
			(layers "F.Cu" "F.Mask" "F.Paste")
			(net "P12V_HDD17")
		)
		(pad "S1" smd rect
			(at 15.875 -1.82499 270)
			(size 0.6096 2.3622)
			(layers "F.Cu" "F.Mask" "F.Paste")
			(net "GND")
		)
		(pad "S2" smd rect
			(at 14.605 -1.82499 270)
			(size 0.6096 2.3622)
			(layers "F.Cu" "F.Mask" "F.Paste")
			(net "SAS_HDD_RX_P17")
		)
		(pad "S3" smd rect
			(at 13.335 -1.82499 270)
			(size 0.6096 2.3622)
			(layers "F.Cu" "F.Mask" "F.Paste")
			(net "SAS_HDD_RX_N17")
		)
		(pad "S4" smd rect
			(at 12.065 -1.82499 270)
			(size 0.6096 2.3622)
			(layers "F.Cu" "F.Mask" "F.Paste")
			(net "GND")
		)
		(pad "S5" smd rect
			(at 10.795 -1.82499 270)
			(size 0.6096 2.3622)
			(layers "F.Cu" "F.Mask" "F.Paste")
			(net "PHY_DRV_A_TO_SCC_A_17_DN")
		)
		(pad "S6" smd rect
			(at 9.525 -1.82499 270)
			(size 0.6096 2.3622)
			(layers "F.Cu" "F.Mask" "F.Paste")
			(net "PHY_DRV_A_TO_SCC_A_17_DP")
		)
		(pad "S7" smd rect
			(at 8.255 -1.82499 270)
			(size 0.6096 2.3622)
			(layers "F.Cu" "F.Mask" "F.Paste")
			(net "GND")
		)
		(pad "S8" smd rect
			(at 7.480046 2.845054 270)
			(size 0.508 2.3622)
			(layers "F.Cu" "F.Mask" "F.Paste")
			(net "GND")
		)
		(pad "S9" smd rect
			(at 6.679946 2.845054 270)
			(size 0.508 2.3622)
			(layers "F.Cu" "F.Mask" "F.Paste")
			(net "Net_454")
		)
		(pad "S10" smd rect
			(at 5.8801 2.845054 270)
			(size 0.508 2.3622)
			(layers "F.Cu" "F.Mask" "F.Paste")
			(net "Net_346")
		)
		(pad "S11" smd rect
			(at 5.08 2.845054 270)
			(size 0.508 2.3622)
			(layers "F.Cu" "F.Mask" "F.Paste")
			(net "GND")
		)
		(pad "S12" smd rect
			(at 4.2799 2.845054 270)
			(size 0.508 2.3622)
			(layers "F.Cu" "F.Mask" "F.Paste")
			(net "Net_382")
		)
		(pad "S13" smd rect
			(at 3.480054 2.845054 270)
			(size 0.508 2.3622)
			(layers "F.Cu" "F.Mask" "F.Paste")
			(net "Net_418")
		)
		(pad "S14" smd rect
			(at 2.679954 2.845054 270)
			(size 0.508 2.3622)
			(layers "F.Cu" "F.Mask" "F.Paste")
			(net "GND")
		)
		(zone
			(layer "F.Cu")
			(hatch none 0.5)
			(connect_pads
				(clearance 0)
			)
			(min_thickness 0.25)
			(keepout
				(tracks not_allowed)
				(vias allowed)
				(pads allowed)
				(copperpour not_allowed)
				(footprints allowed)
			)
			(placement
				(enabled no)
				(sheetname "")
			)
			(fill
				(thermal_gap 0.5)
				(thermal_bridge_width 0.5)
				(island_removal_mode 0)
			)
			(polygon
				(pts
					(xy 189.607698 -189.648592) (xy 182.533798 -189.648592) (xy 182.533798 -196.582792) (xy 183.638698 -196.582792)
					(xy 183.638698 -192.467992) (xy 188.261498 -192.467992) (xy 188.261498 -196.582792) (xy 189.607698 -196.582792)
				)
			)
		)
		(zone
			(layer "F.Cu")
			(hatch none 0.5)
			(connect_pads
				(clearance 0)
			)
			(min_thickness 0.25)
			(keepout
				(tracks allowed)
				(vias not_allowed)
				(pads allowed)
				(copperpour not_allowed)
				(footprints allowed)
			)
			(placement
				(enabled no)
				(sheetname "")
			)
			(fill
				(thermal_gap 0.5)
				(thermal_bridge_width 0.5)
				(island_removal_mode 0)
			)
			(polygon
				(pts
					(xy 189.607698 -189.648592) (xy 182.533798 -189.648592) (xy 182.533798 -196.582792) (xy 183.638698 -196.582792)
					(xy 183.638698 -192.467992) (xy 188.261498 -192.467992) (xy 188.261498 -196.582792) (xy 189.607698 -196.582792)
				)
			)
		)
		(zone
			(layer "F.Cu")
			(hatch none 0.5)
			(connect_pads
				(clearance 0)
			)
			(min_thickness 0.25)
			(keepout
				(tracks allowed)
				(vias not_allowed)
				(pads allowed)
				(copperpour not_allowed)
				(footprints allowed)
			)
			(placement
				(enabled no)
				(sheetname "")
			)
			(fill
				(thermal_gap 0.5)
				(thermal_bridge_width 0.5)
				(island_removal_mode 0)
			)
			(polygon
				(pts
					(xy 189.607698 -156.171392) (xy 182.533798 -156.171392) (xy 182.533798 -149.237192) (xy 183.638698 -149.237192)
					(xy 183.638698 -153.351992) (xy 188.261498 -153.351992) (xy 188.261498 -149.237192) (xy 189.607698 -149.237192)
				)
			)
		)
		(zone
			(layer "F.Cu")
			(hatch none 0.5)
			(connect_pads
				(clearance 0)
			)
			(min_thickness 0.25)
			(keepout
				(tracks not_allowed)
				(vias allowed)
				(pads allowed)
				(copperpour not_allowed)
				(footprints allowed)
			)
			(placement
				(enabled no)
				(sheetname "")
			)
			(fill
				(thermal_gap 0.5)
				(thermal_bridge_width 0.5)
				(island_removal_mode 0)
			)
			(polygon
				(pts
					(xy 189.607698 -156.171392) (xy 182.533798 -156.171392) (xy 182.533798 -149.237192) (xy 183.638698 -149.237192)
					(xy 183.638698 -153.351992) (xy 188.261498 -153.351992) (xy 188.261498 -149.237192) (xy 189.607698 -149.237192)
				)
			)
		)
		(zone
			(layers "F.Cu" "B.Cu" "In1.Cu" "In2.Cu" "In3.Cu" "In4.Cu" "In5.Cu" "In6.Cu"
				"In7.Cu" "In8.Cu" "In9.Cu" "In10.Cu"
			)
			(hatch none 0.5)
			(connect_pads
				(clearance 0)
			)
			(min_thickness 0.25)
			(keepout
				(tracks not_allowed)
				(vias allowed)
				(pads allowed)
				(copperpour not_allowed)
				(footprints allowed)
			)
			(placement
				(enabled no)
				(sheetname "")
			)
			(fill
				(thermal_gap 0.5)
				(thermal_bridge_width 0.5)
				(island_removal_mode 0)
			)
			(polygon
				(pts
					(arc
						(start 186.724798 -154.034998)
						(mid 185.175398 -154.034998)
						(end 186.724798 -154.034998)
					)
				)
			)
		)
		(zone
			(layers "F.Cu" "B.Cu" "In1.Cu" "In2.Cu" "In3.Cu" "In4.Cu" "In5.Cu" "In6.Cu"
				"In7.Cu" "In8.Cu" "In9.Cu" "In10.Cu"
			)
			(hatch none 0.5)
			(connect_pads
				(clearance 0)
			)
			(min_thickness 0.25)
			(keepout
				(tracks not_allowed)
				(vias allowed)
				(pads allowed)
				(copperpour not_allowed)
				(footprints allowed)
			)
			(placement
				(enabled no)
				(sheetname "")
			)
			(fill
				(thermal_gap 0.5)
				(thermal_bridge_width 0.5)
				(island_removal_mode 0)
			)
			(polygon
				(pts
					(arc
						(start 186.927998 -191.784986)
						(mid 184.972198 -191.784986)
						(end 186.927998 -191.784986)
					)
				)
			)
		)
	)
	(footprint ""
		(layer "F.Cu")
		(at 450.815202 -259.01015)
		(property "Reference" "R1243"
			(at 0 0 0)
			(layer "F.SilkS")
			(hide yes)
			(effects
				(font
					(size 1.27 1.27)
				)
			)
		)
		(property "Value" "49K9R2F-L-GP"
			(at 0.064008 -3.993896 0)
			(unlocked yes)
			(layer "F.Fab")
			(hide yes)
			(effects
				(font
					(size 1.016 1.016)
					(thickness 0.1524)
				)
			)
		)
		(property "Device Type" "R402H16"
			(at 0.064008 -5.517896 0)
			(unlocked yes)
			(layer "F.Fab")
			(hide yes)
			(effects
				(font
					(size 1.016 1.016)
					(thickness 0.1524)
				)
			)
		)
		(duplicate_pad_numbers_are_jumpers no)
		(fp_line
			(start -0.508 -0.9398)
			(end -0.508 0.9398)
			(stroke
				(width 0.1524)
				(type default)
			)
			(layer "F.SilkS")
		)
		(fp_line
			(start 0.508 -0.9398)
			(end -0.508 -0.9398)
			(stroke
				(width 0.1524)
				(type default)
			)
			(layer "F.SilkS")
		)
		(fp_rect
			(start -0.508 0.9398)
			(end 0.508 -0.9398)
			(stroke
				(width 0)
				(type default)
			)
			(fill no)
			(layer "F.CrtYd")
		)
		(fp_rect
			(start -0.508 0.9398)
			(end 0.508 -0.9398)
			(stroke
				(width 0)
				(type default)
			)
			(fill no)
			(layer "F.Fab")
		)
		(pad "1" smd custom
			(at 0 -0.4445)
			(size 0.1397 0.1397)
			(layers "F.Cu" "F.Mask" "F.Paste")
			(net "P12V_A")
			(options
				(clearance outline)
				(anchor circle)
			)
			(primitives
				(gr_poly
					(pts
						(arc
							(start -0.1778 -0.2794)
							(mid -0.249642 -0.249642)
							(end -0.2794 -0.1778)
						)
						(arc
							(start -0.2794 0.1778)
							(mid -0.249642 0.249642)
							(end -0.1778 0.2794)
						)
						(arc
							(start 0.1778 0.2794)
							(mid 0.249642 0.249642)
							(end 0.2794 0.1778)
						)
						(arc
							(start 0.2794 -0.1778)
							(mid 0.249642 -0.249642)
							(end 0.1778 -0.2794)
						)
					)
					(width 0)
					(fill yes)
				)
			)
		)
		(pad "2" smd custom
			(at 0 0.4445)
			(size 0.1397 0.1397)
			(layers "F.Cu" "F.Mask" "F.Paste")
			(net "P5V_C_EN_R")
			(options
				(clearance outline)
				(anchor circle)
			)
			(primitives
				(gr_poly
					(pts
						(arc
							(start -0.1778 -0.2794)
							(mid -0.249642 -0.249642)
							(end -0.2794 -0.1778)
						)
						(arc
							(start -0.2794 0.1778)
							(mid -0.249642 0.249642)
							(end -0.1778 0.2794)
						)
						(arc
							(start 0.1778 0.2794)
							(mid 0.249642 0.249642)
							(end 0.2794 0.1778)
						)
						(arc
							(start 0.2794 -0.1778)
							(mid 0.249642 -0.249642)
							(end 0.1778 -0.2794)
						)
					)
					(width 0)
					(fill yes)
				)
			)
		)
	)
	(footprint ""
		(layer "F.Cu")
		(at 210.861148 -11.162538 90)
		(property "Reference" "C40"
			(at 0 0 90)
			(layer "F.SilkS")
			(hide yes)
			(effects
				(font
					(size 1.27 1.27)
				)
			)
		)
		(property "Value" "SC10U16V5KX-7-GP-U"
			(at -0.0762 -6.1214 90)
			(unlocked yes)
			(layer "F.Fab")
			(hide yes)
			(effects
				(font
					(size 1.016 1.016)
					(thickness 0.1524)
				)
			)
		)
		(property "Device Type" "C805H58"
			(at -0.0762 -8.1534 90)
			(unlocked yes)
			(layer "F.Fab")
			(hide yes)
			(effects
				(font
					(size 1.016 1.016)
					(thickness 0.1524)
				)
			)
		)
		(duplicate_pad_numbers_are_jumpers no)
		(fp_line
			(start 0.635 0)
			(end -0.635 0)
			(stroke
				(width 0.508)
				(type default)
			)
			(layer "F.SilkS")
		)
		(fp_rect
			(start -0.9652 1.778)
			(end 0.9652 -1.778)
			(stroke
				(width 0)
				(type default)
			)
			(fill no)
			(layer "F.CrtYd")
		)
		(fp_poly
			(pts
				(xy -0.9652 -1.778) (xy 0.9652 -1.778) (xy 0.9652 1.778) (xy -0.9652 1.778)
			)
			(stroke
				(width 0)
				(type default)
			)
			(fill no)
			(layer "F.Fab")
		)
		(pad "1" smd rect
			(at 0 -0.9652 90)
			(size 1.397 1.143)
			(layers "F.Cu" "F.Mask" "F.Paste")
			(net "P5V_A_2")
		)
		(pad "2" smd rect
			(at 0 0.9652 90)
			(size 1.397 1.143)
			(layers "F.Cu" "F.Mask" "F.Paste")
			(net "GND")
		)
	)
	(footprint ""
		(layer "F.Cu")
		(at 430.387252 -275.735542 180)
		(property "Reference" "R354"
			(at 0 0 180)
			(layer "F.SilkS")
			(hide yes)
			(effects
				(font
					(size 1.27 1.27)
				)
			)
		)
		(property "Value" "0R2J-2-GP"
			(at 0.064008 -3.993896 180)
			(unlocked yes)
			(layer "F.Fab")
			(hide yes)
			(effects
				(font
					(size 1.016 1.016)
					(thickness 0.1524)
				)
			)
		)
		(property "Device Type" "R402H16"
			(at 0.064008 -5.517896 180)
			(unlocked yes)
			(layer "F.Fab")
			(hide yes)
			(effects
				(font
					(size 1.016 1.016)
					(thickness 0.1524)
				)
			)
		)
		(duplicate_pad_numbers_are_jumpers no)
		(fp_line
			(start 0.508 -0.9398)
			(end -0.508 -0.9398)
			(stroke
				(width 0.1524)
				(type default)
			)
			(layer "F.SilkS")
		)
		(fp_line
			(start -0.508 -0.9398)
			(end -0.508 0.9398)
			(stroke
				(width 0.1524)
				(type default)
			)
			(layer "F.SilkS")
		)
		(fp_rect
			(start -0.508 0.9398)
			(end 0.508 -0.9398)
			(stroke
				(width 0)
				(type default)
			)
			(fill no)
			(layer "F.CrtYd")
		)
		(fp_rect
			(start -0.508 0.9398)
			(end 0.508 -0.9398)
			(stroke
				(width 0)
				(type default)
			)
			(fill no)
			(layer "F.Fab")
		)
		(pad "1" smd custom
			(at 0 -0.4445 180)
			(size 0.1397 0.1397)
			(layers "F.Cu" "F.Mask" "F.Paste")
			(net "SW_HDD_G9")
			(options
				(clearance outline)
				(anchor circle)
			)
			(primitives
				(gr_poly
					(pts
						(arc
							(start -0.1778 -0.2794)
							(mid -0.249642 -0.249642)
							(end -0.2794 -0.1778)
						)
						(arc
							(start -0.2794 0.1778)
							(mid -0.249642 0.249642)
							(end -0.1778 0.2794)
						)
						(arc
							(start 0.1778 0.2794)
							(mid 0.249642 0.249642)
							(end 0.2794 0.1778)
						)
						(arc
							(start 0.2794 -0.1778)
							(mid 0.249642 -0.249642)
							(end 0.1778 -0.2794)
						)
					)
					(width 0)
					(fill yes)
				)
			)
		)
		(pad "2" smd custom
			(at 0 0.4445 180)
			(size 0.1397 0.1397)
			(layers "F.Cu" "F.Mask" "F.Paste")
			(net "SW_HDD_R9")
			(options
				(clearance outline)
				(anchor circle)
			)
			(primitives
				(gr_poly
					(pts
						(arc
							(start -0.1778 -0.2794)
							(mid -0.249642 -0.249642)
							(end -0.2794 -0.1778)
						)
						(arc
							(start -0.2794 0.1778)
							(mid -0.249642 0.249642)
							(end -0.1778 0.2794)
						)
						(arc
							(start 0.1778 0.2794)
							(mid 0.249642 0.249642)
							(end 0.2794 0.1778)
						)
						(arc
							(start 0.2794 -0.1778)
							(mid 0.249642 -0.249642)
							(end 0.1778 -0.2794)
						)
					)
					(width 0)
					(fill yes)
				)
			)
		)
	)
	(footprint ""
		(layer "F.Cu")
		(at 464.9089 -57.851294 90)
		(property "Reference" "C491"
			(at 0 0 90)
			(layer "F.SilkS")
			(hide yes)
			(effects
				(font
					(size 1.27 1.27)
				)
			)
		)
		(property "Value" "SCD033U25V2KX-GP"
			(at 1.1811 -2.7051 90)
			(unlocked yes)
			(layer "F.Fab")
			(hide yes)
			(effects
				(font
					(size 1.016 1.016)
					(thickness 0.1524)
				)
			)
		)
		(property "Device Type" "C402H22"
			(at 1.1811 -4.2291 90)
			(unlocked yes)
			(layer "F.Fab")
			(hide yes)
			(effects
				(font
					(size 1.016 1.016)
					(thickness 0.1524)
				)
			)
		)
		(duplicate_pad_numbers_are_jumpers no)
		(fp_rect
			(start -0.4318 0.9525)
			(end 0.4318 -0.9525)
			(stroke
				(width 0)
				(type default)
			)
			(fill no)
			(layer "F.CrtYd")
		)
		(fp_rect
			(start -0.4318 0.9525)
			(end 0.4318 -0.9525)
			(stroke
				(width 0)
				(type default)
			)
			(fill no)
			(layer "F.Fab")
		)
		(pad "1" smd custom
			(at 0 -0.4445 90)
			(size 0.1524 0.1524)
			(layers "F.Cu" "F.Mask" "F.Paste")
			(net "P12V_A")
			(options
				(clearance outline)
				(anchor circle)
			)
			(primitives
				(gr_poly
					(pts
						(arc
							(start 0.3048 -0.2032)
							(mid 0.275042 -0.275042)
							(end 0.2032 -0.3048)
						)
						(arc
							(start -0.2032 -0.3048)
							(mid -0.275042 -0.275042)
							(end -0.3048 -0.2032)
						)
						(arc
							(start -0.3048 0.2032)
							(mid -0.275042 0.275042)
							(end -0.2032 0.3048)
						)
						(arc
							(start 0.2032 0.3048)
							(mid 0.275042 0.275042)
							(end 0.3048 0.2032)
						)
					)
					(width 0)
					(fill yes)
				)
			)
		)
		(pad "2" smd custom
			(at 0 0.4445 90)
			(size 0.1524 0.1524)
			(layers "F.Cu" "F.Mask" "F.Paste")
			(net "SW_HDD_N34")
			(options
				(clearance outline)
				(anchor circle)
			)
			(primitives
				(gr_poly
					(pts
						(arc
							(start 0.3048 -0.2032)
							(mid 0.275042 -0.275042)
							(end 0.2032 -0.3048)
						)
						(arc
							(start -0.2032 -0.3048)
							(mid -0.275042 -0.275042)
							(end -0.3048 -0.2032)
						)
						(arc
							(start -0.3048 0.2032)
							(mid -0.275042 0.275042)
							(end -0.2032 0.3048)
						)
						(arc
							(start 0.2032 0.3048)
							(mid 0.275042 0.275042)
							(end 0.3048 0.2032)
						)
					)
					(width 0)
					(fill yes)
				)
			)
		)
	)
	(footprint ""
		(layer "F.Cu")
		(at 99.228148 -295.064942 90)
		(property "Reference" "R180"
			(at 0 0 90)
			(layer "F.SilkS")
			(hide yes)
			(effects
				(font
					(size 1.27 1.27)
				)
			)
		)
		(property "Value" "220R3F-1-GP"
			(at -0.0254 -2.5146 90)
			(unlocked yes)
			(layer "F.Fab")
			(hide yes)
			(effects
				(font
					(size 1.016 1.016)
					(thickness 0.1524)
				)
			)
		)
		(property "Device Type" "R603H22"
			(at -0.0254 -4.0386 90)
			(unlocked yes)
			(layer "F.Fab")
			(hide yes)
			(effects
				(font
					(size 1.016 1.016)
					(thickness 0.1524)
				)
			)
		)
		(duplicate_pad_numbers_are_jumpers no)
		(fp_line
			(start 0.2032 0)
			(end 0.4826 0)
			(stroke
				(width 0.2032)
				(type default)
			)
			(layer "F.SilkS")
		)
		(fp_line
			(start -0.4826 0)
			(end -0.2032 0)
			(stroke
				(width 0.2032)
				(type default)
			)
			(layer "F.SilkS")
		)
		(fp_rect
			(start -0.5842 1.3335)
			(end 0.5842 -1.3335)
			(stroke
				(width 0)
				(type default)
			)
			(fill no)
			(layer "F.CrtYd")
		)
		(fp_rect
			(start -0.5842 1.3335)
			(end 0.5842 -1.3335)
			(stroke
				(width 0)
				(type default)
			)
			(fill no)
			(layer "F.Fab")
		)
		(pad "1" smd custom
			(at 0 -0.762 90)
			(size 0.2159 0.2159)
			(layers "F.Cu" "F.Mask" "F.Paste")
			(net "HDD_PRSNT_2")
			(options
				(clearance outline)
				(anchor circle)
			)
			(primitives
				(gr_poly
					(pts
						(arc
							(start -0.3302 -0.4318)
							(mid -0.402042 -0.402042)
							(end -0.4318 -0.3302)
						)
						(arc
							(start -0.4318 0.3302)
							(mid -0.402042 0.402042)
							(end -0.3302 0.4318)
						)
						(arc
							(start 0.3302 0.4318)
							(mid 0.402042 0.402042)
							(end 0.4318 0.3302)
						)
						(arc
							(start 0.4318 -0.3302)
							(mid 0.402042 -0.402042)
							(end 0.3302 -0.4318)
						)
					)
					(width 0)
					(fill yes)
				)
			)
		)
		(pad "2" smd custom
			(at 0 0.762 90)
			(size 0.2159 0.2159)
			(layers "F.Cu" "F.Mask" "F.Paste")
			(net "DRIVE_A_2_INS")
			(options
				(clearance outline)
				(anchor circle)
			)
			(primitives
				(gr_poly
					(pts
						(arc
							(start -0.3302 -0.4318)
							(mid -0.402042 -0.402042)
							(end -0.4318 -0.3302)
						)
						(arc
							(start -0.4318 0.3302)
							(mid -0.402042 0.402042)
							(end -0.3302 0.4318)
						)
						(arc
							(start 0.3302 0.4318)
							(mid 0.402042 0.402042)
							(end 0.4318 0.3302)
						)
						(arc
							(start 0.4318 -0.3302)
							(mid 0.402042 -0.402042)
							(end 0.3302 -0.4318)
						)
					)
					(width 0)
					(fill yes)
				)
			)
		)
	)
	(footprint ""
		(layer "F.Cu")
		(at 367.338102 -42.585894 180)
		(property "Reference" "R853"
			(at 0 0 180)
			(layer "F.SilkS")
			(hide yes)
			(effects
				(font
					(size 1.27 1.27)
				)
			)
		)
		(property "Value" "0R2J-2-GP"
			(at 0.064008 -3.993896 180)
			(unlocked yes)
			(layer "F.Fab")
			(hide yes)
			(effects
				(font
					(size 1.016 1.016)
					(thickness 0.1524)
				)
			)
		)
		(property "Device Type" "R402H16"
			(at 0.064008 -5.517896 180)
			(unlocked yes)
			(layer "F.Fab")
			(hide yes)
			(effects
				(font
					(size 1.016 1.016)
					(thickness 0.1524)
				)
			)
		)
		(duplicate_pad_numbers_are_jumpers no)
		(fp_line
			(start 0.508 -0.9398)
			(end -0.508 -0.9398)
			(stroke
				(width 0.1524)
				(type default)
			)
			(layer "F.SilkS")
		)
		(fp_line
			(start -0.508 -0.9398)
			(end -0.508 0.9398)
			(stroke
				(width 0.1524)
				(type default)
			)
			(layer "F.SilkS")
		)
		(fp_rect
			(start -0.508 0.9398)
			(end 0.508 -0.9398)
			(stroke
				(width 0)
				(type default)
			)
			(fill no)
			(layer "F.CrtYd")
		)
		(fp_rect
			(start -0.508 0.9398)
			(end 0.508 -0.9398)
			(stroke
				(width 0)
				(type default)
			)
			(fill no)
			(layer "F.Fab")
		)
		(pad "1" smd custom
			(at 0 -0.4445 180)
			(size 0.1397 0.1397)
			(layers "F.Cu" "F.Mask" "F.Paste")
			(net "DRIVE_A_31_PWR")
			(options
				(clearance outline)
				(anchor circle)
			)
			(primitives
				(gr_poly
					(pts
						(arc
							(start -0.1778 -0.2794)
							(mid -0.249642 -0.249642)
							(end -0.2794 -0.1778)
						)
						(arc
							(start -0.2794 0.1778)
							(mid -0.249642 0.249642)
							(end -0.1778 0.2794)
						)
						(arc
							(start 0.1778 0.2794)
							(mid 0.249642 0.249642)
							(end 0.2794 0.1778)
						)
						(arc
							(start 0.2794 -0.1778)
							(mid 0.249642 -0.249642)
							(end 0.1778 -0.2794)
						)
					)
					(width 0)
					(fill yes)
				)
			)
		)
		(pad "2" smd custom
			(at 0 0.4445 180)
			(size 0.1397 0.1397)
			(layers "F.Cu" "F.Mask" "F.Paste")
			(net "SW_PWR_R_HDD31")
			(options
				(clearance outline)
				(anchor circle)
			)
			(primitives
				(gr_poly
					(pts
						(arc
							(start -0.1778 -0.2794)
							(mid -0.249642 -0.249642)
							(end -0.2794 -0.1778)
						)
						(arc
							(start -0.2794 0.1778)
							(mid -0.249642 0.249642)
							(end -0.1778 0.2794)
						)
						(arc
							(start 0.1778 0.2794)
							(mid 0.249642 0.249642)
							(end 0.2794 0.1778)
						)
						(arc
							(start 0.2794 -0.1778)
							(mid 0.249642 -0.249642)
							(end 0.1778 -0.2794)
						)
					)
					(width 0)
					(fill yes)
				)
			)
		)
	)
	(footprint ""
		(layer "F.Cu")
		(at 346.368116 -285.33471 90)
		(property "Reference" "R578"
			(at 0 0 90)
			(layer "F.SilkS")
			(hide yes)
			(effects
				(font
					(size 1.27 1.27)
				)
			)
		)
		(property "Value" "4K7R2J-2-GP"
			(at 0.064008 -3.993896 90)
			(unlocked yes)
			(layer "F.Fab")
			(hide yes)
			(effects
				(font
					(size 1.016 1.016)
					(thickness 0.1524)
				)
			)
		)
		(property "Device Type" "R402H16"
			(at 0.064008 -5.517896 90)
			(unlocked yes)
			(layer "F.Fab")
			(hide yes)
			(effects
				(font
					(size 1.016 1.016)
					(thickness 0.1524)
				)
			)
		)
		(duplicate_pad_numbers_are_jumpers no)
		(fp_line
			(start 0.508 -0.9398)
			(end -0.508 -0.9398)
			(stroke
				(width 0.1524)
				(type default)
			)
			(layer "F.SilkS")
		)
		(fp_line
			(start -0.508 -0.9398)
			(end -0.508 0.9398)
			(stroke
				(width 0.1524)
				(type default)
			)
			(layer "F.SilkS")
		)
		(fp_rect
			(start -0.508 0.9398)
			(end 0.508 -0.9398)
			(stroke
				(width 0)
				(type default)
			)
			(fill no)
			(layer "F.CrtYd")
		)
		(fp_rect
			(start -0.508 0.9398)
			(end 0.508 -0.9398)
			(stroke
				(width 0)
				(type default)
			)
			(fill no)
			(layer "F.Fab")
		)
		(pad "1" smd custom
			(at 0 -0.4445 90)
			(size 0.1397 0.1397)
			(layers "F.Cu" "F.Mask" "F.Paste")
			(net "DRIVE_B_31_ACT")
			(options
				(clearance outline)
				(anchor circle)
			)
			(primitives
				(gr_poly
					(pts
						(arc
							(start -0.1778 -0.2794)
							(mid -0.249642 -0.249642)
							(end -0.2794 -0.1778)
						)
						(arc
							(start -0.2794 0.1778)
							(mid -0.249642 0.249642)
							(end -0.1778 0.2794)
						)
						(arc
							(start 0.1778 0.2794)
							(mid 0.249642 0.249642)
							(end 0.2794 0.1778)
						)
						(arc
							(start 0.2794 -0.1778)
							(mid 0.249642 -0.249642)
							(end 0.1778 -0.2794)
						)
					)
					(width 0)
					(fill yes)
				)
			)
		)
		(pad "2" smd custom
			(at 0 0.4445 90)
			(size 0.1397 0.1397)
			(layers "F.Cu" "F.Mask" "F.Paste")
			(net "GND")
			(options
				(clearance outline)
				(anchor circle)
			)
			(primitives
				(gr_poly
					(pts
						(arc
							(start -0.1778 -0.2794)
							(mid -0.249642 -0.249642)
							(end -0.2794 -0.1778)
						)
						(arc
							(start -0.2794 0.1778)
							(mid -0.249642 0.249642)
							(end -0.1778 0.2794)
						)
						(arc
							(start 0.1778 0.2794)
							(mid 0.249642 0.249642)
							(end 0.2794 0.1778)
						)
						(arc
							(start 0.2794 -0.1778)
							(mid 0.249642 -0.249642)
							(end 0.1778 -0.2794)
						)
					)
					(width 0)
					(fill yes)
				)
			)
		)
	)
	(footprint ""
		(layer "F.Cu")
		(at 257.173476 -261.35076 180)
		(property "Reference" "R53"
			(at 0 0 180)
			(layer "F.SilkS")
			(hide yes)
			(effects
				(font
					(size 1.27 1.27)
				)
			)
		)
		(property "Value" "4K7R2F-GP"
			(at 0.064008 -3.993896 180)
			(unlocked yes)
			(layer "F.Fab")
			(hide yes)
			(effects
				(font
					(size 1.016 1.016)
					(thickness 0.1524)
				)
			)
		)
		(property "Device Type" "R402H16"
			(at 0.064008 -5.517896 180)
			(unlocked yes)
			(layer "F.Fab")
			(hide yes)
			(effects
				(font
					(size 1.016 1.016)
					(thickness 0.1524)
				)
			)
		)
		(duplicate_pad_numbers_are_jumpers no)
		(fp_line
			(start 0.508 -0.9398)
			(end -0.508 -0.9398)
			(stroke
				(width 0.1524)
				(type default)
			)
			(layer "F.SilkS")
		)
		(fp_line
			(start -0.508 -0.9398)
			(end -0.508 0.9398)
			(stroke
				(width 0.1524)
				(type default)
			)
			(layer "F.SilkS")
		)
		(fp_rect
			(start -0.508 0.9398)
			(end 0.508 -0.9398)
			(stroke
				(width 0)
				(type default)
			)
			(fill no)
			(layer "F.CrtYd")
		)
		(fp_rect
			(start -0.508 0.9398)
			(end 0.508 -0.9398)
			(stroke
				(width 0)
				(type default)
			)
			(fill no)
			(layer "F.Fab")
		)
		(pad "1" smd custom
			(at 0 -0.4445 180)
			(size 0.1397 0.1397)
			(layers "F.Cu" "F.Mask" "F.Paste")
			(net "IO_EXP6_A0")
			(options
				(clearance outline)
				(anchor circle)
			)
			(primitives
				(gr_poly
					(pts
						(arc
							(start -0.1778 -0.2794)
							(mid -0.249642 -0.249642)
							(end -0.2794 -0.1778)
						)
						(arc
							(start -0.2794 0.1778)
							(mid -0.249642 0.249642)
							(end -0.1778 0.2794)
						)
						(arc
							(start 0.1778 0.2794)
							(mid 0.249642 0.249642)
							(end 0.2794 0.1778)
						)
						(arc
							(start 0.2794 -0.1778)
							(mid 0.249642 -0.249642)
							(end 0.1778 -0.2794)
						)
					)
					(width 0)
					(fill yes)
				)
			)
		)
		(pad "2" smd custom
			(at 0 0.4445 180)
			(size 0.1397 0.1397)
			(layers "F.Cu" "F.Mask" "F.Paste")
			(net "GND")
			(options
				(clearance outline)
				(anchor circle)
			)
			(primitives
				(gr_poly
					(pts
						(arc
							(start -0.1778 -0.2794)
							(mid -0.249642 -0.249642)
							(end -0.2794 -0.1778)
						)
						(arc
							(start -0.2794 0.1778)
							(mid -0.249642 0.249642)
							(end -0.1778 0.2794)
						)
						(arc
							(start 0.1778 0.2794)
							(mid 0.249642 0.249642)
							(end 0.2794 0.1778)
						)
						(arc
							(start 0.2794 -0.1778)
							(mid 0.249642 -0.249642)
							(end 0.1778 -0.2794)
						)
					)
					(width 0)
					(fill yes)
				)
			)
		)
	)
	(footprint ""
		(layer "F.Cu")
		(at 132.201666 -142.675102)
		(property "Reference" "R1294"
			(at 0 0 0)
			(layer "F.SilkS")
			(hide yes)
			(effects
				(font
					(size 1.27 1.27)
				)
			)
		)
		(property "Value" "3K3R3F-GP"
			(at -0.0254 -2.5146 0)
			(unlocked yes)
			(layer "F.Fab")
			(hide yes)
			(effects
				(font
					(size 1.016 1.016)
					(thickness 0.1524)
				)
			)
		)
		(property "Device Type" "R603H22"
			(at -0.0254 -4.0386 0)
			(unlocked yes)
			(layer "F.Fab")
			(hide yes)
			(effects
				(font
					(size 1.016 1.016)
					(thickness 0.1524)
				)
			)
		)
		(duplicate_pad_numbers_are_jumpers no)
		(fp_line
			(start -0.4826 0)
			(end -0.2032 0)
			(stroke
				(width 0.2032)
				(type default)
			)
			(layer "F.SilkS")
		)
		(fp_line
			(start 0.2032 0)
			(end 0.4826 0)
			(stroke
				(width 0.2032)
				(type default)
			)
			(layer "F.SilkS")
		)
		(fp_rect
			(start -0.5842 1.3335)
			(end 0.5842 -1.3335)
			(stroke
				(width 0)
				(type default)
			)
			(fill no)
			(layer "F.CrtYd")
		)
		(fp_rect
			(start -0.5842 1.3335)
			(end 0.5842 -1.3335)
			(stroke
				(width 0)
				(type default)
			)
			(fill no)
			(layer "F.Fab")
		)
		(pad "1" smd custom
			(at 0 -0.762)
			(size 0.2159 0.2159)
			(layers "F.Cu" "F.Mask" "F.Paste")
			(net "P12V_A")
			(options
				(clearance outline)
				(anchor circle)
			)
			(primitives
				(gr_poly
					(pts
						(arc
							(start -0.3302 -0.4318)
							(mid -0.402042 -0.402042)
							(end -0.4318 -0.3302)
						)
						(arc
							(start -0.4318 0.3302)
							(mid -0.402042 0.402042)
							(end -0.3302 0.4318)
						)
						(arc
							(start 0.3302 0.4318)
							(mid 0.402042 0.402042)
							(end 0.4318 0.3302)
						)
						(arc
							(start 0.4318 -0.3302)
							(mid 0.402042 -0.402042)
							(end 0.3302 -0.4318)
						)
					)
					(width 0)
					(fill yes)
				)
			)
		)
		(pad "2" smd custom
			(at 0 0.762)
			(size 0.2159 0.2159)
			(layers "F.Cu" "F.Mask" "F.Paste")
			(net "VCCP_A")
			(options
				(clearance outline)
				(anchor circle)
			)
			(primitives
				(gr_poly
					(pts
						(arc
							(start -0.3302 -0.4318)
							(mid -0.402042 -0.402042)
							(end -0.4318 -0.3302)
						)
						(arc
							(start -0.4318 0.3302)
							(mid -0.402042 0.402042)
							(end -0.3302 0.4318)
						)
						(arc
							(start 0.3302 0.4318)
							(mid 0.402042 0.402042)
							(end 0.4318 0.3302)
						)
						(arc
							(start 0.4318 -0.3302)
							(mid 0.402042 -0.402042)
							(end 0.3302 -0.4318)
						)
					)
					(width 0)
					(fill yes)
				)
			)
		)
	)
	(footprint ""
		(layer "F.Cu")
		(at 146.884898 -285.285942 180)
		(property "Reference" "Q24"
			(at 0 0 180)
			(layer "F.SilkS")
			(hide yes)
			(effects
				(font
					(size 1.27 1.27)
				)
			)
		)
		(property "Value" "AO4406AL-GP"
			(at -3.707384 -1.5367 180)
			(unlocked yes)
			(layer "F.Fab")
			(hide yes)
			(effects
				(font
					(size 1.016 1.016)
					(thickness 0.1524)
				)
			)
		)
		(property "Device Type" "SOIC8H69"
			(at -3.707384 -3.0607 180)
			(unlocked yes)
			(layer "F.Fab")
			(hide yes)
			(effects
				(font
					(size 1.016 1.016)
					(thickness 0.1524)
				)
			)
		)
		(duplicate_pad_numbers_are_jumpers no)
		(fp_line
			(start 2.1336 1.4224)
			(end 2.1336 -1.4224)
			(stroke
				(width 0.1524)
				(type default)
			)
			(layer "F.SilkS")
		)
		(fp_line
			(start 2.1336 -1.4224)
			(end -2.7432 -1.4224)
			(stroke
				(width 0.1524)
				(type default)
			)
			(layer "F.SilkS")
		)
		(fp_line
			(start -2.1844 -0.0508)
			(end -2.7178 0.508)
			(stroke
				(width 0.1524)
				(type default)
			)
			(layer "F.SilkS")
		)
		(fp_line
			(start -2.6289 3.4417)
			(end -2.6289 1.4732)
			(stroke
				(width 0.381)
				(type default)
			)
			(layer "F.SilkS")
		)
		(fp_line
			(start -2.7178 -0.508)
			(end -2.1844 -0.0508)
			(stroke
				(width 0.1524)
				(type default)
			)
			(layer "F.SilkS")
		)
		(fp_line
			(start -2.7432 1.4224)
			(end 2.1336 1.4224)
			(stroke
				(width 0.1524)
				(type default)
			)
			(layer "F.SilkS")
		)
		(fp_line
			(start -2.7432 1.4224)
			(end -2.6416 1.4224)
			(stroke
				(width 0.1524)
				(type default)
			)
			(layer "F.SilkS")
		)
		(fp_line
			(start -2.7432 -1.4224)
			(end -2.7432 1.4224)
			(stroke
				(width 0.1524)
				(type default)
			)
			(layer "F.SilkS")
		)
		(fp_poly
			(pts
				(xy -2.2098 -1.4224) (xy -2.2098 1.4224) (xy 2.2098 1.4224) (xy 2.2098 -1.4224)
			)
			(stroke
				(width 0)
				(type default)
			)
			(fill yes)
			(layer "F.SilkS")
		)
		(fp_rect
			(start -2.450084 2.999994)
			(end 2.450084 -2.999994)
			(stroke
				(width 0)
				(type default)
			)
			(fill no)
			(layer "F.CrtYd")
		)
		(fp_poly
			(pts
				(xy -2.8194 3.6322) (xy -2.8194 -3.6322) (xy 2.8194 -3.6322) (xy 2.8194 1.18364) (xy 2.450084 1.18364)
				(xy 2.450084 -2.999994) (xy -2.450084 -2.999994) (xy -2.450084 2.999994) (xy 2.450084 2.999994)
				(xy 2.450084 1.18618) (xy 2.8194 1.18618) (xy 2.8194 3.6322)
			)
			(stroke
				(width 0)
				(type default)
			)
			(fill no)
			(layer "F.CrtYd")
		)
		(fp_rect
			(start -2.8194 3.6322)
			(end 2.8194 -3.6322)
			(stroke
				(width 0)
				(type default)
			)
			(fill no)
			(layer "F.Fab")
		)
		(pad "1" smd rect
			(at -1.905 2.54 180)
			(size 0.635 1.651)
			(layers "F.Cu" "F.Mask" "F.Paste")
			(net "P5V_HDD4")
		)
		(pad "2" smd rect
			(at -0.635 2.54 180)
			(size 0.635 1.651)
			(layers "F.Cu" "F.Mask" "F.Paste")
			(net "P5V_HDD4")
		)
		(pad "3" smd rect
			(at 0.635 2.54 180)
			(size 0.635 1.651)
			(layers "F.Cu" "F.Mask" "F.Paste")
			(net "P5V_HDD4")
		)
		(pad "4" smd rect
			(at 1.905 2.54 180)
			(size 0.635 1.651)
			(layers "F.Cu" "F.Mask" "F.Paste")
			(net "SW_HDD_P4")
		)
		(pad "5" smd rect
			(at 1.905 -2.54 180)
			(size 0.635 1.651)
			(layers "F.Cu" "F.Mask" "F.Paste")
			(net "P5V_A_1")
		)
		(pad "6" smd rect
			(at 0.635 -2.54 180)
			(size 0.635 1.651)
			(layers "F.Cu" "F.Mask" "F.Paste")
			(net "P5V_A_1")
		)
		(pad "7" smd rect
			(at -0.635 -2.54 180)
			(size 0.635 1.651)
			(layers "F.Cu" "F.Mask" "F.Paste")
			(net "P5V_A_1")
		)
		(pad "8" smd rect
			(at -1.905 -2.54 180)
			(size 0.635 1.651)
			(layers "F.Cu" "F.Mask" "F.Paste")
			(net "P5V_A_1")
		)
	)
	(footprint ""
		(layer "F.Cu")
		(at 377.846082 -290.591748 90)
		(property "Reference" "R592"
			(at 0 0 90)
			(layer "F.SilkS")
			(hide yes)
			(effects
				(font
					(size 1.27 1.27)
				)
			)
		)
		(property "Value" "4K7R2J-2-GP"
			(at 0.064008 -3.993896 90)
			(unlocked yes)
			(layer "F.Fab")
			(hide yes)
			(effects
				(font
					(size 1.016 1.016)
					(thickness 0.1524)
				)
			)
		)
		(property "Device Type" "R402H16"
			(at 0.064008 -5.517896 90)
			(unlocked yes)
			(layer "F.Fab")
			(hide yes)
			(effects
				(font
					(size 1.016 1.016)
					(thickness 0.1524)
				)
			)
		)
		(duplicate_pad_numbers_are_jumpers no)
		(fp_line
			(start 0.508 -0.9398)
			(end -0.508 -0.9398)
			(stroke
				(width 0.1524)
				(type default)
			)
			(layer "F.SilkS")
		)
		(fp_line
			(start -0.508 -0.9398)
			(end -0.508 0.9398)
			(stroke
				(width 0.1524)
				(type default)
			)
			(layer "F.SilkS")
		)
		(fp_rect
			(start -0.508 0.9398)
			(end 0.508 -0.9398)
			(stroke
				(width 0)
				(type default)
			)
			(fill no)
			(layer "F.CrtYd")
		)
		(fp_rect
			(start -0.508 0.9398)
			(end 0.508 -0.9398)
			(stroke
				(width 0)
				(type default)
			)
			(fill no)
			(layer "F.Fab")
		)
		(pad "1" smd custom
			(at 0 -0.4445 90)
			(size 0.1397 0.1397)
			(layers "F.Cu" "F.Mask" "F.Paste")
			(net "DRIVE_B_32_FLT_LED")
			(options
				(clearance outline)
				(anchor circle)
			)
			(primitives
				(gr_poly
					(pts
						(arc
							(start -0.1778 -0.2794)
							(mid -0.249642 -0.249642)
							(end -0.2794 -0.1778)
						)
						(arc
							(start -0.2794 0.1778)
							(mid -0.249642 0.249642)
							(end -0.1778 0.2794)
						)
						(arc
							(start 0.1778 0.2794)
							(mid 0.249642 0.249642)
							(end 0.2794 0.1778)
						)
						(arc
							(start 0.2794 -0.1778)
							(mid 0.249642 -0.249642)
							(end 0.1778 -0.2794)
						)
					)
					(width 0)
					(fill yes)
				)
			)
		)
		(pad "2" smd custom
			(at 0 0.4445 90)
			(size 0.1397 0.1397)
			(layers "F.Cu" "F.Mask" "F.Paste")
			(net "GND")
			(options
				(clearance outline)
				(anchor circle)
			)
			(primitives
				(gr_poly
					(pts
						(arc
							(start -0.1778 -0.2794)
							(mid -0.249642 -0.249642)
							(end -0.2794 -0.1778)
						)
						(arc
							(start -0.2794 0.1778)
							(mid -0.249642 0.249642)
							(end -0.1778 0.2794)
						)
						(arc
							(start 0.1778 0.2794)
							(mid 0.249642 0.249642)
							(end 0.2794 0.1778)
						)
						(arc
							(start 0.2794 -0.1778)
							(mid 0.249642 -0.249642)
							(end 0.1778 -0.2794)
						)
					)
					(width 0)
					(fill yes)
				)
			)
		)
	)
	(footprint ""
		(layer "F.Cu")
		(at 51.511708 -157.605984 90)
		(property "Reference" "R446"
			(at 0 0 90)
			(layer "F.SilkS")
			(hide yes)
			(effects
				(font
					(size 1.27 1.27)
				)
			)
		)
		(property "Value" "0R2J-2-GP"
			(at 0.064008 -3.993896 90)
			(unlocked yes)
			(layer "F.Fab")
			(hide yes)
			(effects
				(font
					(size 1.016 1.016)
					(thickness 0.1524)
				)
			)
		)
		(property "Device Type" "R402H16"
			(at 0.064008 -5.517896 90)
			(unlocked yes)
			(layer "F.Fab")
			(hide yes)
			(effects
				(font
					(size 1.016 1.016)
					(thickness 0.1524)
				)
			)
		)
		(duplicate_pad_numbers_are_jumpers no)
		(fp_line
			(start 0.508 -0.9398)
			(end -0.508 -0.9398)
			(stroke
				(width 0.1524)
				(type default)
			)
			(layer "F.SilkS")
		)
		(fp_line
			(start -0.508 -0.9398)
			(end -0.508 0.9398)
			(stroke
				(width 0.1524)
				(type default)
			)
			(layer "F.SilkS")
		)
		(fp_rect
			(start -0.508 0.9398)
			(end 0.508 -0.9398)
			(stroke
				(width 0)
				(type default)
			)
			(fill no)
			(layer "F.CrtYd")
		)
		(fp_rect
			(start -0.508 0.9398)
			(end 0.508 -0.9398)
			(stroke
				(width 0)
				(type default)
			)
			(fill no)
			(layer "F.Fab")
		)
		(pad "1" smd custom
			(at 0 -0.4445 90)
			(size 0.1397 0.1397)
			(layers "F.Cu" "F.Mask" "F.Paste")
			(net "SW_HDD_G13")
			(options
				(clearance outline)
				(anchor circle)
			)
			(primitives
				(gr_poly
					(pts
						(arc
							(start -0.1778 -0.2794)
							(mid -0.249642 -0.249642)
							(end -0.2794 -0.1778)
						)
						(arc
							(start -0.2794 0.1778)
							(mid -0.249642 0.249642)
							(end -0.1778 0.2794)
						)
						(arc
							(start 0.1778 0.2794)
							(mid 0.249642 0.249642)
							(end 0.2794 0.1778)
						)
						(arc
							(start 0.2794 -0.1778)
							(mid 0.249642 -0.249642)
							(end 0.1778 -0.2794)
						)
					)
					(width 0)
					(fill yes)
				)
			)
		)
		(pad "2" smd custom
			(at 0 0.4445 90)
			(size 0.1397 0.1397)
			(layers "F.Cu" "F.Mask" "F.Paste")
			(net "SW_HDD_R13")
			(options
				(clearance outline)
				(anchor circle)
			)
			(primitives
				(gr_poly
					(pts
						(arc
							(start -0.1778 -0.2794)
							(mid -0.249642 -0.249642)
							(end -0.2794 -0.1778)
						)
						(arc
							(start -0.2794 0.1778)
							(mid -0.249642 0.249642)
							(end -0.1778 0.2794)
						)
						(arc
							(start 0.1778 0.2794)
							(mid 0.249642 0.249642)
							(end 0.2794 0.1778)
						)
						(arc
							(start 0.2794 -0.1778)
							(mid 0.249642 -0.249642)
							(end 0.1778 -0.2794)
						)
					)
					(width 0)
					(fill yes)
				)
			)
		)
	)
	(footprint ""
		(layer "F.Cu")
		(at 78.298548 -277.183342 180)
		(property "Reference" "R192"
			(at 0 0 180)
			(layer "F.SilkS")
			(hide yes)
			(effects
				(font
					(size 1.27 1.27)
				)
			)
		)
		(property "Value" "200KR2F-L-GP"
			(at 0.064008 -3.993896 180)
			(unlocked yes)
			(layer "F.Fab")
			(hide yes)
			(effects
				(font
					(size 1.016 1.016)
					(thickness 0.1524)
				)
			)
		)
		(property "Device Type" "R402H16"
			(at 0.064008 -5.517896 180)
			(unlocked yes)
			(layer "F.Fab")
			(hide yes)
			(effects
				(font
					(size 1.016 1.016)
					(thickness 0.1524)
				)
			)
		)
		(duplicate_pad_numbers_are_jumpers no)
		(fp_line
			(start 0.508 -0.9398)
			(end -0.508 -0.9398)
			(stroke
				(width 0.1524)
				(type default)
			)
			(layer "F.SilkS")
		)
		(fp_line
			(start -0.508 -0.9398)
			(end -0.508 0.9398)
			(stroke
				(width 0.1524)
				(type default)
			)
			(layer "F.SilkS")
		)
		(fp_rect
			(start -0.508 0.9398)
			(end 0.508 -0.9398)
			(stroke
				(width 0)
				(type default)
			)
			(fill no)
			(layer "F.CrtYd")
		)
		(fp_rect
			(start -0.508 0.9398)
			(end 0.508 -0.9398)
			(stroke
				(width 0)
				(type default)
			)
			(fill no)
			(layer "F.Fab")
		)
		(pad "1" smd custom
			(at 0 -0.4445 180)
			(size 0.1397 0.1397)
			(layers "F.Cu" "F.Mask" "F.Paste")
			(net "SW_HDD_R2")
			(options
				(clearance outline)
				(anchor circle)
			)
			(primitives
				(gr_poly
					(pts
						(arc
							(start -0.1778 -0.2794)
							(mid -0.249642 -0.249642)
							(end -0.2794 -0.1778)
						)
						(arc
							(start -0.2794 0.1778)
							(mid -0.249642 0.249642)
							(end -0.1778 0.2794)
						)
						(arc
							(start 0.1778 0.2794)
							(mid 0.249642 0.249642)
							(end 0.2794 0.1778)
						)
						(arc
							(start 0.2794 -0.1778)
							(mid 0.249642 -0.249642)
							(end 0.1778 -0.2794)
						)
					)
					(width 0)
					(fill yes)
				)
			)
		)
		(pad "2" smd custom
			(at 0 0.4445 180)
			(size 0.1397 0.1397)
			(layers "F.Cu" "F.Mask" "F.Paste")
			(net "SW_HDD_N2")
			(options
				(clearance outline)
				(anchor circle)
			)
			(primitives
				(gr_poly
					(pts
						(arc
							(start -0.1778 -0.2794)
							(mid -0.249642 -0.249642)
							(end -0.2794 -0.1778)
						)
						(arc
							(start -0.2794 0.1778)
							(mid -0.249642 0.249642)
							(end -0.1778 0.2794)
						)
						(arc
							(start 0.1778 0.2794)
							(mid 0.249642 0.249642)
							(end 0.2794 0.1778)
						)
						(arc
							(start 0.2794 -0.1778)
							(mid 0.249642 -0.249642)
							(end 0.1778 -0.2794)
						)
					)
					(width 0)
					(fill yes)
				)
			)
		)
	)
	(footprint ""
		(layer "F.Cu")
		(at 363.655102 -272.585942)
		(property "Reference" "R304"
			(at 0 0 0)
			(layer "F.SilkS")
			(hide yes)
			(effects
				(font
					(size 1.27 1.27)
				)
			)
		)
		(property "Value" "4K7R2J-2-GP"
			(at 0.064008 -3.993896 0)
			(unlocked yes)
			(layer "F.Fab")
			(hide yes)
			(effects
				(font
					(size 1.016 1.016)
					(thickness 0.1524)
				)
			)
		)
		(property "Device Type" "R402H16"
			(at 0.064008 -5.517896 0)
			(unlocked yes)
			(layer "F.Fab")
			(hide yes)
			(effects
				(font
					(size 1.016 1.016)
					(thickness 0.1524)
				)
			)
		)
		(duplicate_pad_numbers_are_jumpers no)
		(fp_line
			(start -0.508 -0.9398)
			(end -0.508 0.9398)
			(stroke
				(width 0.1524)
				(type default)
			)
			(layer "F.SilkS")
		)
		(fp_line
			(start 0.508 -0.9398)
			(end -0.508 -0.9398)
			(stroke
				(width 0.1524)
				(type default)
			)
			(layer "F.SilkS")
		)
		(fp_rect
			(start -0.508 0.9398)
			(end 0.508 -0.9398)
			(stroke
				(width 0)
				(type default)
			)
			(fill no)
			(layer "F.CrtYd")
		)
		(fp_rect
			(start -0.508 0.9398)
			(end 0.508 -0.9398)
			(stroke
				(width 0)
				(type default)
			)
			(fill no)
			(layer "F.Fab")
		)
		(pad "1" smd custom
			(at 0 -0.4445)
			(size 0.1397 0.1397)
			(layers "F.Cu" "F.Mask" "F.Paste")
			(net "SW_PWR_R_HDD7")
			(options
				(clearance outline)
				(anchor circle)
			)
			(primitives
				(gr_poly
					(pts
						(arc
							(start -0.1778 -0.2794)
							(mid -0.249642 -0.249642)
							(end -0.2794 -0.1778)
						)
						(arc
							(start -0.2794 0.1778)
							(mid -0.249642 0.249642)
							(end -0.1778 0.2794)
						)
						(arc
							(start 0.1778 0.2794)
							(mid 0.249642 0.249642)
							(end 0.2794 0.1778)
						)
						(arc
							(start 0.2794 -0.1778)
							(mid 0.249642 -0.249642)
							(end 0.1778 -0.2794)
						)
					)
					(width 0)
					(fill yes)
				)
			)
		)
		(pad "2" smd custom
			(at 0 0.4445)
			(size 0.1397 0.1397)
			(layers "F.Cu" "F.Mask" "F.Paste")
			(net "GND")
			(options
				(clearance outline)
				(anchor circle)
			)
			(primitives
				(gr_poly
					(pts
						(arc
							(start -0.1778 -0.2794)
							(mid -0.249642 -0.249642)
							(end -0.2794 -0.1778)
						)
						(arc
							(start -0.2794 0.1778)
							(mid -0.249642 0.249642)
							(end -0.1778 0.2794)
						)
						(arc
							(start 0.1778 0.2794)
							(mid 0.249642 0.249642)
							(end 0.2794 0.1778)
						)
						(arc
							(start 0.2794 -0.1778)
							(mid 0.249642 -0.249642)
							(end 0.1778 -0.2794)
						)
					)
					(width 0)
					(fill yes)
				)
			)
		)
	)
	(footprint ""
		(layer "F.Cu")
		(at 398.83715 -160.735518 180)
		(property "Reference" "R607"
			(at 0 0 180)
			(layer "F.SilkS")
			(hide yes)
			(effects
				(font
					(size 1.27 1.27)
				)
			)
		)
		(property "Value" "0R2J-2-GP"
			(at 0.064008 -3.993896 180)
			(unlocked yes)
			(layer "F.Fab")
			(hide yes)
			(effects
				(font
					(size 1.016 1.016)
					(thickness 0.1524)
				)
			)
		)
		(property "Device Type" "R402H16"
			(at 0.064008 -5.517896 180)
			(unlocked yes)
			(layer "F.Fab")
			(hide yes)
			(effects
				(font
					(size 1.016 1.016)
					(thickness 0.1524)
				)
			)
		)
		(duplicate_pad_numbers_are_jumpers no)
		(fp_line
			(start 0.508 -0.9398)
			(end -0.508 -0.9398)
			(stroke
				(width 0.1524)
				(type default)
			)
			(layer "F.SilkS")
		)
		(fp_line
			(start -0.508 -0.9398)
			(end -0.508 0.9398)
			(stroke
				(width 0.1524)
				(type default)
			)
			(layer "F.SilkS")
		)
		(fp_rect
			(start -0.508 0.9398)
			(end 0.508 -0.9398)
			(stroke
				(width 0)
				(type default)
			)
			(fill no)
			(layer "F.CrtYd")
		)
		(fp_rect
			(start -0.508 0.9398)
			(end 0.508 -0.9398)
			(stroke
				(width 0)
				(type default)
			)
			(fill no)
			(layer "F.Fab")
		)
		(pad "1" smd custom
			(at 0 -0.4445 180)
			(size 0.1397 0.1397)
			(layers "F.Cu" "F.Mask" "F.Paste")
			(net "SW_HDD_G20")
			(options
				(clearance outline)
				(anchor circle)
			)
			(primitives
				(gr_poly
					(pts
						(arc
							(start -0.1778 -0.2794)
							(mid -0.249642 -0.249642)
							(end -0.2794 -0.1778)
						)
						(arc
							(start -0.2794 0.1778)
							(mid -0.249642 0.249642)
							(end -0.1778 0.2794)
						)
						(arc
							(start 0.1778 0.2794)
							(mid 0.249642 0.249642)
							(end 0.2794 0.1778)
						)
						(arc
							(start 0.2794 -0.1778)
							(mid 0.249642 -0.249642)
							(end 0.1778 -0.2794)
						)
					)
					(width 0)
					(fill yes)
				)
			)
		)
		(pad "2" smd custom
			(at 0 0.4445 180)
			(size 0.1397 0.1397)
			(layers "F.Cu" "F.Mask" "F.Paste")
			(net "SW_HDD_R20")
			(options
				(clearance outline)
				(anchor circle)
			)
			(primitives
				(gr_poly
					(pts
						(arc
							(start -0.1778 -0.2794)
							(mid -0.249642 -0.249642)
							(end -0.2794 -0.1778)
						)
						(arc
							(start -0.2794 0.1778)
							(mid -0.249642 0.249642)
							(end -0.1778 0.2794)
						)
						(arc
							(start 0.1778 0.2794)
							(mid 0.249642 0.249642)
							(end 0.2794 0.1778)
						)
						(arc
							(start 0.2794 -0.1778)
							(mid 0.249642 -0.249642)
							(end 0.1778 -0.2794)
						)
					)
					(width 0)
					(fill yes)
				)
			)
		)
	)
	(footprint ""
		(layer "F.Cu")
		(at 331.47 -73.954894 180)
		(property "Reference" "C435"
			(at 0 0 180)
			(layer "F.SilkS")
			(hide yes)
			(effects
				(font
					(size 1.27 1.27)
				)
			)
		)
		(property "Value" "SC4D7U25V5KX-1-GP"
			(at -0.0762 -6.1214 180)
			(unlocked yes)
			(layer "F.Fab")
			(hide yes)
			(effects
				(font
					(size 1.016 1.016)
					(thickness 0.1524)
				)
			)
		)
		(property "Device Type" "C805H58"
			(at -0.0762 -8.1534 180)
			(unlocked yes)
			(layer "F.Fab")
			(hide yes)
			(effects
				(font
					(size 1.016 1.016)
					(thickness 0.1524)
				)
			)
		)
		(duplicate_pad_numbers_are_jumpers no)
		(fp_line
			(start 0.635 0)
			(end -0.635 0)
			(stroke
				(width 0.508)
				(type default)
			)
			(layer "F.SilkS")
		)
		(fp_rect
			(start -0.9652 1.778)
			(end 0.9652 -1.778)
			(stroke
				(width 0)
				(type default)
			)
			(fill no)
			(layer "F.CrtYd")
		)
		(fp_poly
			(pts
				(xy -0.9652 -1.778) (xy 0.9652 -1.778) (xy 0.9652 1.778) (xy -0.9652 1.778)
			)
			(stroke
				(width 0)
				(type default)
			)
			(fill no)
			(layer "F.Fab")
		)
		(pad "1" smd rect
			(at 0 -0.9652 180)
			(size 1.397 1.143)
			(layers "F.Cu" "F.Mask" "F.Paste")
			(net "P12V_HDD30")
		)
		(pad "2" smd rect
			(at 0 0.9652 180)
			(size 1.397 1.143)
			(layers "F.Cu" "F.Mask" "F.Paste")
			(net "GND")
		)
	)
	(footprint ""
		(layer "F.Cu")
		(at 14.722602 -127.799338 180)
		(property "Reference" "Q239"
			(at 0 0 180)
			(layer "F.SilkS")
			(hide yes)
			(effects
				(font
					(size 1.27 1.27)
				)
			)
		)
		(property "Value" "2N7002K-2-GP"
			(at 0.127 -8.9662 180)
			(unlocked yes)
			(layer "F.Fab")
			(hide yes)
			(effects
				(font
					(size 1.016 1.016)
					(thickness 0.1524)
				)
			)
		)
		(property "Device Type" "SOT23DGS2D4H44"
			(at 0.127 -10.4902 180)
			(unlocked yes)
			(layer "F.Fab")
			(hide yes)
			(effects
				(font
					(size 1.016 1.016)
					(thickness 0.1524)
				)
			)
		)
		(duplicate_pad_numbers_are_jumpers no)
		(fp_line
			(start 1.651 1.778)
			(end 1.651 -1.778)
			(stroke
				(width 0.1524)
				(type default)
			)
			(layer "F.SilkS")
		)
		(fp_line
			(start 1.651 -1.778)
			(end -1.651 -1.778)
			(stroke
				(width 0.1524)
				(type default)
			)
			(layer "F.SilkS")
		)
		(fp_line
			(start -1.651 1.778)
			(end 1.651 1.778)
			(stroke
				(width 0.1524)
				(type default)
			)
			(layer "F.SilkS")
		)
		(fp_line
			(start -1.651 -1.778)
			(end -1.651 1.778)
			(stroke
				(width 0.1524)
				(type default)
			)
			(layer "F.SilkS")
		)
		(fp_poly
			(pts
				(xy -1.778 1.8796) (xy -1.778 -1.8796) (xy 1.778 -1.8796) (xy 1.778 1.8796)
			)
			(stroke
				(width 0)
				(type default)
			)
			(fill no)
			(layer "F.CrtYd")
		)
		(fp_poly
			(pts
				(xy -1.778 1.8796) (xy -1.778 -1.8796) (xy 1.778 -1.8796) (xy 1.778 1.8796)
			)
			(stroke
				(width 0)
				(type default)
			)
			(fill no)
			(layer "F.Fab")
		)
		(pad "D" smd custom
			(at 0 -0.9525 180)
			(size 0.1905 0.1905)
			(layers "F.Cu" "F.Mask" "F.Paste")
			(net "FLT_HDD12_N")
			(options
				(clearance outline)
				(anchor circle)
			)
			(primitives
				(gr_poly
					(pts
						(arc
							(start -0.1778 0.5715)
							(mid -0.321484 0.511984)
							(end -0.381 0.3683)
						)
						(arc
							(start -0.381 -0.3683)
							(mid -0.321484 -0.511984)
							(end -0.1778 -0.5715)
						)
						(arc
							(start 0.1778 -0.5715)
							(mid 0.321484 -0.511984)
							(end 0.381 -0.3683)
						)
						(arc
							(start 0.381 0.3683)
							(mid 0.321484 0.511984)
							(end 0.1778 0.5715)
						)
					)
					(width 0)
					(fill yes)
				)
			)
		)
		(pad "G" smd custom
			(at -0.98425 0.9525 180)
			(size 0.1905 0.1905)
			(layers "F.Cu" "F.Mask" "F.Paste")
			(net "DRIVE_A_12_FLT_LED")
			(options
				(clearance outline)
				(anchor circle)
			)
			(primitives
				(gr_poly
					(pts
						(arc
							(start -0.1778 0.5715)
							(mid -0.321484 0.511984)
							(end -0.381 0.3683)
						)
						(arc
							(start -0.381 -0.3683)
							(mid -0.321484 -0.511984)
							(end -0.1778 -0.5715)
						)
						(arc
							(start 0.1778 -0.5715)
							(mid 0.321484 -0.511984)
							(end 0.381 -0.3683)
						)
						(arc
							(start 0.381 0.3683)
							(mid 0.321484 0.511984)
							(end 0.1778 0.5715)
						)
					)
					(width 0)
					(fill yes)
				)
			)
		)
		(pad "S" smd custom
			(at 0.98425 0.9525 180)
			(size 0.1905 0.1905)
			(layers "F.Cu" "F.Mask" "F.Paste")
			(net "GND")
			(options
				(clearance outline)
				(anchor circle)
			)
			(primitives
				(gr_poly
					(pts
						(arc
							(start -0.1778 0.5715)
							(mid -0.321484 0.511984)
							(end -0.381 0.3683)
						)
						(arc
							(start -0.381 -0.3683)
							(mid -0.321484 -0.511984)
							(end -0.1778 -0.5715)
						)
						(arc
							(start 0.1778 -0.5715)
							(mid 0.321484 -0.511984)
							(end 0.381 -0.3683)
						)
						(arc
							(start 0.381 0.3683)
							(mid 0.321484 0.511984)
							(end 0.1778 0.5715)
						)
					)
					(width 0)
					(fill yes)
				)
			)
		)
	)
	(footprint ""
		(layer "F.Cu")
		(at 363.655102 -157.585918)
		(property "Reference" "R579"
			(at 0 0 0)
			(layer "F.SilkS")
			(hide yes)
			(effects
				(font
					(size 1.27 1.27)
				)
			)
		)
		(property "Value" "4K7R2J-2-GP"
			(at 0.064008 -3.993896 0)
			(unlocked yes)
			(layer "F.Fab")
			(hide yes)
			(effects
				(font
					(size 1.016 1.016)
					(thickness 0.1524)
				)
			)
		)
		(property "Device Type" "R402H16"
			(at 0.064008 -5.517896 0)
			(unlocked yes)
			(layer "F.Fab")
			(hide yes)
			(effects
				(font
					(size 1.016 1.016)
					(thickness 0.1524)
				)
			)
		)
		(duplicate_pad_numbers_are_jumpers no)
		(fp_line
			(start -0.508 -0.9398)
			(end -0.508 0.9398)
			(stroke
				(width 0.1524)
				(type default)
			)
			(layer "F.SilkS")
		)
		(fp_line
			(start 0.508 -0.9398)
			(end -0.508 -0.9398)
			(stroke
				(width 0.1524)
				(type default)
			)
			(layer "F.SilkS")
		)
		(fp_rect
			(start -0.508 0.9398)
			(end 0.508 -0.9398)
			(stroke
				(width 0)
				(type default)
			)
			(fill no)
			(layer "F.CrtYd")
		)
		(fp_rect
			(start -0.508 0.9398)
			(end 0.508 -0.9398)
			(stroke
				(width 0)
				(type default)
			)
			(fill no)
			(layer "F.Fab")
		)
		(pad "1" smd custom
			(at 0 -0.4445)
			(size 0.1397 0.1397)
			(layers "F.Cu" "F.Mask" "F.Paste")
			(net "SW_PWR_R_HDD19")
			(options
				(clearance outline)
				(anchor circle)
			)
			(primitives
				(gr_poly
					(pts
						(arc
							(start -0.1778 -0.2794)
							(mid -0.249642 -0.249642)
							(end -0.2794 -0.1778)
						)
						(arc
							(start -0.2794 0.1778)
							(mid -0.249642 0.249642)
							(end -0.1778 0.2794)
						)
						(arc
							(start 0.1778 0.2794)
							(mid 0.249642 0.249642)
							(end 0.2794 0.1778)
						)
						(arc
							(start 0.2794 -0.1778)
							(mid 0.249642 -0.249642)
							(end 0.1778 -0.2794)
						)
					)
					(width 0)
					(fill yes)
				)
			)
		)
		(pad "2" smd custom
			(at 0 0.4445)
			(size 0.1397 0.1397)
			(layers "F.Cu" "F.Mask" "F.Paste")
			(net "GND")
			(options
				(clearance outline)
				(anchor circle)
			)
			(primitives
				(gr_poly
					(pts
						(arc
							(start -0.1778 -0.2794)
							(mid -0.249642 -0.249642)
							(end -0.2794 -0.1778)
						)
						(arc
							(start -0.2794 0.1778)
							(mid -0.249642 0.249642)
							(end -0.1778 0.2794)
						)
						(arc
							(start 0.1778 0.2794)
							(mid 0.249642 0.249642)
							(end 0.2794 0.1778)
						)
						(arc
							(start 0.2794 -0.1778)
							(mid 0.249642 -0.249642)
							(end 0.1778 -0.2794)
						)
					)
					(width 0)
					(fill yes)
				)
			)
		)
	)
	(footprint ""
		(layer "F.Cu")
		(at 246.253 -387.4008 -90)
		(property "Reference" "R1157"
			(at 0 0 270)
			(layer "F.SilkS")
			(hide yes)
			(effects
				(font
					(size 1.27 1.27)
				)
			)
		)
		(property "Value" "10R2F-L-GP"
			(at 0.064008 -3.993896 270)
			(unlocked yes)
			(layer "F.Fab")
			(hide yes)
			(effects
				(font
					(size 1.016 1.016)
					(thickness 0.1524)
				)
			)
		)
		(property "Device Type" "R402H14"
			(at 0.064008 -5.517896 270)
			(unlocked yes)
			(layer "F.Fab")
			(hide yes)
			(effects
				(font
					(size 1.016 1.016)
					(thickness 0.1524)
				)
			)
		)
		(duplicate_pad_numbers_are_jumpers no)
		(fp_line
			(start -0.508 -0.9398)
			(end -0.508 0.9398)
			(stroke
				(width 0.1524)
				(type default)
			)
			(layer "F.SilkS")
		)
		(fp_line
			(start 0.508 -0.9398)
			(end -0.508 -0.9398)
			(stroke
				(width 0.1524)
				(type default)
			)
			(layer "F.SilkS")
		)
		(fp_rect
			(start -0.508 0.9398)
			(end 0.508 -0.9398)
			(stroke
				(width 0)
				(type default)
			)
			(fill no)
			(layer "F.CrtYd")
		)
		(fp_rect
			(start -0.508 0.9398)
			(end 0.508 -0.9398)
			(stroke
				(width 0)
				(type default)
			)
			(fill no)
			(layer "F.Fab")
		)
		(pad "1" smd custom
			(at 0 -0.4445 270)
			(size 0.1397 0.1397)
			(layers "F.Cu" "F.Mask" "F.Paste")
			(net "MB3_CM_SENSE_R1_N")
			(options
				(clearance outline)
				(anchor circle)
			)
			(primitives
				(gr_poly
					(pts
						(arc
							(start -0.1778 -0.2794)
							(mid -0.249642 -0.249642)
							(end -0.2794 -0.1778)
						)
						(arc
							(start -0.2794 0.1778)
							(mid -0.249642 0.249642)
							(end -0.1778 0.2794)
						)
						(arc
							(start 0.1778 0.2794)
							(mid 0.249642 0.249642)
							(end 0.2794 0.1778)
						)
						(arc
							(start 0.2794 -0.1778)
							(mid 0.249642 -0.249642)
							(end 0.1778 -0.2794)
						)
					)
					(width 0)
					(fill yes)
				)
			)
		)
		(pad "2" smd custom
			(at 0 0.4445 270)
			(size 0.1397 0.1397)
			(layers "F.Cu" "F.Mask" "F.Paste")
			(net "MB3_HS_SENSE_N")
			(options
				(clearance outline)
				(anchor circle)
			)
			(primitives
				(gr_poly
					(pts
						(arc
							(start -0.1778 -0.2794)
							(mid -0.249642 -0.249642)
							(end -0.2794 -0.1778)
						)
						(arc
							(start -0.2794 0.1778)
							(mid -0.249642 0.249642)
							(end -0.1778 0.2794)
						)
						(arc
							(start 0.1778 0.2794)
							(mid 0.249642 0.249642)
							(end 0.2794 0.1778)
						)
						(arc
							(start 0.2794 -0.1778)
							(mid 0.249642 -0.249642)
							(end 0.1778 -0.2794)
						)
					)
					(width 0)
					(fill yes)
				)
			)
		)
	)
	(footprint ""
		(layer "F.Cu")
		(at 403.095968 -127.788924 180)
		(property "Reference" "Q284"
			(at 0 0 180)
			(layer "F.SilkS")
			(hide yes)
			(effects
				(font
					(size 1.27 1.27)
				)
			)
		)
		(property "Value" "SSM3K324R-GP"
			(at 0.127 -8.9662 180)
			(unlocked yes)
			(layer "F.Fab")
			(hide yes)
			(effects
				(font
					(size 1.016 1.016)
					(thickness 0.1524)
				)
			)
		)
		(property "Device Type" "SOT23DGS2D4H35"
			(at 0.127 -10.4902 180)
			(unlocked yes)
			(layer "F.Fab")
			(hide yes)
			(effects
				(font
					(size 1.016 1.016)
					(thickness 0.1524)
				)
			)
		)
		(duplicate_pad_numbers_are_jumpers no)
		(fp_line
			(start 1.651 1.778)
			(end 1.651 -1.778)
			(stroke
				(width 0.1524)
				(type default)
			)
			(layer "F.SilkS")
		)
		(fp_line
			(start 1.651 -1.778)
			(end -1.651 -1.778)
			(stroke
				(width 0.1524)
				(type default)
			)
			(layer "F.SilkS")
		)
		(fp_line
			(start -1.651 1.778)
			(end 1.651 1.778)
			(stroke
				(width 0.1524)
				(type default)
			)
			(layer "F.SilkS")
		)
		(fp_line
			(start -1.651 -1.778)
			(end -1.651 1.778)
			(stroke
				(width 0.1524)
				(type default)
			)
			(layer "F.SilkS")
		)
		(fp_poly
			(pts
				(xy -1.778 1.8796) (xy -1.778 -1.8796) (xy 1.778 -1.8796) (xy 1.778 1.8796)
			)
			(stroke
				(width 0)
				(type default)
			)
			(fill no)
			(layer "F.CrtYd")
		)
		(fp_poly
			(pts
				(xy -1.778 1.8796) (xy -1.778 -1.8796) (xy 1.778 -1.8796) (xy 1.778 1.8796)
			)
			(stroke
				(width 0)
				(type default)
			)
			(fill no)
			(layer "F.Fab")
		)
		(pad "D" smd custom
			(at 0 -0.9525 180)
			(size 0.1905 0.1905)
			(layers "F.Cu" "F.Mask" "F.Paste")
			(net "DRV_ACT_21_N")
			(options
				(clearance outline)
				(anchor circle)
			)
			(primitives
				(gr_poly
					(pts
						(arc
							(start -0.1778 0.5715)
							(mid -0.321484 0.511984)
							(end -0.381 0.3683)
						)
						(arc
							(start -0.381 -0.3683)
							(mid -0.321484 -0.511984)
							(end -0.1778 -0.5715)
						)
						(arc
							(start 0.1778 -0.5715)
							(mid 0.321484 -0.511984)
							(end 0.381 -0.3683)
						)
						(arc
							(start 0.381 0.3683)
							(mid 0.321484 0.511984)
							(end 0.1778 0.5715)
						)
					)
					(width 0)
					(fill yes)
				)
			)
		)
		(pad "G" smd custom
			(at -0.98425 0.9525 180)
			(size 0.1905 0.1905)
			(layers "F.Cu" "F.Mask" "F.Paste")
			(net "DRIVE_A_21_ACT")
			(options
				(clearance outline)
				(anchor circle)
			)
			(primitives
				(gr_poly
					(pts
						(arc
							(start -0.1778 0.5715)
							(mid -0.321484 0.511984)
							(end -0.381 0.3683)
						)
						(arc
							(start -0.381 -0.3683)
							(mid -0.321484 -0.511984)
							(end -0.1778 -0.5715)
						)
						(arc
							(start 0.1778 -0.5715)
							(mid 0.321484 -0.511984)
							(end 0.381 -0.3683)
						)
						(arc
							(start 0.381 0.3683)
							(mid 0.321484 0.511984)
							(end 0.1778 0.5715)
						)
					)
					(width 0)
					(fill yes)
				)
			)
		)
		(pad "S" smd custom
			(at 0.98425 0.9525 180)
			(size 0.1905 0.1905)
			(layers "F.Cu" "F.Mask" "F.Paste")
			(net "GND")
			(options
				(clearance outline)
				(anchor circle)
			)
			(primitives
				(gr_poly
					(pts
						(arc
							(start -0.1778 0.5715)
							(mid -0.321484 0.511984)
							(end -0.381 0.3683)
						)
						(arc
							(start -0.381 -0.3683)
							(mid -0.321484 -0.511984)
							(end -0.1778 -0.5715)
						)
						(arc
							(start 0.1778 -0.5715)
							(mid 0.321484 -0.511984)
							(end 0.381 -0.3683)
						)
						(arc
							(start 0.381 0.3683)
							(mid 0.321484 0.511984)
							(end 0.1778 0.5715)
						)
					)
					(width 0)
					(fill yes)
				)
			)
		)
	)
	(footprint ""
		(layer "F.Cu")
		(at 147.248372 -145.388838 180)
		(property "Reference" "R1059"
			(at 0 0 180)
			(layer "F.SilkS")
			(hide yes)
			(effects
				(font
					(size 1.27 1.27)
				)
			)
		)
		(property "Value" "62KR2F-GP"
			(at 0.064008 -3.993896 180)
			(unlocked yes)
			(layer "F.Fab")
			(hide yes)
			(effects
				(font
					(size 1.016 1.016)
					(thickness 0.1524)
				)
			)
		)
		(property "Device Type" "R402H16"
			(at 0.064008 -5.517896 180)
			(unlocked yes)
			(layer "F.Fab")
			(hide yes)
			(effects
				(font
					(size 1.016 1.016)
					(thickness 0.1524)
				)
			)
		)
		(duplicate_pad_numbers_are_jumpers no)
		(fp_line
			(start 0.508 -0.9398)
			(end -0.508 -0.9398)
			(stroke
				(width 0.1524)
				(type default)
			)
			(layer "F.SilkS")
		)
		(fp_line
			(start -0.508 -0.9398)
			(end -0.508 0.9398)
			(stroke
				(width 0.1524)
				(type default)
			)
			(layer "F.SilkS")
		)
		(fp_rect
			(start -0.508 0.9398)
			(end 0.508 -0.9398)
			(stroke
				(width 0)
				(type default)
			)
			(fill no)
			(layer "F.CrtYd")
		)
		(fp_rect
			(start -0.508 0.9398)
			(end 0.508 -0.9398)
			(stroke
				(width 0)
				(type default)
			)
			(fill no)
			(layer "F.Fab")
		)
		(pad "1" smd custom
			(at 0 -0.4445 180)
			(size 0.1397 0.1397)
			(layers "F.Cu" "F.Mask" "F.Paste")
			(net "MB0_ISET_R")
			(options
				(clearance outline)
				(anchor circle)
			)
			(primitives
				(gr_poly
					(pts
						(arc
							(start -0.1778 -0.2794)
							(mid -0.249642 -0.249642)
							(end -0.2794 -0.1778)
						)
						(arc
							(start -0.2794 0.1778)
							(mid -0.249642 0.249642)
							(end -0.1778 0.2794)
						)
						(arc
							(start 0.1778 0.2794)
							(mid 0.249642 0.249642)
							(end 0.2794 0.1778)
						)
						(arc
							(start 0.2794 -0.1778)
							(mid 0.249642 -0.249642)
							(end 0.1778 -0.2794)
						)
					)
					(width 0)
					(fill yes)
				)
			)
		)
		(pad "2" smd custom
			(at 0 0.4445 180)
			(size 0.1397 0.1397)
			(layers "F.Cu" "F.Mask" "F.Paste")
			(net "AGND_CURRENT_MONOA")
			(options
				(clearance outline)
				(anchor circle)
			)
			(primitives
				(gr_poly
					(pts
						(arc
							(start -0.1778 -0.2794)
							(mid -0.249642 -0.249642)
							(end -0.2794 -0.1778)
						)
						(arc
							(start -0.2794 0.1778)
							(mid -0.249642 0.249642)
							(end -0.1778 0.2794)
						)
						(arc
							(start 0.1778 0.2794)
							(mid 0.249642 0.249642)
							(end 0.2794 0.1778)
						)
						(arc
							(start 0.2794 -0.1778)
							(mid 0.249642 -0.249642)
							(end 0.1778 -0.2794)
						)
					)
					(width 0)
					(fill yes)
				)
			)
		)
	)
	(footprint ""
		(layer "F.Cu")
		(at 364.5408 -132.1054)
		(property "Reference" "R1091"
			(at 0 0 0)
			(layer "F.SilkS")
			(hide yes)
			(effects
				(font
					(size 1.27 1.27)
				)
			)
		)
		(property "Value" "137KR2F-1-GP"
			(at 0.064008 -3.993896 0)
			(unlocked yes)
			(layer "F.Fab")
			(hide yes)
			(effects
				(font
					(size 1.016 1.016)
					(thickness 0.1524)
				)
			)
		)
		(property "Device Type" "R402H16"
			(at 0.064008 -5.517896 0)
			(unlocked yes)
			(layer "F.Fab")
			(hide yes)
			(effects
				(font
					(size 1.016 1.016)
					(thickness 0.1524)
				)
			)
		)
		(duplicate_pad_numbers_are_jumpers no)
		(fp_line
			(start -0.508 -0.9398)
			(end -0.508 0.9398)
			(stroke
				(width 0.1524)
				(type default)
			)
			(layer "F.SilkS")
		)
		(fp_line
			(start 0.508 -0.9398)
			(end -0.508 -0.9398)
			(stroke
				(width 0.1524)
				(type default)
			)
			(layer "F.SilkS")
		)
		(fp_rect
			(start -0.508 0.9398)
			(end 0.508 -0.9398)
			(stroke
				(width 0)
				(type default)
			)
			(fill no)
			(layer "F.CrtYd")
		)
		(fp_rect
			(start -0.508 0.9398)
			(end 0.508 -0.9398)
			(stroke
				(width 0)
				(type default)
			)
			(fill no)
			(layer "F.Fab")
		)
		(pad "1" smd custom
			(at 0 -0.4445)
			(size 0.1397 0.1397)
			(layers "F.Cu" "F.Mask" "F.Paste")
			(net "MB1_PSET_R")
			(options
				(clearance outline)
				(anchor circle)
			)
			(primitives
				(gr_poly
					(pts
						(arc
							(start -0.1778 -0.2794)
							(mid -0.249642 -0.249642)
							(end -0.2794 -0.1778)
						)
						(arc
							(start -0.2794 0.1778)
							(mid -0.249642 0.249642)
							(end -0.1778 0.2794)
						)
						(arc
							(start 0.1778 0.2794)
							(mid 0.249642 0.249642)
							(end 0.2794 0.1778)
						)
						(arc
							(start 0.2794 -0.1778)
							(mid 0.249642 -0.249642)
							(end 0.1778 -0.2794)
						)
					)
					(width 0)
					(fill yes)
				)
			)
		)
		(pad "2" smd custom
			(at 0 0.4445)
			(size 0.1397 0.1397)
			(layers "F.Cu" "F.Mask" "F.Paste")
			(net "AGND_CURRENT_MONOB")
			(options
				(clearance outline)
				(anchor circle)
			)
			(primitives
				(gr_poly
					(pts
						(arc
							(start -0.1778 -0.2794)
							(mid -0.249642 -0.249642)
							(end -0.2794 -0.1778)
						)
						(arc
							(start -0.2794 0.1778)
							(mid -0.249642 0.249642)
							(end -0.1778 0.2794)
						)
						(arc
							(start 0.1778 0.2794)
							(mid 0.249642 0.249642)
							(end 0.2794 0.1778)
						)
						(arc
							(start 0.2794 -0.1778)
							(mid 0.249642 -0.249642)
							(end 0.1778 -0.2794)
						)
					)
					(width 0)
					(fill yes)
				)
			)
		)
	)
	(footprint ""
		(layer "F.Cu")
		(at 387.83895 -277.750016 -90)
		(property "Reference" "VIA19"
			(at 0 0 270)
			(layer "F.SilkS")
			(hide yes)
			(effects
				(font
					(size 1.27 1.27)
				)
			)
		)
		(property "Value" "100OHM-8L-1D6MM-L18L16-GP"
			(at -3.7211 -4.5085 270)
			(unlocked yes)
			(layer "F.Fab")
			(hide yes)
			(effects
				(font
					(size 1.016 1.016)
					(thickness 0.1524)
				)
			)
		)
		(property "Device Type" "VIA-PCIE-4P-394076"
			(at -3.7211 -6.0325 270)
			(unlocked yes)
			(layer "F.Fab")
			(hide yes)
			(effects
				(font
					(size 1.016 1.016)
					(thickness 0.1524)
				)
			)
		)
		(duplicate_pad_numbers_are_jumpers no)
		(fp_rect
			(start -1.9685 0.381)
			(end 1.9685 -0.381)
			(stroke
				(width 0)
				(type default)
			)
			(fill no)
			(layer "F.CrtYd")
		)
		(fp_rect
			(start -1.9685 0.381)
			(end 1.9685 -0.381)
			(stroke
				(width 0)
				(type default)
			)
			(fill no)
			(layer "F.Fab")
		)
		(pad "1" thru_hole circle
			(at -1.5875 0 270)
			(size 0.508 0.508)
			(drill 0.254)
			(layers "*.Cu" "*.Mask")
			(remove_unused_layers no)
			(net "GND")
			(clearance 0.127)
			(thermal_gap 0.127)
		)
		(pad "2" thru_hole circle
			(at -0.5715 0 270)
			(size 0.508 0.508)
			(drill 0.254)
			(layers "*.Cu" "*.Mask")
			(remove_unused_layers no)
			(net "PHY_DRV_A_TO_SCC_A_8_DP")
			(clearance 0.127)
			(thermal_gap 0.127)
		)
		(pad "3" thru_hole circle
			(at 0.5715 0 270)
			(size 0.508 0.508)
			(drill 0.254)
			(layers "*.Cu" "*.Mask")
			(remove_unused_layers no)
			(net "PHY_DRV_A_TO_SCC_A_8_DN")
			(clearance 0.127)
			(thermal_gap 0.127)
		)
		(pad "4" thru_hole circle
			(at 1.5875 0 270)
			(size 0.508 0.508)
			(drill 0.254)
			(layers "*.Cu" "*.Mask")
			(remove_unused_layers no)
			(net "GND")
			(clearance 0.127)
			(thermal_gap 0.127)
		)
	)
	(footprint ""
		(layer "F.Cu")
		(at 338.565236 -33.550352 180)
		(property "Reference" "R70"
			(at 0 0 180)
			(layer "F.SilkS")
			(hide yes)
			(effects
				(font
					(size 1.27 1.27)
				)
			)
		)
		(property "Value" "4K7R2F-GP"
			(at 0.064008 -3.993896 180)
			(unlocked yes)
			(layer "F.Fab")
			(hide yes)
			(effects
				(font
					(size 1.016 1.016)
					(thickness 0.1524)
				)
			)
		)
		(property "Device Type" "R402H16"
			(at 0.064008 -5.517896 180)
			(unlocked yes)
			(layer "F.Fab")
			(hide yes)
			(effects
				(font
					(size 1.016 1.016)
					(thickness 0.1524)
				)
			)
		)
		(duplicate_pad_numbers_are_jumpers no)
		(fp_line
			(start 0.508 -0.9398)
			(end -0.508 -0.9398)
			(stroke
				(width 0.1524)
				(type default)
			)
			(layer "F.SilkS")
		)
		(fp_line
			(start -0.508 -0.9398)
			(end -0.508 0.9398)
			(stroke
				(width 0.1524)
				(type default)
			)
			(layer "F.SilkS")
		)
		(fp_rect
			(start -0.508 0.9398)
			(end 0.508 -0.9398)
			(stroke
				(width 0)
				(type default)
			)
			(fill no)
			(layer "F.CrtYd")
		)
		(fp_rect
			(start -0.508 0.9398)
			(end 0.508 -0.9398)
			(stroke
				(width 0)
				(type default)
			)
			(fill no)
			(layer "F.Fab")
		)
		(pad "1" smd custom
			(at 0 -0.4445 180)
			(size 0.1397 0.1397)
			(layers "F.Cu" "F.Mask" "F.Paste")
			(net "IO_EXP11_A0")
			(options
				(clearance outline)
				(anchor circle)
			)
			(primitives
				(gr_poly
					(pts
						(arc
							(start -0.1778 -0.2794)
							(mid -0.249642 -0.249642)
							(end -0.2794 -0.1778)
						)
						(arc
							(start -0.2794 0.1778)
							(mid -0.249642 0.249642)
							(end -0.1778 0.2794)
						)
						(arc
							(start 0.1778 0.2794)
							(mid 0.249642 0.249642)
							(end 0.2794 0.1778)
						)
						(arc
							(start 0.2794 -0.1778)
							(mid 0.249642 -0.249642)
							(end 0.1778 -0.2794)
						)
					)
					(width 0)
					(fill yes)
				)
			)
		)
		(pad "2" smd custom
			(at 0 0.4445 180)
			(size 0.1397 0.1397)
			(layers "F.Cu" "F.Mask" "F.Paste")
			(net "GND")
			(options
				(clearance outline)
				(anchor circle)
			)
			(primitives
				(gr_poly
					(pts
						(arc
							(start -0.1778 -0.2794)
							(mid -0.249642 -0.249642)
							(end -0.2794 -0.1778)
						)
						(arc
							(start -0.2794 0.1778)
							(mid -0.249642 0.249642)
							(end -0.1778 0.2794)
						)
						(arc
							(start 0.1778 0.2794)
							(mid 0.249642 0.249642)
							(end 0.2794 0.1778)
						)
						(arc
							(start 0.2794 -0.1778)
							(mid 0.249642 -0.249642)
							(end 0.1778 -0.2794)
						)
					)
					(width 0)
					(fill yes)
				)
			)
		)
	)
	(footprint ""
		(layer "F.Cu")
		(at 176.657 -64.683894 90)
		(property "Reference" "R798"
			(at 0 0 90)
			(layer "F.SilkS")
			(hide yes)
			(effects
				(font
					(size 1.27 1.27)
				)
			)
		)
		(property "Value" "2R6F-GP"
			(at -0.0508 -4.8514 90)
			(unlocked yes)
			(layer "F.Fab")
			(hide yes)
			(effects
				(font
					(size 1.016 1.016)
					(thickness 0.1524)
				)
			)
		)
		(property "Device Type" "R1206H26"
			(at 0 -6.3754 90)
			(unlocked yes)
			(layer "F.Fab")
			(hide yes)
			(effects
				(font
					(size 1.016 1.016)
					(thickness 0.1524)
				)
			)
		)
		(duplicate_pad_numbers_are_jumpers no)
		(fp_line
			(start 1.016 -2.2352)
			(end 1.016 2.2352)
			(stroke
				(width 0.1524)
				(type default)
			)
			(layer "F.SilkS")
		)
		(fp_line
			(start -1.016 -2.2352)
			(end 1.016 -2.2352)
			(stroke
				(width 0.1524)
				(type default)
			)
			(layer "F.SilkS")
		)
		(fp_line
			(start 1.016 2.2352)
			(end -1.016 2.2352)
			(stroke
				(width 0.1524)
				(type default)
			)
			(layer "F.SilkS")
		)
		(fp_line
			(start -1.016 2.2352)
			(end -1.016 -2.2352)
			(stroke
				(width 0.1524)
				(type default)
			)
			(layer "F.SilkS")
		)
		(fp_rect
			(start -1.0922 2.3114)
			(end 1.0922 -2.3114)
			(stroke
				(width 0)
				(type default)
			)
			(fill no)
			(layer "F.CrtYd")
		)
		(fp_poly
			(pts
				(xy -1.0922 -2.3114) (xy 1.0922 -2.3114) (xy 1.0922 2.3114) (xy -1.0922 2.3114)
			)
			(stroke
				(width 0)
				(type default)
			)
			(fill no)
			(layer "F.Fab")
		)
		(pad "1" smd rect
			(at 0 -1.397 90)
			(size 1.651 1.27)
			(layers "F.Cu" "F.Mask" "F.Paste")
			(net "P12V_HDD29")
		)
		(pad "2" smd rect
			(at 0 1.397 90)
			(size 1.651 1.27)
			(layers "F.Cu" "F.Mask" "F.Paste")
			(net "12V_PRE_29")
		)
	)
	(footprint ""
		(layer "F.Cu")
		(at 413.318452 -61.102494 -90)
		(property "Reference" "C474"
			(at 0 0 270)
			(layer "F.SilkS")
			(hide yes)
			(effects
				(font
					(size 1.27 1.27)
				)
			)
		)
		(property "Value" "SCD01U50V2KX-1GP"
			(at 1.1811 -2.7051 270)
			(unlocked yes)
			(layer "F.Fab")
			(hide yes)
			(effects
				(font
					(size 1.016 1.016)
					(thickness 0.1524)
				)
			)
		)
		(property "Device Type" "C402H22"
			(at 1.1811 -4.2291 270)
			(unlocked yes)
			(layer "F.Fab")
			(hide yes)
			(effects
				(font
					(size 1.016 1.016)
					(thickness 0.1524)
				)
			)
		)
		(duplicate_pad_numbers_are_jumpers no)
		(fp_rect
			(start -0.4318 0.9525)
			(end 0.4318 -0.9525)
			(stroke
				(width 0)
				(type default)
			)
			(fill no)
			(layer "F.CrtYd")
		)
		(fp_rect
			(start -0.4318 0.9525)
			(end 0.4318 -0.9525)
			(stroke
				(width 0)
				(type default)
			)
			(fill no)
			(layer "F.Fab")
		)
		(pad "1" smd custom
			(at 0 -0.4445 270)
			(size 0.1524 0.1524)
			(layers "F.Cu" "F.Mask" "F.Paste")
			(net "HDD_PRSNT_33")
			(options
				(clearance outline)
				(anchor circle)
			)
			(primitives
				(gr_poly
					(pts
						(arc
							(start 0.3048 -0.2032)
							(mid 0.275042 -0.275042)
							(end 0.2032 -0.3048)
						)
						(arc
							(start -0.2032 -0.3048)
							(mid -0.275042 -0.275042)
							(end -0.3048 -0.2032)
						)
						(arc
							(start -0.3048 0.2032)
							(mid -0.275042 0.275042)
							(end -0.2032 0.3048)
						)
						(arc
							(start 0.2032 0.3048)
							(mid 0.275042 0.275042)
							(end 0.3048 0.2032)
						)
					)
					(width 0)
					(fill yes)
				)
			)
		)
		(pad "2" smd custom
			(at 0 0.4445 270)
			(size 0.1524 0.1524)
			(layers "F.Cu" "F.Mask" "F.Paste")
			(net "GND")
			(options
				(clearance outline)
				(anchor circle)
			)
			(primitives
				(gr_poly
					(pts
						(arc
							(start 0.3048 -0.2032)
							(mid 0.275042 -0.275042)
							(end 0.2032 -0.3048)
						)
						(arc
							(start -0.2032 -0.3048)
							(mid -0.275042 -0.275042)
							(end -0.3048 -0.2032)
						)
						(arc
							(start -0.3048 0.2032)
							(mid -0.275042 0.275042)
							(end -0.2032 0.3048)
						)
						(arc
							(start 0.2032 0.3048)
							(mid 0.275042 0.275042)
							(end 0.3048 0.2032)
						)
					)
					(width 0)
					(fill yes)
				)
			)
		)
	)
	(footprint ""
		(layer "F.Cu")
		(at 141.042898 -59.857894)
		(property "Reference" "Q170"
			(at 0 0 0)
			(layer "F.SilkS")
			(hide yes)
			(effects
				(font
					(size 1.27 1.27)
				)
			)
		)
		(property "Value" "AO4407AL-GP"
			(at -3.707384 -1.5367 0)
			(unlocked yes)
			(layer "F.Fab")
			(hide yes)
			(effects
				(font
					(size 1.016 1.016)
					(thickness 0.1524)
				)
			)
		)
		(property "Device Type" "SOIC8H69"
			(at -3.707384 -3.0607 0)
			(unlocked yes)
			(layer "F.Fab")
			(hide yes)
			(effects
				(font
					(size 1.016 1.016)
					(thickness 0.1524)
				)
			)
		)
		(duplicate_pad_numbers_are_jumpers no)
		(fp_line
			(start -2.7432 -1.4224)
			(end -2.7432 1.4224)
			(stroke
				(width 0.1524)
				(type default)
			)
			(layer "F.SilkS")
		)
		(fp_line
			(start -2.7432 1.4224)
			(end -2.6416 1.4224)
			(stroke
				(width 0.1524)
				(type default)
			)
			(layer "F.SilkS")
		)
		(fp_line
			(start -2.7432 1.4224)
			(end 2.1336 1.4224)
			(stroke
				(width 0.1524)
				(type default)
			)
			(layer "F.SilkS")
		)
		(fp_line
			(start -2.7178 -0.508)
			(end -2.1844 -0.0508)
			(stroke
				(width 0.1524)
				(type default)
			)
			(layer "F.SilkS")
		)
		(fp_line
			(start -2.6289 3.4417)
			(end -2.6289 1.4732)
			(stroke
				(width 0.381)
				(type default)
			)
			(layer "F.SilkS")
		)
		(fp_line
			(start -2.1844 -0.0508)
			(end -2.7178 0.508)
			(stroke
				(width 0.1524)
				(type default)
			)
			(layer "F.SilkS")
		)
		(fp_line
			(start 2.1336 -1.4224)
			(end -2.7432 -1.4224)
			(stroke
				(width 0.1524)
				(type default)
			)
			(layer "F.SilkS")
		)
		(fp_line
			(start 2.1336 1.4224)
			(end 2.1336 -1.4224)
			(stroke
				(width 0.1524)
				(type default)
			)
			(layer "F.SilkS")
		)
		(fp_poly
			(pts
				(xy -2.2098 -1.4224) (xy -2.2098 1.4224) (xy 2.2098 1.4224) (xy 2.2098 -1.4224)
			)
			(stroke
				(width 0)
				(type default)
			)
			(fill yes)
			(layer "F.SilkS")
		)
		(fp_rect
			(start -2.450084 2.999994)
			(end 2.450084 -2.999994)
			(stroke
				(width 0)
				(type default)
			)
			(fill no)
			(layer "F.CrtYd")
		)
		(fp_poly
			(pts
				(xy -2.8194 3.6322) (xy -2.8194 -3.6322) (xy 2.8194 -3.6322) (xy 2.8194 1.18364) (xy 2.450084 1.18364)
				(xy 2.450084 -2.999994) (xy -2.450084 -2.999994) (xy -2.450084 2.999994) (xy 2.450084 2.999994)
				(xy 2.450084 1.18618) (xy 2.8194 1.18618) (xy 2.8194 3.6322)
			)
			(stroke
				(width 0)
				(type default)
			)
			(fill no)
			(layer "F.CrtYd")
		)
		(fp_rect
			(start -2.8194 3.6322)
			(end 2.8194 -3.6322)
			(stroke
				(width 0)
				(type default)
			)
			(fill no)
			(layer "F.Fab")
		)
		(pad "1" smd rect
			(at -1.905 2.54)
			(size 0.635 1.651)
			(layers "F.Cu" "F.Mask" "F.Paste")
			(net "P12V_A")
		)
		(pad "2" smd rect
			(at -0.635 2.54)
			(size 0.635 1.651)
			(layers "F.Cu" "F.Mask" "F.Paste")
			(net "P12V_A")
		)
		(pad "3" smd rect
			(at 0.635 2.54)
			(size 0.635 1.651)
			(layers "F.Cu" "F.Mask" "F.Paste")
			(net "P12V_A")
		)
		(pad "4" smd rect
			(at 1.905 2.54)
			(size 0.635 1.651)
			(layers "F.Cu" "F.Mask" "F.Paste")
			(net "SW_HDD_N28")
		)
		(pad "5" smd rect
			(at 1.905 -2.54)
			(size 0.635 1.651)
			(layers "F.Cu" "F.Mask" "F.Paste")
			(net "P12V_HDD28")
		)
		(pad "6" smd rect
			(at 0.635 -2.54)
			(size 0.635 1.651)
			(layers "F.Cu" "F.Mask" "F.Paste")
			(net "P12V_HDD28")
		)
		(pad "7" smd rect
			(at -0.635 -2.54)
			(size 0.635 1.651)
			(layers "F.Cu" "F.Mask" "F.Paste")
			(net "P12V_HDD28")
		)
		(pad "8" smd rect
			(at -1.905 -2.54)
			(size 0.635 1.651)
			(layers "F.Cu" "F.Mask" "F.Paste")
			(net "P12V_HDD28")
		)
	)
	(footprint ""
		(layer "F.Cu")
		(at 300.689772 -184.5945 90)
		(property "Reference" "C121"
			(at 0 0 90)
			(layer "F.SilkS")
			(hide yes)
			(effects
				(font
					(size 1.27 1.27)
				)
			)
		)
		(property "Value" "SC22U25V6KX-2-GP-U"
			(at -2.860802 -5.279644 90)
			(unlocked yes)
			(layer "F.Fab")
			(hide yes)
			(effects
				(font
					(size 1.016 1.016)
					(thickness 0.1524)
				)
			)
		)
		(property "Device Type" "C1206-TO0D3H75"
			(at -2.860802 -6.803644 90)
			(unlocked yes)
			(layer "F.Fab")
			(hide yes)
			(effects
				(font
					(size 1.016 1.016)
					(thickness 0.1524)
				)
			)
		)
		(duplicate_pad_numbers_are_jumpers no)
		(fp_line
			(start 1.3081 -2.3749)
			(end 1.3081 2.3749)
			(stroke
				(width 0.1524)
				(type default)
			)
			(layer "F.SilkS")
		)
		(fp_line
			(start -1.3081 -2.3749)
			(end 1.3081 -2.3749)
			(stroke
				(width 0.1524)
				(type default)
			)
			(layer "F.SilkS")
		)
		(fp_line
			(start 1.3081 2.3749)
			(end -1.3081 2.3749)
			(stroke
				(width 0.1524)
				(type default)
			)
			(layer "F.SilkS")
		)
		(fp_line
			(start -1.3081 2.3749)
			(end -1.3081 -2.3749)
			(stroke
				(width 0.1524)
				(type default)
			)
			(layer "F.SilkS")
		)
		(fp_rect
			(start -0.8001 1.6002)
			(end 0.8001 -1.6002)
			(stroke
				(width 0)
				(type default)
			)
			(fill no)
			(layer "F.CrtYd")
		)
		(fp_poly
			(pts
				(xy -1.5621 2.4511) (xy -1.5621 1.6002) (xy 0.8001 1.6002) (xy 0.8001 -1.6002) (xy -0.8001 -1.6002)
				(xy -0.8001 1.5875) (xy -1.5621 1.5875) (xy -1.5621 -2.4511) (xy 1.5621 -2.4511) (xy 1.5621 2.4511)
			)
			(stroke
				(width 0)
				(type default)
			)
			(fill no)
			(layer "F.CrtYd")
		)
		(fp_rect
			(start -1.5621 2.4511)
			(end 1.5621 -2.4511)
			(stroke
				(width 0)
				(type default)
			)
			(fill no)
			(layer "F.Fab")
		)
		(pad "1" smd rect
			(at 0 -1.392936 90)
			(size 2.1082 1.4478)
			(layers "F.Cu" "F.Mask" "F.Paste")
			(net "P12V_B_COMP")
		)
		(pad "2" smd rect
			(at 0 1.392936 90)
			(size 2.1082 1.4478)
			(layers "F.Cu" "F.Mask" "F.Paste")
			(net "GND")
		)
	)
	(footprint ""
		(layer "F.Cu")
		(at 318.262 -291.127942 -90)
		(property "Reference" "C124"
			(at 0 0 270)
			(layer "F.SilkS")
			(hide yes)
			(effects
				(font
					(size 1.27 1.27)
				)
			)
		)
		(property "Value" "SCD01U50V2KX-1GP"
			(at 1.1811 -2.7051 270)
			(unlocked yes)
			(layer "F.Fab")
			(hide yes)
			(effects
				(font
					(size 1.016 1.016)
					(thickness 0.1524)
				)
			)
		)
		(property "Device Type" "C402H22"
			(at 1.1811 -4.2291 270)
			(unlocked yes)
			(layer "F.Fab")
			(hide yes)
			(effects
				(font
					(size 1.016 1.016)
					(thickness 0.1524)
				)
			)
		)
		(duplicate_pad_numbers_are_jumpers no)
		(fp_rect
			(start -0.4318 0.9525)
			(end 0.4318 -0.9525)
			(stroke
				(width 0)
				(type default)
			)
			(fill no)
			(layer "F.CrtYd")
		)
		(fp_rect
			(start -0.4318 0.9525)
			(end 0.4318 -0.9525)
			(stroke
				(width 0)
				(type default)
			)
			(fill no)
			(layer "F.Fab")
		)
		(pad "1" smd custom
			(at 0 -0.4445 270)
			(size 0.1524 0.1524)
			(layers "F.Cu" "F.Mask" "F.Paste")
			(net "HDD_PRSNT_6")
			(options
				(clearance outline)
				(anchor circle)
			)
			(primitives
				(gr_poly
					(pts
						(arc
							(start 0.3048 -0.2032)
							(mid 0.275042 -0.275042)
							(end 0.2032 -0.3048)
						)
						(arc
							(start -0.2032 -0.3048)
							(mid -0.275042 -0.275042)
							(end -0.3048 -0.2032)
						)
						(arc
							(start -0.3048 0.2032)
							(mid -0.275042 0.275042)
							(end -0.2032 0.3048)
						)
						(arc
							(start 0.2032 0.3048)
							(mid 0.275042 0.275042)
							(end 0.3048 0.2032)
						)
					)
					(width 0)
					(fill yes)
				)
			)
		)
		(pad "2" smd custom
			(at 0 0.4445 270)
			(size 0.1524 0.1524)
			(layers "F.Cu" "F.Mask" "F.Paste")
			(net "GND")
			(options
				(clearance outline)
				(anchor circle)
			)
			(primitives
				(gr_poly
					(pts
						(arc
							(start 0.3048 -0.2032)
							(mid 0.275042 -0.275042)
							(end 0.2032 -0.3048)
						)
						(arc
							(start -0.2032 -0.3048)
							(mid -0.275042 -0.275042)
							(end -0.3048 -0.2032)
						)
						(arc
							(start -0.3048 0.2032)
							(mid -0.275042 0.275042)
							(end -0.2032 0.3048)
						)
						(arc
							(start 0.2032 0.3048)
							(mid 0.275042 0.275042)
							(end 0.3048 0.2032)
						)
					)
					(width 0)
					(fill yes)
				)
			)
		)
	)
	(footprint ""
		(layer "F.Cu")
		(at 315.484256 -290.934902 90)
		(property "Reference" "R576"
			(at 0 0 90)
			(layer "F.SilkS")
			(hide yes)
			(effects
				(font
					(size 1.27 1.27)
				)
			)
		)
		(property "Value" "4K7R2J-2-GP"
			(at 0.064008 -3.993896 90)
			(unlocked yes)
			(layer "F.Fab")
			(hide yes)
			(effects
				(font
					(size 1.016 1.016)
					(thickness 0.1524)
				)
			)
		)
		(property "Device Type" "R402H16"
			(at 0.064008 -5.517896 90)
			(unlocked yes)
			(layer "F.Fab")
			(hide yes)
			(effects
				(font
					(size 1.016 1.016)
					(thickness 0.1524)
				)
			)
		)
		(duplicate_pad_numbers_are_jumpers no)
		(fp_line
			(start 0.508 -0.9398)
			(end -0.508 -0.9398)
			(stroke
				(width 0.1524)
				(type default)
			)
			(layer "F.SilkS")
		)
		(fp_line
			(start -0.508 -0.9398)
			(end -0.508 0.9398)
			(stroke
				(width 0.1524)
				(type default)
			)
			(layer "F.SilkS")
		)
		(fp_rect
			(start -0.508 0.9398)
			(end 0.508 -0.9398)
			(stroke
				(width 0)
				(type default)
			)
			(fill no)
			(layer "F.CrtYd")
		)
		(fp_rect
			(start -0.508 0.9398)
			(end 0.508 -0.9398)
			(stroke
				(width 0)
				(type default)
			)
			(fill no)
			(layer "F.Fab")
		)
		(pad "1" smd custom
			(at 0 -0.4445 90)
			(size 0.1397 0.1397)
			(layers "F.Cu" "F.Mask" "F.Paste")
			(net "DRIVE_B_30_ACT")
			(options
				(clearance outline)
				(anchor circle)
			)
			(primitives
				(gr_poly
					(pts
						(arc
							(start -0.1778 -0.2794)
							(mid -0.249642 -0.249642)
							(end -0.2794 -0.1778)
						)
						(arc
							(start -0.2794 0.1778)
							(mid -0.249642 0.249642)
							(end -0.1778 0.2794)
						)
						(arc
							(start 0.1778 0.2794)
							(mid 0.249642 0.249642)
							(end 0.2794 0.1778)
						)
						(arc
							(start 0.2794 -0.1778)
							(mid 0.249642 -0.249642)
							(end 0.1778 -0.2794)
						)
					)
					(width 0)
					(fill yes)
				)
			)
		)
		(pad "2" smd custom
			(at 0 0.4445 90)
			(size 0.1397 0.1397)
			(layers "F.Cu" "F.Mask" "F.Paste")
			(net "GND")
			(options
				(clearance outline)
				(anchor circle)
			)
			(primitives
				(gr_poly
					(pts
						(arc
							(start -0.1778 -0.2794)
							(mid -0.249642 -0.249642)
							(end -0.2794 -0.1778)
						)
						(arc
							(start -0.2794 0.1778)
							(mid -0.249642 0.249642)
							(end -0.1778 0.2794)
						)
						(arc
							(start 0.1778 0.2794)
							(mid 0.249642 0.249642)
							(end 0.2794 0.1778)
						)
						(arc
							(start 0.2794 -0.1778)
							(mid 0.249642 -0.249642)
							(end 0.1778 -0.2794)
						)
					)
					(width 0)
					(fill yes)
				)
			)
		)
	)
	(footprint ""
		(layer "F.Cu")
		(at 190.246 -183.747918)
		(property "Reference" "TP87"
			(at 0 0 0)
			(layer "F.SilkS")
			(hide yes)
			(effects
				(font
					(size 1.27 1.27)
				)
			)
		)
		(property "Value" "TPAD32-GP"
			(at -0.0508 -1.6764 0)
			(unlocked yes)
			(layer "F.Fab")
			(hide yes)
			(effects
				(font
					(size 1.016 1.016)
					(thickness 0.1524)
				)
			)
		)
		(property "Device Type" "TPAD32"
			(at -0.0508 -3.2004 0)
			(unlocked yes)
			(layer "F.Fab")
			(hide yes)
			(effects
				(font
					(size 1.016 1.016)
					(thickness 0.1524)
				)
			)
		)
		(duplicate_pad_numbers_are_jumpers no)
		(fp_poly
			(pts
				(arc
					(start 0.4064 0)
					(mid -0.4064 0)
					(end 0.4064 0)
				)
			)
			(stroke
				(width 0)
				(type default)
			)
			(fill no)
			(layer "F.CrtYd")
		)
		(fp_poly
			(pts
				(arc
					(start 0.7112 0)
					(mid -0.7112 0)
					(end 0.7112 0)
				)
			)
			(stroke
				(width 0)
				(type default)
			)
			(fill no)
			(layer "F.Fab")
		)
		(pad "1" smd circle
			(at 0 0)
			(size 0.8128 0.8128)
			(layers "F.Cu" "F.Mask" "F.Paste")
			(net "ACT_HDD_17")
		)
	)
	(footprint ""
		(layer "F.Cu")
		(at 223.347534 -377.002294 180)
		(property "Reference" "R156"
			(at 0 0 180)
			(layer "F.SilkS")
			(hide yes)
			(effects
				(font
					(size 1.27 1.27)
				)
			)
		)
		(property "Value" "0R2J-2-GP"
			(at 0.064008 -3.993896 180)
			(unlocked yes)
			(layer "F.Fab")
			(hide yes)
			(effects
				(font
					(size 1.016 1.016)
					(thickness 0.1524)
				)
			)
		)
		(property "Device Type" "R402H16"
			(at 0.064008 -5.517896 180)
			(unlocked yes)
			(layer "F.Fab")
			(hide yes)
			(effects
				(font
					(size 1.016 1.016)
					(thickness 0.1524)
				)
			)
		)
		(duplicate_pad_numbers_are_jumpers no)
		(fp_line
			(start 0.508 -0.9398)
			(end -0.508 -0.9398)
			(stroke
				(width 0.1524)
				(type default)
			)
			(layer "F.SilkS")
		)
		(fp_line
			(start -0.508 -0.9398)
			(end -0.508 0.9398)
			(stroke
				(width 0.1524)
				(type default)
			)
			(layer "F.SilkS")
		)
		(fp_rect
			(start -0.508 0.9398)
			(end 0.508 -0.9398)
			(stroke
				(width 0)
				(type default)
			)
			(fill no)
			(layer "F.CrtYd")
		)
		(fp_rect
			(start -0.508 0.9398)
			(end 0.508 -0.9398)
			(stroke
				(width 0)
				(type default)
			)
			(fill no)
			(layer "F.Fab")
		)
		(pad "1" smd custom
			(at 0 -0.4445 180)
			(size 0.1397 0.1397)
			(layers "F.Cu" "F.Mask" "F.Paste")
			(net "IO_EXP3_LED_SDA")
			(options
				(clearance outline)
				(anchor circle)
			)
			(primitives
				(gr_poly
					(pts
						(arc
							(start -0.1778 -0.2794)
							(mid -0.249642 -0.249642)
							(end -0.2794 -0.1778)
						)
						(arc
							(start -0.2794 0.1778)
							(mid -0.249642 0.249642)
							(end -0.1778 0.2794)
						)
						(arc
							(start 0.1778 0.2794)
							(mid 0.249642 0.249642)
							(end 0.2794 0.1778)
						)
						(arc
							(start 0.2794 -0.1778)
							(mid 0.249642 -0.249642)
							(end 0.1778 -0.2794)
						)
					)
					(width 0)
					(fill yes)
				)
			)
		)
		(pad "2" smd custom
			(at 0 0.4445 180)
			(size 0.1397 0.1397)
			(layers "F.Cu" "F.Mask" "F.Paste")
			(net "I2C_DRIVE_B_FLT_LED_SDA")
			(options
				(clearance outline)
				(anchor circle)
			)
			(primitives
				(gr_poly
					(pts
						(arc
							(start -0.1778 -0.2794)
							(mid -0.249642 -0.249642)
							(end -0.2794 -0.1778)
						)
						(arc
							(start -0.2794 0.1778)
							(mid -0.249642 0.249642)
							(end -0.1778 0.2794)
						)
						(arc
							(start 0.1778 0.2794)
							(mid 0.249642 0.249642)
							(end 0.2794 0.1778)
						)
						(arc
							(start 0.2794 -0.1778)
							(mid 0.249642 -0.249642)
							(end 0.1778 -0.2794)
						)
					)
					(width 0)
					(fill yes)
				)
			)
		)
	)
	(footprint ""
		(layer "F.Cu")
		(at 404.400004 -289.999928)
		(property "Reference" ""
			(at 0 0 0)
			(layer "F.SilkS")
			(hide yes)
			(effects
				(font
					(size 1.27 1.27)
				)
			)
		)
		(property "Value" "*"
			(at -6.3373 -0.4572 0)
			(unlocked yes)
			(layer "F.Fab")
			(hide yes)
			(effects
				(font
					(size 1.016 1.016)
					(thickness 0.1524)
				)
			)
		)
		(duplicate_pad_numbers_are_jumpers no)
		(fp_poly
			(pts
				(arc
					(start 5.0673 0)
					(mid -5.0673 0)
					(end 5.0673 0)
				)
			)
			(stroke
				(width 0)
				(type default)
			)
			(fill no)
			(layer "B.CrtYd")
		)
		(fp_poly
			(pts
				(arc
					(start 5.0673 0)
					(mid -5.0673 0)
					(end 5.0673 0)
				)
			)
			(stroke
				(width 0)
				(type default)
			)
			(fill no)
			(layer "F.CrtYd")
		)
		(fp_poly
			(pts
				(arc
					(start 5.0673 0)
					(mid -5.0673 0)
					(end 5.0673 0)
				)
			)
			(stroke
				(width 0)
				(type default)
			)
			(fill no)
			(layer "B.Fab")
		)
		(fp_poly
			(pts
				(arc
					(start 5.0673 0)
					(mid -5.0673 0)
					(end 5.0673 0)
				)
			)
			(stroke
				(width 0)
				(type default)
			)
			(fill no)
			(layer "F.Fab")
		)
		(pad "1" thru_hole circle
			(at 0 0)
			(size 9.525 9.525)
			(drill 3.556)
			(layers "*.Cu" "*.Mask")
			(remove_unused_layers no)
			(net "Net_94")
			(clearance -2.4765)
			(thermal_gap 0.3048)
			(padstack
				(mode front_inner_back)
				(layer "Inner"
					(shape circle)
					(size 3.9624 3.9624)
					(clearance 0.3048)
				)
				(layer "B.Cu"
					(shape circle)
					(size 9.525 9.525)
					(clearance -2.4765)
				)
			)
		)
		(zone
			(layers "F.Cu" "B.Cu" "In1.Cu" "In2.Cu" "In3.Cu" "In4.Cu" "In5.Cu" "In6.Cu"
				"In7.Cu" "In8.Cu" "In9.Cu" "In10.Cu"
			)
			(hatch none 0.5)
			(connect_pads
				(clearance 0)
			)
			(min_thickness 0.25)
			(keepout
				(tracks not_allowed)
				(vias allowed)
				(pads allowed)
				(copperpour not_allowed)
				(footprints allowed)
			)
			(placement
				(enabled no)
				(sheetname "")
			)
			(fill
				(thermal_gap 0.5)
				(thermal_bridge_width 0.5)
				(island_removal_mode 0)
			)
			(polygon
				(pts
					(arc
						(start 409.162504 -289.999928)
						(mid 399.637504 -289.999928)
						(end 409.162504 -289.999928)
					)
				)
			)
		)
	)
	(footprint ""
		(layer "F.Cu")
		(at 364.290102 -278.554942 -90)
		(property "Reference" "R298"
			(at 0 0 270)
			(layer "F.SilkS")
			(hide yes)
			(effects
				(font
					(size 1.27 1.27)
				)
			)
		)
		(property "Value" "4K7R2J-2-GP"
			(at 0.064008 -3.993896 270)
			(unlocked yes)
			(layer "F.Fab")
			(hide yes)
			(effects
				(font
					(size 1.016 1.016)
					(thickness 0.1524)
				)
			)
		)
		(property "Device Type" "R402H16"
			(at 0.064008 -5.517896 270)
			(unlocked yes)
			(layer "F.Fab")
			(hide yes)
			(effects
				(font
					(size 1.016 1.016)
					(thickness 0.1524)
				)
			)
		)
		(duplicate_pad_numbers_are_jumpers no)
		(fp_line
			(start -0.508 -0.9398)
			(end -0.508 0.9398)
			(stroke
				(width 0.1524)
				(type default)
			)
			(layer "F.SilkS")
		)
		(fp_line
			(start 0.508 -0.9398)
			(end -0.508 -0.9398)
			(stroke
				(width 0.1524)
				(type default)
			)
			(layer "F.SilkS")
		)
		(fp_rect
			(start -0.508 0.9398)
			(end 0.508 -0.9398)
			(stroke
				(width 0)
				(type default)
			)
			(fill no)
			(layer "F.CrtYd")
		)
		(fp_rect
			(start -0.508 0.9398)
			(end 0.508 -0.9398)
			(stroke
				(width 0)
				(type default)
			)
			(fill no)
			(layer "F.Fab")
		)
		(pad "1" smd custom
			(at 0 -0.4445 270)
			(size 0.1397 0.1397)
			(layers "F.Cu" "F.Mask" "F.Paste")
			(net "P12V_A")
			(options
				(clearance outline)
				(anchor circle)
			)
			(primitives
				(gr_poly
					(pts
						(arc
							(start -0.1778 -0.2794)
							(mid -0.249642 -0.249642)
							(end -0.2794 -0.1778)
						)
						(arc
							(start -0.2794 0.1778)
							(mid -0.249642 0.249642)
							(end -0.1778 0.2794)
						)
						(arc
							(start 0.1778 0.2794)
							(mid 0.249642 0.249642)
							(end 0.2794 0.1778)
						)
						(arc
							(start 0.2794 -0.1778)
							(mid 0.249642 -0.249642)
							(end 0.1778 -0.2794)
						)
					)
					(width 0)
					(fill yes)
				)
			)
		)
		(pad "2" smd custom
			(at 0 0.4445 270)
			(size 0.1397 0.1397)
			(layers "F.Cu" "F.Mask" "F.Paste")
			(net "SW_HDD_P7")
			(options
				(clearance outline)
				(anchor circle)
			)
			(primitives
				(gr_poly
					(pts
						(arc
							(start -0.1778 -0.2794)
							(mid -0.249642 -0.249642)
							(end -0.2794 -0.1778)
						)
						(arc
							(start -0.2794 0.1778)
							(mid -0.249642 0.249642)
							(end -0.1778 0.2794)
						)
						(arc
							(start 0.1778 0.2794)
							(mid 0.249642 0.249642)
							(end 0.2794 0.1778)
						)
						(arc
							(start 0.2794 -0.1778)
							(mid 0.249642 -0.249642)
							(end 0.1778 -0.2794)
						)
					)
					(width 0)
					(fill yes)
				)
			)
		)
	)
	(footprint ""
		(layer "F.Cu")
		(at 428.152052 -73.954894 180)
		(property "Reference" "C475"
			(at 0 0 180)
			(layer "F.SilkS")
			(hide yes)
			(effects
				(font
					(size 1.27 1.27)
				)
			)
		)
		(property "Value" "SC4D7U25V5KX-1-GP"
			(at -0.0762 -6.1214 180)
			(unlocked yes)
			(layer "F.Fab")
			(hide yes)
			(effects
				(font
					(size 1.016 1.016)
					(thickness 0.1524)
				)
			)
		)
		(property "Device Type" "C805H58"
			(at -0.0762 -8.1534 180)
			(unlocked yes)
			(layer "F.Fab")
			(hide yes)
			(effects
				(font
					(size 1.016 1.016)
					(thickness 0.1524)
				)
			)
		)
		(duplicate_pad_numbers_are_jumpers no)
		(fp_line
			(start 0.635 0)
			(end -0.635 0)
			(stroke
				(width 0.508)
				(type default)
			)
			(layer "F.SilkS")
		)
		(fp_rect
			(start -0.9652 1.778)
			(end 0.9652 -1.778)
			(stroke
				(width 0)
				(type default)
			)
			(fill no)
			(layer "F.CrtYd")
		)
		(fp_poly
			(pts
				(xy -0.9652 -1.778) (xy 0.9652 -1.778) (xy 0.9652 1.778) (xy -0.9652 1.778)
			)
			(stroke
				(width 0)
				(type default)
			)
			(fill no)
			(layer "F.Fab")
		)
		(pad "1" smd rect
			(at 0 -0.9652 180)
			(size 1.397 1.143)
			(layers "F.Cu" "F.Mask" "F.Paste")
			(net "P12V_HDD33")
		)
		(pad "2" smd rect
			(at 0 0.9652 180)
			(size 1.397 1.143)
			(layers "F.Cu" "F.Mask" "F.Paste")
			(net "GND")
		)
	)
	(footprint ""
		(layer "F.Cu")
		(at 86.096348 -48.554894 90)
		(property "Reference" "R740"
			(at 0 0 90)
			(layer "F.SilkS")
			(hide yes)
			(effects
				(font
					(size 1.27 1.27)
				)
			)
		)
		(property "Value" "4K7R2J-2-GP"
			(at 0.064008 -3.993896 90)
			(unlocked yes)
			(layer "F.Fab")
			(hide yes)
			(effects
				(font
					(size 1.016 1.016)
					(thickness 0.1524)
				)
			)
		)
		(property "Device Type" "R402H16"
			(at 0.064008 -5.517896 90)
			(unlocked yes)
			(layer "F.Fab")
			(hide yes)
			(effects
				(font
					(size 1.016 1.016)
					(thickness 0.1524)
				)
			)
		)
		(duplicate_pad_numbers_are_jumpers no)
		(fp_line
			(start 0.508 -0.9398)
			(end -0.508 -0.9398)
			(stroke
				(width 0.1524)
				(type default)
			)
			(layer "F.SilkS")
		)
		(fp_line
			(start -0.508 -0.9398)
			(end -0.508 0.9398)
			(stroke
				(width 0.1524)
				(type default)
			)
			(layer "F.SilkS")
		)
		(fp_rect
			(start -0.508 0.9398)
			(end 0.508 -0.9398)
			(stroke
				(width 0)
				(type default)
			)
			(fill no)
			(layer "F.CrtYd")
		)
		(fp_rect
			(start -0.508 0.9398)
			(end 0.508 -0.9398)
			(stroke
				(width 0)
				(type default)
			)
			(fill no)
			(layer "F.Fab")
		)
		(pad "1" smd custom
			(at 0 -0.4445 90)
			(size 0.1397 0.1397)
			(layers "F.Cu" "F.Mask" "F.Paste")
			(net "SW_PWR_R_HDD26")
			(options
				(clearance outline)
				(anchor circle)
			)
			(primitives
				(gr_poly
					(pts
						(arc
							(start -0.1778 -0.2794)
							(mid -0.249642 -0.249642)
							(end -0.2794 -0.1778)
						)
						(arc
							(start -0.2794 0.1778)
							(mid -0.249642 0.249642)
							(end -0.1778 0.2794)
						)
						(arc
							(start 0.1778 0.2794)
							(mid 0.249642 0.249642)
							(end 0.2794 0.1778)
						)
						(arc
							(start 0.2794 -0.1778)
							(mid 0.249642 -0.249642)
							(end 0.1778 -0.2794)
						)
					)
					(width 0)
					(fill yes)
				)
			)
		)
		(pad "2" smd custom
			(at 0 0.4445 90)
			(size 0.1397 0.1397)
			(layers "F.Cu" "F.Mask" "F.Paste")
			(net "GND")
			(options
				(clearance outline)
				(anchor circle)
			)
			(primitives
				(gr_poly
					(pts
						(arc
							(start -0.1778 -0.2794)
							(mid -0.249642 -0.249642)
							(end -0.2794 -0.1778)
						)
						(arc
							(start -0.2794 0.1778)
							(mid -0.249642 0.249642)
							(end -0.1778 0.2794)
						)
						(arc
							(start 0.1778 0.2794)
							(mid 0.249642 0.249642)
							(end 0.2794 0.1778)
						)
						(arc
							(start 0.2794 -0.1778)
							(mid 0.249642 -0.249642)
							(end 0.1778 -0.2794)
						)
					)
					(width 0)
					(fill yes)
				)
			)
		)
	)
	(footprint ""
		(layer "F.Cu")
		(at 307.64607 -294.435276 180)
		(property "Reference" "R278"
			(at 0 0 180)
			(layer "F.SilkS")
			(hide yes)
			(effects
				(font
					(size 1.27 1.27)
				)
			)
		)
		(property "Value" "91R3F-1-GP"
			(at -0.0254 -2.5146 180)
			(unlocked yes)
			(layer "F.Fab")
			(hide yes)
			(effects
				(font
					(size 1.016 1.016)
					(thickness 0.1524)
				)
			)
		)
		(property "Device Type" "R603H22"
			(at -0.0254 -4.0386 180)
			(unlocked yes)
			(layer "F.Fab")
			(hide yes)
			(effects
				(font
					(size 1.016 1.016)
					(thickness 0.1524)
				)
			)
		)
		(duplicate_pad_numbers_are_jumpers no)
		(fp_line
			(start 0.2032 0)
			(end 0.4826 0)
			(stroke
				(width 0.2032)
				(type default)
			)
			(layer "F.SilkS")
		)
		(fp_line
			(start -0.4826 0)
			(end -0.2032 0)
			(stroke
				(width 0.2032)
				(type default)
			)
			(layer "F.SilkS")
		)
		(fp_rect
			(start -0.5842 1.3335)
			(end 0.5842 -1.3335)
			(stroke
				(width 0)
				(type default)
			)
			(fill no)
			(layer "F.CrtYd")
		)
		(fp_rect
			(start -0.5842 1.3335)
			(end 0.5842 -1.3335)
			(stroke
				(width 0)
				(type default)
			)
			(fill no)
			(layer "F.Fab")
		)
		(pad "1" smd custom
			(at 0 -0.762 180)
			(size 0.2159 0.2159)
			(layers "F.Cu" "F.Mask" "F.Paste")
			(net "P5V_B")
			(options
				(clearance outline)
				(anchor circle)
			)
			(primitives
				(gr_poly
					(pts
						(arc
							(start -0.3302 -0.4318)
							(mid -0.402042 -0.402042)
							(end -0.4318 -0.3302)
						)
						(arc
							(start -0.4318 0.3302)
							(mid -0.402042 0.402042)
							(end -0.3302 0.4318)
						)
						(arc
							(start 0.3302 0.4318)
							(mid 0.402042 0.402042)
							(end 0.4318 0.3302)
						)
						(arc
							(start 0.4318 -0.3302)
							(mid 0.402042 -0.402042)
							(end 0.3302 -0.4318)
						)
					)
					(width 0)
					(fill yes)
				)
			)
		)
		(pad "2" smd custom
			(at 0 0.762 180)
			(size 0.2159 0.2159)
			(layers "F.Cu" "F.Mask" "F.Paste")
			(net "DRV_ACT_30")
			(options
				(clearance outline)
				(anchor circle)
			)
			(primitives
				(gr_poly
					(pts
						(arc
							(start -0.3302 -0.4318)
							(mid -0.402042 -0.402042)
							(end -0.4318 -0.3302)
						)
						(arc
							(start -0.4318 0.3302)
							(mid -0.402042 0.402042)
							(end -0.3302 0.4318)
						)
						(arc
							(start 0.3302 0.4318)
							(mid 0.402042 0.402042)
							(end 0.4318 0.3302)
						)
						(arc
							(start 0.4318 -0.3302)
							(mid 0.402042 -0.402042)
							(end 0.3302 -0.4318)
						)
					)
					(width 0)
					(fill yes)
				)
			)
		)
	)
	(footprint ""
		(layer "F.Cu")
		(at 133.286754 -295.423336 90)
		(property "Reference" "R563"
			(at 0 0 90)
			(layer "F.SilkS")
			(hide yes)
			(effects
				(font
					(size 1.27 1.27)
				)
			)
		)
		(property "Value" "4K7R2J-2-GP"
			(at 0.064008 -3.993896 90)
			(unlocked yes)
			(layer "F.Fab")
			(hide yes)
			(effects
				(font
					(size 1.016 1.016)
					(thickness 0.1524)
				)
			)
		)
		(property "Device Type" "R402H16"
			(at 0.064008 -5.517896 90)
			(unlocked yes)
			(layer "F.Fab")
			(hide yes)
			(effects
				(font
					(size 1.016 1.016)
					(thickness 0.1524)
				)
			)
		)
		(duplicate_pad_numbers_are_jumpers no)
		(fp_line
			(start 0.508 -0.9398)
			(end -0.508 -0.9398)
			(stroke
				(width 0.1524)
				(type default)
			)
			(layer "F.SilkS")
		)
		(fp_line
			(start -0.508 -0.9398)
			(end -0.508 0.9398)
			(stroke
				(width 0.1524)
				(type default)
			)
			(layer "F.SilkS")
		)
		(fp_rect
			(start -0.508 0.9398)
			(end 0.508 -0.9398)
			(stroke
				(width 0)
				(type default)
			)
			(fill no)
			(layer "F.CrtYd")
		)
		(fp_rect
			(start -0.508 0.9398)
			(end 0.508 -0.9398)
			(stroke
				(width 0)
				(type default)
			)
			(fill no)
			(layer "F.Fab")
		)
		(pad "1" smd custom
			(at 0 -0.4445 90)
			(size 0.1397 0.1397)
			(layers "F.Cu" "F.Mask" "F.Paste")
			(net "DRIVE_B_28_ACT")
			(options
				(clearance outline)
				(anchor circle)
			)
			(primitives
				(gr_poly
					(pts
						(arc
							(start -0.1778 -0.2794)
							(mid -0.249642 -0.249642)
							(end -0.2794 -0.1778)
						)
						(arc
							(start -0.2794 0.1778)
							(mid -0.249642 0.249642)
							(end -0.1778 0.2794)
						)
						(arc
							(start 0.1778 0.2794)
							(mid 0.249642 0.249642)
							(end 0.2794 0.1778)
						)
						(arc
							(start 0.2794 -0.1778)
							(mid 0.249642 -0.249642)
							(end 0.1778 -0.2794)
						)
					)
					(width 0)
					(fill yes)
				)
			)
		)
		(pad "2" smd custom
			(at 0 0.4445 90)
			(size 0.1397 0.1397)
			(layers "F.Cu" "F.Mask" "F.Paste")
			(net "GND")
			(options
				(clearance outline)
				(anchor circle)
			)
			(primitives
				(gr_poly
					(pts
						(arc
							(start -0.1778 -0.2794)
							(mid -0.249642 -0.249642)
							(end -0.2794 -0.1778)
						)
						(arc
							(start -0.2794 0.1778)
							(mid -0.249642 0.249642)
							(end -0.1778 0.2794)
						)
						(arc
							(start 0.1778 0.2794)
							(mid 0.249642 0.249642)
							(end 0.2794 0.1778)
						)
						(arc
							(start 0.2794 -0.1778)
							(mid 0.249642 -0.249642)
							(end 0.1778 -0.2794)
						)
					)
					(width 0)
					(fill yes)
				)
			)
		)
	)
	(footprint ""
		(layer "F.Cu")
		(at 18.500598 -275.633942)
		(property "Reference" "R975"
			(at 0 0 0)
			(layer "F.SilkS")
			(hide yes)
			(effects
				(font
					(size 1.27 1.27)
				)
			)
		)
		(property "Value" "0R2J-2-GP"
			(at 0.064008 -3.993896 0)
			(unlocked yes)
			(layer "F.Fab")
			(hide yes)
			(effects
				(font
					(size 1.016 1.016)
					(thickness 0.1524)
				)
			)
		)
		(property "Device Type" "R402H16"
			(at 0.064008 -5.517896 0)
			(unlocked yes)
			(layer "F.Fab")
			(hide yes)
			(effects
				(font
					(size 1.016 1.016)
					(thickness 0.1524)
				)
			)
		)
		(duplicate_pad_numbers_are_jumpers no)
		(fp_line
			(start -0.508 -0.9398)
			(end -0.508 0.9398)
			(stroke
				(width 0.1524)
				(type default)
			)
			(layer "F.SilkS")
		)
		(fp_line
			(start 0.508 -0.9398)
			(end -0.508 -0.9398)
			(stroke
				(width 0.1524)
				(type default)
			)
			(layer "F.SilkS")
		)
		(fp_rect
			(start -0.508 0.9398)
			(end 0.508 -0.9398)
			(stroke
				(width 0)
				(type default)
			)
			(fill no)
			(layer "F.CrtYd")
		)
		(fp_rect
			(start -0.508 0.9398)
			(end 0.508 -0.9398)
			(stroke
				(width 0)
				(type default)
			)
			(fill no)
			(layer "F.Fab")
		)
		(pad "1" smd custom
			(at 0 -0.4445)
			(size 0.1397 0.1397)
			(layers "F.Cu" "F.Mask" "F.Paste")
			(net "SW_HDD_G0")
			(options
				(clearance outline)
				(anchor circle)
			)
			(primitives
				(gr_poly
					(pts
						(arc
							(start -0.1778 -0.2794)
							(mid -0.249642 -0.249642)
							(end -0.2794 -0.1778)
						)
						(arc
							(start -0.2794 0.1778)
							(mid -0.249642 0.249642)
							(end -0.1778 0.2794)
						)
						(arc
							(start 0.1778 0.2794)
							(mid 0.249642 0.249642)
							(end 0.2794 0.1778)
						)
						(arc
							(start 0.2794 -0.1778)
							(mid 0.249642 -0.249642)
							(end 0.1778 -0.2794)
						)
					)
					(width 0)
					(fill yes)
				)
			)
		)
		(pad "2" smd custom
			(at 0 0.4445)
			(size 0.1397 0.1397)
			(layers "F.Cu" "F.Mask" "F.Paste")
			(net "SW_HDD_R0")
			(options
				(clearance outline)
				(anchor circle)
			)
			(primitives
				(gr_poly
					(pts
						(arc
							(start -0.1778 -0.2794)
							(mid -0.249642 -0.249642)
							(end -0.2794 -0.1778)
						)
						(arc
							(start -0.2794 0.1778)
							(mid -0.249642 0.249642)
							(end -0.1778 0.2794)
						)
						(arc
							(start 0.1778 0.2794)
							(mid 0.249642 0.249642)
							(end 0.2794 0.1778)
						)
						(arc
							(start 0.2794 -0.1778)
							(mid 0.249642 -0.249642)
							(end 0.1778 -0.2794)
						)
					)
					(width 0)
					(fill yes)
				)
			)
		)
	)
	(footprint ""
		(layer "F.Cu")
		(at 402.57222 -245.315486 -90)
		(property "Reference" "R488"
			(at 0 0 270)
			(layer "F.SilkS")
			(hide yes)
			(effects
				(font
					(size 1.27 1.27)
				)
			)
		)
		(property "Value" "4K7R2J-2-GP"
			(at 0.064008 -3.993896 270)
			(unlocked yes)
			(layer "F.Fab")
			(hide yes)
			(effects
				(font
					(size 1.016 1.016)
					(thickness 0.1524)
				)
			)
		)
		(property "Device Type" "R402H16"
			(at 0.064008 -5.517896 270)
			(unlocked yes)
			(layer "F.Fab")
			(hide yes)
			(effects
				(font
					(size 1.016 1.016)
					(thickness 0.1524)
				)
			)
		)
		(duplicate_pad_numbers_are_jumpers no)
		(fp_line
			(start -0.508 -0.9398)
			(end -0.508 0.9398)
			(stroke
				(width 0.1524)
				(type default)
			)
			(layer "F.SilkS")
		)
		(fp_line
			(start 0.508 -0.9398)
			(end -0.508 -0.9398)
			(stroke
				(width 0.1524)
				(type default)
			)
			(layer "F.SilkS")
		)
		(fp_rect
			(start -0.508 0.9398)
			(end 0.508 -0.9398)
			(stroke
				(width 0)
				(type default)
			)
			(fill no)
			(layer "F.CrtYd")
		)
		(fp_rect
			(start -0.508 0.9398)
			(end 0.508 -0.9398)
			(stroke
				(width 0)
				(type default)
			)
			(fill no)
			(layer "F.Fab")
		)
		(pad "1" smd custom
			(at 0 -0.4445 270)
			(size 0.1397 0.1397)
			(layers "F.Cu" "F.Mask" "F.Paste")
			(net "DRIVE_A_9_ACT")
			(options
				(clearance outline)
				(anchor circle)
			)
			(primitives
				(gr_poly
					(pts
						(arc
							(start -0.1778 -0.2794)
							(mid -0.249642 -0.249642)
							(end -0.2794 -0.1778)
						)
						(arc
							(start -0.2794 0.1778)
							(mid -0.249642 0.249642)
							(end -0.1778 0.2794)
						)
						(arc
							(start 0.1778 0.2794)
							(mid 0.249642 0.249642)
							(end 0.2794 0.1778)
						)
						(arc
							(start 0.2794 -0.1778)
							(mid 0.249642 -0.249642)
							(end 0.1778 -0.2794)
						)
					)
					(width 0)
					(fill yes)
				)
			)
		)
		(pad "2" smd custom
			(at 0 0.4445 270)
			(size 0.1397 0.1397)
			(layers "F.Cu" "F.Mask" "F.Paste")
			(net "GND")
			(options
				(clearance outline)
				(anchor circle)
			)
			(primitives
				(gr_poly
					(pts
						(arc
							(start -0.1778 -0.2794)
							(mid -0.249642 -0.249642)
							(end -0.2794 -0.1778)
						)
						(arc
							(start -0.2794 0.1778)
							(mid -0.249642 0.249642)
							(end -0.1778 0.2794)
						)
						(arc
							(start 0.1778 0.2794)
							(mid 0.249642 0.249642)
							(end 0.2794 0.1778)
						)
						(arc
							(start 0.2794 -0.1778)
							(mid 0.249642 -0.249642)
							(end 0.1778 -0.2794)
						)
					)
					(width 0)
					(fill yes)
				)
			)
		)
	)
	(footprint ""
		(layer "F.Cu")
		(at 14.715998 -294.683942 -90)
		(property "Reference" "C512"
			(at 0 0 270)
			(layer "F.SilkS")
			(hide yes)
			(effects
				(font
					(size 1.27 1.27)
				)
			)
		)
		(property "Value" "SC4D7U25V5KX-1-GP"
			(at -0.0762 -6.1214 270)
			(unlocked yes)
			(layer "F.Fab")
			(hide yes)
			(effects
				(font
					(size 1.016 1.016)
					(thickness 0.1524)
				)
			)
		)
		(property "Device Type" "C805H58"
			(at -0.0762 -8.1534 270)
			(unlocked yes)
			(layer "F.Fab")
			(hide yes)
			(effects
				(font
					(size 1.016 1.016)
					(thickness 0.1524)
				)
			)
		)
		(duplicate_pad_numbers_are_jumpers no)
		(fp_line
			(start 0.635 0)
			(end -0.635 0)
			(stroke
				(width 0.508)
				(type default)
			)
			(layer "F.SilkS")
		)
		(fp_rect
			(start -0.9652 1.778)
			(end 0.9652 -1.778)
			(stroke
				(width 0)
				(type default)
			)
			(fill no)
			(layer "F.CrtYd")
		)
		(fp_poly
			(pts
				(xy -0.9652 -1.778) (xy 0.9652 -1.778) (xy 0.9652 1.778) (xy -0.9652 1.778)
			)
			(stroke
				(width 0)
				(type default)
			)
			(fill no)
			(layer "F.Fab")
		)
		(pad "1" smd rect
			(at 0 -0.9652 270)
			(size 1.397 1.143)
			(layers "F.Cu" "F.Mask" "F.Paste")
			(net "P12V_HDD0")
		)
		(pad "2" smd rect
			(at 0 0.9652 270)
			(size 1.397 1.143)
			(layers "F.Cu" "F.Mask" "F.Paste")
			(net "GND")
		)
	)
	(footprint ""
		(layer "F.Cu")
		(at 377.594876 -127.254)
		(property "Reference" "R332"
			(at 0 0 0)
			(layer "F.SilkS")
			(hide yes)
			(effects
				(font
					(size 1.27 1.27)
				)
			)
		)
		(property "Value" "130R3F-GP"
			(at -0.0254 -2.5146 0)
			(unlocked yes)
			(layer "F.Fab")
			(hide yes)
			(effects
				(font
					(size 1.016 1.016)
					(thickness 0.1524)
				)
			)
		)
		(property "Device Type" "R603H22"
			(at -0.0254 -4.0386 0)
			(unlocked yes)
			(layer "F.Fab")
			(hide yes)
			(effects
				(font
					(size 1.016 1.016)
					(thickness 0.1524)
				)
			)
		)
		(duplicate_pad_numbers_are_jumpers no)
		(fp_line
			(start -0.4826 0)
			(end -0.2032 0)
			(stroke
				(width 0.2032)
				(type default)
			)
			(layer "F.SilkS")
		)
		(fp_line
			(start 0.2032 0)
			(end 0.4826 0)
			(stroke
				(width 0.2032)
				(type default)
			)
			(layer "F.SilkS")
		)
		(fp_rect
			(start -0.5842 1.3335)
			(end 0.5842 -1.3335)
			(stroke
				(width 0)
				(type default)
			)
			(fill no)
			(layer "F.CrtYd")
		)
		(fp_rect
			(start -0.5842 1.3335)
			(end 0.5842 -1.3335)
			(stroke
				(width 0)
				(type default)
			)
			(fill no)
			(layer "F.Fab")
		)
		(pad "1" smd custom
			(at 0 -0.762)
			(size 0.2159 0.2159)
			(layers "F.Cu" "F.Mask" "F.Paste")
			(net "P5V_A_3")
			(options
				(clearance outline)
				(anchor circle)
			)
			(primitives
				(gr_poly
					(pts
						(arc
							(start -0.3302 -0.4318)
							(mid -0.402042 -0.402042)
							(end -0.4318 -0.3302)
						)
						(arc
							(start -0.4318 0.3302)
							(mid -0.402042 0.402042)
							(end -0.3302 0.4318)
						)
						(arc
							(start 0.3302 0.4318)
							(mid 0.402042 0.402042)
							(end 0.4318 0.3302)
						)
						(arc
							(start 0.4318 -0.3302)
							(mid 0.402042 -0.402042)
							(end 0.3302 -0.4318)
						)
					)
					(width 0)
					(fill yes)
				)
			)
		)
		(pad "2" smd custom
			(at 0 0.762)
			(size 0.2159 0.2159)
			(layers "F.Cu" "F.Mask" "F.Paste")
			(net "FLT_HDD20")
			(options
				(clearance outline)
				(anchor circle)
			)
			(primitives
				(gr_poly
					(pts
						(arc
							(start -0.3302 -0.4318)
							(mid -0.402042 -0.402042)
							(end -0.4318 -0.3302)
						)
						(arc
							(start -0.4318 0.3302)
							(mid -0.402042 0.402042)
							(end -0.3302 0.4318)
						)
						(arc
							(start 0.3302 0.4318)
							(mid 0.402042 0.402042)
							(end 0.4318 0.3302)
						)
						(arc
							(start 0.4318 -0.3302)
							(mid 0.402042 -0.402042)
							(end 0.3302 -0.4318)
						)
					)
					(width 0)
					(fill yes)
				)
			)
		)
	)
	(footprint ""
		(layer "F.Cu")
		(at 87.340948 -74.462894 180)
		(property "Reference" "C385"
			(at 0 0 180)
			(layer "F.SilkS")
			(hide yes)
			(effects
				(font
					(size 1.27 1.27)
				)
			)
		)
		(property "Value" "SC1U25V3KX-GP"
			(at 0 -2.8194 180)
			(unlocked yes)
			(layer "F.Fab")
			(hide yes)
			(effects
				(font
					(size 1.016 1.016)
					(thickness 0.1524)
				)
			)
		)
		(property "Device Type" "C603H36"
			(at 0 -4.3434 180)
			(unlocked yes)
			(layer "F.Fab")
			(hide yes)
			(effects
				(font
					(size 1.016 1.016)
					(thickness 0.1524)
				)
			)
		)
		(duplicate_pad_numbers_are_jumpers no)
		(fp_line
			(start 0.508 0)
			(end -0.508 0)
			(stroke
				(width 0.2032)
				(type default)
			)
			(layer "F.SilkS")
		)
		(fp_rect
			(start -0.5842 1.3335)
			(end 0.5842 -1.3335)
			(stroke
				(width 0)
				(type default)
			)
			(fill no)
			(layer "F.CrtYd")
		)
		(fp_rect
			(start -0.5842 1.3335)
			(end 0.5842 -1.3335)
			(stroke
				(width 0)
				(type default)
			)
			(fill no)
			(layer "F.Fab")
		)
		(pad "1" smd custom
			(at 0 -0.762 180)
			(size 0.2159 0.2159)
			(layers "F.Cu" "F.Mask" "F.Paste")
			(net "P12V_HDD26")
			(options
				(clearance outline)
				(anchor circle)
			)
			(primitives
				(gr_poly
					(pts
						(arc
							(start -0.3302 -0.4318)
							(mid -0.402042 -0.402042)
							(end -0.4318 -0.3302)
						)
						(arc
							(start -0.4318 0.3302)
							(mid -0.402042 0.402042)
							(end -0.3302 0.4318)
						)
						(arc
							(start 0.3302 0.4318)
							(mid 0.402042 0.402042)
							(end 0.4318 0.3302)
						)
						(arc
							(start 0.4318 -0.3302)
							(mid 0.402042 -0.402042)
							(end 0.3302 -0.4318)
						)
					)
					(width 0)
					(fill yes)
				)
			)
		)
		(pad "2" smd custom
			(at 0 0.762 180)
			(size 0.2159 0.2159)
			(layers "F.Cu" "F.Mask" "F.Paste")
			(net "GND")
			(options
				(clearance outline)
				(anchor circle)
			)
			(primitives
				(gr_poly
					(pts
						(arc
							(start -0.3302 -0.4318)
							(mid -0.402042 -0.402042)
							(end -0.4318 -0.3302)
						)
						(arc
							(start -0.4318 0.3302)
							(mid -0.402042 0.402042)
							(end -0.3302 0.4318)
						)
						(arc
							(start 0.3302 0.4318)
							(mid 0.402042 0.402042)
							(end 0.4318 0.3302)
						)
						(arc
							(start 0.4318 -0.3302)
							(mid 0.402042 -0.402042)
							(end 0.3302 -0.4318)
						)
					)
					(width 0)
					(fill yes)
				)
			)
		)
	)
	(footprint ""
		(layer "F.Cu")
		(at 230.8606 -391.033 -90)
		(property "Reference" "R1148"
			(at 0 0 270)
			(layer "F.SilkS")
			(hide yes)
			(effects
				(font
					(size 1.27 1.27)
				)
			)
		)
		(property "Value" "0R0603-PAD-2-GP-U"
			(at 2.1209 -0.1397 270)
			(unlocked yes)
			(layer "F.Fab")
			(hide yes)
			(effects
				(font
					(size 1.016 1.016)
					(thickness 0.1524)
				)
			)
		)
		(property "Device Type" "0R0603-PAD-1-U"
			(at 2.1209 -1.6637 270)
			(unlocked yes)
			(layer "F.Fab")
			(hide yes)
			(effects
				(font
					(size 1.016 1.016)
					(thickness 0.1524)
				)
			)
		)
		(duplicate_pad_numbers_are_jumpers no)
		(fp_rect
			(start -0.5842 1.3335)
			(end 0.5842 -1.3335)
			(stroke
				(width 0)
				(type default)
			)
			(fill no)
			(layer "F.CrtYd")
		)
		(fp_rect
			(start -0.5842 1.3335)
			(end 0.5842 -1.3335)
			(stroke
				(width 0)
				(type default)
			)
			(fill no)
			(layer "F.Fab")
		)
		(pad "1" smd custom
			(at 0 -0.762 270)
			(size 0.2159 0.2159)
			(layers "F.Cu" "F.Mask" "F.Paste")
			(net "AGND_CURRENT_DPB")
			(options
				(clearance outline)
				(anchor circle)
			)
			(primitives
				(gr_poly
					(pts
						(arc
							(start -0.3302 -0.5842)
							(mid -0.402042 -0.554442)
							(end -0.4318 -0.4826)
						)
						(arc
							(start -0.4318 0.4826)
							(mid -0.402042 0.554442)
							(end -0.3302 0.5842)
						)
						(arc
							(start 0.3302 0.5842)
							(mid 0.402042 0.554442)
							(end 0.4318 0.4826)
						)
						(arc
							(start 0.4318 -0.4826)
							(mid 0.402042 -0.554442)
							(end 0.3302 -0.5842)
						)
					)
					(width 0)
					(fill yes)
				)
			)
		)
		(pad "2" smd custom
			(at 0 0.762 270)
			(size 0.2159 0.2159)
			(layers "F.Cu" "F.Mask" "F.Paste")
			(net "GND")
			(options
				(clearance outline)
				(anchor circle)
			)
			(primitives
				(gr_poly
					(pts
						(arc
							(start -0.4318 0.4826)
							(mid -0.402042 0.554442)
							(end -0.3302 0.5842)
						)
						(arc
							(start 0.3302 0.5842)
							(mid 0.402042 0.554442)
							(end 0.4318 0.4826)
						)
						(arc
							(start 0.4318 -0.4826)
							(mid 0.402042 -0.554442)
							(end 0.3302 -0.5842)
						)
						(arc
							(start -0.3302 -0.5842)
							(mid -0.402042 -0.554442)
							(end -0.4318 -0.4826)
						)
					)
					(width 0)
					(fill yes)
				)
			)
		)
	)
	(footprint ""
		(layer "F.Cu")
		(at 49.215802 -149.79015 -90)
		(property "Reference" "R1227"
			(at 0 0 270)
			(layer "F.SilkS")
			(hide yes)
			(effects
				(font
					(size 1.27 1.27)
				)
			)
		)
		(property "Value" "10KR2F-2-GP"
			(at 0.064008 -3.993896 270)
			(unlocked yes)
			(layer "F.Fab")
			(hide yes)
			(effects
				(font
					(size 1.016 1.016)
					(thickness 0.1524)
				)
			)
		)
		(property "Device Type" "R402H16"
			(at 0.064008 -5.517896 270)
			(unlocked yes)
			(layer "F.Fab")
			(hide yes)
			(effects
				(font
					(size 1.016 1.016)
					(thickness 0.1524)
				)
			)
		)
		(duplicate_pad_numbers_are_jumpers no)
		(fp_line
			(start -0.508 -0.9398)
			(end -0.508 0.9398)
			(stroke
				(width 0.1524)
				(type default)
			)
			(layer "F.SilkS")
		)
		(fp_line
			(start 0.508 -0.9398)
			(end -0.508 -0.9398)
			(stroke
				(width 0.1524)
				(type default)
			)
			(layer "F.SilkS")
		)
		(fp_rect
			(start -0.508 0.9398)
			(end 0.508 -0.9398)
			(stroke
				(width 0)
				(type default)
			)
			(fill no)
			(layer "F.CrtYd")
		)
		(fp_rect
			(start -0.508 0.9398)
			(end 0.508 -0.9398)
			(stroke
				(width 0)
				(type default)
			)
			(fill no)
			(layer "F.Fab")
		)
		(pad "1" smd custom
			(at 0 -0.4445 270)
			(size 0.1397 0.1397)
			(layers "F.Cu" "F.Mask" "F.Paste")
			(net "P5V_B_EN_R")
			(options
				(clearance outline)
				(anchor circle)
			)
			(primitives
				(gr_poly
					(pts
						(arc
							(start -0.1778 -0.2794)
							(mid -0.249642 -0.249642)
							(end -0.2794 -0.1778)
						)
						(arc
							(start -0.2794 0.1778)
							(mid -0.249642 0.249642)
							(end -0.1778 0.2794)
						)
						(arc
							(start 0.1778 0.2794)
							(mid 0.249642 0.249642)
							(end 0.2794 0.1778)
						)
						(arc
							(start 0.2794 -0.1778)
							(mid 0.249642 -0.249642)
							(end 0.1778 -0.2794)
						)
					)
					(width 0)
					(fill yes)
				)
			)
		)
		(pad "2" smd custom
			(at 0 0.4445 270)
			(size 0.1397 0.1397)
			(layers "F.Cu" "F.Mask" "F.Paste")
			(net "GND")
			(options
				(clearance outline)
				(anchor circle)
			)
			(primitives
				(gr_poly
					(pts
						(arc
							(start -0.1778 -0.2794)
							(mid -0.249642 -0.249642)
							(end -0.2794 -0.1778)
						)
						(arc
							(start -0.2794 0.1778)
							(mid -0.249642 0.249642)
							(end -0.1778 0.2794)
						)
						(arc
							(start 0.1778 0.2794)
							(mid 0.249642 0.249642)
							(end 0.2794 0.1778)
						)
						(arc
							(start 0.2794 -0.1778)
							(mid 0.249642 -0.249642)
							(end 0.1778 -0.2794)
						)
					)
					(width 0)
					(fill yes)
				)
			)
		)
	)
	(footprint ""
		(layer "F.Cu")
		(at 363.655102 -42.585894)
		(property "Reference" "R855"
			(at 0 0 0)
			(layer "F.SilkS")
			(hide yes)
			(effects
				(font
					(size 1.27 1.27)
				)
			)
		)
		(property "Value" "4K7R2J-2-GP"
			(at 0.064008 -3.993896 0)
			(unlocked yes)
			(layer "F.Fab")
			(hide yes)
			(effects
				(font
					(size 1.016 1.016)
					(thickness 0.1524)
				)
			)
		)
		(property "Device Type" "R402H16"
			(at 0.064008 -5.517896 0)
			(unlocked yes)
			(layer "F.Fab")
			(hide yes)
			(effects
				(font
					(size 1.016 1.016)
					(thickness 0.1524)
				)
			)
		)
		(duplicate_pad_numbers_are_jumpers no)
		(fp_line
			(start -0.508 -0.9398)
			(end -0.508 0.9398)
			(stroke
				(width 0.1524)
				(type default)
			)
			(layer "F.SilkS")
		)
		(fp_line
			(start 0.508 -0.9398)
			(end -0.508 -0.9398)
			(stroke
				(width 0.1524)
				(type default)
			)
			(layer "F.SilkS")
		)
		(fp_rect
			(start -0.508 0.9398)
			(end 0.508 -0.9398)
			(stroke
				(width 0)
				(type default)
			)
			(fill no)
			(layer "F.CrtYd")
		)
		(fp_rect
			(start -0.508 0.9398)
			(end 0.508 -0.9398)
			(stroke
				(width 0)
				(type default)
			)
			(fill no)
			(layer "F.Fab")
		)
		(pad "1" smd custom
			(at 0 -0.4445)
			(size 0.1397 0.1397)
			(layers "F.Cu" "F.Mask" "F.Paste")
			(net "SW_PWR_R_HDD31")
			(options
				(clearance outline)
				(anchor circle)
			)
			(primitives
				(gr_poly
					(pts
						(arc
							(start -0.1778 -0.2794)
							(mid -0.249642 -0.249642)
							(end -0.2794 -0.1778)
						)
						(arc
							(start -0.2794 0.1778)
							(mid -0.249642 0.249642)
							(end -0.1778 0.2794)
						)
						(arc
							(start 0.1778 0.2794)
							(mid 0.249642 0.249642)
							(end 0.2794 0.1778)
						)
						(arc
							(start 0.2794 -0.1778)
							(mid 0.249642 -0.249642)
							(end 0.1778 -0.2794)
						)
					)
					(width 0)
					(fill yes)
				)
			)
		)
		(pad "2" smd custom
			(at 0 0.4445)
			(size 0.1397 0.1397)
			(layers "F.Cu" "F.Mask" "F.Paste")
			(net "GND")
			(options
				(clearance outline)
				(anchor circle)
			)
			(primitives
				(gr_poly
					(pts
						(arc
							(start -0.1778 -0.2794)
							(mid -0.249642 -0.249642)
							(end -0.2794 -0.1778)
						)
						(arc
							(start -0.2794 0.1778)
							(mid -0.249642 0.249642)
							(end -0.1778 0.2794)
						)
						(arc
							(start 0.1778 0.2794)
							(mid 0.249642 0.249642)
							(end 0.2794 0.1778)
						)
						(arc
							(start 0.2794 -0.1778)
							(mid 0.249642 -0.249642)
							(end 0.1778 -0.2794)
						)
					)
					(width 0)
					(fill yes)
				)
			)
		)
	)
	(footprint ""
		(layer "F.Cu")
		(at 298.831 -284.099)
		(property "Reference" "R10"
			(at 0 0 0)
			(layer "F.SilkS")
			(hide yes)
			(effects
				(font
					(size 1.27 1.27)
				)
			)
		)
		(property "Value" "0R2J-2-GP"
			(at 0.064008 -3.993896 0)
			(unlocked yes)
			(layer "F.Fab")
			(hide yes)
			(effects
				(font
					(size 1.016 1.016)
					(thickness 0.1524)
				)
			)
		)
		(property "Device Type" "R402H16"
			(at 0.064008 -5.517896 0)
			(unlocked yes)
			(layer "F.Fab")
			(hide yes)
			(effects
				(font
					(size 1.016 1.016)
					(thickness 0.1524)
				)
			)
		)
		(duplicate_pad_numbers_are_jumpers no)
		(fp_line
			(start -0.508 -0.9398)
			(end -0.508 0.9398)
			(stroke
				(width 0.1524)
				(type default)
			)
			(layer "F.SilkS")
		)
		(fp_line
			(start 0.508 -0.9398)
			(end -0.508 -0.9398)
			(stroke
				(width 0.1524)
				(type default)
			)
			(layer "F.SilkS")
		)
		(fp_rect
			(start -0.508 0.9398)
			(end 0.508 -0.9398)
			(stroke
				(width 0)
				(type default)
			)
			(fill no)
			(layer "F.CrtYd")
		)
		(fp_rect
			(start -0.508 0.9398)
			(end 0.508 -0.9398)
			(stroke
				(width 0)
				(type default)
			)
			(fill no)
			(layer "F.Fab")
		)
		(pad "1" smd custom
			(at 0 -0.4445)
			(size 0.1397 0.1397)
			(layers "F.Cu" "F.Mask" "F.Paste")
			(net "SCC_A_HS_EN")
			(options
				(clearance outline)
				(anchor circle)
			)
			(primitives
				(gr_poly
					(pts
						(arc
							(start -0.1778 -0.2794)
							(mid -0.249642 -0.249642)
							(end -0.2794 -0.1778)
						)
						(arc
							(start -0.2794 0.1778)
							(mid -0.249642 0.249642)
							(end -0.1778 0.2794)
						)
						(arc
							(start 0.1778 0.2794)
							(mid 0.249642 0.249642)
							(end 0.2794 0.1778)
						)
						(arc
							(start 0.2794 -0.1778)
							(mid 0.249642 -0.249642)
							(end 0.1778 -0.2794)
						)
					)
					(width 0)
					(fill yes)
				)
			)
		)
		(pad "2" smd custom
			(at 0 0.4445)
			(size 0.1397 0.1397)
			(layers "F.Cu" "F.Mask" "F.Paste")
			(net "GND")
			(options
				(clearance outline)
				(anchor circle)
			)
			(primitives
				(gr_poly
					(pts
						(arc
							(start -0.1778 -0.2794)
							(mid -0.249642 -0.249642)
							(end -0.2794 -0.1778)
						)
						(arc
							(start -0.2794 0.1778)
							(mid -0.249642 0.249642)
							(end -0.1778 0.2794)
						)
						(arc
							(start 0.1778 0.2794)
							(mid 0.249642 0.249642)
							(end 0.2794 0.1778)
						)
						(arc
							(start 0.2794 -0.1778)
							(mid 0.249642 -0.249642)
							(end 0.1778 -0.2794)
						)
					)
					(width 0)
					(fill yes)
				)
			)
		)
	)
	(footprint ""
		(layer "F.Cu")
		(at 478.832926 -177.270918)
		(property "Reference" "R658"
			(at 0 0 0)
			(layer "F.SilkS")
			(hide yes)
			(effects
				(font
					(size 1.27 1.27)
				)
			)
		)
		(property "Value" "2R6F-GP"
			(at -0.0508 -4.8514 0)
			(unlocked yes)
			(layer "F.Fab")
			(hide yes)
			(effects
				(font
					(size 1.016 1.016)
					(thickness 0.1524)
				)
			)
		)
		(property "Device Type" "R1206H26"
			(at 0 -6.3754 0)
			(unlocked yes)
			(layer "F.Fab")
			(hide yes)
			(effects
				(font
					(size 1.016 1.016)
					(thickness 0.1524)
				)
			)
		)
		(duplicate_pad_numbers_are_jumpers no)
		(fp_line
			(start -1.016 -2.2352)
			(end 1.016 -2.2352)
			(stroke
				(width 0.1524)
				(type default)
			)
			(layer "F.SilkS")
		)
		(fp_line
			(start -1.016 2.2352)
			(end -1.016 -2.2352)
			(stroke
				(width 0.1524)
				(type default)
			)
			(layer "F.SilkS")
		)
		(fp_line
			(start 1.016 -2.2352)
			(end 1.016 2.2352)
			(stroke
				(width 0.1524)
				(type default)
			)
			(layer "F.SilkS")
		)
		(fp_line
			(start 1.016 2.2352)
			(end -1.016 2.2352)
			(stroke
				(width 0.1524)
				(type default)
			)
			(layer "F.SilkS")
		)
		(fp_rect
			(start -1.0922 2.3114)
			(end 1.0922 -2.3114)
			(stroke
				(width 0)
				(type default)
			)
			(fill no)
			(layer "F.CrtYd")
		)
		(fp_poly
			(pts
				(xy -1.0922 -2.3114) (xy 1.0922 -2.3114) (xy 1.0922 2.3114) (xy -1.0922 2.3114)
			)
			(stroke
				(width 0)
				(type default)
			)
			(fill no)
			(layer "F.Fab")
		)
		(pad "1" smd rect
			(at 0 -1.397)
			(size 1.651 1.27)
			(layers "F.Cu" "F.Mask" "F.Paste")
			(net "P5V_HDD23")
		)
		(pad "2" smd rect
			(at 0 1.397)
			(size 1.651 1.27)
			(layers "F.Cu" "F.Mask" "F.Paste")
			(net "5V_PRE_23")
		)
	)
	(footprint ""
		(layer "F.Cu")
		(at 262.7376 -230.3018 180)
		(property "Reference" "R96"
			(at 0 0 180)
			(layer "F.SilkS")
			(hide yes)
			(effects
				(font
					(size 1.27 1.27)
				)
			)
		)
		(property "Value" "4K7R2F-GP"
			(at 0.064008 -3.993896 180)
			(unlocked yes)
			(layer "F.Fab")
			(hide yes)
			(effects
				(font
					(size 1.016 1.016)
					(thickness 0.1524)
				)
			)
		)
		(property "Device Type" "R402H16"
			(at 0.064008 -5.517896 180)
			(unlocked yes)
			(layer "F.Fab")
			(hide yes)
			(effects
				(font
					(size 1.016 1.016)
					(thickness 0.1524)
				)
			)
		)
		(duplicate_pad_numbers_are_jumpers no)
		(fp_line
			(start 0.508 -0.9398)
			(end -0.508 -0.9398)
			(stroke
				(width 0.1524)
				(type default)
			)
			(layer "F.SilkS")
		)
		(fp_line
			(start -0.508 -0.9398)
			(end -0.508 0.9398)
			(stroke
				(width 0.1524)
				(type default)
			)
			(layer "F.SilkS")
		)
		(fp_rect
			(start -0.508 0.9398)
			(end 0.508 -0.9398)
			(stroke
				(width 0)
				(type default)
			)
			(fill no)
			(layer "F.CrtYd")
		)
		(fp_rect
			(start -0.508 0.9398)
			(end 0.508 -0.9398)
			(stroke
				(width 0)
				(type default)
			)
			(fill no)
			(layer "F.Fab")
		)
		(pad "1" smd custom
			(at 0 -0.4445 180)
			(size 0.1397 0.1397)
			(layers "F.Cu" "F.Mask" "F.Paste")
			(net "P3V3_STBY_A")
			(options
				(clearance outline)
				(anchor circle)
			)
			(primitives
				(gr_poly
					(pts
						(arc
							(start -0.1778 -0.2794)
							(mid -0.249642 -0.249642)
							(end -0.2794 -0.1778)
						)
						(arc
							(start -0.2794 0.1778)
							(mid -0.249642 0.249642)
							(end -0.1778 0.2794)
						)
						(arc
							(start 0.1778 0.2794)
							(mid 0.249642 0.249642)
							(end 0.2794 0.1778)
						)
						(arc
							(start 0.2794 -0.1778)
							(mid 0.249642 -0.249642)
							(end 0.1778 -0.2794)
						)
					)
					(width 0)
					(fill yes)
				)
			)
		)
		(pad "2" smd custom
			(at 0 0.4445 180)
			(size 0.1397 0.1397)
			(layers "F.Cu" "F.Mask" "F.Paste")
			(net "IO_EXP3_A0")
			(options
				(clearance outline)
				(anchor circle)
			)
			(primitives
				(gr_poly
					(pts
						(arc
							(start -0.1778 -0.2794)
							(mid -0.249642 -0.249642)
							(end -0.2794 -0.1778)
						)
						(arc
							(start -0.2794 0.1778)
							(mid -0.249642 0.249642)
							(end -0.1778 0.2794)
						)
						(arc
							(start 0.1778 0.2794)
							(mid 0.249642 0.249642)
							(end 0.2794 0.1778)
						)
						(arc
							(start 0.2794 -0.1778)
							(mid 0.249642 -0.249642)
							(end 0.1778 -0.2794)
						)
					)
					(width 0)
					(fill yes)
				)
			)
		)
	)
	(footprint ""
		(layer "F.Cu")
		(at 164.28212 -185.085482)
		(property "Reference" "Q268"
			(at 0 0 0)
			(layer "F.SilkS")
			(hide yes)
			(effects
				(font
					(size 1.27 1.27)
				)
			)
		)
		(property "Value" "SSM3K324R-GP"
			(at 0.127 -8.9662 0)
			(unlocked yes)
			(layer "F.Fab")
			(hide yes)
			(effects
				(font
					(size 1.016 1.016)
					(thickness 0.1524)
				)
			)
		)
		(property "Device Type" "SOT23DGS2D4H35"
			(at 0.127 -10.4902 0)
			(unlocked yes)
			(layer "F.Fab")
			(hide yes)
			(effects
				(font
					(size 1.016 1.016)
					(thickness 0.1524)
				)
			)
		)
		(duplicate_pad_numbers_are_jumpers no)
		(fp_line
			(start -1.651 -1.778)
			(end -1.651 1.778)
			(stroke
				(width 0.1524)
				(type default)
			)
			(layer "F.SilkS")
		)
		(fp_line
			(start -1.651 1.778)
			(end 1.651 1.778)
			(stroke
				(width 0.1524)
				(type default)
			)
			(layer "F.SilkS")
		)
		(fp_line
			(start 1.651 -1.778)
			(end -1.651 -1.778)
			(stroke
				(width 0.1524)
				(type default)
			)
			(layer "F.SilkS")
		)
		(fp_line
			(start 1.651 1.778)
			(end 1.651 -1.778)
			(stroke
				(width 0.1524)
				(type default)
			)
			(layer "F.SilkS")
		)
		(fp_poly
			(pts
				(xy -1.778 1.8796) (xy -1.778 -1.8796) (xy 1.778 -1.8796) (xy 1.778 1.8796)
			)
			(stroke
				(width 0)
				(type default)
			)
			(fill no)
			(layer "F.CrtYd")
		)
		(fp_poly
			(pts
				(xy -1.778 1.8796) (xy -1.778 -1.8796) (xy 1.778 -1.8796) (xy 1.778 1.8796)
			)
			(stroke
				(width 0)
				(type default)
			)
			(fill no)
			(layer "F.Fab")
		)
		(pad "D" smd custom
			(at 0 -0.9525)
			(size 0.1905 0.1905)
			(layers "F.Cu" "F.Mask" "F.Paste")
			(net "DRV_ACT_5_N")
			(options
				(clearance outline)
				(anchor circle)
			)
			(primitives
				(gr_poly
					(pts
						(arc
							(start -0.1778 0.5715)
							(mid -0.321484 0.511984)
							(end -0.381 0.3683)
						)
						(arc
							(start -0.381 -0.3683)
							(mid -0.321484 -0.511984)
							(end -0.1778 -0.5715)
						)
						(arc
							(start 0.1778 -0.5715)
							(mid 0.321484 -0.511984)
							(end 0.381 -0.3683)
						)
						(arc
							(start 0.381 0.3683)
							(mid 0.321484 0.511984)
							(end 0.1778 0.5715)
						)
					)
					(width 0)
					(fill yes)
				)
			)
		)
		(pad "G" smd custom
			(at -0.98425 0.9525)
			(size 0.1905 0.1905)
			(layers "F.Cu" "F.Mask" "F.Paste")
			(net "DRIVE_A_5_ACT")
			(options
				(clearance outline)
				(anchor circle)
			)
			(primitives
				(gr_poly
					(pts
						(arc
							(start -0.1778 0.5715)
							(mid -0.321484 0.511984)
							(end -0.381 0.3683)
						)
						(arc
							(start -0.381 -0.3683)
							(mid -0.321484 -0.511984)
							(end -0.1778 -0.5715)
						)
						(arc
							(start 0.1778 -0.5715)
							(mid 0.321484 -0.511984)
							(end 0.381 -0.3683)
						)
						(arc
							(start 0.381 0.3683)
							(mid 0.321484 0.511984)
							(end 0.1778 0.5715)
						)
					)
					(width 0)
					(fill yes)
				)
			)
		)
		(pad "S" smd custom
			(at 0.98425 0.9525)
			(size 0.1905 0.1905)
			(layers "F.Cu" "F.Mask" "F.Paste")
			(net "GND")
			(options
				(clearance outline)
				(anchor circle)
			)
			(primitives
				(gr_poly
					(pts
						(arc
							(start -0.1778 0.5715)
							(mid -0.321484 0.511984)
							(end -0.381 0.3683)
						)
						(arc
							(start -0.381 -0.3683)
							(mid -0.321484 -0.511984)
							(end -0.1778 -0.5715)
						)
						(arc
							(start 0.1778 -0.5715)
							(mid 0.321484 -0.511984)
							(end 0.381 -0.3683)
						)
						(arc
							(start 0.381 0.3683)
							(mid 0.321484 0.511984)
							(end 0.1778 0.5715)
						)
					)
					(width 0)
					(fill yes)
				)
			)
		)
	)
	(footprint ""
		(layer "F.Cu")
		(at 444.391542 -242.809522 180)
		(property "Reference" "Q273"
			(at 0 0 180)
			(layer "F.SilkS")
			(hide yes)
			(effects
				(font
					(size 1.27 1.27)
				)
			)
		)
		(property "Value" "SSM3K324R-GP"
			(at 0.127 -8.9662 180)
			(unlocked yes)
			(layer "F.Fab")
			(hide yes)
			(effects
				(font
					(size 1.016 1.016)
					(thickness 0.1524)
				)
			)
		)
		(property "Device Type" "SOT23DGS2D4H35"
			(at 0.127 -10.4902 180)
			(unlocked yes)
			(layer "F.Fab")
			(hide yes)
			(effects
				(font
					(size 1.016 1.016)
					(thickness 0.1524)
				)
			)
		)
		(duplicate_pad_numbers_are_jumpers no)
		(fp_line
			(start 1.651 1.778)
			(end 1.651 -1.778)
			(stroke
				(width 0.1524)
				(type default)
			)
			(layer "F.SilkS")
		)
		(fp_line
			(start 1.651 -1.778)
			(end -1.651 -1.778)
			(stroke
				(width 0.1524)
				(type default)
			)
			(layer "F.SilkS")
		)
		(fp_line
			(start -1.651 1.778)
			(end 1.651 1.778)
			(stroke
				(width 0.1524)
				(type default)
			)
			(layer "F.SilkS")
		)
		(fp_line
			(start -1.651 -1.778)
			(end -1.651 1.778)
			(stroke
				(width 0.1524)
				(type default)
			)
			(layer "F.SilkS")
		)
		(fp_poly
			(pts
				(xy -1.778 1.8796) (xy -1.778 -1.8796) (xy 1.778 -1.8796) (xy 1.778 1.8796)
			)
			(stroke
				(width 0)
				(type default)
			)
			(fill no)
			(layer "F.CrtYd")
		)
		(fp_poly
			(pts
				(xy -1.778 1.8796) (xy -1.778 -1.8796) (xy 1.778 -1.8796) (xy 1.778 1.8796)
			)
			(stroke
				(width 0)
				(type default)
			)
			(fill no)
			(layer "F.Fab")
		)
		(pad "D" smd custom
			(at 0 -0.9525 180)
			(size 0.1905 0.1905)
			(layers "F.Cu" "F.Mask" "F.Paste")
			(net "DRV_ACT_10_N")
			(options
				(clearance outline)
				(anchor circle)
			)
			(primitives
				(gr_poly
					(pts
						(arc
							(start -0.1778 0.5715)
							(mid -0.321484 0.511984)
							(end -0.381 0.3683)
						)
						(arc
							(start -0.381 -0.3683)
							(mid -0.321484 -0.511984)
							(end -0.1778 -0.5715)
						)
						(arc
							(start 0.1778 -0.5715)
							(mid 0.321484 -0.511984)
							(end 0.381 -0.3683)
						)
						(arc
							(start 0.381 0.3683)
							(mid 0.321484 0.511984)
							(end 0.1778 0.5715)
						)
					)
					(width 0)
					(fill yes)
				)
			)
		)
		(pad "G" smd custom
			(at -0.98425 0.9525 180)
			(size 0.1905 0.1905)
			(layers "F.Cu" "F.Mask" "F.Paste")
			(net "DRIVE_A_10_ACT")
			(options
				(clearance outline)
				(anchor circle)
			)
			(primitives
				(gr_poly
					(pts
						(arc
							(start -0.1778 0.5715)
							(mid -0.321484 0.511984)
							(end -0.381 0.3683)
						)
						(arc
							(start -0.381 -0.3683)
							(mid -0.321484 -0.511984)
							(end -0.1778 -0.5715)
						)
						(arc
							(start 0.1778 -0.5715)
							(mid 0.321484 -0.511984)
							(end 0.381 -0.3683)
						)
						(arc
							(start 0.381 0.3683)
							(mid 0.321484 0.511984)
							(end 0.1778 0.5715)
						)
					)
					(width 0)
					(fill yes)
				)
			)
		)
		(pad "S" smd custom
			(at 0.98425 0.9525 180)
			(size 0.1905 0.1905)
			(layers "F.Cu" "F.Mask" "F.Paste")
			(net "GND")
			(options
				(clearance outline)
				(anchor circle)
			)
			(primitives
				(gr_poly
					(pts
						(arc
							(start -0.1778 0.5715)
							(mid -0.321484 0.511984)
							(end -0.381 0.3683)
						)
						(arc
							(start -0.381 -0.3683)
							(mid -0.321484 -0.511984)
							(end -0.1778 -0.5715)
						)
						(arc
							(start 0.1778 -0.5715)
							(mid 0.321484 -0.511984)
							(end 0.381 -0.3683)
						)
						(arc
							(start 0.381 0.3683)
							(mid 0.321484 0.511984)
							(end 0.1778 0.5715)
						)
					)
					(width 0)
					(fill yes)
				)
			)
		)
	)
	(footprint ""
		(layer "F.Cu")
		(at 107.099862 -289.999928)
		(property "Reference" ""
			(at 0 0 0)
			(layer "F.SilkS")
			(hide yes)
			(effects
				(font
					(size 1.27 1.27)
				)
			)
		)
		(property "Value" "*"
			(at -6.3373 -0.4572 0)
			(unlocked yes)
			(layer "F.Fab")
			(hide yes)
			(effects
				(font
					(size 1.016 1.016)
					(thickness 0.1524)
				)
			)
		)
		(duplicate_pad_numbers_are_jumpers no)
		(fp_poly
			(pts
				(arc
					(start 5.0673 0)
					(mid -5.0673 0)
					(end 5.0673 0)
				)
			)
			(stroke
				(width 0)
				(type default)
			)
			(fill no)
			(layer "B.CrtYd")
		)
		(fp_poly
			(pts
				(arc
					(start 5.0673 0)
					(mid -5.0673 0)
					(end 5.0673 0)
				)
			)
			(stroke
				(width 0)
				(type default)
			)
			(fill no)
			(layer "F.CrtYd")
		)
		(fp_poly
			(pts
				(arc
					(start 5.0673 0)
					(mid -5.0673 0)
					(end 5.0673 0)
				)
			)
			(stroke
				(width 0)
				(type default)
			)
			(fill no)
			(layer "B.Fab")
		)
		(fp_poly
			(pts
				(arc
					(start 5.0673 0)
					(mid -5.0673 0)
					(end 5.0673 0)
				)
			)
			(stroke
				(width 0)
				(type default)
			)
			(fill no)
			(layer "F.Fab")
		)
		(pad "1" thru_hole circle
			(at 0 0)
			(size 9.525 9.525)
			(drill 3.556)
			(layers "*.Cu" "*.Mask")
			(remove_unused_layers no)
			(net "Net_91")
			(clearance -2.4765)
			(thermal_gap 0.3048)
			(padstack
				(mode front_inner_back)
				(layer "Inner"
					(shape circle)
					(size 3.9624 3.9624)
					(clearance 0.3048)
				)
				(layer "B.Cu"
					(shape circle)
					(size 9.525 9.525)
					(clearance -2.4765)
				)
			)
		)
		(zone
			(layers "F.Cu" "B.Cu" "In1.Cu" "In2.Cu" "In3.Cu" "In4.Cu" "In5.Cu" "In6.Cu"
				"In7.Cu" "In8.Cu" "In9.Cu" "In10.Cu"
			)
			(hatch none 0.5)
			(connect_pads
				(clearance 0)
			)
			(min_thickness 0.25)
			(keepout
				(tracks not_allowed)
				(vias allowed)
				(pads allowed)
				(copperpour not_allowed)
				(footprints allowed)
			)
			(placement
				(enabled no)
				(sheetname "")
			)
			(fill
				(thermal_gap 0.5)
				(thermal_bridge_width 0.5)
				(island_removal_mode 0)
			)
			(polygon
				(pts
					(arc
						(start 111.862362 -289.999928)
						(mid 102.337362 -289.999928)
						(end 111.862362 -289.999928)
					)
				)
			)
		)
	)
	(footprint ""
		(layer "F.Cu")
		(at 98.823018 -296.67962)
		(property "Reference" "R562"
			(at 0 0 0)
			(layer "F.SilkS")
			(hide yes)
			(effects
				(font
					(size 1.27 1.27)
				)
			)
		)
		(property "Value" "4K7R2J-2-GP"
			(at 0.064008 -3.993896 0)
			(unlocked yes)
			(layer "F.Fab")
			(hide yes)
			(effects
				(font
					(size 1.016 1.016)
					(thickness 0.1524)
				)
			)
		)
		(property "Device Type" "R402H16"
			(at 0.064008 -5.517896 0)
			(unlocked yes)
			(layer "F.Fab")
			(hide yes)
			(effects
				(font
					(size 1.016 1.016)
					(thickness 0.1524)
				)
			)
		)
		(duplicate_pad_numbers_are_jumpers no)
		(fp_line
			(start -0.508 -0.9398)
			(end -0.508 0.9398)
			(stroke
				(width 0.1524)
				(type default)
			)
			(layer "F.SilkS")
		)
		(fp_line
			(start 0.508 -0.9398)
			(end -0.508 -0.9398)
			(stroke
				(width 0.1524)
				(type default)
			)
			(layer "F.SilkS")
		)
		(fp_rect
			(start -0.508 0.9398)
			(end 0.508 -0.9398)
			(stroke
				(width 0)
				(type default)
			)
			(fill no)
			(layer "F.CrtYd")
		)
		(fp_rect
			(start -0.508 0.9398)
			(end 0.508 -0.9398)
			(stroke
				(width 0)
				(type default)
			)
			(fill no)
			(layer "F.Fab")
		)
		(pad "1" smd custom
			(at 0 -0.4445)
			(size 0.1397 0.1397)
			(layers "F.Cu" "F.Mask" "F.Paste")
			(net "DRIVE_B_27_ACT")
			(options
				(clearance outline)
				(anchor circle)
			)
			(primitives
				(gr_poly
					(pts
						(arc
							(start -0.1778 -0.2794)
							(mid -0.249642 -0.249642)
							(end -0.2794 -0.1778)
						)
						(arc
							(start -0.2794 0.1778)
							(mid -0.249642 0.249642)
							(end -0.1778 0.2794)
						)
						(arc
							(start 0.1778 0.2794)
							(mid 0.249642 0.249642)
							(end 0.2794 0.1778)
						)
						(arc
							(start 0.2794 -0.1778)
							(mid 0.249642 -0.249642)
							(end 0.1778 -0.2794)
						)
					)
					(width 0)
					(fill yes)
				)
			)
		)
		(pad "2" smd custom
			(at 0 0.4445)
			(size 0.1397 0.1397)
			(layers "F.Cu" "F.Mask" "F.Paste")
			(net "GND")
			(options
				(clearance outline)
				(anchor circle)
			)
			(primitives
				(gr_poly
					(pts
						(arc
							(start -0.1778 -0.2794)
							(mid -0.249642 -0.249642)
							(end -0.2794 -0.1778)
						)
						(arc
							(start -0.2794 0.1778)
							(mid -0.249642 0.249642)
							(end -0.1778 0.2794)
						)
						(arc
							(start 0.1778 0.2794)
							(mid 0.249642 0.249642)
							(end 0.2794 0.1778)
						)
						(arc
							(start 0.2794 -0.1778)
							(mid 0.249642 -0.249642)
							(end 0.1778 -0.2794)
						)
					)
					(width 0)
					(fill yes)
				)
			)
		)
	)
	(footprint ""
		(layer "F.Cu")
		(at 339.628734 -27.23769)
		(property "Reference" "U19"
			(at 0 0 0)
			(layer "F.SilkS")
			(hide yes)
			(effects
				(font
					(size 1.27 1.27)
				)
			)
		)
		(property "Value" "TCA9555PWR-GP"
			(at 0 -6.9342 0)
			(unlocked yes)
			(layer "F.Fab")
			(hide yes)
			(effects
				(font
					(size 1.016 1.016)
					(thickness 0.1524)
				)
			)
		)
		(property "Device Type" "TSOIC24H48"
			(at 0 -8.5852 0)
			(unlocked yes)
			(layer "F.Fab")
			(hide yes)
			(effects
				(font
					(size 1.016 1.016)
					(thickness 0.1524)
				)
			)
		)
		(duplicate_pad_numbers_are_jumpers no)
		(fp_line
			(start -4.2291 -1.397)
			(end 3.81 -1.397)
			(stroke
				(width 0.1524)
				(type default)
			)
			(layer "F.SilkS")
		)
		(fp_line
			(start -4.2291 -0.8001)
			(end -3.429 0)
			(stroke
				(width 0.1524)
				(type default)
			)
			(layer "F.SilkS")
		)
		(fp_line
			(start -4.2291 3.937)
			(end -4.2291 -1.397)
			(stroke
				(width 0.1524)
				(type default)
			)
			(layer "F.SilkS")
		)
		(fp_line
			(start -4.22656 3.81)
			(end -4.2291 1.397)
			(stroke
				(width 0.508)
				(type default)
			)
			(layer "F.SilkS")
		)
		(fp_line
			(start -3.429 0)
			(end -4.2291 0.8001)
			(stroke
				(width 0.1524)
				(type default)
			)
			(layer "F.SilkS")
		)
		(fp_line
			(start 3.81 -1.397)
			(end 3.81 1.397)
			(stroke
				(width 0.1524)
				(type default)
			)
			(layer "F.SilkS")
		)
		(fp_line
			(start 3.81 1.397)
			(end -4.2291 1.397)
			(stroke
				(width 0.1524)
				(type default)
			)
			(layer "F.SilkS")
		)
		(fp_poly
			(pts
				(xy -3.90652 -1.8542) (xy 3.90652 -1.8542) (xy 3.90652 1.8542) (xy -3.90652 1.8542)
			)
			(stroke
				(width 0)
				(type default)
			)
			(fill yes)
			(layer "F.SilkS")
		)
		(fp_poly
			(pts
				(xy -4.2164 3.81) (xy 4.2164 3.81) (xy 4.22656 -3.81) (xy -4.2164 -3.81)
			)
			(stroke
				(width 0)
				(type default)
			)
			(fill no)
			(layer "F.CrtYd")
		)
		(fp_poly
			(pts
				(xy -4.22656 -3.81) (xy 4.22656 -3.81) (xy 4.22656 3.81) (xy -4.22656 3.81)
			)
			(stroke
				(width 0)
				(type default)
			)
			(fill no)
			(layer "F.Fab")
		)
		(pad "1" smd rect
			(at -3.57632 2.8194)
			(size 0.3556 1.524)
			(layers "F.Cu" "F.Mask" "F.Paste")
			(net "BMC_B_MISC_ALERT_N")
		)
		(pad "2" smd rect
			(at -2.92608 2.8194)
			(size 0.3556 1.524)
			(layers "F.Cu" "F.Mask" "F.Paste")
			(net "IO_EXP11_A1")
		)
		(pad "3" smd rect
			(at -2.27584 2.8194)
			(size 0.3556 1.524)
			(layers "F.Cu" "F.Mask" "F.Paste")
			(net "IO_EXP11_A2")
		)
		(pad "4" smd rect
			(at -1.6256 2.8194)
			(size 0.3556 1.524)
			(layers "F.Cu" "F.Mask" "F.Paste")
			(net "COMP_B_INS_N")
		)
		(pad "5" smd rect
			(at -0.97536 2.8194)
			(size 0.3556 1.524)
			(layers "F.Cu" "F.Mask" "F.Paste")
			(net "FAN_0_INS_N")
		)
		(pad "6" smd rect
			(at -0.32512 2.8194)
			(size 0.3556 1.524)
			(layers "F.Cu" "F.Mask" "F.Paste")
			(net "FAN_1_INS_N")
		)
		(pad "7" smd rect
			(at 0.32512 2.8194)
			(size 0.3556 1.524)
			(layers "F.Cu" "F.Mask" "F.Paste")
			(net "FAN_2_INS_N")
		)
		(pad "8" smd rect
			(at 0.97536 2.8194)
			(size 0.3556 1.524)
			(layers "F.Cu" "F.Mask" "F.Paste")
			(net "FAN_3_INS_N")
		)
		(pad "9" smd rect
			(at 1.6256 2.8194)
			(size 0.3556 1.524)
			(layers "F.Cu" "F.Mask" "F.Paste")
			(net "IOM_A_INS_N")
		)
		(pad "10" smd rect
			(at 2.27584 2.8194)
			(size 0.3556 1.524)
			(layers "F.Cu" "F.Mask" "F.Paste")
			(net "SCC_A_INS_N")
		)
		(pad "11" smd rect
			(at 2.92608 2.8194)
			(size 0.3556 1.524)
			(layers "F.Cu" "F.Mask" "F.Paste")
			(net "SCC_B_INS_N")
		)
		(pad "12" smd rect
			(at 3.57632 2.8194)
			(size 0.3556 1.524)
			(layers "F.Cu" "F.Mask" "F.Paste")
			(net "GND")
		)
		(pad "13" smd rect
			(at 3.57632 -2.8194)
			(size 0.3556 1.524)
			(layers "F.Cu" "F.Mask" "F.Paste")
			(net "SCC_B_TYPE_0")
		)
		(pad "14" smd rect
			(at 2.92608 -2.8194)
			(size 0.3556 1.524)
			(layers "F.Cu" "F.Mask" "F.Paste")
			(net "SCC_B_TYPE_1")
		)
		(pad "15" smd rect
			(at 2.27584 -2.8194)
			(size 0.3556 1.524)
			(layers "F.Cu" "F.Mask" "F.Paste")
			(net "SCC_B_TYPE_2")
		)
		(pad "16" smd rect
			(at 1.6256 -2.8194)
			(size 0.3556 1.524)
			(layers "F.Cu" "F.Mask" "F.Paste")
			(net "SCC_B_TYPE_3")
		)
		(pad "17" smd rect
			(at 0.97536 -2.8194)
			(size 0.3556 1.524)
			(layers "F.Cu" "F.Mask" "F.Paste")
			(net "SCC_B_STBY_PGOOD")
		)
		(pad "18" smd rect
			(at 0.32512 -2.8194)
			(size 0.3556 1.524)
			(layers "F.Cu" "F.Mask" "F.Paste")
			(net "SCC_B_FULL_PGOOD")
		)
		(pad "19" smd rect
			(at -0.32512 -2.8194)
			(size 0.3556 1.524)
			(layers "F.Cu" "F.Mask" "F.Paste")
			(net "COMP_B_PGOOD")
		)
		(pad "20" smd rect
			(at -0.97536 -2.8194)
			(size 0.3556 1.524)
			(layers "F.Cu" "F.Mask" "F.Paste")
			(net "DRAWER_CLOSED_N")
		)
		(pad "21" smd rect
			(at -1.6256 -2.8194)
			(size 0.3556 1.524)
			(layers "F.Cu" "F.Mask" "F.Paste")
			(net "IO_EXP11_A0")
		)
		(pad "22" smd rect
			(at -2.27584 -2.8194)
			(size 0.3556 1.524)
			(layers "F.Cu" "F.Mask" "F.Paste")
			(net "IO_EXP11_SCL")
		)
		(pad "23" smd rect
			(at -2.92608 -2.8194)
			(size 0.3556 1.524)
			(layers "F.Cu" "F.Mask" "F.Paste")
			(net "IO_EXP11_SDA")
		)
		(pad "24" smd rect
			(at -3.57632 -2.8194)
			(size 0.3556 1.524)
			(layers "F.Cu" "F.Mask" "F.Paste")
			(net "P3V3_STBY_B")
		)
	)
	(footprint ""
		(layer "F.Cu")
		(at 117.646196 -48.554894 90)
		(property "Reference" "R763"
			(at 0 0 90)
			(layer "F.SilkS")
			(hide yes)
			(effects
				(font
					(size 1.27 1.27)
				)
			)
		)
		(property "Value" "4K7R2J-2-GP"
			(at 0.064008 -3.993896 90)
			(unlocked yes)
			(layer "F.Fab")
			(hide yes)
			(effects
				(font
					(size 1.016 1.016)
					(thickness 0.1524)
				)
			)
		)
		(property "Device Type" "R402H16"
			(at 0.064008 -5.517896 90)
			(unlocked yes)
			(layer "F.Fab")
			(hide yes)
			(effects
				(font
					(size 1.016 1.016)
					(thickness 0.1524)
				)
			)
		)
		(duplicate_pad_numbers_are_jumpers no)
		(fp_line
			(start 0.508 -0.9398)
			(end -0.508 -0.9398)
			(stroke
				(width 0.1524)
				(type default)
			)
			(layer "F.SilkS")
		)
		(fp_line
			(start -0.508 -0.9398)
			(end -0.508 0.9398)
			(stroke
				(width 0.1524)
				(type default)
			)
			(layer "F.SilkS")
		)
		(fp_rect
			(start -0.508 0.9398)
			(end 0.508 -0.9398)
			(stroke
				(width 0)
				(type default)
			)
			(fill no)
			(layer "F.CrtYd")
		)
		(fp_rect
			(start -0.508 0.9398)
			(end 0.508 -0.9398)
			(stroke
				(width 0)
				(type default)
			)
			(fill no)
			(layer "F.Fab")
		)
		(pad "1" smd custom
			(at 0 -0.4445 90)
			(size 0.1397 0.1397)
			(layers "F.Cu" "F.Mask" "F.Paste")
			(net "SW_PWR_R_HDD27")
			(options
				(clearance outline)
				(anchor circle)
			)
			(primitives
				(gr_poly
					(pts
						(arc
							(start -0.1778 -0.2794)
							(mid -0.249642 -0.249642)
							(end -0.2794 -0.1778)
						)
						(arc
							(start -0.2794 0.1778)
							(mid -0.249642 0.249642)
							(end -0.1778 0.2794)
						)
						(arc
							(start 0.1778 0.2794)
							(mid 0.249642 0.249642)
							(end 0.2794 0.1778)
						)
						(arc
							(start 0.2794 -0.1778)
							(mid 0.249642 -0.249642)
							(end 0.1778 -0.2794)
						)
					)
					(width 0)
					(fill yes)
				)
			)
		)
		(pad "2" smd custom
			(at 0 0.4445 90)
			(size 0.1397 0.1397)
			(layers "F.Cu" "F.Mask" "F.Paste")
			(net "GND")
			(options
				(clearance outline)
				(anchor circle)
			)
			(primitives
				(gr_poly
					(pts
						(arc
							(start -0.1778 -0.2794)
							(mid -0.249642 -0.249642)
							(end -0.2794 -0.1778)
						)
						(arc
							(start -0.2794 0.1778)
							(mid -0.249642 0.249642)
							(end -0.1778 0.2794)
						)
						(arc
							(start 0.1778 0.2794)
							(mid 0.249642 0.249642)
							(end 0.2794 0.1778)
						)
						(arc
							(start 0.2794 -0.1778)
							(mid 0.249642 -0.249642)
							(end 0.1778 -0.2794)
						)
					)
					(width 0)
					(fill yes)
				)
			)
		)
	)
	(footprint ""
		(layer "F.Cu")
		(at 231.4448 -386.715 90)
		(property "Reference" "U36"
			(at 0 0 90)
			(layer "F.SilkS")
			(hide yes)
			(effects
				(font
					(size 1.27 1.27)
				)
			)
		)
		(property "Value" "SN74LVC1G08DCKR-GP"
			(at -2.3368 -8.6868 90)
			(unlocked yes)
			(layer "F.Fab")
			(hide yes)
			(effects
				(font
					(size 1.016 1.016)
					(thickness 0.1524)
				)
			)
		)
		(property "Device Type" "SC70-5H44"
			(at -2.3114 -10.414 90)
			(unlocked yes)
			(layer "F.Fab")
			(hide yes)
			(effects
				(font
					(size 1.016 1.016)
					(thickness 0.1524)
				)
			)
		)
		(duplicate_pad_numbers_are_jumpers no)
		(fp_line
			(start 1.3843 -1.8034)
			(end 1.3843 -1.1176)
			(stroke
				(width 0.3302)
				(type default)
			)
			(layer "F.SilkS")
		)
		(fp_line
			(start 0.6604 -1.8034)
			(end 1.3843 -1.8034)
			(stroke
				(width 0.3302)
				(type default)
			)
			(layer "F.SilkS")
		)
		(fp_line
			(start 1.27 -1.7018)
			(end 1.27 1.7018)
			(stroke
				(width 0.1524)
				(type default)
			)
			(layer "F.SilkS")
		)
		(fp_line
			(start -1.27 -1.7018)
			(end 1.27 -1.7018)
			(stroke
				(width 0.1524)
				(type default)
			)
			(layer "F.SilkS")
		)
		(fp_line
			(start 1.27 1.7018)
			(end -1.27 1.7018)
			(stroke
				(width 0.1524)
				(type default)
			)
			(layer "F.SilkS")
		)
		(fp_line
			(start -1.27 1.7018)
			(end -1.27 -1.7018)
			(stroke
				(width 0.1524)
				(type default)
			)
			(layer "F.SilkS")
		)
		(fp_rect
			(start -1.524 1.9558)
			(end 1.524 -1.9558)
			(stroke
				(width 0)
				(type default)
			)
			(fill no)
			(layer "F.CrtYd")
		)
		(fp_poly
			(pts
				(xy -1.524 -1.9558) (xy 1.524 -1.9558) (xy 1.524 1.9558) (xy -1.524 1.9558)
			)
			(stroke
				(width 0)
				(type default)
			)
			(fill no)
			(layer "F.Fab")
		)
		(pad "1" smd rect
			(at 0.65024 -0.8255 90)
			(size 0.4064 1.2192)
			(layers "F.Cu" "F.Mask" "F.Paste")
			(net "P12V_IN_PGOOD")
		)
		(pad "2" smd rect
			(at 0 -0.8255 90)
			(size 0.4064 1.2192)
			(layers "F.Cu" "F.Mask" "F.Paste")
			(net "DPB_PWR_BTN_BUF_A")
		)
		(pad "3" smd rect
			(at -0.65024 -0.8255 90)
			(size 0.4064 1.2192)
			(layers "F.Cu" "F.Mask" "F.Paste")
			(net "GND")
		)
		(pad "4" smd rect
			(at -0.65024 0.8255 90)
			(size 0.4064 1.2192)
			(layers "F.Cu" "F.Mask" "F.Paste")
			(net "MB3_HS_ENABLE")
		)
		(pad "5" smd rect
			(at 0.65024 0.8255 90)
			(size 0.4064 1.2192)
			(layers "F.Cu" "F.Mask" "F.Paste")
			(net "P3V3_IN_BIAS")
		)
	)
	(footprint ""
		(layer "F.Cu")
		(at 146.630898 -48.554894 180)
		(property "Reference" "Q169"
			(at 0 0 180)
			(layer "F.SilkS")
			(hide yes)
			(effects
				(font
					(size 1.27 1.27)
				)
			)
		)
		(property "Value" "2N7002KDW-GP"
			(at -2.3622 -8.2042 180)
			(unlocked yes)
			(layer "F.Fab")
			(hide yes)
			(effects
				(font
					(size 1.016 1.016)
					(thickness 0.1524)
				)
			)
		)
		(property "Device Type" "SOT-363H44"
			(at -2.3622 -10.1092 180)
			(unlocked yes)
			(layer "F.Fab")
			(hide yes)
			(effects
				(font
					(size 1.016 1.016)
					(thickness 0.1524)
				)
			)
		)
		(duplicate_pad_numbers_are_jumpers no)
		(fp_line
			(start 1.4478 1.7018)
			(end 1.4478 -1.7018)
			(stroke
				(width 0.1524)
				(type default)
			)
			(layer "F.SilkS")
		)
		(fp_line
			(start 1.4478 -1.7018)
			(end -1.4478 -1.7018)
			(stroke
				(width 0.1524)
				(type default)
			)
			(layer "F.SilkS")
		)
		(fp_line
			(start -1.27 1.524)
			(end -1.27 0.6604)
			(stroke
				(width 0.4826)
				(type default)
			)
			(layer "F.SilkS")
		)
		(fp_line
			(start -1.4478 1.7018)
			(end 1.4478 1.7018)
			(stroke
				(width 0.1524)
				(type default)
			)
			(layer "F.SilkS")
		)
		(fp_line
			(start -1.4478 -1.7018)
			(end -1.4478 1.7018)
			(stroke
				(width 0.1524)
				(type default)
			)
			(layer "F.SilkS")
		)
		(fp_poly
			(pts
				(xy -1.524 -1.778) (xy 1.524 -1.778) (xy 1.524 1.778) (xy -1.524 1.778)
			)
			(stroke
				(width 0)
				(type default)
			)
			(fill no)
			(layer "F.CrtYd")
		)
		(fp_poly
			(pts
				(xy -1.524 -1.778) (xy 1.524 -1.778) (xy 1.524 1.778) (xy -1.524 1.778)
			)
			(stroke
				(width 0)
				(type default)
			)
			(fill no)
			(layer "F.Fab")
		)
		(pad "1" smd rect
			(at -0.65024 0.9398 180)
			(size 0.4064 1.016)
			(layers "F.Cu" "F.Mask" "F.Paste")
			(net "GND")
		)
		(pad "2" smd rect
			(at 0 0.9398 180)
			(size 0.4064 1.016)
			(layers "F.Cu" "F.Mask" "F.Paste")
			(net "SW_PWR_R_HDD28")
		)
		(pad "3" smd rect
			(at 0.65024 0.9398 180)
			(size 0.4064 1.016)
			(layers "F.Cu" "F.Mask" "F.Paste")
			(net "SW_HDD_P28")
		)
		(pad "4" smd rect
			(at 0.65024 -0.9398 180)
			(size 0.4064 1.016)
			(layers "F.Cu" "F.Mask" "F.Paste")
			(net "GND")
		)
		(pad "5" smd rect
			(at 0 -0.9398 180)
			(size 0.4064 1.016)
			(layers "F.Cu" "F.Mask" "F.Paste")
			(net "SW_HDD_G28")
		)
		(pad "6" smd rect
			(at -0.65024 -0.9398 180)
			(size 0.4064 1.016)
			(layers "F.Cu" "F.Mask" "F.Paste")
			(net "SW_HDD_R28")
		)
	)
	(footprint ""
		(layer "F.Cu")
		(at 178.435 -170.285918 180)
		(property "Reference" "Q101"
			(at 0 0 180)
			(layer "F.SilkS")
			(hide yes)
			(effects
				(font
					(size 1.27 1.27)
				)
			)
		)
		(property "Value" "AO4406AL-GP"
			(at -3.707384 -1.5367 180)
			(unlocked yes)
			(layer "F.Fab")
			(hide yes)
			(effects
				(font
					(size 1.016 1.016)
					(thickness 0.1524)
				)
			)
		)
		(property "Device Type" "SOIC8H69"
			(at -3.707384 -3.0607 180)
			(unlocked yes)
			(layer "F.Fab")
			(hide yes)
			(effects
				(font
					(size 1.016 1.016)
					(thickness 0.1524)
				)
			)
		)
		(duplicate_pad_numbers_are_jumpers no)
		(fp_line
			(start 2.1336 1.4224)
			(end 2.1336 -1.4224)
			(stroke
				(width 0.1524)
				(type default)
			)
			(layer "F.SilkS")
		)
		(fp_line
			(start 2.1336 -1.4224)
			(end -2.7432 -1.4224)
			(stroke
				(width 0.1524)
				(type default)
			)
			(layer "F.SilkS")
		)
		(fp_line
			(start -2.1844 -0.0508)
			(end -2.7178 0.508)
			(stroke
				(width 0.1524)
				(type default)
			)
			(layer "F.SilkS")
		)
		(fp_line
			(start -2.6289 3.4417)
			(end -2.6289 1.4732)
			(stroke
				(width 0.381)
				(type default)
			)
			(layer "F.SilkS")
		)
		(fp_line
			(start -2.7178 -0.508)
			(end -2.1844 -0.0508)
			(stroke
				(width 0.1524)
				(type default)
			)
			(layer "F.SilkS")
		)
		(fp_line
			(start -2.7432 1.4224)
			(end 2.1336 1.4224)
			(stroke
				(width 0.1524)
				(type default)
			)
			(layer "F.SilkS")
		)
		(fp_line
			(start -2.7432 1.4224)
			(end -2.6416 1.4224)
			(stroke
				(width 0.1524)
				(type default)
			)
			(layer "F.SilkS")
		)
		(fp_line
			(start -2.7432 -1.4224)
			(end -2.7432 1.4224)
			(stroke
				(width 0.1524)
				(type default)
			)
			(layer "F.SilkS")
		)
		(fp_poly
			(pts
				(xy -2.2098 -1.4224) (xy -2.2098 1.4224) (xy 2.2098 1.4224) (xy 2.2098 -1.4224)
			)
			(stroke
				(width 0)
				(type default)
			)
			(fill yes)
			(layer "F.SilkS")
		)
		(fp_rect
			(start -2.450084 2.999994)
			(end 2.450084 -2.999994)
			(stroke
				(width 0)
				(type default)
			)
			(fill no)
			(layer "F.CrtYd")
		)
		(fp_poly
			(pts
				(xy -2.8194 3.6322) (xy -2.8194 -3.6322) (xy 2.8194 -3.6322) (xy 2.8194 1.18364) (xy 2.450084 1.18364)
				(xy 2.450084 -2.999994) (xy -2.450084 -2.999994) (xy -2.450084 2.999994) (xy 2.450084 2.999994)
				(xy 2.450084 1.18618) (xy 2.8194 1.18618) (xy 2.8194 3.6322)
			)
			(stroke
				(width 0)
				(type default)
			)
			(fill no)
			(layer "F.CrtYd")
		)
		(fp_rect
			(start -2.8194 3.6322)
			(end 2.8194 -3.6322)
			(stroke
				(width 0)
				(type default)
			)
			(fill no)
			(layer "F.Fab")
		)
		(pad "1" smd rect
			(at -1.905 2.54 180)
			(size 0.635 1.651)
			(layers "F.Cu" "F.Mask" "F.Paste")
			(net "P5V_HDD17")
		)
		(pad "2" smd rect
			(at -0.635 2.54 180)
			(size 0.635 1.651)
			(layers "F.Cu" "F.Mask" "F.Paste")
			(net "P5V_HDD17")
		)
		(pad "3" smd rect
			(at 0.635 2.54 180)
			(size 0.635 1.651)
			(layers "F.Cu" "F.Mask" "F.Paste")
			(net "P5V_HDD17")
		)
		(pad "4" smd rect
			(at 1.905 2.54 180)
			(size 0.635 1.651)
			(layers "F.Cu" "F.Mask" "F.Paste")
			(net "SW_HDD_P17")
		)
		(pad "5" smd rect
			(at 1.905 -2.54 180)
			(size 0.635 1.651)
			(layers "F.Cu" "F.Mask" "F.Paste")
			(net "P5V_A_2")
		)
		(pad "6" smd rect
			(at 0.635 -2.54 180)
			(size 0.635 1.651)
			(layers "F.Cu" "F.Mask" "F.Paste")
			(net "P5V_A_2")
		)
		(pad "7" smd rect
			(at -0.635 -2.54 180)
			(size 0.635 1.651)
			(layers "F.Cu" "F.Mask" "F.Paste")
			(net "P5V_A_2")
		)
		(pad "8" smd rect
			(at -1.905 -2.54 180)
			(size 0.635 1.651)
			(layers "F.Cu" "F.Mask" "F.Paste")
			(net "P5V_A_2")
		)
	)
	(footprint ""
		(layer "F.Cu")
		(at 64.0588 -47.749968 -90)
		(property "Reference" "VIA60"
			(at 0 0 270)
			(layer "F.SilkS")
			(hide yes)
			(effects
				(font
					(size 1.27 1.27)
				)
			)
		)
		(property "Value" "100OHM-8L-1D6MM-L18L16-GP"
			(at -3.7211 -4.5085 270)
			(unlocked yes)
			(layer "F.Fab")
			(hide yes)
			(effects
				(font
					(size 1.016 1.016)
					(thickness 0.1524)
				)
			)
		)
		(property "Device Type" "VIA-PCIE-4P-394076"
			(at -3.7211 -6.0325 270)
			(unlocked yes)
			(layer "F.Fab")
			(hide yes)
			(effects
				(font
					(size 1.016 1.016)
					(thickness 0.1524)
				)
			)
		)
		(duplicate_pad_numbers_are_jumpers no)
		(fp_rect
			(start -1.9685 0.381)
			(end 1.9685 -0.381)
			(stroke
				(width 0)
				(type default)
			)
			(fill no)
			(layer "F.CrtYd")
		)
		(fp_rect
			(start -1.9685 0.381)
			(end 1.9685 -0.381)
			(stroke
				(width 0)
				(type default)
			)
			(fill no)
			(layer "F.Fab")
		)
		(pad "1" thru_hole circle
			(at -1.5875 0 270)
			(size 0.508 0.508)
			(drill 0.254)
			(layers "*.Cu" "*.Mask")
			(remove_unused_layers no)
			(net "GND")
			(clearance 0.127)
			(thermal_gap 0.127)
		)
		(pad "2" thru_hole circle
			(at -0.5715 0 270)
			(size 0.508 0.508)
			(drill 0.254)
			(layers "*.Cu" "*.Mask")
			(remove_unused_layers no)
			(net "PHY_DRV_A_TO_SCC_A_25_DP")
			(clearance 0.127)
			(thermal_gap 0.127)
		)
		(pad "3" thru_hole circle
			(at 0.5715 0 270)
			(size 0.508 0.508)
			(drill 0.254)
			(layers "*.Cu" "*.Mask")
			(remove_unused_layers no)
			(net "PHY_DRV_A_TO_SCC_A_25_DN")
			(clearance 0.127)
			(thermal_gap 0.127)
		)
		(pad "4" thru_hole circle
			(at 1.5875 0 270)
			(size 0.508 0.508)
			(drill 0.254)
			(layers "*.Cu" "*.Mask")
			(remove_unused_layers no)
			(net "GND")
			(clearance 0.127)
			(thermal_gap 0.127)
		)
	)
	(footprint ""
		(layer "F.Cu")
		(at 364.7948 -140.1064 180)
		(property "Reference" "C570"
			(at 0 0 180)
			(layer "F.SilkS")
			(hide yes)
			(effects
				(font
					(size 1.27 1.27)
				)
			)
		)
		(property "Value" "SCD015U25V2KX-GP"
			(at 1.1811 -2.7051 180)
			(unlocked yes)
			(layer "F.Fab")
			(hide yes)
			(effects
				(font
					(size 1.016 1.016)
					(thickness 0.1524)
				)
			)
		)
		(property "Device Type" "C402H22"
			(at 1.1811 -4.2291 180)
			(unlocked yes)
			(layer "F.Fab")
			(hide yes)
			(effects
				(font
					(size 1.016 1.016)
					(thickness 0.1524)
				)
			)
		)
		(duplicate_pad_numbers_are_jumpers no)
		(fp_rect
			(start -0.4318 0.9525)
			(end 0.4318 -0.9525)
			(stroke
				(width 0)
				(type default)
			)
			(fill no)
			(layer "F.CrtYd")
		)
		(fp_rect
			(start -0.4318 0.9525)
			(end 0.4318 -0.9525)
			(stroke
				(width 0)
				(type default)
			)
			(fill no)
			(layer "F.Fab")
		)
		(pad "1" smd custom
			(at 0 -0.4445 180)
			(size 0.1524 0.1524)
			(layers "F.Cu" "F.Mask" "F.Paste")
			(net "MB1_HS_SENSE_P")
			(options
				(clearance outline)
				(anchor circle)
			)
			(primitives
				(gr_poly
					(pts
						(arc
							(start 0.3048 -0.2032)
							(mid 0.275042 -0.275042)
							(end 0.2032 -0.3048)
						)
						(arc
							(start -0.2032 -0.3048)
							(mid -0.275042 -0.275042)
							(end -0.3048 -0.2032)
						)
						(arc
							(start -0.3048 0.2032)
							(mid -0.275042 0.275042)
							(end -0.2032 0.3048)
						)
						(arc
							(start 0.2032 0.3048)
							(mid 0.275042 0.275042)
							(end 0.3048 0.2032)
						)
					)
					(width 0)
					(fill yes)
				)
			)
		)
		(pad "2" smd custom
			(at 0 0.4445 180)
			(size 0.1524 0.1524)
			(layers "F.Cu" "F.Mask" "F.Paste")
			(net "MB1_HS_SENSE_N")
			(options
				(clearance outline)
				(anchor circle)
			)
			(primitives
				(gr_poly
					(pts
						(arc
							(start 0.3048 -0.2032)
							(mid 0.275042 -0.275042)
							(end 0.2032 -0.3048)
						)
						(arc
							(start -0.2032 -0.3048)
							(mid -0.275042 -0.275042)
							(end -0.3048 -0.2032)
						)
						(arc
							(start -0.3048 0.2032)
							(mid -0.275042 0.275042)
							(end -0.2032 0.3048)
						)
						(arc
							(start 0.2032 0.3048)
							(mid 0.275042 0.275042)
							(end 0.3048 0.2032)
						)
					)
					(width 0)
					(fill yes)
				)
			)
		)
	)
	(footprint ""
		(layer "F.Cu")
		(at 32.528002 -253.29515 -90)
		(property "Reference" "C603"
			(at 0 0 270)
			(layer "F.SilkS")
			(hide yes)
			(effects
				(font
					(size 1.27 1.27)
				)
			)
		)
		(property "Value" "SC1U16V3KX-5GP"
			(at 0 -2.8194 270)
			(unlocked yes)
			(layer "F.Fab")
			(hide yes)
			(effects
				(font
					(size 1.016 1.016)
					(thickness 0.1524)
				)
			)
		)
		(property "Device Type" "C603H36"
			(at 0 -4.3434 270)
			(unlocked yes)
			(layer "F.Fab")
			(hide yes)
			(effects
				(font
					(size 1.016 1.016)
					(thickness 0.1524)
				)
			)
		)
		(duplicate_pad_numbers_are_jumpers no)
		(fp_line
			(start 0.508 0)
			(end -0.508 0)
			(stroke
				(width 0.2032)
				(type default)
			)
			(layer "F.SilkS")
		)
		(fp_rect
			(start -0.5842 1.3335)
			(end 0.5842 -1.3335)
			(stroke
				(width 0)
				(type default)
			)
			(fill no)
			(layer "F.CrtYd")
		)
		(fp_rect
			(start -0.5842 1.3335)
			(end 0.5842 -1.3335)
			(stroke
				(width 0)
				(type default)
			)
			(fill no)
			(layer "F.Fab")
		)
		(pad "1" smd custom
			(at 0 -0.762 270)
			(size 0.2159 0.2159)
			(layers "F.Cu" "F.Mask" "F.Paste")
			(net "P5V_A_EN_R")
			(options
				(clearance outline)
				(anchor circle)
			)
			(primitives
				(gr_poly
					(pts
						(arc
							(start -0.3302 -0.4318)
							(mid -0.402042 -0.402042)
							(end -0.4318 -0.3302)
						)
						(arc
							(start -0.4318 0.3302)
							(mid -0.402042 0.402042)
							(end -0.3302 0.4318)
						)
						(arc
							(start 0.3302 0.4318)
							(mid 0.402042 0.402042)
							(end 0.4318 0.3302)
						)
						(arc
							(start 0.4318 -0.3302)
							(mid 0.402042 -0.402042)
							(end 0.3302 -0.4318)
						)
					)
					(width 0)
					(fill yes)
				)
			)
		)
		(pad "2" smd custom
			(at 0 0.762 270)
			(size 0.2159 0.2159)
			(layers "F.Cu" "F.Mask" "F.Paste")
			(net "GND")
			(options
				(clearance outline)
				(anchor circle)
			)
			(primitives
				(gr_poly
					(pts
						(arc
							(start -0.3302 -0.4318)
							(mid -0.402042 -0.402042)
							(end -0.4318 -0.3302)
						)
						(arc
							(start -0.4318 0.3302)
							(mid -0.402042 0.402042)
							(end -0.3302 0.4318)
						)
						(arc
							(start 0.3302 0.4318)
							(mid 0.402042 0.402042)
							(end 0.4318 0.3302)
						)
						(arc
							(start 0.4318 -0.3302)
							(mid 0.402042 -0.402042)
							(end 0.3302 -0.4318)
						)
					)
					(width 0)
					(fill yes)
				)
			)
		)
	)
	(footprint ""
		(layer "F.Cu")
		(at 369.935506 -132.096764)
		(property "Reference" "R1095"
			(at 0 0 0)
			(layer "F.SilkS")
			(hide yes)
			(effects
				(font
					(size 1.27 1.27)
				)
			)
		)
		(property "Value" "22D6R2F-L1-GP"
			(at 0.064008 -3.993896 0)
			(unlocked yes)
			(layer "F.Fab")
			(hide yes)
			(effects
				(font
					(size 1.016 1.016)
					(thickness 0.1524)
				)
			)
		)
		(property "Device Type" "R402H16"
			(at 0.064008 -5.517896 0)
			(unlocked yes)
			(layer "F.Fab")
			(hide yes)
			(effects
				(font
					(size 1.016 1.016)
					(thickness 0.1524)
				)
			)
		)
		(duplicate_pad_numbers_are_jumpers no)
		(fp_line
			(start -0.508 -0.9398)
			(end -0.508 0.9398)
			(stroke
				(width 0.1524)
				(type default)
			)
			(layer "F.SilkS")
		)
		(fp_line
			(start 0.508 -0.9398)
			(end -0.508 -0.9398)
			(stroke
				(width 0.1524)
				(type default)
			)
			(layer "F.SilkS")
		)
		(fp_rect
			(start -0.508 0.9398)
			(end 0.508 -0.9398)
			(stroke
				(width 0)
				(type default)
			)
			(fill no)
			(layer "F.CrtYd")
		)
		(fp_rect
			(start -0.508 0.9398)
			(end 0.508 -0.9398)
			(stroke
				(width 0)
				(type default)
			)
			(fill no)
			(layer "F.Fab")
		)
		(pad "1" smd custom
			(at 0 -0.4445)
			(size 0.1397 0.1397)
			(layers "F.Cu" "F.Mask" "F.Paste")
			(net "MB1_ISTART_R")
			(options
				(clearance outline)
				(anchor circle)
			)
			(primitives
				(gr_poly
					(pts
						(arc
							(start -0.1778 -0.2794)
							(mid -0.249642 -0.249642)
							(end -0.2794 -0.1778)
						)
						(arc
							(start -0.2794 0.1778)
							(mid -0.249642 0.249642)
							(end -0.1778 0.2794)
						)
						(arc
							(start 0.1778 0.2794)
							(mid 0.249642 0.249642)
							(end 0.2794 0.1778)
						)
						(arc
							(start 0.2794 -0.1778)
							(mid 0.249642 -0.249642)
							(end 0.1778 -0.2794)
						)
					)
					(width 0)
					(fill yes)
				)
			)
		)
		(pad "2" smd custom
			(at 0 0.4445)
			(size 0.1397 0.1397)
			(layers "F.Cu" "F.Mask" "F.Paste")
			(net "AGND_CURRENT_MONOB")
			(options
				(clearance outline)
				(anchor circle)
			)
			(primitives
				(gr_poly
					(pts
						(arc
							(start -0.1778 -0.2794)
							(mid -0.249642 -0.249642)
							(end -0.2794 -0.1778)
						)
						(arc
							(start -0.2794 0.1778)
							(mid -0.249642 0.249642)
							(end -0.1778 0.2794)
						)
						(arc
							(start 0.1778 0.2794)
							(mid 0.249642 0.249642)
							(end 0.2794 0.1778)
						)
						(arc
							(start 0.2794 -0.1778)
							(mid 0.249642 -0.249642)
							(end 0.1778 -0.2794)
						)
					)
					(width 0)
					(fill yes)
				)
			)
		)
	)
	(footprint ""
		(layer "F.Cu")
		(at 156.275532 -136.84123 90)
		(property "Reference" "R1053"
			(at 0 0 90)
			(layer "F.SilkS")
			(hide yes)
			(effects
				(font
					(size 1.27 1.27)
				)
			)
		)
		(property "Value" "10R2F-L-GP"
			(at 0.064008 -3.993896 90)
			(unlocked yes)
			(layer "F.Fab")
			(hide yes)
			(effects
				(font
					(size 1.016 1.016)
					(thickness 0.1524)
				)
			)
		)
		(property "Device Type" "R402H14"
			(at 0.064008 -5.517896 90)
			(unlocked yes)
			(layer "F.Fab")
			(hide yes)
			(effects
				(font
					(size 1.016 1.016)
					(thickness 0.1524)
				)
			)
		)
		(duplicate_pad_numbers_are_jumpers no)
		(fp_line
			(start 0.508 -0.9398)
			(end -0.508 -0.9398)
			(stroke
				(width 0.1524)
				(type default)
			)
			(layer "F.SilkS")
		)
		(fp_line
			(start -0.508 -0.9398)
			(end -0.508 0.9398)
			(stroke
				(width 0.1524)
				(type default)
			)
			(layer "F.SilkS")
		)
		(fp_rect
			(start -0.508 0.9398)
			(end 0.508 -0.9398)
			(stroke
				(width 0)
				(type default)
			)
			(fill no)
			(layer "F.CrtYd")
		)
		(fp_rect
			(start -0.508 0.9398)
			(end 0.508 -0.9398)
			(stroke
				(width 0)
				(type default)
			)
			(fill no)
			(layer "F.Fab")
		)
		(pad "1" smd custom
			(at 0 -0.4445 90)
			(size 0.1397 0.1397)
			(layers "F.Cu" "F.Mask" "F.Paste")
			(net "MB0_CM_SENSE_R1_N")
			(options
				(clearance outline)
				(anchor circle)
			)
			(primitives
				(gr_poly
					(pts
						(arc
							(start -0.1778 -0.2794)
							(mid -0.249642 -0.249642)
							(end -0.2794 -0.1778)
						)
						(arc
							(start -0.2794 0.1778)
							(mid -0.249642 0.249642)
							(end -0.1778 0.2794)
						)
						(arc
							(start 0.1778 0.2794)
							(mid 0.249642 0.249642)
							(end 0.2794 0.1778)
						)
						(arc
							(start 0.2794 -0.1778)
							(mid 0.249642 -0.249642)
							(end 0.1778 -0.2794)
						)
					)
					(width 0)
					(fill yes)
				)
			)
		)
		(pad "2" smd custom
			(at 0 0.4445 90)
			(size 0.1397 0.1397)
			(layers "F.Cu" "F.Mask" "F.Paste")
			(net "MB0_CM_SENSE_N")
			(options
				(clearance outline)
				(anchor circle)
			)
			(primitives
				(gr_poly
					(pts
						(arc
							(start -0.1778 -0.2794)
							(mid -0.249642 -0.249642)
							(end -0.2794 -0.1778)
						)
						(arc
							(start -0.2794 0.1778)
							(mid -0.249642 0.249642)
							(end -0.1778 0.2794)
						)
						(arc
							(start 0.1778 0.2794)
							(mid 0.249642 0.249642)
							(end 0.2794 0.1778)
						)
						(arc
							(start 0.2794 -0.1778)
							(mid 0.249642 -0.249642)
							(end 0.1778 -0.2794)
						)
					)
					(width 0)
					(fill yes)
				)
			)
		)
	)
	(footprint ""
		(layer "F.Cu")
		(at 338.074 -164.443918 90)
		(property "Reference" "R560"
			(at 0 0 90)
			(layer "F.SilkS")
			(hide yes)
			(effects
				(font
					(size 1.27 1.27)
				)
			)
		)
		(property "Value" "200KR2F-L-GP"
			(at 0.064008 -3.993896 90)
			(unlocked yes)
			(layer "F.Fab")
			(hide yes)
			(effects
				(font
					(size 1.016 1.016)
					(thickness 0.1524)
				)
			)
		)
		(property "Device Type" "R402H16"
			(at 0.064008 -5.517896 90)
			(unlocked yes)
			(layer "F.Fab")
			(hide yes)
			(effects
				(font
					(size 1.016 1.016)
					(thickness 0.1524)
				)
			)
		)
		(duplicate_pad_numbers_are_jumpers no)
		(fp_line
			(start 0.508 -0.9398)
			(end -0.508 -0.9398)
			(stroke
				(width 0.1524)
				(type default)
			)
			(layer "F.SilkS")
		)
		(fp_line
			(start -0.508 -0.9398)
			(end -0.508 0.9398)
			(stroke
				(width 0.1524)
				(type default)
			)
			(layer "F.SilkS")
		)
		(fp_rect
			(start -0.508 0.9398)
			(end 0.508 -0.9398)
			(stroke
				(width 0)
				(type default)
			)
			(fill no)
			(layer "F.CrtYd")
		)
		(fp_rect
			(start -0.508 0.9398)
			(end 0.508 -0.9398)
			(stroke
				(width 0)
				(type default)
			)
			(fill no)
			(layer "F.Fab")
		)
		(pad "1" smd custom
			(at 0 -0.4445 90)
			(size 0.1397 0.1397)
			(layers "F.Cu" "F.Mask" "F.Paste")
			(net "SW_HDD_R18")
			(options
				(clearance outline)
				(anchor circle)
			)
			(primitives
				(gr_poly
					(pts
						(arc
							(start -0.1778 -0.2794)
							(mid -0.249642 -0.249642)
							(end -0.2794 -0.1778)
						)
						(arc
							(start -0.2794 0.1778)
							(mid -0.249642 0.249642)
							(end -0.1778 0.2794)
						)
						(arc
							(start 0.1778 0.2794)
							(mid 0.249642 0.249642)
							(end 0.2794 0.1778)
						)
						(arc
							(start 0.2794 -0.1778)
							(mid 0.249642 -0.249642)
							(end 0.1778 -0.2794)
						)
					)
					(width 0)
					(fill yes)
				)
			)
		)
		(pad "2" smd custom
			(at 0 0.4445 90)
			(size 0.1397 0.1397)
			(layers "F.Cu" "F.Mask" "F.Paste")
			(net "SW_HDD_N18")
			(options
				(clearance outline)
				(anchor circle)
			)
			(primitives
				(gr_poly
					(pts
						(arc
							(start -0.1778 -0.2794)
							(mid -0.249642 -0.249642)
							(end -0.2794 -0.1778)
						)
						(arc
							(start -0.2794 0.1778)
							(mid -0.249642 0.249642)
							(end -0.1778 0.2794)
						)
						(arc
							(start 0.1778 0.2794)
							(mid 0.249642 0.249642)
							(end 0.2794 0.1778)
						)
						(arc
							(start 0.2794 -0.1778)
							(mid 0.249642 -0.249642)
							(end 0.1778 -0.2794)
						)
					)
					(width 0)
					(fill yes)
				)
			)
		)
	)
	(footprint ""
		(layer "F.Cu")
		(at 272.923 -284.734 180)
		(property "Reference" "R115"
			(at 0 0 180)
			(layer "F.SilkS")
			(hide yes)
			(effects
				(font
					(size 1.27 1.27)
				)
			)
		)
		(property "Value" "0R2J-2-GP"
			(at 0.064008 -3.993896 180)
			(unlocked yes)
			(layer "F.Fab")
			(hide yes)
			(effects
				(font
					(size 1.016 1.016)
					(thickness 0.1524)
				)
			)
		)
		(property "Device Type" "R402H16"
			(at 0.064008 -5.517896 180)
			(unlocked yes)
			(layer "F.Fab")
			(hide yes)
			(effects
				(font
					(size 1.016 1.016)
					(thickness 0.1524)
				)
			)
		)
		(duplicate_pad_numbers_are_jumpers no)
		(fp_line
			(start 0.508 -0.9398)
			(end -0.508 -0.9398)
			(stroke
				(width 0.1524)
				(type default)
			)
			(layer "F.SilkS")
		)
		(fp_line
			(start -0.508 -0.9398)
			(end -0.508 0.9398)
			(stroke
				(width 0.1524)
				(type default)
			)
			(layer "F.SilkS")
		)
		(fp_rect
			(start -0.508 0.9398)
			(end 0.508 -0.9398)
			(stroke
				(width 0)
				(type default)
			)
			(fill no)
			(layer "F.CrtYd")
		)
		(fp_rect
			(start -0.508 0.9398)
			(end 0.508 -0.9398)
			(stroke
				(width 0)
				(type default)
			)
			(fill no)
			(layer "F.Fab")
		)
		(pad "1" smd custom
			(at 0 -0.4445 180)
			(size 0.1397 0.1397)
			(layers "F.Cu" "F.Mask" "F.Paste")
			(net "IO_EXP1_LED_SDA")
			(options
				(clearance outline)
				(anchor circle)
			)
			(primitives
				(gr_poly
					(pts
						(arc
							(start -0.1778 -0.2794)
							(mid -0.249642 -0.249642)
							(end -0.2794 -0.1778)
						)
						(arc
							(start -0.2794 0.1778)
							(mid -0.249642 0.249642)
							(end -0.1778 0.2794)
						)
						(arc
							(start 0.1778 0.2794)
							(mid 0.249642 0.249642)
							(end 0.2794 0.1778)
						)
						(arc
							(start 0.2794 -0.1778)
							(mid 0.249642 -0.249642)
							(end 0.1778 -0.2794)
						)
					)
					(width 0)
					(fill yes)
				)
			)
		)
		(pad "2" smd custom
			(at 0 0.4445 180)
			(size 0.1397 0.1397)
			(layers "F.Cu" "F.Mask" "F.Paste")
			(net "I2C_DRIVE_A_FLT_LED_SDA")
			(options
				(clearance outline)
				(anchor circle)
			)
			(primitives
				(gr_poly
					(pts
						(arc
							(start -0.1778 -0.2794)
							(mid -0.249642 -0.249642)
							(end -0.2794 -0.1778)
						)
						(arc
							(start -0.2794 0.1778)
							(mid -0.249642 0.249642)
							(end -0.1778 0.2794)
						)
						(arc
							(start 0.1778 0.2794)
							(mid 0.249642 0.249642)
							(end 0.2794 0.1778)
						)
						(arc
							(start 0.2794 -0.1778)
							(mid 0.249642 -0.249642)
							(end 0.1778 -0.2794)
						)
					)
					(width 0)
					(fill yes)
				)
			)
		)
	)
	(footprint ""
		(layer "F.Cu")
		(at 286.015938 -224.384616)
		(property "Reference" "TC16"
			(at 0 0 0)
			(layer "F.SilkS")
			(hide yes)
			(effects
				(font
					(size 1.27 1.27)
				)
			)
		)
		(property "Value" "SE270U16VM-8-GP"
			(at -4.5974 -2.54 0)
			(unlocked yes)
			(layer "F.Fab")
			(hide yes)
			(effects
				(font
					(size 1.016 1.016)
					(thickness 0.1524)
				)
			)
		)
		(property "Device Type" "SE361416H394"
			(at -4.5974 -4.064 0)
			(unlocked yes)
			(layer "F.Fab")
			(hide yes)
			(effects
				(font
					(size 1.016 1.016)
					(thickness 0.1524)
				)
			)
		)
		(duplicate_pad_numbers_are_jumpers no)
		(fp_line
			(start -3.556 -3.4163)
			(end -2.3622 -4.6101)
			(stroke
				(width 0.1524)
				(type default)
			)
			(layer "F.SilkS")
		)
		(fp_line
			(start -3.556 4.6101)
			(end -3.556 -3.4163)
			(stroke
				(width 0.1524)
				(type default)
			)
			(layer "F.SilkS")
		)
		(fp_line
			(start -2.3622 -4.6101)
			(end 2.3622 -4.6101)
			(stroke
				(width 0.1524)
				(type default)
			)
			(layer "F.SilkS")
		)
		(fp_line
			(start 2.3622 -4.6101)
			(end 3.556 -3.4163)
			(stroke
				(width 0.1524)
				(type default)
			)
			(layer "F.SilkS")
		)
		(fp_line
			(start 3.556 -3.4163)
			(end 3.556 4.6101)
			(stroke
				(width 0.1524)
				(type default)
			)
			(layer "F.SilkS")
		)
		(fp_line
			(start 3.556 4.6101)
			(end -3.556 4.6101)
			(stroke
				(width 0.1524)
				(type default)
			)
			(layer "F.SilkS")
		)
		(fp_rect
			(start -3.302 3.6449)
			(end 3.302 -3.6449)
			(stroke
				(width 0)
				(type default)
			)
			(fill no)
			(layer "F.CrtYd")
		)
		(fp_poly
			(pts
				(xy 3.81 4.6863) (xy 3.81 -3.4925) (xy 3.302 -3.4925) (xy 3.302 3.6449) (xy -3.302 3.6449) (xy -3.302 -3.6449)
				(xy 3.302 -3.6449) (xy 3.302 -3.5052) (xy 3.81 -3.5052) (xy 3.81 -4.6863) (xy -3.81 -4.6863) (xy -3.81 4.6863)
			)
			(stroke
				(width 0)
				(type default)
			)
			(fill no)
			(layer "F.CrtYd")
		)
		(fp_rect
			(start -3.81 4.6863)
			(end 3.81 -4.6863)
			(stroke
				(width 0)
				(type default)
			)
			(fill no)
			(layer "F.Fab")
		)
		(pad "1" smd rect
			(at 0 -2.574036)
			(size 1.4224 3.556)
			(layers "F.Cu" "F.Mask" "F.Paste")
			(net "P12V_A")
		)
		(pad "2" smd rect
			(at 0 2.574036)
			(size 1.4224 3.556)
			(layers "F.Cu" "F.Mask" "F.Paste")
			(net "GND")
		)
	)
	(footprint ""
		(layer "F.Cu")
		(at 145.17116 -145.38071 180)
		(property "Reference" "R1061"
			(at 0 0 180)
			(layer "F.SilkS")
			(hide yes)
			(effects
				(font
					(size 1.27 1.27)
				)
			)
		)
		(property "Value" "22D6R2F-L1-GP"
			(at 0.064008 -3.993896 180)
			(unlocked yes)
			(layer "F.Fab")
			(hide yes)
			(effects
				(font
					(size 1.016 1.016)
					(thickness 0.1524)
				)
			)
		)
		(property "Device Type" "R402H16"
			(at 0.064008 -5.517896 180)
			(unlocked yes)
			(layer "F.Fab")
			(hide yes)
			(effects
				(font
					(size 1.016 1.016)
					(thickness 0.1524)
				)
			)
		)
		(duplicate_pad_numbers_are_jumpers no)
		(fp_line
			(start 0.508 -0.9398)
			(end -0.508 -0.9398)
			(stroke
				(width 0.1524)
				(type default)
			)
			(layer "F.SilkS")
		)
		(fp_line
			(start -0.508 -0.9398)
			(end -0.508 0.9398)
			(stroke
				(width 0.1524)
				(type default)
			)
			(layer "F.SilkS")
		)
		(fp_rect
			(start -0.508 0.9398)
			(end 0.508 -0.9398)
			(stroke
				(width 0)
				(type default)
			)
			(fill no)
			(layer "F.CrtYd")
		)
		(fp_rect
			(start -0.508 0.9398)
			(end 0.508 -0.9398)
			(stroke
				(width 0)
				(type default)
			)
			(fill no)
			(layer "F.Fab")
		)
		(pad "1" smd custom
			(at 0 -0.4445 180)
			(size 0.1397 0.1397)
			(layers "F.Cu" "F.Mask" "F.Paste")
			(net "MB0_ISTART_R")
			(options
				(clearance outline)
				(anchor circle)
			)
			(primitives
				(gr_poly
					(pts
						(arc
							(start -0.1778 -0.2794)
							(mid -0.249642 -0.249642)
							(end -0.2794 -0.1778)
						)
						(arc
							(start -0.2794 0.1778)
							(mid -0.249642 0.249642)
							(end -0.1778 0.2794)
						)
						(arc
							(start 0.1778 0.2794)
							(mid 0.249642 0.249642)
							(end 0.2794 0.1778)
						)
						(arc
							(start 0.2794 -0.1778)
							(mid 0.249642 -0.249642)
							(end 0.1778 -0.2794)
						)
					)
					(width 0)
					(fill yes)
				)
			)
		)
		(pad "2" smd custom
			(at 0 0.4445 180)
			(size 0.1397 0.1397)
			(layers "F.Cu" "F.Mask" "F.Paste")
			(net "AGND_CURRENT_MONOA")
			(options
				(clearance outline)
				(anchor circle)
			)
			(primitives
				(gr_poly
					(pts
						(arc
							(start -0.1778 -0.2794)
							(mid -0.249642 -0.249642)
							(end -0.2794 -0.1778)
						)
						(arc
							(start -0.2794 0.1778)
							(mid -0.249642 0.249642)
							(end -0.1778 0.2794)
						)
						(arc
							(start 0.1778 0.2794)
							(mid 0.249642 0.249642)
							(end 0.2794 0.1778)
						)
						(arc
							(start 0.2794 -0.1778)
							(mid 0.249642 -0.249642)
							(end 0.1778 -0.2794)
						)
					)
					(width 0)
					(fill yes)
				)
			)
		)
	)
	(footprint ""
		(layer "F.Cu")
		(at 127.113284 -43.660568 90)
		(property "Reference" "C390"
			(at 0 0 90)
			(layer "F.SilkS")
			(hide yes)
			(effects
				(font
					(size 1.27 1.27)
				)
			)
		)
		(property "Value" "SCD01U16V1KX-GP"
			(at -2.8321 -1.7399 90)
			(unlocked yes)
			(layer "F.Fab")
			(hide yes)
			(effects
				(font
					(size 1.016 1.016)
					(thickness 0.1524)
				)
			)
		)
		(property "Device Type" "C0201H13"
			(at -2.8321 -3.2639 90)
			(unlocked yes)
			(layer "F.Fab")
			(hide yes)
			(effects
				(font
					(size 1.016 1.016)
					(thickness 0.1524)
				)
			)
		)
		(duplicate_pad_numbers_are_jumpers no)
		(fp_rect
			(start -0.2794 0.6477)
			(end 0.2794 -0.6477)
			(stroke
				(width 0)
				(type default)
			)
			(fill no)
			(layer "F.CrtYd")
		)
		(fp_rect
			(start -0.2794 0.6477)
			(end 0.2794 -0.6477)
			(stroke
				(width 0)
				(type default)
			)
			(fill no)
			(layer "F.Fab")
		)
		(pad "1" smd custom
			(at 0 -0.2794 90)
			(size 0.0762 0.0762)
			(layers "F.Cu" "F.Mask" "F.Paste")
			(net "SAS_HDD_RX_P27")
			(options
				(clearance outline)
				(anchor circle)
			)
			(primitives
				(gr_poly
					(pts
						(arc
							(start 0.1524 -0.127)
							(mid 0.137521 -0.162921)
							(end 0.1016 -0.1778)
						)
						(arc
							(start -0.1016 -0.1778)
							(mid -0.137521 -0.162921)
							(end -0.1524 -0.127)
						)
						(arc
							(start -0.1524 0.127)
							(mid -0.137521 0.162921)
							(end -0.1016 0.1778)
						)
						(arc
							(start 0.1016 0.1778)
							(mid 0.137521 0.162921)
							(end 0.1524 0.127)
						)
					)
					(width 0)
					(fill yes)
				)
			)
		)
		(pad "2" smd custom
			(at 0 0.2794 90)
			(size 0.0762 0.0762)
			(layers "F.Cu" "F.Mask" "F.Paste")
			(net "PHY_SCC_A_TO_DRV_A_27_DP")
			(options
				(clearance outline)
				(anchor circle)
			)
			(primitives
				(gr_poly
					(pts
						(arc
							(start 0.1524 -0.127)
							(mid 0.137521 -0.162921)
							(end 0.1016 -0.1778)
						)
						(arc
							(start -0.1016 -0.1778)
							(mid -0.137521 -0.162921)
							(end -0.1524 -0.127)
						)
						(arc
							(start -0.1524 0.127)
							(mid -0.137521 0.162921)
							(end -0.1016 0.1778)
						)
						(arc
							(start 0.1016 0.1778)
							(mid 0.137521 0.162921)
							(end 0.1524 0.127)
						)
					)
					(width 0)
					(fill yes)
				)
			)
		)
	)
	(footprint ""
		(layer "F.Cu")
		(at 395.20495 -42.585894)
		(property "Reference" "R878"
			(at 0 0 0)
			(layer "F.SilkS")
			(hide yes)
			(effects
				(font
					(size 1.27 1.27)
				)
			)
		)
		(property "Value" "4K7R2J-2-GP"
			(at 0.064008 -3.993896 0)
			(unlocked yes)
			(layer "F.Fab")
			(hide yes)
			(effects
				(font
					(size 1.016 1.016)
					(thickness 0.1524)
				)
			)
		)
		(property "Device Type" "R402H16"
			(at 0.064008 -5.517896 0)
			(unlocked yes)
			(layer "F.Fab")
			(hide yes)
			(effects
				(font
					(size 1.016 1.016)
					(thickness 0.1524)
				)
			)
		)
		(duplicate_pad_numbers_are_jumpers no)
		(fp_line
			(start -0.508 -0.9398)
			(end -0.508 0.9398)
			(stroke
				(width 0.1524)
				(type default)
			)
			(layer "F.SilkS")
		)
		(fp_line
			(start 0.508 -0.9398)
			(end -0.508 -0.9398)
			(stroke
				(width 0.1524)
				(type default)
			)
			(layer "F.SilkS")
		)
		(fp_rect
			(start -0.508 0.9398)
			(end 0.508 -0.9398)
			(stroke
				(width 0)
				(type default)
			)
			(fill no)
			(layer "F.CrtYd")
		)
		(fp_rect
			(start -0.508 0.9398)
			(end 0.508 -0.9398)
			(stroke
				(width 0)
				(type default)
			)
			(fill no)
			(layer "F.Fab")
		)
		(pad "1" smd custom
			(at 0 -0.4445)
			(size 0.1397 0.1397)
			(layers "F.Cu" "F.Mask" "F.Paste")
			(net "SW_PWR_R_HDD32")
			(options
				(clearance outline)
				(anchor circle)
			)
			(primitives
				(gr_poly
					(pts
						(arc
							(start -0.1778 -0.2794)
							(mid -0.249642 -0.249642)
							(end -0.2794 -0.1778)
						)
						(arc
							(start -0.2794 0.1778)
							(mid -0.249642 0.249642)
							(end -0.1778 0.2794)
						)
						(arc
							(start 0.1778 0.2794)
							(mid 0.249642 0.249642)
							(end 0.2794 0.1778)
						)
						(arc
							(start 0.2794 -0.1778)
							(mid 0.249642 -0.249642)
							(end 0.1778 -0.2794)
						)
					)
					(width 0)
					(fill yes)
				)
			)
		)
		(pad "2" smd custom
			(at 0 0.4445)
			(size 0.1397 0.1397)
			(layers "F.Cu" "F.Mask" "F.Paste")
			(net "GND")
			(options
				(clearance outline)
				(anchor circle)
			)
			(primitives
				(gr_poly
					(pts
						(arc
							(start -0.1778 -0.2794)
							(mid -0.249642 -0.249642)
							(end -0.2794 -0.1778)
						)
						(arc
							(start -0.2794 0.1778)
							(mid -0.249642 0.249642)
							(end -0.1778 0.2794)
						)
						(arc
							(start 0.1778 0.2794)
							(mid 0.249642 0.249642)
							(end 0.2794 0.1778)
						)
						(arc
							(start 0.2794 -0.1778)
							(mid 0.249642 -0.249642)
							(end 0.1778 -0.2794)
						)
					)
					(width 0)
					(fill yes)
				)
			)
		)
	)
	(footprint ""
		(layer "F.Cu")
		(at 148.548344 -128.697228 -90)
		(property "Reference" "R143"
			(at 0 0 270)
			(layer "F.SilkS")
			(hide yes)
			(effects
				(font
					(size 1.27 1.27)
				)
			)
		)
		(property "Value" "0R5J-5-GP"
			(at 0 -8.9535 270)
			(unlocked yes)
			(layer "F.Fab")
			(hide yes)
			(effects
				(font
					(size 1.27 1.016)
					(thickness 0.1524)
				)
			)
		)
		(property "Device Type" "R805H24"
			(at 0 -10.6299 270)
			(unlocked yes)
			(layer "F.Fab")
			(hide yes)
			(effects
				(font
					(size 1.27 1.016)
					(thickness 0.1524)
				)
			)
		)
		(duplicate_pad_numbers_are_jumpers no)
		(fp_line
			(start -0.889 1.7018)
			(end 0.889 1.7018)
			(stroke
				(width 0.1524)
				(type default)
			)
			(layer "F.SilkS")
		)
		(fp_line
			(start 0.889 1.7018)
			(end 0.889 -0.508)
			(stroke
				(width 0.1524)
				(type default)
			)
			(layer "F.SilkS")
		)
		(fp_line
			(start -0.889 0.0762)
			(end -0.889 1.7018)
			(stroke
				(width 0.1524)
				(type default)
			)
			(layer "F.SilkS")
		)
		(fp_line
			(start -0.889 -1.7018)
			(end -0.889 0.2794)
			(stroke
				(width 0.1524)
				(type default)
			)
			(layer "F.SilkS")
		)
		(fp_line
			(start 0.889 -1.7018)
			(end 0.889 -0.381)
			(stroke
				(width 0.1524)
				(type default)
			)
			(layer "F.SilkS")
		)
		(fp_line
			(start 0.889 -1.7018)
			(end -0.889 -1.7018)
			(stroke
				(width 0.1524)
				(type default)
			)
			(layer "F.SilkS")
		)
		(fp_poly
			(pts
				(xy 0.9652 -1.778) (xy 0.9652 1.778) (xy -0.9652 1.778) (xy -0.9652 -1.778)
			)
			(stroke
				(width 0)
				(type default)
			)
			(fill no)
			(layer "F.CrtYd")
		)
		(fp_rect
			(start -0.9652 1.778)
			(end 0.9652 -1.778)
			(stroke
				(width 0)
				(type default)
			)
			(fill no)
			(layer "F.Fab")
		)
		(pad "1" smd rect
			(at 0 -0.9652 270)
			(size 1.397 1.143)
			(layers "F.Cu" "F.Mask" "F.Paste")
			(net "MB0_CM_GATE_R")
		)
		(pad "2" smd rect
			(at 0 0.9652 270)
			(size 1.397 1.143)
			(layers "F.Cu" "F.Mask" "F.Paste")
			(net "MB0_CM_GATE_C")
		)
	)
	(footprint ""
		(layer "F.Cu")
		(at 350.320102 -61.127894 -90)
		(property "Reference" "C449"
			(at 0 0 270)
			(layer "F.SilkS")
			(hide yes)
			(effects
				(font
					(size 1.27 1.27)
				)
			)
		)
		(property "Value" "SCD01U50V2KX-1GP"
			(at 1.1811 -2.7051 270)
			(unlocked yes)
			(layer "F.Fab")
			(hide yes)
			(effects
				(font
					(size 1.016 1.016)
					(thickness 0.1524)
				)
			)
		)
		(property "Device Type" "C402H22"
			(at 1.1811 -4.2291 270)
			(unlocked yes)
			(layer "F.Fab")
			(hide yes)
			(effects
				(font
					(size 1.016 1.016)
					(thickness 0.1524)
				)
			)
		)
		(duplicate_pad_numbers_are_jumpers no)
		(fp_rect
			(start -0.4318 0.9525)
			(end 0.4318 -0.9525)
			(stroke
				(width 0)
				(type default)
			)
			(fill no)
			(layer "F.CrtYd")
		)
		(fp_rect
			(start -0.4318 0.9525)
			(end 0.4318 -0.9525)
			(stroke
				(width 0)
				(type default)
			)
			(fill no)
			(layer "F.Fab")
		)
		(pad "1" smd custom
			(at 0 -0.4445 270)
			(size 0.1524 0.1524)
			(layers "F.Cu" "F.Mask" "F.Paste")
			(net "HDD_PRSNT_31")
			(options
				(clearance outline)
				(anchor circle)
			)
			(primitives
				(gr_poly
					(pts
						(arc
							(start 0.3048 -0.2032)
							(mid 0.275042 -0.275042)
							(end 0.2032 -0.3048)
						)
						(arc
							(start -0.2032 -0.3048)
							(mid -0.275042 -0.275042)
							(end -0.3048 -0.2032)
						)
						(arc
							(start -0.3048 0.2032)
							(mid -0.275042 0.275042)
							(end -0.2032 0.3048)
						)
						(arc
							(start 0.2032 0.3048)
							(mid 0.275042 0.275042)
							(end 0.3048 0.2032)
						)
					)
					(width 0)
					(fill yes)
				)
			)
		)
		(pad "2" smd custom
			(at 0 0.4445 270)
			(size 0.1524 0.1524)
			(layers "F.Cu" "F.Mask" "F.Paste")
			(net "GND")
			(options
				(clearance outline)
				(anchor circle)
			)
			(primitives
				(gr_poly
					(pts
						(arc
							(start 0.3048 -0.2032)
							(mid 0.275042 -0.275042)
							(end 0.2032 -0.3048)
						)
						(arc
							(start -0.2032 -0.3048)
							(mid -0.275042 -0.275042)
							(end -0.3048 -0.2032)
						)
						(arc
							(start -0.3048 0.2032)
							(mid -0.275042 0.275042)
							(end -0.2032 0.3048)
						)
						(arc
							(start 0.2032 0.3048)
							(mid 0.275042 0.275042)
							(end 0.3048 0.2032)
						)
					)
					(width 0)
					(fill yes)
				)
			)
		)
	)
	(footprint ""
		(layer "F.Cu")
		(at 403.107144 -242.820698 180)
		(property "Reference" "Q272"
			(at 0 0 180)
			(layer "F.SilkS")
			(hide yes)
			(effects
				(font
					(size 1.27 1.27)
				)
			)
		)
		(property "Value" "SSM3K324R-GP"
			(at 0.127 -8.9662 180)
			(unlocked yes)
			(layer "F.Fab")
			(hide yes)
			(effects
				(font
					(size 1.016 1.016)
					(thickness 0.1524)
				)
			)
		)
		(property "Device Type" "SOT23DGS2D4H35"
			(at 0.127 -10.4902 180)
			(unlocked yes)
			(layer "F.Fab")
			(hide yes)
			(effects
				(font
					(size 1.016 1.016)
					(thickness 0.1524)
				)
			)
		)
		(duplicate_pad_numbers_are_jumpers no)
		(fp_line
			(start 1.651 1.778)
			(end 1.651 -1.778)
			(stroke
				(width 0.1524)
				(type default)
			)
			(layer "F.SilkS")
		)
		(fp_line
			(start 1.651 -1.778)
			(end -1.651 -1.778)
			(stroke
				(width 0.1524)
				(type default)
			)
			(layer "F.SilkS")
		)
		(fp_line
			(start -1.651 1.778)
			(end 1.651 1.778)
			(stroke
				(width 0.1524)
				(type default)
			)
			(layer "F.SilkS")
		)
		(fp_line
			(start -1.651 -1.778)
			(end -1.651 1.778)
			(stroke
				(width 0.1524)
				(type default)
			)
			(layer "F.SilkS")
		)
		(fp_poly
			(pts
				(xy -1.778 1.8796) (xy -1.778 -1.8796) (xy 1.778 -1.8796) (xy 1.778 1.8796)
			)
			(stroke
				(width 0)
				(type default)
			)
			(fill no)
			(layer "F.CrtYd")
		)
		(fp_poly
			(pts
				(xy -1.778 1.8796) (xy -1.778 -1.8796) (xy 1.778 -1.8796) (xy 1.778 1.8796)
			)
			(stroke
				(width 0)
				(type default)
			)
			(fill no)
			(layer "F.Fab")
		)
		(pad "D" smd custom
			(at 0 -0.9525 180)
			(size 0.1905 0.1905)
			(layers "F.Cu" "F.Mask" "F.Paste")
			(net "DRV_ACT_9_N")
			(options
				(clearance outline)
				(anchor circle)
			)
			(primitives
				(gr_poly
					(pts
						(arc
							(start -0.1778 0.5715)
							(mid -0.321484 0.511984)
							(end -0.381 0.3683)
						)
						(arc
							(start -0.381 -0.3683)
							(mid -0.321484 -0.511984)
							(end -0.1778 -0.5715)
						)
						(arc
							(start 0.1778 -0.5715)
							(mid 0.321484 -0.511984)
							(end 0.381 -0.3683)
						)
						(arc
							(start 0.381 0.3683)
							(mid 0.321484 0.511984)
							(end 0.1778 0.5715)
						)
					)
					(width 0)
					(fill yes)
				)
			)
		)
		(pad "G" smd custom
			(at -0.98425 0.9525 180)
			(size 0.1905 0.1905)
			(layers "F.Cu" "F.Mask" "F.Paste")
			(net "DRIVE_A_9_ACT")
			(options
				(clearance outline)
				(anchor circle)
			)
			(primitives
				(gr_poly
					(pts
						(arc
							(start -0.1778 0.5715)
							(mid -0.321484 0.511984)
							(end -0.381 0.3683)
						)
						(arc
							(start -0.381 -0.3683)
							(mid -0.321484 -0.511984)
							(end -0.1778 -0.5715)
						)
						(arc
							(start 0.1778 -0.5715)
							(mid 0.321484 -0.511984)
							(end 0.381 -0.3683)
						)
						(arc
							(start 0.381 0.3683)
							(mid 0.321484 0.511984)
							(end 0.1778 0.5715)
						)
					)
					(width 0)
					(fill yes)
				)
			)
		)
		(pad "S" smd custom
			(at 0.98425 0.9525 180)
			(size 0.1905 0.1905)
			(layers "F.Cu" "F.Mask" "F.Paste")
			(net "GND")
			(options
				(clearance outline)
				(anchor circle)
			)
			(primitives
				(gr_poly
					(pts
						(arc
							(start -0.1778 0.5715)
							(mid -0.321484 0.511984)
							(end -0.381 0.3683)
						)
						(arc
							(start -0.381 -0.3683)
							(mid -0.321484 -0.511984)
							(end -0.1778 -0.5715)
						)
						(arc
							(start 0.1778 -0.5715)
							(mid 0.321484 -0.511984)
							(end 0.381 -0.3683)
						)
						(arc
							(start 0.381 0.3683)
							(mid 0.321484 0.511984)
							(end 0.1778 0.5715)
						)
					)
					(width 0)
					(fill yes)
				)
			)
		)
	)
	(footprint ""
		(layer "F.Cu")
		(at 114.725196 -283.736542 90)
		(property "Reference" "C88"
			(at 0 0 90)
			(layer "F.SilkS")
			(hide yes)
			(effects
				(font
					(size 1.27 1.27)
				)
			)
		)
		(property "Value" "SCD033U25V2KX-GP"
			(at 1.1811 -2.7051 90)
			(unlocked yes)
			(layer "F.Fab")
			(hide yes)
			(effects
				(font
					(size 1.016 1.016)
					(thickness 0.1524)
				)
			)
		)
		(property "Device Type" "C402H22"
			(at 1.1811 -4.2291 90)
			(unlocked yes)
			(layer "F.Fab")
			(hide yes)
			(effects
				(font
					(size 1.016 1.016)
					(thickness 0.1524)
				)
			)
		)
		(duplicate_pad_numbers_are_jumpers no)
		(fp_rect
			(start -0.4318 0.9525)
			(end 0.4318 -0.9525)
			(stroke
				(width 0)
				(type default)
			)
			(fill no)
			(layer "F.CrtYd")
		)
		(fp_rect
			(start -0.4318 0.9525)
			(end 0.4318 -0.9525)
			(stroke
				(width 0)
				(type default)
			)
			(fill no)
			(layer "F.Fab")
		)
		(pad "1" smd custom
			(at 0 -0.4445 90)
			(size 0.1524 0.1524)
			(layers "F.Cu" "F.Mask" "F.Paste")
			(net "P12V_A")
			(options
				(clearance outline)
				(anchor circle)
			)
			(primitives
				(gr_poly
					(pts
						(arc
							(start 0.3048 -0.2032)
							(mid 0.275042 -0.275042)
							(end 0.2032 -0.3048)
						)
						(arc
							(start -0.2032 -0.3048)
							(mid -0.275042 -0.275042)
							(end -0.3048 -0.2032)
						)
						(arc
							(start -0.3048 0.2032)
							(mid -0.275042 0.275042)
							(end -0.2032 0.3048)
						)
						(arc
							(start 0.2032 0.3048)
							(mid 0.275042 0.275042)
							(end 0.3048 0.2032)
						)
					)
					(width 0)
					(fill yes)
				)
			)
		)
		(pad "2" smd custom
			(at 0 0.4445 90)
			(size 0.1524 0.1524)
			(layers "F.Cu" "F.Mask" "F.Paste")
			(net "SW_HDD_N3")
			(options
				(clearance outline)
				(anchor circle)
			)
			(primitives
				(gr_poly
					(pts
						(arc
							(start 0.3048 -0.2032)
							(mid 0.275042 -0.275042)
							(end 0.2032 -0.3048)
						)
						(arc
							(start -0.2032 -0.3048)
							(mid -0.275042 -0.275042)
							(end -0.3048 -0.2032)
						)
						(arc
							(start -0.3048 0.2032)
							(mid -0.275042 0.275042)
							(end -0.2032 0.3048)
						)
						(arc
							(start 0.2032 0.3048)
							(mid 0.275042 0.275042)
							(end 0.3048 0.2032)
						)
					)
					(width 0)
					(fill yes)
				)
			)
		)
	)
	(footprint ""
		(layer "F.Cu")
		(at 241.427 -249.174)
		(property "Reference" "R49"
			(at 0 0 0)
			(layer "F.SilkS")
			(hide yes)
			(effects
				(font
					(size 1.27 1.27)
				)
			)
		)
		(property "Value" "4K7R2F-GP"
			(at 0.064008 -3.993896 0)
			(unlocked yes)
			(layer "F.Fab")
			(hide yes)
			(effects
				(font
					(size 1.016 1.016)
					(thickness 0.1524)
				)
			)
		)
		(property "Device Type" "R402H16"
			(at 0.064008 -5.517896 0)
			(unlocked yes)
			(layer "F.Fab")
			(hide yes)
			(effects
				(font
					(size 1.016 1.016)
					(thickness 0.1524)
				)
			)
		)
		(duplicate_pad_numbers_are_jumpers no)
		(fp_line
			(start -0.508 -0.9398)
			(end -0.508 0.9398)
			(stroke
				(width 0.1524)
				(type default)
			)
			(layer "F.SilkS")
		)
		(fp_line
			(start 0.508 -0.9398)
			(end -0.508 -0.9398)
			(stroke
				(width 0.1524)
				(type default)
			)
			(layer "F.SilkS")
		)
		(fp_rect
			(start -0.508 0.9398)
			(end 0.508 -0.9398)
			(stroke
				(width 0)
				(type default)
			)
			(fill no)
			(layer "F.CrtYd")
		)
		(fp_rect
			(start -0.508 0.9398)
			(end 0.508 -0.9398)
			(stroke
				(width 0)
				(type default)
			)
			(fill no)
			(layer "F.Fab")
		)
		(pad "1" smd custom
			(at 0 -0.4445)
			(size 0.1397 0.1397)
			(layers "F.Cu" "F.Mask" "F.Paste")
			(net "IO_EXP5_A1")
			(options
				(clearance outline)
				(anchor circle)
			)
			(primitives
				(gr_poly
					(pts
						(arc
							(start -0.1778 -0.2794)
							(mid -0.249642 -0.249642)
							(end -0.2794 -0.1778)
						)
						(arc
							(start -0.2794 0.1778)
							(mid -0.249642 0.249642)
							(end -0.1778 0.2794)
						)
						(arc
							(start 0.1778 0.2794)
							(mid 0.249642 0.249642)
							(end 0.2794 0.1778)
						)
						(arc
							(start 0.2794 -0.1778)
							(mid 0.249642 -0.249642)
							(end 0.1778 -0.2794)
						)
					)
					(width 0)
					(fill yes)
				)
			)
		)
		(pad "2" smd custom
			(at 0 0.4445)
			(size 0.1397 0.1397)
			(layers "F.Cu" "F.Mask" "F.Paste")
			(net "GND")
			(options
				(clearance outline)
				(anchor circle)
			)
			(primitives
				(gr_poly
					(pts
						(arc
							(start -0.1778 -0.2794)
							(mid -0.249642 -0.249642)
							(end -0.2794 -0.1778)
						)
						(arc
							(start -0.2794 0.1778)
							(mid -0.249642 0.249642)
							(end -0.1778 0.2794)
						)
						(arc
							(start 0.1778 0.2794)
							(mid 0.249642 0.249642)
							(end 0.2794 0.1778)
						)
						(arc
							(start 0.2794 -0.1778)
							(mid 0.249642 -0.249642)
							(end 0.1778 -0.2794)
						)
					)
					(width 0)
					(fill yes)
				)
			)
		)
	)
	(footprint ""
		(layer "F.Cu")
		(at 83.530948 -163.554918 180)
		(property "Reference" "Q85"
			(at 0 0 180)
			(layer "F.SilkS")
			(hide yes)
			(effects
				(font
					(size 1.27 1.27)
				)
			)
		)
		(property "Value" "2N7002KDW-GP"
			(at -2.3622 -8.2042 180)
			(unlocked yes)
			(layer "F.Fab")
			(hide yes)
			(effects
				(font
					(size 1.016 1.016)
					(thickness 0.1524)
				)
			)
		)
		(property "Device Type" "SOT-363H44"
			(at -2.3622 -10.1092 180)
			(unlocked yes)
			(layer "F.Fab")
			(hide yes)
			(effects
				(font
					(size 1.016 1.016)
					(thickness 0.1524)
				)
			)
		)
		(duplicate_pad_numbers_are_jumpers no)
		(fp_line
			(start 1.4478 1.7018)
			(end 1.4478 -1.7018)
			(stroke
				(width 0.1524)
				(type default)
			)
			(layer "F.SilkS")
		)
		(fp_line
			(start 1.4478 -1.7018)
			(end -1.4478 -1.7018)
			(stroke
				(width 0.1524)
				(type default)
			)
			(layer "F.SilkS")
		)
		(fp_line
			(start -1.27 1.524)
			(end -1.27 0.6604)
			(stroke
				(width 0.4826)
				(type default)
			)
			(layer "F.SilkS")
		)
		(fp_line
			(start -1.4478 1.7018)
			(end 1.4478 1.7018)
			(stroke
				(width 0.1524)
				(type default)
			)
			(layer "F.SilkS")
		)
		(fp_line
			(start -1.4478 -1.7018)
			(end -1.4478 1.7018)
			(stroke
				(width 0.1524)
				(type default)
			)
			(layer "F.SilkS")
		)
		(fp_poly
			(pts
				(xy -1.524 -1.778) (xy 1.524 -1.778) (xy 1.524 1.778) (xy -1.524 1.778)
			)
			(stroke
				(width 0)
				(type default)
			)
			(fill no)
			(layer "F.CrtYd")
		)
		(fp_poly
			(pts
				(xy -1.524 -1.778) (xy 1.524 -1.778) (xy 1.524 1.778) (xy -1.524 1.778)
			)
			(stroke
				(width 0)
				(type default)
			)
			(fill no)
			(layer "F.Fab")
		)
		(pad "1" smd rect
			(at -0.65024 0.9398 180)
			(size 0.4064 1.016)
			(layers "F.Cu" "F.Mask" "F.Paste")
			(net "GND")
		)
		(pad "2" smd rect
			(at 0 0.9398 180)
			(size 0.4064 1.016)
			(layers "F.Cu" "F.Mask" "F.Paste")
			(net "SW_PWR_R_HDD14")
		)
		(pad "3" smd rect
			(at 0.65024 0.9398 180)
			(size 0.4064 1.016)
			(layers "F.Cu" "F.Mask" "F.Paste")
			(net "SW_HDD_P14")
		)
		(pad "4" smd rect
			(at 0.65024 -0.9398 180)
			(size 0.4064 1.016)
			(layers "F.Cu" "F.Mask" "F.Paste")
			(net "GND")
		)
		(pad "5" smd rect
			(at 0 -0.9398 180)
			(size 0.4064 1.016)
			(layers "F.Cu" "F.Mask" "F.Paste")
			(net "SW_HDD_G14")
		)
		(pad "6" smd rect
			(at -0.65024 -0.9398 180)
			(size 0.4064 1.016)
			(layers "F.Cu" "F.Mask" "F.Paste")
			(net "SW_HDD_R14")
		)
	)
	(footprint ""
		(layer "F.Cu")
		(at 112.450118 -209.399886)
		(property "Reference" "FLED4"
			(at 0 0 0)
			(layer "F.SilkS")
			(hide yes)
			(effects
				(font
					(size 1.27 1.27)
				)
			)
		)
		(property "Value" "LED-BY-19-GP"
			(at -2.132076 1.414018 0)
			(unlocked yes)
			(layer "F.Fab")
			(hide yes)
			(effects
				(font
					(size 1.016 1.016)
					(thickness 0.1524)
				)
			)
		)
		(property "Device Type" "LED-1615-4PH26"
			(at -2.132076 -0.109982 0)
			(unlocked yes)
			(layer "F.Fab")
			(hide yes)
			(effects
				(font
					(size 1.016 1.016)
					(thickness 0.1524)
				)
			)
		)
		(duplicate_pad_numbers_are_jumpers no)
		(fp_line
			(start -1.2954 0.254)
			(end -1.2954 1.6002)
			(stroke
				(width 0.508)
				(type default)
			)
			(layer "F.SilkS")
		)
		(fp_line
			(start -1.2954 1.6002)
			(end 1.2954 1.6002)
			(stroke
				(width 0.508)
				(type default)
			)
			(layer "F.SilkS")
		)
		(fp_line
			(start -1.1176 -1.4224)
			(end 1.1176 -1.4224)
			(stroke
				(width 0.1524)
				(type default)
			)
			(layer "F.SilkS")
		)
		(fp_line
			(start -1.1176 1.4224)
			(end -1.1176 -1.4224)
			(stroke
				(width 0.1524)
				(type default)
			)
			(layer "F.SilkS")
		)
		(fp_line
			(start 1.1176 -1.4224)
			(end 1.1176 1.4224)
			(stroke
				(width 0.1524)
				(type default)
			)
			(layer "F.SilkS")
		)
		(fp_line
			(start 1.1176 1.4224)
			(end -1.1176 1.4224)
			(stroke
				(width 0.1524)
				(type default)
			)
			(layer "F.SilkS")
		)
		(fp_line
			(start 1.2954 1.6002)
			(end 1.2954 0.254)
			(stroke
				(width 0.508)
				(type default)
			)
			(layer "F.SilkS")
		)
		(fp_rect
			(start -0.7493 0.8001)
			(end 0.7493 -0.8001)
			(stroke
				(width 0)
				(type default)
			)
			(fill no)
			(layer "F.CrtYd")
		)
		(fp_poly
			(pts
				(xy -1.3716 1.6764) (xy -1.3716 -1.6764) (xy 1.3716 -1.6764) (xy 1.3716 0.0635) (xy 0.7493 0.0635)
				(xy 0.7493 -0.8001) (xy -0.7493 -0.8001) (xy -0.7493 0.8001) (xy 0.7493 0.8001) (xy 0.7493 0.0762)
				(xy 1.3716 0.0762) (xy 1.3716 1.6764)
			)
			(stroke
				(width 0)
				(type default)
			)
			(fill no)
			(layer "F.CrtYd")
		)
		(fp_rect
			(start -1.3716 1.6764)
			(end 1.3716 -1.6764)
			(stroke
				(width 0)
				(type default)
			)
			(fill no)
			(layer "F.Fab")
		)
		(pad "1" smd rect
			(at 0.50038 -0.73025)
			(size 0.7112 0.8636)
			(layers "F.Cu" "F.Mask" "F.Paste")
			(net "DRV_ACT_3")
		)
		(pad "2" smd rect
			(at -0.50038 -0.73025)
			(size 0.7112 0.8636)
			(layers "F.Cu" "F.Mask" "F.Paste")
			(net "FLT_HDD3")
		)
		(pad "3" smd rect
			(at 0.50038 0.73025)
			(size 0.7112 0.8636)
			(layers "F.Cu" "F.Mask" "F.Paste")
			(net "DRV_ACT_3_N")
		)
		(pad "4" smd rect
			(at -0.50038 0.73025)
			(size 0.7112 0.8636)
			(layers "F.Cu" "F.Mask" "F.Paste")
			(net "FLT_HDD3_N")
		)
	)
	(footprint ""
		(layer "F.Cu")
		(at 375.16181 -242.799108 180)
		(property "Reference" "Q235"
			(at 0 0 180)
			(layer "F.SilkS")
			(hide yes)
			(effects
				(font
					(size 1.27 1.27)
				)
			)
		)
		(property "Value" "2N7002K-2-GP"
			(at 0.127 -8.9662 180)
			(unlocked yes)
			(layer "F.Fab")
			(hide yes)
			(effects
				(font
					(size 1.016 1.016)
					(thickness 0.1524)
				)
			)
		)
		(property "Device Type" "SOT23DGS2D4H44"
			(at 0.127 -10.4902 180)
			(unlocked yes)
			(layer "F.Fab")
			(hide yes)
			(effects
				(font
					(size 1.016 1.016)
					(thickness 0.1524)
				)
			)
		)
		(duplicate_pad_numbers_are_jumpers no)
		(fp_line
			(start 1.651 1.778)
			(end 1.651 -1.778)
			(stroke
				(width 0.1524)
				(type default)
			)
			(layer "F.SilkS")
		)
		(fp_line
			(start 1.651 -1.778)
			(end -1.651 -1.778)
			(stroke
				(width 0.1524)
				(type default)
			)
			(layer "F.SilkS")
		)
		(fp_line
			(start -1.651 1.778)
			(end 1.651 1.778)
			(stroke
				(width 0.1524)
				(type default)
			)
			(layer "F.SilkS")
		)
		(fp_line
			(start -1.651 -1.778)
			(end -1.651 1.778)
			(stroke
				(width 0.1524)
				(type default)
			)
			(layer "F.SilkS")
		)
		(fp_poly
			(pts
				(xy -1.778 1.8796) (xy -1.778 -1.8796) (xy 1.778 -1.8796) (xy 1.778 1.8796)
			)
			(stroke
				(width 0)
				(type default)
			)
			(fill no)
			(layer "F.CrtYd")
		)
		(fp_poly
			(pts
				(xy -1.778 1.8796) (xy -1.778 -1.8796) (xy 1.778 -1.8796) (xy 1.778 1.8796)
			)
			(stroke
				(width 0)
				(type default)
			)
			(fill no)
			(layer "F.Fab")
		)
		(pad "D" smd custom
			(at 0 -0.9525 180)
			(size 0.1905 0.1905)
			(layers "F.Cu" "F.Mask" "F.Paste")
			(net "FLT_HDD8_N")
			(options
				(clearance outline)
				(anchor circle)
			)
			(primitives
				(gr_poly
					(pts
						(arc
							(start -0.1778 0.5715)
							(mid -0.321484 0.511984)
							(end -0.381 0.3683)
						)
						(arc
							(start -0.381 -0.3683)
							(mid -0.321484 -0.511984)
							(end -0.1778 -0.5715)
						)
						(arc
							(start 0.1778 -0.5715)
							(mid 0.321484 -0.511984)
							(end 0.381 -0.3683)
						)
						(arc
							(start 0.381 0.3683)
							(mid 0.321484 0.511984)
							(end 0.1778 0.5715)
						)
					)
					(width 0)
					(fill yes)
				)
			)
		)
		(pad "G" smd custom
			(at -0.98425 0.9525 180)
			(size 0.1905 0.1905)
			(layers "F.Cu" "F.Mask" "F.Paste")
			(net "DRIVE_A_8_FLT_LED")
			(options
				(clearance outline)
				(anchor circle)
			)
			(primitives
				(gr_poly
					(pts
						(arc
							(start -0.1778 0.5715)
							(mid -0.321484 0.511984)
							(end -0.381 0.3683)
						)
						(arc
							(start -0.381 -0.3683)
							(mid -0.321484 -0.511984)
							(end -0.1778 -0.5715)
						)
						(arc
							(start 0.1778 -0.5715)
							(mid 0.321484 -0.511984)
							(end 0.381 -0.3683)
						)
						(arc
							(start 0.381 0.3683)
							(mid 0.321484 0.511984)
							(end 0.1778 0.5715)
						)
					)
					(width 0)
					(fill yes)
				)
			)
		)
		(pad "S" smd custom
			(at 0.98425 0.9525 180)
			(size 0.1905 0.1905)
			(layers "F.Cu" "F.Mask" "F.Paste")
			(net "GND")
			(options
				(clearance outline)
				(anchor circle)
			)
			(primitives
				(gr_poly
					(pts
						(arc
							(start -0.1778 0.5715)
							(mid -0.321484 0.511984)
							(end -0.381 0.3683)
						)
						(arc
							(start -0.381 -0.3683)
							(mid -0.321484 -0.511984)
							(end -0.1778 -0.5715)
						)
						(arc
							(start 0.1778 -0.5715)
							(mid 0.321484 -0.511984)
							(end 0.381 -0.3683)
						)
						(arc
							(start 0.381 0.3683)
							(mid 0.321484 0.511984)
							(end 0.1778 0.5715)
						)
					)
					(width 0)
					(fill yes)
				)
			)
		)
	)
	(footprint ""
		(layer "F.Cu")
		(at 420.200074 -172.909992 -90)
		(property "Reference" "HDDSAS21"
			(at 0 0 270)
			(layer "F.SilkS")
			(hide yes)
			(effects
				(font
					(size 1.27 1.27)
				)
			)
		)
		(property "Value" "SKT-SAS15P-14P-45-GP"
			(at -20.7645 -8.9789 270)
			(unlocked yes)
			(layer "F.Fab")
			(hide yes)
			(effects
				(font
					(size 1.016 1.016)
					(thickness 0.1524)
				)
			)
		)
		(property "Device Type" "10120818-001C-TRLF"
			(at -20.7645 -10.5029 270)
			(unlocked yes)
			(layer "F.Fab")
			(hide yes)
			(effects
				(font
					(size 1.016 1.016)
					(thickness 0.1524)
				)
			)
		)
		(duplicate_pad_numbers_are_jumpers no)
		(fp_line
			(start 1.651 4.2926)
			(end 1.651 3.0099)
			(stroke
				(width 0.1524)
				(type default)
			)
			(layer "F.SilkS")
		)
		(fp_line
			(start 8.509 4.2926)
			(end 1.651 4.2926)
			(stroke
				(width 0.1524)
				(type default)
			)
			(layer "F.SilkS")
		)
		(fp_line
			(start -23.4188 3.0099)
			(end -23.4188 -3.2512)
			(stroke
				(width 0.1524)
				(type default)
			)
			(layer "F.SilkS")
		)
		(fp_line
			(start 1.651 3.0099)
			(end -23.4188 3.0099)
			(stroke
				(width 0.1524)
				(type default)
			)
			(layer "F.SilkS")
		)
		(fp_line
			(start 8.509 3.0099)
			(end 8.509 4.2926)
			(stroke
				(width 0.1524)
				(type default)
			)
			(layer "F.SilkS")
		)
		(fp_line
			(start 23.4188 3.0099)
			(end 8.509 3.0099)
			(stroke
				(width 0.1524)
				(type default)
			)
			(layer "F.SilkS")
		)
		(fp_line
			(start -23.4188 -3.2512)
			(end 23.4188 -3.2512)
			(stroke
				(width 0.1524)
				(type default)
			)
			(layer "F.SilkS")
		)
		(fp_line
			(start 23.4188 -3.2512)
			(end 23.4188 3.0099)
			(stroke
				(width 0.1524)
				(type default)
			)
			(layer "F.SilkS")
		)
		(fp_line
			(start 15.5067 -3.3401)
			(end 16.2687 -3.3401)
			(stroke
				(width 0.3302)
				(type default)
			)
			(layer "F.SilkS")
		)
		(fp_poly
			(pts
				(xy 15.868904 -3.230372) (xy 16.503904 -3.865372) (xy 15.233904 -3.865372)
			)
			(stroke
				(width 0)
				(type default)
			)
			(fill yes)
			(layer "F.SilkS")
		)
		(fp_poly
			(pts
				(xy -22.8727 -2.7559) (xy 22.8727 -2.7559) (xy 22.8727 2.7559) (xy 8.255 2.7559) (xy 8.255 3.5179)
				(xy 1.905 3.5179) (xy 1.905 2.7559) (xy -22.8727 2.7559)
			)
			(stroke
				(width 0)
				(type default)
			)
			(fill no)
			(layer "F.CrtYd")
		)
		(fp_poly
			(pts
				(xy 1.397 4.5466) (xy 1.397 3.2639) (xy -23.6728 3.2639) (xy -23.6728 -3.5052) (xy 23.6728 -3.5052)
				(xy 23.6728 -0.00635) (xy 22.8727 -0.00635) (xy 22.8727 -2.7559) (xy -22.8727 -2.7559) (xy -22.8727 2.7559)
				(xy 1.905 2.7559) (xy 1.905 3.5179) (xy 8.255 3.5179) (xy 8.255 2.7559) (xy 22.8727 2.7559) (xy 22.8727 0.00635)
				(xy 23.6728 0.00635) (xy 23.6728 3.2639) (xy 8.763 3.2639) (xy 8.763 4.5466)
			)
			(stroke
				(width 0)
				(type default)
			)
			(fill no)
			(layer "F.CrtYd")
		)
		(fp_poly
			(pts
				(xy 1.397 4.5466) (xy 1.397 3.2639) (xy -23.6728 3.2639) (xy -23.6728 -3.5052) (xy 23.6728 -3.5052)
				(xy 23.6728 3.2639) (xy 8.763 3.2639) (xy 8.763 4.5466)
			)
			(stroke
				(width 0)
				(type default)
			)
			(fill no)
			(layer "F.Fab")
		)
		(pad "" np_thru_hole circle
			(at -18.874994 0 270)
			(size 0.254 0.254)
			(drill 1.3462)
			(layers "*.Cu" "*.Mask")
			(clearance 0.9017)
			(thermal_gap 0.9017)
		)
		(pad "" np_thru_hole circle
			(at 18.874994 0 270)
			(size 0.254 0.254)
			(drill 0.9398)
			(layers "*.Cu" "*.Mask")
			(clearance 0.6985)
			(thermal_gap 0.6985)
		)
		(pad "G1" smd rect
			(at 21.874988 0 270)
			(size 2.5908 2.5908)
			(layers "F.Cu" "F.Mask" "F.Paste")
			(net "GND")
		)
		(pad "G2" smd rect
			(at -21.874988 0 270)
			(size 2.5908 2.5908)
			(layers "F.Cu" "F.Mask" "F.Paste")
			(net "GND")
		)
		(pad "P1" smd rect
			(at 1.905 -1.82499 270)
			(size 0.6096 2.3622)
			(layers "F.Cu" "F.Mask" "F.Paste")
			(net "Net_2106")
		)
		(pad "P2" smd rect
			(at 0.635 -1.82499 270)
			(size 0.6096 2.3622)
			(layers "F.Cu" "F.Mask" "F.Paste")
			(net "Net_2107")
		)
		(pad "P3" smd rect
			(at -0.635 -1.82499 270)
			(size 0.6096 2.3622)
			(layers "F.Cu" "F.Mask" "F.Paste")
			(net "Net_2108")
		)
		(pad "P4" smd rect
			(at -1.905 -1.82499 270)
			(size 0.6096 2.3622)
			(layers "F.Cu" "F.Mask" "F.Paste")
			(net "GND")
		)
		(pad "P5" smd rect
			(at -3.175 -1.82499 270)
			(size 0.6096 2.3622)
			(layers "F.Cu" "F.Mask" "F.Paste")
			(net "HDD_PRSNT_21")
		)
		(pad "P6" smd rect
			(at -4.445 -1.82499 270)
			(size 0.6096 2.3622)
			(layers "F.Cu" "F.Mask" "F.Paste")
			(net "GND")
		)
		(pad "P7" smd rect
			(at -5.715 -1.82499 270)
			(size 0.6096 2.3622)
			(layers "F.Cu" "F.Mask" "F.Paste")
			(net "5V_PRE_21")
		)
		(pad "P8" smd rect
			(at -6.985 -1.82499 270)
			(size 0.6096 2.3622)
			(layers "F.Cu" "F.Mask" "F.Paste")
			(net "P5V_HDD21")
		)
		(pad "P9" smd rect
			(at -8.255 -1.82499 270)
			(size 0.6096 2.3622)
			(layers "F.Cu" "F.Mask" "F.Paste")
			(net "P5V_HDD21")
		)
		(pad "P10" smd rect
			(at -9.525 -1.82499 270)
			(size 0.6096 2.3622)
			(layers "F.Cu" "F.Mask" "F.Paste")
			(net "GND")
		)
		(pad "P11" smd rect
			(at -10.795 -1.82499 270)
			(size 0.6096 2.3622)
			(layers "F.Cu" "F.Mask" "F.Paste")
			(net "ACT_HDD_21")
		)
		(pad "P12" smd rect
			(at -12.065 -1.82499 270)
			(size 0.6096 2.3622)
			(layers "F.Cu" "F.Mask" "F.Paste")
			(net "GND")
		)
		(pad "P13" smd rect
			(at -13.335 -1.82499 270)
			(size 0.6096 2.3622)
			(layers "F.Cu" "F.Mask" "F.Paste")
			(net "12V_PRE_21")
		)
		(pad "P14" smd rect
			(at -14.605 -1.82499 270)
			(size 0.6096 2.3622)
			(layers "F.Cu" "F.Mask" "F.Paste")
			(net "P12V_HDD21")
		)
		(pad "P15" smd rect
			(at -15.875 -1.82499 270)
			(size 0.6096 2.3622)
			(layers "F.Cu" "F.Mask" "F.Paste")
			(net "P12V_HDD21")
		)
		(pad "S1" smd rect
			(at 15.875 -1.82499 270)
			(size 0.6096 2.3622)
			(layers "F.Cu" "F.Mask" "F.Paste")
			(net "GND")
		)
		(pad "S2" smd rect
			(at 14.605 -1.82499 270)
			(size 0.6096 2.3622)
			(layers "F.Cu" "F.Mask" "F.Paste")
			(net "SAS_HDD_RX_P21")
		)
		(pad "S3" smd rect
			(at 13.335 -1.82499 270)
			(size 0.6096 2.3622)
			(layers "F.Cu" "F.Mask" "F.Paste")
			(net "SAS_HDD_RX_N21")
		)
		(pad "S4" smd rect
			(at 12.065 -1.82499 270)
			(size 0.6096 2.3622)
			(layers "F.Cu" "F.Mask" "F.Paste")
			(net "GND")
		)
		(pad "S5" smd rect
			(at 10.795 -1.82499 270)
			(size 0.6096 2.3622)
			(layers "F.Cu" "F.Mask" "F.Paste")
			(net "PHY_DRV_A_TO_SCC_A_21_DN")
		)
		(pad "S6" smd rect
			(at 9.525 -1.82499 270)
			(size 0.6096 2.3622)
			(layers "F.Cu" "F.Mask" "F.Paste")
			(net "PHY_DRV_A_TO_SCC_A_21_DP")
		)
		(pad "S7" smd rect
			(at 8.255 -1.82499 270)
			(size 0.6096 2.3622)
			(layers "F.Cu" "F.Mask" "F.Paste")
			(net "GND")
		)
		(pad "S8" smd rect
			(at 7.480046 2.845054 270)
			(size 0.508 2.3622)
			(layers "F.Cu" "F.Mask" "F.Paste")
			(net "GND")
		)
		(pad "S9" smd rect
			(at 6.679946 2.845054 270)
			(size 0.508 2.3622)
			(layers "F.Cu" "F.Mask" "F.Paste")
			(net "Net_459")
		)
		(pad "S10" smd rect
			(at 5.8801 2.845054 270)
			(size 0.508 2.3622)
			(layers "F.Cu" "F.Mask" "F.Paste")
			(net "Net_351")
		)
		(pad "S11" smd rect
			(at 5.08 2.845054 270)
			(size 0.508 2.3622)
			(layers "F.Cu" "F.Mask" "F.Paste")
			(net "GND")
		)
		(pad "S12" smd rect
			(at 4.2799 2.845054 270)
			(size 0.508 2.3622)
			(layers "F.Cu" "F.Mask" "F.Paste")
			(net "Net_387")
		)
		(pad "S13" smd rect
			(at 3.480054 2.845054 270)
			(size 0.508 2.3622)
			(layers "F.Cu" "F.Mask" "F.Paste")
			(net "Net_423")
		)
		(pad "S14" smd rect
			(at 2.679954 2.845054 270)
			(size 0.508 2.3622)
			(layers "F.Cu" "F.Mask" "F.Paste")
			(net "GND")
		)
		(zone
			(layer "F.Cu")
			(hatch none 0.5)
			(connect_pads
				(clearance 0)
			)
			(min_thickness 0.25)
			(keepout
				(tracks allowed)
				(vias not_allowed)
				(pads allowed)
				(copperpour not_allowed)
				(footprints allowed)
			)
			(placement
				(enabled no)
				(sheetname "")
			)
			(fill
				(thermal_gap 0.5)
				(thermal_bridge_width 0.5)
				(island_removal_mode 0)
			)
			(polygon
				(pts
					(xy 423.857674 -189.648592) (xy 416.783774 -189.648592) (xy 416.783774 -196.582792) (xy 417.888674 -196.582792)
					(xy 417.888674 -192.467992) (xy 422.511474 -192.467992) (xy 422.511474 -196.582792) (xy 423.857674 -196.582792)
				)
			)
		)
		(zone
			(layer "F.Cu")
			(hatch none 0.5)
			(connect_pads
				(clearance 0)
			)
			(min_thickness 0.25)
			(keepout
				(tracks not_allowed)
				(vias allowed)
				(pads allowed)
				(copperpour not_allowed)
				(footprints allowed)
			)
			(placement
				(enabled no)
				(sheetname "")
			)
			(fill
				(thermal_gap 0.5)
				(thermal_bridge_width 0.5)
				(island_removal_mode 0)
			)
			(polygon
				(pts
					(xy 423.857674 -189.648592) (xy 416.783774 -189.648592) (xy 416.783774 -196.582792) (xy 417.888674 -196.582792)
					(xy 417.888674 -192.467992) (xy 422.511474 -192.467992) (xy 422.511474 -196.582792) (xy 423.857674 -196.582792)
				)
			)
		)
		(zone
			(layer "F.Cu")
			(hatch none 0.5)
			(connect_pads
				(clearance 0)
			)
			(min_thickness 0.25)
			(keepout
				(tracks allowed)
				(vias not_allowed)
				(pads allowed)
				(copperpour not_allowed)
				(footprints allowed)
			)
			(placement
				(enabled no)
				(sheetname "")
			)
			(fill
				(thermal_gap 0.5)
				(thermal_bridge_width 0.5)
				(island_removal_mode 0)
			)
			(polygon
				(pts
					(xy 423.857674 -156.171392) (xy 416.783774 -156.171392) (xy 416.783774 -149.237192) (xy 417.888674 -149.237192)
					(xy 417.888674 -153.351992) (xy 422.511474 -153.351992) (xy 422.511474 -149.237192) (xy 423.857674 -149.237192)
				)
			)
		)
		(zone
			(layer "F.Cu")
			(hatch none 0.5)
			(connect_pads
				(clearance 0)
			)
			(min_thickness 0.25)
			(keepout
				(tracks not_allowed)
				(vias allowed)
				(pads allowed)
				(copperpour not_allowed)
				(footprints allowed)
			)
			(placement
				(enabled no)
				(sheetname "")
			)
			(fill
				(thermal_gap 0.5)
				(thermal_bridge_width 0.5)
				(island_removal_mode 0)
			)
			(polygon
				(pts
					(xy 423.857674 -156.171392) (xy 416.783774 -156.171392) (xy 416.783774 -149.237192) (xy 417.888674 -149.237192)
					(xy 417.888674 -153.351992) (xy 422.511474 -153.351992) (xy 422.511474 -149.237192) (xy 423.857674 -149.237192)
				)
			)
		)
		(zone
			(layers "F.Cu" "B.Cu" "In1.Cu" "In2.Cu" "In3.Cu" "In4.Cu" "In5.Cu" "In6.Cu"
				"In7.Cu" "In8.Cu" "In9.Cu" "In10.Cu"
			)
			(hatch none 0.5)
			(connect_pads
				(clearance 0)
			)
			(min_thickness 0.25)
			(keepout
				(tracks not_allowed)
				(vias allowed)
				(pads allowed)
				(copperpour not_allowed)
				(footprints allowed)
			)
			(placement
				(enabled no)
				(sheetname "")
			)
			(fill
				(thermal_gap 0.5)
				(thermal_bridge_width 0.5)
				(island_removal_mode 0)
			)
			(polygon
				(pts
					(arc
						(start 420.974774 -154.034998)
						(mid 419.425374 -154.034998)
						(end 420.974774 -154.034998)
					)
				)
			)
		)
		(zone
			(layers "F.Cu" "B.Cu" "In1.Cu" "In2.Cu" "In3.Cu" "In4.Cu" "In5.Cu" "In6.Cu"
				"In7.Cu" "In8.Cu" "In9.Cu" "In10.Cu"
			)
			(hatch none 0.5)
			(connect_pads
				(clearance 0)
			)
			(min_thickness 0.25)
			(keepout
				(tracks not_allowed)
				(vias allowed)
				(pads allowed)
				(copperpour not_allowed)
				(footprints allowed)
			)
			(placement
				(enabled no)
				(sheetname "")
			)
			(fill
				(thermal_gap 0.5)
				(thermal_bridge_width 0.5)
				(island_removal_mode 0)
			)
			(polygon
				(pts
					(arc
						(start 421.177974 -191.784986)
						(mid 419.222174 -191.784986)
						(end 421.177974 -191.784986)
					)
				)
			)
		)
	)
	(footprint ""
		(layer "F.Cu")
		(at 117.646196 -44.821094 -90)
		(property "Reference" "R761"
			(at 0 0 270)
			(layer "F.SilkS")
			(hide yes)
			(effects
				(font
					(size 1.27 1.27)
				)
			)
		)
		(property "Value" "0R2J-2-GP"
			(at 0.064008 -3.993896 270)
			(unlocked yes)
			(layer "F.Fab")
			(hide yes)
			(effects
				(font
					(size 1.016 1.016)
					(thickness 0.1524)
				)
			)
		)
		(property "Device Type" "R402H16"
			(at 0.064008 -5.517896 270)
			(unlocked yes)
			(layer "F.Fab")
			(hide yes)
			(effects
				(font
					(size 1.016 1.016)
					(thickness 0.1524)
				)
			)
		)
		(duplicate_pad_numbers_are_jumpers no)
		(fp_line
			(start -0.508 -0.9398)
			(end -0.508 0.9398)
			(stroke
				(width 0.1524)
				(type default)
			)
			(layer "F.SilkS")
		)
		(fp_line
			(start 0.508 -0.9398)
			(end -0.508 -0.9398)
			(stroke
				(width 0.1524)
				(type default)
			)
			(layer "F.SilkS")
		)
		(fp_rect
			(start -0.508 0.9398)
			(end 0.508 -0.9398)
			(stroke
				(width 0)
				(type default)
			)
			(fill no)
			(layer "F.CrtYd")
		)
		(fp_rect
			(start -0.508 0.9398)
			(end 0.508 -0.9398)
			(stroke
				(width 0)
				(type default)
			)
			(fill no)
			(layer "F.Fab")
		)
		(pad "1" smd custom
			(at 0 -0.4445 270)
			(size 0.1397 0.1397)
			(layers "F.Cu" "F.Mask" "F.Paste")
			(net "DRIVE_A_27_PWR")
			(options
				(clearance outline)
				(anchor circle)
			)
			(primitives
				(gr_poly
					(pts
						(arc
							(start -0.1778 -0.2794)
							(mid -0.249642 -0.249642)
							(end -0.2794 -0.1778)
						)
						(arc
							(start -0.2794 0.1778)
							(mid -0.249642 0.249642)
							(end -0.1778 0.2794)
						)
						(arc
							(start 0.1778 0.2794)
							(mid 0.249642 0.249642)
							(end 0.2794 0.1778)
						)
						(arc
							(start 0.2794 -0.1778)
							(mid 0.249642 -0.249642)
							(end 0.1778 -0.2794)
						)
					)
					(width 0)
					(fill yes)
				)
			)
		)
		(pad "2" smd custom
			(at 0 0.4445 270)
			(size 0.1397 0.1397)
			(layers "F.Cu" "F.Mask" "F.Paste")
			(net "SW_PWR_R_HDD27")
			(options
				(clearance outline)
				(anchor circle)
			)
			(primitives
				(gr_poly
					(pts
						(arc
							(start -0.1778 -0.2794)
							(mid -0.249642 -0.249642)
							(end -0.2794 -0.1778)
						)
						(arc
							(start -0.2794 0.1778)
							(mid -0.249642 0.249642)
							(end -0.1778 0.2794)
						)
						(arc
							(start 0.1778 0.2794)
							(mid 0.249642 0.249642)
							(end 0.2794 0.1778)
						)
						(arc
							(start 0.2794 -0.1778)
							(mid 0.249642 -0.249642)
							(end 0.1778 -0.2794)
						)
					)
					(width 0)
					(fill yes)
				)
			)
		)
	)
	(footprint ""
		(layer "F.Cu")
		(at 243.713 -249.174)
		(property "Reference" "R50"
			(at 0 0 0)
			(layer "F.SilkS")
			(hide yes)
			(effects
				(font
					(size 1.27 1.27)
				)
			)
		)
		(property "Value" "4K7R2F-GP"
			(at 0.064008 -3.993896 0)
			(unlocked yes)
			(layer "F.Fab")
			(hide yes)
			(effects
				(font
					(size 1.016 1.016)
					(thickness 0.1524)
				)
			)
		)
		(property "Device Type" "R402H16"
			(at 0.064008 -5.517896 0)
			(unlocked yes)
			(layer "F.Fab")
			(hide yes)
			(effects
				(font
					(size 1.016 1.016)
					(thickness 0.1524)
				)
			)
		)
		(duplicate_pad_numbers_are_jumpers no)
		(fp_line
			(start -0.508 -0.9398)
			(end -0.508 0.9398)
			(stroke
				(width 0.1524)
				(type default)
			)
			(layer "F.SilkS")
		)
		(fp_line
			(start 0.508 -0.9398)
			(end -0.508 -0.9398)
			(stroke
				(width 0.1524)
				(type default)
			)
			(layer "F.SilkS")
		)
		(fp_rect
			(start -0.508 0.9398)
			(end 0.508 -0.9398)
			(stroke
				(width 0)
				(type default)
			)
			(fill no)
			(layer "F.CrtYd")
		)
		(fp_rect
			(start -0.508 0.9398)
			(end 0.508 -0.9398)
			(stroke
				(width 0)
				(type default)
			)
			(fill no)
			(layer "F.Fab")
		)
		(pad "1" smd custom
			(at 0 -0.4445)
			(size 0.1397 0.1397)
			(layers "F.Cu" "F.Mask" "F.Paste")
			(net "IO_EXP5_A2")
			(options
				(clearance outline)
				(anchor circle)
			)
			(primitives
				(gr_poly
					(pts
						(arc
							(start -0.1778 -0.2794)
							(mid -0.249642 -0.249642)
							(end -0.2794 -0.1778)
						)
						(arc
							(start -0.2794 0.1778)
							(mid -0.249642 0.249642)
							(end -0.1778 0.2794)
						)
						(arc
							(start 0.1778 0.2794)
							(mid 0.249642 0.249642)
							(end 0.2794 0.1778)
						)
						(arc
							(start 0.2794 -0.1778)
							(mid 0.249642 -0.249642)
							(end 0.1778 -0.2794)
						)
					)
					(width 0)
					(fill yes)
				)
			)
		)
		(pad "2" smd custom
			(at 0 0.4445)
			(size 0.1397 0.1397)
			(layers "F.Cu" "F.Mask" "F.Paste")
			(net "GND")
			(options
				(clearance outline)
				(anchor circle)
			)
			(primitives
				(gr_poly
					(pts
						(arc
							(start -0.1778 -0.2794)
							(mid -0.249642 -0.249642)
							(end -0.2794 -0.1778)
						)
						(arc
							(start -0.2794 0.1778)
							(mid -0.249642 0.249642)
							(end -0.1778 0.2794)
						)
						(arc
							(start 0.1778 0.2794)
							(mid 0.249642 0.249642)
							(end 0.2794 0.1778)
						)
						(arc
							(start 0.2794 -0.1778)
							(mid 0.249642 -0.249642)
							(end 0.1778 -0.2794)
						)
					)
					(width 0)
					(fill yes)
				)
			)
		)
	)
	(footprint ""
		(layer "F.Cu")
		(at 271.759172 -238.924846 180)
		(property "Reference" "R443"
			(at 0 0 180)
			(layer "F.SilkS")
			(hide yes)
			(effects
				(font
					(size 1.27 1.27)
				)
			)
		)
		(property "Value" "1KR2F-3-GP"
			(at 0.064008 -3.993896 180)
			(unlocked yes)
			(layer "F.Fab")
			(hide yes)
			(effects
				(font
					(size 1.016 1.016)
					(thickness 0.1524)
				)
			)
		)
		(property "Device Type" "R402H16"
			(at 0.064008 -5.517896 180)
			(unlocked yes)
			(layer "F.Fab")
			(hide yes)
			(effects
				(font
					(size 1.016 1.016)
					(thickness 0.1524)
				)
			)
		)
		(duplicate_pad_numbers_are_jumpers no)
		(fp_line
			(start 0.508 -0.9398)
			(end -0.508 -0.9398)
			(stroke
				(width 0.1524)
				(type default)
			)
			(layer "F.SilkS")
		)
		(fp_line
			(start -0.508 -0.9398)
			(end -0.508 0.9398)
			(stroke
				(width 0.1524)
				(type default)
			)
			(layer "F.SilkS")
		)
		(fp_rect
			(start -0.508 0.9398)
			(end 0.508 -0.9398)
			(stroke
				(width 0)
				(type default)
			)
			(fill no)
			(layer "F.CrtYd")
		)
		(fp_rect
			(start -0.508 0.9398)
			(end 0.508 -0.9398)
			(stroke
				(width 0)
				(type default)
			)
			(fill no)
			(layer "F.Fab")
		)
		(pad "1" smd custom
			(at 0 -0.4445 180)
			(size 0.1397 0.1397)
			(layers "F.Cu" "F.Mask" "F.Paste")
			(net "P3V3_STBY_A")
			(options
				(clearance outline)
				(anchor circle)
			)
			(primitives
				(gr_poly
					(pts
						(arc
							(start -0.1778 -0.2794)
							(mid -0.249642 -0.249642)
							(end -0.2794 -0.1778)
						)
						(arc
							(start -0.2794 0.1778)
							(mid -0.249642 0.249642)
							(end -0.1778 0.2794)
						)
						(arc
							(start 0.1778 0.2794)
							(mid 0.249642 0.249642)
							(end 0.2794 0.1778)
						)
						(arc
							(start 0.2794 -0.1778)
							(mid 0.249642 -0.249642)
							(end 0.1778 -0.2794)
						)
					)
					(width 0)
					(fill yes)
				)
			)
		)
		(pad "2" smd custom
			(at 0 0.4445 180)
			(size 0.1397 0.1397)
			(layers "F.Cu" "F.Mask" "F.Paste")
			(net "I2C_BMC_A_EXP_A_SCL")
			(options
				(clearance outline)
				(anchor circle)
			)
			(primitives
				(gr_poly
					(pts
						(arc
							(start -0.1778 -0.2794)
							(mid -0.249642 -0.249642)
							(end -0.2794 -0.1778)
						)
						(arc
							(start -0.2794 0.1778)
							(mid -0.249642 0.249642)
							(end -0.1778 0.2794)
						)
						(arc
							(start 0.1778 0.2794)
							(mid 0.249642 0.249642)
							(end 0.2794 0.1778)
						)
						(arc
							(start 0.2794 -0.1778)
							(mid 0.249642 -0.249642)
							(end 0.1778 -0.2794)
						)
					)
					(width 0)
					(fill yes)
				)
			)
		)
	)
	(footprint ""
		(layer "F.Cu")
		(at 149.345396 -131.49453)
		(property "Reference" "R1069"
			(at 0 0 0)
			(layer "F.SilkS")
			(hide yes)
			(effects
				(font
					(size 1.27 1.27)
				)
			)
		)
		(property "Value" "0R5J-5-GP"
			(at 0 -8.9535 0)
			(unlocked yes)
			(layer "F.Fab")
			(hide yes)
			(effects
				(font
					(size 1.27 1.016)
					(thickness 0.1524)
				)
			)
		)
		(property "Device Type" "R805H24"
			(at 0 -10.6299 0)
			(unlocked yes)
			(layer "F.Fab")
			(hide yes)
			(effects
				(font
					(size 1.27 1.016)
					(thickness 0.1524)
				)
			)
		)
		(duplicate_pad_numbers_are_jumpers no)
		(fp_line
			(start -0.889 -1.7018)
			(end -0.889 0.2794)
			(stroke
				(width 0.1524)
				(type default)
			)
			(layer "F.SilkS")
		)
		(fp_line
			(start -0.889 0.0762)
			(end -0.889 1.7018)
			(stroke
				(width 0.1524)
				(type default)
			)
			(layer "F.SilkS")
		)
		(fp_line
			(start -0.889 1.7018)
			(end 0.889 1.7018)
			(stroke
				(width 0.1524)
				(type default)
			)
			(layer "F.SilkS")
		)
		(fp_line
			(start 0.889 -1.7018)
			(end -0.889 -1.7018)
			(stroke
				(width 0.1524)
				(type default)
			)
			(layer "F.SilkS")
		)
		(fp_line
			(start 0.889 -1.7018)
			(end 0.889 -0.381)
			(stroke
				(width 0.1524)
				(type default)
			)
			(layer "F.SilkS")
		)
		(fp_line
			(start 0.889 1.7018)
			(end 0.889 -0.508)
			(stroke
				(width 0.1524)
				(type default)
			)
			(layer "F.SilkS")
		)
		(fp_poly
			(pts
				(xy 0.9652 -1.778) (xy 0.9652 1.778) (xy -0.9652 1.778) (xy -0.9652 -1.778)
			)
			(stroke
				(width 0)
				(type default)
			)
			(fill no)
			(layer "F.CrtYd")
		)
		(fp_rect
			(start -0.9652 1.778)
			(end 0.9652 -1.778)
			(stroke
				(width 0)
				(type default)
			)
			(fill no)
			(layer "F.Fab")
		)
		(pad "1" smd rect
			(at 0 -0.9652)
			(size 1.397 1.143)
			(layers "F.Cu" "F.Mask" "F.Paste")
			(net "MB0_CM_GATE")
		)
		(pad "2" smd rect
			(at 0 0.9652)
			(size 1.397 1.143)
			(layers "F.Cu" "F.Mask" "F.Paste")
			(net "MB0_CM_GATE_R")
		)
	)
	(footprint ""
		(layer "F.Cu")
		(at 181.991 -304.462942 180)
		(property "Reference" "C112"
			(at 0 0 180)
			(layer "F.SilkS")
			(hide yes)
			(effects
				(font
					(size 1.27 1.27)
				)
			)
		)
		(property "Value" "SC1U25V3KX-GP"
			(at 0 -2.8194 180)
			(unlocked yes)
			(layer "F.Fab")
			(hide yes)
			(effects
				(font
					(size 1.016 1.016)
					(thickness 0.1524)
				)
			)
		)
		(property "Device Type" "C603H36"
			(at 0 -4.3434 180)
			(unlocked yes)
			(layer "F.Fab")
			(hide yes)
			(effects
				(font
					(size 1.016 1.016)
					(thickness 0.1524)
				)
			)
		)
		(duplicate_pad_numbers_are_jumpers no)
		(fp_line
			(start 0.508 0)
			(end -0.508 0)
			(stroke
				(width 0.2032)
				(type default)
			)
			(layer "F.SilkS")
		)
		(fp_rect
			(start -0.5842 1.3335)
			(end 0.5842 -1.3335)
			(stroke
				(width 0)
				(type default)
			)
			(fill no)
			(layer "F.CrtYd")
		)
		(fp_rect
			(start -0.5842 1.3335)
			(end 0.5842 -1.3335)
			(stroke
				(width 0)
				(type default)
			)
			(fill no)
			(layer "F.Fab")
		)
		(pad "1" smd custom
			(at 0 -0.762 180)
			(size 0.2159 0.2159)
			(layers "F.Cu" "F.Mask" "F.Paste")
			(net "P12V_HDD5")
			(options
				(clearance outline)
				(anchor circle)
			)
			(primitives
				(gr_poly
					(pts
						(arc
							(start -0.3302 -0.4318)
							(mid -0.402042 -0.402042)
							(end -0.4318 -0.3302)
						)
						(arc
							(start -0.4318 0.3302)
							(mid -0.402042 0.402042)
							(end -0.3302 0.4318)
						)
						(arc
							(start 0.3302 0.4318)
							(mid 0.402042 0.402042)
							(end 0.4318 0.3302)
						)
						(arc
							(start 0.4318 -0.3302)
							(mid 0.402042 -0.402042)
							(end 0.3302 -0.4318)
						)
					)
					(width 0)
					(fill yes)
				)
			)
		)
		(pad "2" smd custom
			(at 0 0.762 180)
			(size 0.2159 0.2159)
			(layers "F.Cu" "F.Mask" "F.Paste")
			(net "GND")
			(options
				(clearance outline)
				(anchor circle)
			)
			(primitives
				(gr_poly
					(pts
						(arc
							(start -0.3302 -0.4318)
							(mid -0.402042 -0.402042)
							(end -0.4318 -0.3302)
						)
						(arc
							(start -0.4318 0.3302)
							(mid -0.402042 0.402042)
							(end -0.3302 0.4318)
						)
						(arc
							(start 0.3302 0.4318)
							(mid 0.402042 0.402042)
							(end 0.4318 0.3302)
						)
						(arc
							(start 0.4318 -0.3302)
							(mid 0.402042 -0.402042)
							(end 0.3302 -0.4318)
						)
					)
					(width 0)
					(fill yes)
				)
			)
		)
	)
	(footprint ""
		(layer "F.Cu")
		(at 430.438052 -42.585894 180)
		(property "Reference" "R899"
			(at 0 0 180)
			(layer "F.SilkS")
			(hide yes)
			(effects
				(font
					(size 1.27 1.27)
				)
			)
		)
		(property "Value" "0R2J-2-GP"
			(at 0.064008 -3.993896 180)
			(unlocked yes)
			(layer "F.Fab")
			(hide yes)
			(effects
				(font
					(size 1.016 1.016)
					(thickness 0.1524)
				)
			)
		)
		(property "Device Type" "R402H16"
			(at 0.064008 -5.517896 180)
			(unlocked yes)
			(layer "F.Fab")
			(hide yes)
			(effects
				(font
					(size 1.016 1.016)
					(thickness 0.1524)
				)
			)
		)
		(duplicate_pad_numbers_are_jumpers no)
		(fp_line
			(start 0.508 -0.9398)
			(end -0.508 -0.9398)
			(stroke
				(width 0.1524)
				(type default)
			)
			(layer "F.SilkS")
		)
		(fp_line
			(start -0.508 -0.9398)
			(end -0.508 0.9398)
			(stroke
				(width 0.1524)
				(type default)
			)
			(layer "F.SilkS")
		)
		(fp_rect
			(start -0.508 0.9398)
			(end 0.508 -0.9398)
			(stroke
				(width 0)
				(type default)
			)
			(fill no)
			(layer "F.CrtYd")
		)
		(fp_rect
			(start -0.508 0.9398)
			(end 0.508 -0.9398)
			(stroke
				(width 0)
				(type default)
			)
			(fill no)
			(layer "F.Fab")
		)
		(pad "1" smd custom
			(at 0 -0.4445 180)
			(size 0.1397 0.1397)
			(layers "F.Cu" "F.Mask" "F.Paste")
			(net "DRIVE_A_33_PWR")
			(options
				(clearance outline)
				(anchor circle)
			)
			(primitives
				(gr_poly
					(pts
						(arc
							(start -0.1778 -0.2794)
							(mid -0.249642 -0.249642)
							(end -0.2794 -0.1778)
						)
						(arc
							(start -0.2794 0.1778)
							(mid -0.249642 0.249642)
							(end -0.1778 0.2794)
						)
						(arc
							(start 0.1778 0.2794)
							(mid 0.249642 0.249642)
							(end 0.2794 0.1778)
						)
						(arc
							(start 0.2794 -0.1778)
							(mid 0.249642 -0.249642)
							(end 0.1778 -0.2794)
						)
					)
					(width 0)
					(fill yes)
				)
			)
		)
		(pad "2" smd custom
			(at 0 0.4445 180)
			(size 0.1397 0.1397)
			(layers "F.Cu" "F.Mask" "F.Paste")
			(net "SW_PWR_R_HDD33")
			(options
				(clearance outline)
				(anchor circle)
			)
			(primitives
				(gr_poly
					(pts
						(arc
							(start -0.1778 -0.2794)
							(mid -0.249642 -0.249642)
							(end -0.2794 -0.1778)
						)
						(arc
							(start -0.2794 0.1778)
							(mid -0.249642 0.249642)
							(end -0.1778 0.2794)
						)
						(arc
							(start 0.1778 0.2794)
							(mid 0.249642 0.249642)
							(end 0.2794 0.1778)
						)
						(arc
							(start 0.2794 -0.1778)
							(mid 0.249642 -0.249642)
							(end 0.1778 -0.2794)
						)
					)
					(width 0)
					(fill yes)
				)
			)
		)
	)
	(footprint ""
		(layer "F.Cu")
		(at 35.543998 -183.747918)
		(property "Reference" "TP62"
			(at 0 0 0)
			(layer "F.SilkS")
			(hide yes)
			(effects
				(font
					(size 1.27 1.27)
				)
			)
		)
		(property "Value" "TPAD32-GP"
			(at -0.0508 -1.6764 0)
			(unlocked yes)
			(layer "F.Fab")
			(hide yes)
			(effects
				(font
					(size 1.016 1.016)
					(thickness 0.1524)
				)
			)
		)
		(property "Device Type" "TPAD32"
			(at -0.0508 -3.2004 0)
			(unlocked yes)
			(layer "F.Fab")
			(hide yes)
			(effects
				(font
					(size 1.016 1.016)
					(thickness 0.1524)
				)
			)
		)
		(duplicate_pad_numbers_are_jumpers no)
		(fp_poly
			(pts
				(arc
					(start 0.4064 0)
					(mid -0.4064 0)
					(end 0.4064 0)
				)
			)
			(stroke
				(width 0)
				(type default)
			)
			(fill no)
			(layer "F.CrtYd")
		)
		(fp_poly
			(pts
				(arc
					(start 0.7112 0)
					(mid -0.7112 0)
					(end 0.7112 0)
				)
			)
			(stroke
				(width 0)
				(type default)
			)
			(fill no)
			(layer "F.Fab")
		)
		(pad "1" smd circle
			(at 0 0)
			(size 0.8128 0.8128)
			(layers "F.Cu" "F.Mask" "F.Paste")
			(net "ACT_HDD_12")
		)
	)
	(footprint ""
		(layer "F.Cu")
		(at 79.924148 -52.085494 90)
		(property "Reference" "R735"
			(at 0 0 90)
			(layer "F.SilkS")
			(hide yes)
			(effects
				(font
					(size 1.27 1.27)
				)
			)
		)
		(property "Value" "4K7R2J-2-GP"
			(at 0.064008 -3.993896 90)
			(unlocked yes)
			(layer "F.Fab")
			(hide yes)
			(effects
				(font
					(size 1.016 1.016)
					(thickness 0.1524)
				)
			)
		)
		(property "Device Type" "R402H16"
			(at 0.064008 -5.517896 90)
			(unlocked yes)
			(layer "F.Fab")
			(hide yes)
			(effects
				(font
					(size 1.016 1.016)
					(thickness 0.1524)
				)
			)
		)
		(duplicate_pad_numbers_are_jumpers no)
		(fp_line
			(start 0.508 -0.9398)
			(end -0.508 -0.9398)
			(stroke
				(width 0.1524)
				(type default)
			)
			(layer "F.SilkS")
		)
		(fp_line
			(start -0.508 -0.9398)
			(end -0.508 0.9398)
			(stroke
				(width 0.1524)
				(type default)
			)
			(layer "F.SilkS")
		)
		(fp_rect
			(start -0.508 0.9398)
			(end 0.508 -0.9398)
			(stroke
				(width 0)
				(type default)
			)
			(fill no)
			(layer "F.CrtYd")
		)
		(fp_rect
			(start -0.508 0.9398)
			(end 0.508 -0.9398)
			(stroke
				(width 0)
				(type default)
			)
			(fill no)
			(layer "F.Fab")
		)
		(pad "1" smd custom
			(at 0 -0.4445 90)
			(size 0.1397 0.1397)
			(layers "F.Cu" "F.Mask" "F.Paste")
			(net "P12V_A")
			(options
				(clearance outline)
				(anchor circle)
			)
			(primitives
				(gr_poly
					(pts
						(arc
							(start -0.1778 -0.2794)
							(mid -0.249642 -0.249642)
							(end -0.2794 -0.1778)
						)
						(arc
							(start -0.2794 0.1778)
							(mid -0.249642 0.249642)
							(end -0.1778 0.2794)
						)
						(arc
							(start 0.1778 0.2794)
							(mid 0.249642 0.249642)
							(end 0.2794 0.1778)
						)
						(arc
							(start 0.2794 -0.1778)
							(mid 0.249642 -0.249642)
							(end 0.1778 -0.2794)
						)
					)
					(width 0)
					(fill yes)
				)
			)
		)
		(pad "2" smd custom
			(at 0 0.4445 90)
			(size 0.1397 0.1397)
			(layers "F.Cu" "F.Mask" "F.Paste")
			(net "SW_HDD_P26")
			(options
				(clearance outline)
				(anchor circle)
			)
			(primitives
				(gr_poly
					(pts
						(arc
							(start -0.1778 -0.2794)
							(mid -0.249642 -0.249642)
							(end -0.2794 -0.1778)
						)
						(arc
							(start -0.2794 0.1778)
							(mid -0.249642 0.249642)
							(end -0.1778 0.2794)
						)
						(arc
							(start 0.1778 0.2794)
							(mid 0.249642 0.249642)
							(end 0.2794 0.1778)
						)
						(arc
							(start 0.2794 -0.1778)
							(mid 0.249642 -0.249642)
							(end 0.1778 -0.2794)
						)
					)
					(width 0)
					(fill yes)
				)
			)
		)
	)
	(footprint ""
		(layer "F.Cu")
		(at 430.438052 -272.585942 180)
		(property "Reference" "R348"
			(at 0 0 180)
			(layer "F.SilkS")
			(hide yes)
			(effects
				(font
					(size 1.27 1.27)
				)
			)
		)
		(property "Value" "0R2J-2-GP"
			(at 0.064008 -3.993896 180)
			(unlocked yes)
			(layer "F.Fab")
			(hide yes)
			(effects
				(font
					(size 1.016 1.016)
					(thickness 0.1524)
				)
			)
		)
		(property "Device Type" "R402H16"
			(at 0.064008 -5.517896 180)
			(unlocked yes)
			(layer "F.Fab")
			(hide yes)
			(effects
				(font
					(size 1.016 1.016)
					(thickness 0.1524)
				)
			)
		)
		(duplicate_pad_numbers_are_jumpers no)
		(fp_line
			(start 0.508 -0.9398)
			(end -0.508 -0.9398)
			(stroke
				(width 0.1524)
				(type default)
			)
			(layer "F.SilkS")
		)
		(fp_line
			(start -0.508 -0.9398)
			(end -0.508 0.9398)
			(stroke
				(width 0.1524)
				(type default)
			)
			(layer "F.SilkS")
		)
		(fp_rect
			(start -0.508 0.9398)
			(end 0.508 -0.9398)
			(stroke
				(width 0)
				(type default)
			)
			(fill no)
			(layer "F.CrtYd")
		)
		(fp_rect
			(start -0.508 0.9398)
			(end 0.508 -0.9398)
			(stroke
				(width 0)
				(type default)
			)
			(fill no)
			(layer "F.Fab")
		)
		(pad "1" smd custom
			(at 0 -0.4445 180)
			(size 0.1397 0.1397)
			(layers "F.Cu" "F.Mask" "F.Paste")
			(net "DRIVE_A_9_PWR")
			(options
				(clearance outline)
				(anchor circle)
			)
			(primitives
				(gr_poly
					(pts
						(arc
							(start -0.1778 -0.2794)
							(mid -0.249642 -0.249642)
							(end -0.2794 -0.1778)
						)
						(arc
							(start -0.2794 0.1778)
							(mid -0.249642 0.249642)
							(end -0.1778 0.2794)
						)
						(arc
							(start 0.1778 0.2794)
							(mid 0.249642 0.249642)
							(end 0.2794 0.1778)
						)
						(arc
							(start 0.2794 -0.1778)
							(mid 0.249642 -0.249642)
							(end 0.1778 -0.2794)
						)
					)
					(width 0)
					(fill yes)
				)
			)
		)
		(pad "2" smd custom
			(at 0 0.4445 180)
			(size 0.1397 0.1397)
			(layers "F.Cu" "F.Mask" "F.Paste")
			(net "SW_PWR_R_HDD9")
			(options
				(clearance outline)
				(anchor circle)
			)
			(primitives
				(gr_poly
					(pts
						(arc
							(start -0.1778 -0.2794)
							(mid -0.249642 -0.249642)
							(end -0.2794 -0.1778)
						)
						(arc
							(start -0.2794 0.1778)
							(mid -0.249642 0.249642)
							(end -0.1778 0.2794)
						)
						(arc
							(start 0.1778 0.2794)
							(mid 0.249642 0.249642)
							(end 0.2794 0.1778)
						)
						(arc
							(start 0.2794 -0.1778)
							(mid 0.249642 -0.249642)
							(end 0.1778 -0.2794)
						)
					)
					(width 0)
					(fill yes)
				)
			)
		)
	)
	(footprint ""
		(layer "F.Cu")
		(at 180.7464 -161.014918 -90)
		(property "Reference" "R529"
			(at 0 0 270)
			(layer "F.SilkS")
			(hide yes)
			(effects
				(font
					(size 1.27 1.27)
				)
			)
		)
		(property "Value" "1KR2F-3-GP"
			(at 0.064008 -3.993896 270)
			(unlocked yes)
			(layer "F.Fab")
			(hide yes)
			(effects
				(font
					(size 1.016 1.016)
					(thickness 0.1524)
				)
			)
		)
		(property "Device Type" "R402H16"
			(at 0.064008 -5.517896 270)
			(unlocked yes)
			(layer "F.Fab")
			(hide yes)
			(effects
				(font
					(size 1.016 1.016)
					(thickness 0.1524)
				)
			)
		)
		(duplicate_pad_numbers_are_jumpers no)
		(fp_line
			(start -0.508 -0.9398)
			(end -0.508 0.9398)
			(stroke
				(width 0.1524)
				(type default)
			)
			(layer "F.SilkS")
		)
		(fp_line
			(start 0.508 -0.9398)
			(end -0.508 -0.9398)
			(stroke
				(width 0.1524)
				(type default)
			)
			(layer "F.SilkS")
		)
		(fp_rect
			(start -0.508 0.9398)
			(end 0.508 -0.9398)
			(stroke
				(width 0)
				(type default)
			)
			(fill no)
			(layer "F.CrtYd")
		)
		(fp_rect
			(start -0.508 0.9398)
			(end 0.508 -0.9398)
			(stroke
				(width 0)
				(type default)
			)
			(fill no)
			(layer "F.Fab")
		)
		(pad "1" smd custom
			(at 0 -0.4445 270)
			(size 0.1397 0.1397)
			(layers "F.Cu" "F.Mask" "F.Paste")
			(net "P3V3_STBY_A")
			(options
				(clearance outline)
				(anchor circle)
			)
			(primitives
				(gr_poly
					(pts
						(arc
							(start -0.1778 -0.2794)
							(mid -0.249642 -0.249642)
							(end -0.2794 -0.1778)
						)
						(arc
							(start -0.2794 0.1778)
							(mid -0.249642 0.249642)
							(end -0.1778 0.2794)
						)
						(arc
							(start 0.1778 0.2794)
							(mid 0.249642 0.249642)
							(end 0.2794 0.1778)
						)
						(arc
							(start 0.2794 -0.1778)
							(mid 0.249642 -0.249642)
							(end 0.1778 -0.2794)
						)
					)
					(width 0)
					(fill yes)
				)
			)
		)
		(pad "2" smd custom
			(at 0 0.4445 270)
			(size 0.1397 0.1397)
			(layers "F.Cu" "F.Mask" "F.Paste")
			(net "SW_PWR_R_HDD17")
			(options
				(clearance outline)
				(anchor circle)
			)
			(primitives
				(gr_poly
					(pts
						(arc
							(start -0.1778 -0.2794)
							(mid -0.249642 -0.249642)
							(end -0.2794 -0.1778)
						)
						(arc
							(start -0.2794 0.1778)
							(mid -0.249642 0.249642)
							(end -0.1778 0.2794)
						)
						(arc
							(start 0.1778 0.2794)
							(mid 0.249642 0.249642)
							(end 0.2794 0.1778)
						)
						(arc
							(start 0.2794 -0.1778)
							(mid 0.249642 -0.249642)
							(end 0.1778 -0.2794)
						)
					)
					(width 0)
					(fill yes)
				)
			)
		)
	)
	(footprint ""
		(layer "F.Cu")
		(at 370.259102 -171.809918 -90)
		(property "Reference" "R582"
			(at 0 0 270)
			(layer "F.SilkS")
			(hide yes)
			(effects
				(font
					(size 1.27 1.27)
				)
			)
		)
		(property "Value" "300KR2F-GP"
			(at 0.064008 -3.993896 270)
			(unlocked yes)
			(layer "F.Fab")
			(hide yes)
			(effects
				(font
					(size 1.016 1.016)
					(thickness 0.1524)
				)
			)
		)
		(property "Device Type" "R402H16"
			(at 0.064008 -5.517896 270)
			(unlocked yes)
			(layer "F.Fab")
			(hide yes)
			(effects
				(font
					(size 1.016 1.016)
					(thickness 0.1524)
				)
			)
		)
		(duplicate_pad_numbers_are_jumpers no)
		(fp_line
			(start -0.508 -0.9398)
			(end -0.508 0.9398)
			(stroke
				(width 0.1524)
				(type default)
			)
			(layer "F.SilkS")
		)
		(fp_line
			(start 0.508 -0.9398)
			(end -0.508 -0.9398)
			(stroke
				(width 0.1524)
				(type default)
			)
			(layer "F.SilkS")
		)
		(fp_rect
			(start -0.508 0.9398)
			(end 0.508 -0.9398)
			(stroke
				(width 0)
				(type default)
			)
			(fill no)
			(layer "F.CrtYd")
		)
		(fp_rect
			(start -0.508 0.9398)
			(end 0.508 -0.9398)
			(stroke
				(width 0)
				(type default)
			)
			(fill no)
			(layer "F.Fab")
		)
		(pad "1" smd custom
			(at 0 -0.4445 270)
			(size 0.1397 0.1397)
			(layers "F.Cu" "F.Mask" "F.Paste")
			(net "SW_HDD_N19")
			(options
				(clearance outline)
				(anchor circle)
			)
			(primitives
				(gr_poly
					(pts
						(arc
							(start -0.1778 -0.2794)
							(mid -0.249642 -0.249642)
							(end -0.2794 -0.1778)
						)
						(arc
							(start -0.2794 0.1778)
							(mid -0.249642 0.249642)
							(end -0.1778 0.2794)
						)
						(arc
							(start 0.1778 0.2794)
							(mid 0.249642 0.249642)
							(end 0.2794 0.1778)
						)
						(arc
							(start 0.2794 -0.1778)
							(mid 0.249642 -0.249642)
							(end 0.1778 -0.2794)
						)
					)
					(width 0)
					(fill yes)
				)
			)
		)
		(pad "2" smd custom
			(at 0 0.4445 270)
			(size 0.1397 0.1397)
			(layers "F.Cu" "F.Mask" "F.Paste")
			(net "P12V_A")
			(options
				(clearance outline)
				(anchor circle)
			)
			(primitives
				(gr_poly
					(pts
						(arc
							(start -0.1778 -0.2794)
							(mid -0.249642 -0.249642)
							(end -0.2794 -0.1778)
						)
						(arc
							(start -0.2794 0.1778)
							(mid -0.249642 0.249642)
							(end -0.1778 0.2794)
						)
						(arc
							(start 0.1778 0.2794)
							(mid 0.249642 0.249642)
							(end 0.2794 0.1778)
						)
						(arc
							(start 0.2794 -0.1778)
							(mid 0.249642 -0.249642)
							(end 0.1778 -0.2794)
						)
					)
					(width 0)
					(fill yes)
				)
			)
		)
	)
	(footprint ""
		(layer "F.Cu")
		(at 255.364234 -11.186922 90)
		(property "Reference" "TP217"
			(at 0 0 90)
			(layer "F.SilkS")
			(hide yes)
			(effects
				(font
					(size 1.27 1.27)
				)
			)
		)
		(property "Value" "TPAD32-GP"
			(at -0.0508 -1.6764 90)
			(unlocked yes)
			(layer "F.Fab")
			(hide yes)
			(effects
				(font
					(size 1.016 1.016)
					(thickness 0.1524)
				)
			)
		)
		(property "Device Type" "TPAD32"
			(at -0.0508 -3.2004 90)
			(unlocked yes)
			(layer "F.Fab")
			(hide yes)
			(effects
				(font
					(size 1.016 1.016)
					(thickness 0.1524)
				)
			)
		)
		(duplicate_pad_numbers_are_jumpers no)
		(fp_poly
			(pts
				(arc
					(start 0 0.4064)
					(mid 0 -0.4064)
					(end 0 0.4064)
				)
			)
			(stroke
				(width 0)
				(type default)
			)
			(fill no)
			(layer "F.CrtYd")
		)
		(fp_poly
			(pts
				(arc
					(start 0 0.7112)
					(mid 0 -0.7112)
					(end 0 0.7112)
				)
			)
			(stroke
				(width 0)
				(type default)
			)
			(fill no)
			(layer "F.Fab")
		)
		(pad "1" smd circle
			(at 0 0 90)
			(size 0.8128 0.8128)
			(layers "F.Cu" "F.Mask" "F.Paste")
			(net "TP_COMP_A_NCSI_RXD1")
		)
	)
	(footprint ""
		(layer "F.Cu")
		(at 77.815948 -294.683942 -90)
		(property "Reference" "C71"
			(at 0 0 270)
			(layer "F.SilkS")
			(hide yes)
			(effects
				(font
					(size 1.27 1.27)
				)
			)
		)
		(property "Value" "SC4D7U25V5KX-1-GP"
			(at -0.0762 -6.1214 270)
			(unlocked yes)
			(layer "F.Fab")
			(hide yes)
			(effects
				(font
					(size 1.016 1.016)
					(thickness 0.1524)
				)
			)
		)
		(property "Device Type" "C805H58"
			(at -0.0762 -8.1534 270)
			(unlocked yes)
			(layer "F.Fab")
			(hide yes)
			(effects
				(font
					(size 1.016 1.016)
					(thickness 0.1524)
				)
			)
		)
		(duplicate_pad_numbers_are_jumpers no)
		(fp_line
			(start 0.635 0)
			(end -0.635 0)
			(stroke
				(width 0.508)
				(type default)
			)
			(layer "F.SilkS")
		)
		(fp_rect
			(start -0.9652 1.778)
			(end 0.9652 -1.778)
			(stroke
				(width 0)
				(type default)
			)
			(fill no)
			(layer "F.CrtYd")
		)
		(fp_poly
			(pts
				(xy -0.9652 -1.778) (xy 0.9652 -1.778) (xy 0.9652 1.778) (xy -0.9652 1.778)
			)
			(stroke
				(width 0)
				(type default)
			)
			(fill no)
			(layer "F.Fab")
		)
		(pad "1" smd rect
			(at 0 -0.9652 270)
			(size 1.397 1.143)
			(layers "F.Cu" "F.Mask" "F.Paste")
			(net "P12V_HDD2")
		)
		(pad "2" smd rect
			(at 0 0.9652 270)
			(size 1.397 1.143)
			(layers "F.Cu" "F.Mask" "F.Paste")
			(net "GND")
		)
	)
	(footprint ""
		(layer "F.Cu")
		(at 381.00635 -65.039494 -90)
		(property "Reference" "R870"
			(at 0 0 270)
			(layer "F.SilkS")
			(hide yes)
			(effects
				(font
					(size 1.27 1.27)
				)
			)
		)
		(property "Value" "220R3F-1-GP"
			(at -0.0254 -2.5146 270)
			(unlocked yes)
			(layer "F.Fab")
			(hide yes)
			(effects
				(font
					(size 1.016 1.016)
					(thickness 0.1524)
				)
			)
		)
		(property "Device Type" "R603H22"
			(at -0.0254 -4.0386 270)
			(unlocked yes)
			(layer "F.Fab")
			(hide yes)
			(effects
				(font
					(size 1.016 1.016)
					(thickness 0.1524)
				)
			)
		)
		(duplicate_pad_numbers_are_jumpers no)
		(fp_line
			(start -0.4826 0)
			(end -0.2032 0)
			(stroke
				(width 0.2032)
				(type default)
			)
			(layer "F.SilkS")
		)
		(fp_line
			(start 0.2032 0)
			(end 0.4826 0)
			(stroke
				(width 0.2032)
				(type default)
			)
			(layer "F.SilkS")
		)
		(fp_rect
			(start -0.5842 1.3335)
			(end 0.5842 -1.3335)
			(stroke
				(width 0)
				(type default)
			)
			(fill no)
			(layer "F.CrtYd")
		)
		(fp_rect
			(start -0.5842 1.3335)
			(end 0.5842 -1.3335)
			(stroke
				(width 0)
				(type default)
			)
			(fill no)
			(layer "F.Fab")
		)
		(pad "1" smd custom
			(at 0 -0.762 270)
			(size 0.2159 0.2159)
			(layers "F.Cu" "F.Mask" "F.Paste")
			(net "HDD_PRSNT_32")
			(options
				(clearance outline)
				(anchor circle)
			)
			(primitives
				(gr_poly
					(pts
						(arc
							(start -0.3302 -0.4318)
							(mid -0.402042 -0.402042)
							(end -0.4318 -0.3302)
						)
						(arc
							(start -0.4318 0.3302)
							(mid -0.402042 0.402042)
							(end -0.3302 0.4318)
						)
						(arc
							(start 0.3302 0.4318)
							(mid 0.402042 0.402042)
							(end 0.4318 0.3302)
						)
						(arc
							(start 0.4318 -0.3302)
							(mid 0.402042 -0.402042)
							(end 0.3302 -0.4318)
						)
					)
					(width 0)
					(fill yes)
				)
			)
		)
		(pad "2" smd custom
			(at 0 0.762 270)
			(size 0.2159 0.2159)
			(layers "F.Cu" "F.Mask" "F.Paste")
			(net "DRIVE_A_32_INS")
			(options
				(clearance outline)
				(anchor circle)
			)
			(primitives
				(gr_poly
					(pts
						(arc
							(start -0.3302 -0.4318)
							(mid -0.402042 -0.402042)
							(end -0.4318 -0.3302)
						)
						(arc
							(start -0.4318 0.3302)
							(mid -0.402042 0.402042)
							(end -0.3302 0.4318)
						)
						(arc
							(start 0.3302 0.4318)
							(mid 0.402042 0.402042)
							(end 0.4318 0.3302)
						)
						(arc
							(start 0.4318 -0.3302)
							(mid 0.402042 -0.402042)
							(end 0.3302 -0.4318)
						)
					)
					(width 0)
					(fill yes)
				)
			)
		)
	)
	(footprint ""
		(layer "F.Cu")
		(at 54.546246 -278.554942 90)
		(property "Reference" "R164"
			(at 0 0 90)
			(layer "F.SilkS")
			(hide yes)
			(effects
				(font
					(size 1.27 1.27)
				)
			)
		)
		(property "Value" "4K7R2J-2-GP"
			(at 0.064008 -3.993896 90)
			(unlocked yes)
			(layer "F.Fab")
			(hide yes)
			(effects
				(font
					(size 1.016 1.016)
					(thickness 0.1524)
				)
			)
		)
		(property "Device Type" "R402H16"
			(at 0.064008 -5.517896 90)
			(unlocked yes)
			(layer "F.Fab")
			(hide yes)
			(effects
				(font
					(size 1.016 1.016)
					(thickness 0.1524)
				)
			)
		)
		(duplicate_pad_numbers_are_jumpers no)
		(fp_line
			(start 0.508 -0.9398)
			(end -0.508 -0.9398)
			(stroke
				(width 0.1524)
				(type default)
			)
			(layer "F.SilkS")
		)
		(fp_line
			(start -0.508 -0.9398)
			(end -0.508 0.9398)
			(stroke
				(width 0.1524)
				(type default)
			)
			(layer "F.SilkS")
		)
		(fp_rect
			(start -0.508 0.9398)
			(end 0.508 -0.9398)
			(stroke
				(width 0)
				(type default)
			)
			(fill no)
			(layer "F.CrtYd")
		)
		(fp_rect
			(start -0.508 0.9398)
			(end 0.508 -0.9398)
			(stroke
				(width 0)
				(type default)
			)
			(fill no)
			(layer "F.Fab")
		)
		(pad "1" smd custom
			(at 0 -0.4445 90)
			(size 0.1397 0.1397)
			(layers "F.Cu" "F.Mask" "F.Paste")
			(net "SW_PWR_R_HDD1")
			(options
				(clearance outline)
				(anchor circle)
			)
			(primitives
				(gr_poly
					(pts
						(arc
							(start -0.1778 -0.2794)
							(mid -0.249642 -0.249642)
							(end -0.2794 -0.1778)
						)
						(arc
							(start -0.2794 0.1778)
							(mid -0.249642 0.249642)
							(end -0.1778 0.2794)
						)
						(arc
							(start 0.1778 0.2794)
							(mid 0.249642 0.249642)
							(end 0.2794 0.1778)
						)
						(arc
							(start 0.2794 -0.1778)
							(mid 0.249642 -0.249642)
							(end 0.1778 -0.2794)
						)
					)
					(width 0)
					(fill yes)
				)
			)
		)
		(pad "2" smd custom
			(at 0 0.4445 90)
			(size 0.1397 0.1397)
			(layers "F.Cu" "F.Mask" "F.Paste")
			(net "GND")
			(options
				(clearance outline)
				(anchor circle)
			)
			(primitives
				(gr_poly
					(pts
						(arc
							(start -0.1778 -0.2794)
							(mid -0.249642 -0.249642)
							(end -0.2794 -0.1778)
						)
						(arc
							(start -0.2794 0.1778)
							(mid -0.249642 0.249642)
							(end -0.1778 0.2794)
						)
						(arc
							(start 0.1778 0.2794)
							(mid 0.249642 0.249642)
							(end 0.2794 0.1778)
						)
						(arc
							(start 0.2794 -0.1778)
							(mid 0.249642 -0.249642)
							(end 0.1778 -0.2794)
						)
					)
					(width 0)
					(fill yes)
				)
			)
		)
	)
	(footprint ""
		(layer "F.Cu")
		(at 140.992098 -45.608494 90)
		(property "Reference" "R788"
			(at 0 0 90)
			(layer "F.SilkS")
			(hide yes)
			(effects
				(font
					(size 1.27 1.27)
				)
			)
		)
		(property "Value" "4K7R2J-2-GP"
			(at 0.064008 -3.993896 90)
			(unlocked yes)
			(layer "F.Fab")
			(hide yes)
			(effects
				(font
					(size 1.016 1.016)
					(thickness 0.1524)
				)
			)
		)
		(property "Device Type" "R402H16"
			(at 0.064008 -5.517896 90)
			(unlocked yes)
			(layer "F.Fab")
			(hide yes)
			(effects
				(font
					(size 1.016 1.016)
					(thickness 0.1524)
				)
			)
		)
		(duplicate_pad_numbers_are_jumpers no)
		(fp_line
			(start 0.508 -0.9398)
			(end -0.508 -0.9398)
			(stroke
				(width 0.1524)
				(type default)
			)
			(layer "F.SilkS")
		)
		(fp_line
			(start -0.508 -0.9398)
			(end -0.508 0.9398)
			(stroke
				(width 0.1524)
				(type default)
			)
			(layer "F.SilkS")
		)
		(fp_rect
			(start -0.508 0.9398)
			(end 0.508 -0.9398)
			(stroke
				(width 0)
				(type default)
			)
			(fill no)
			(layer "F.CrtYd")
		)
		(fp_rect
			(start -0.508 0.9398)
			(end 0.508 -0.9398)
			(stroke
				(width 0)
				(type default)
			)
			(fill no)
			(layer "F.Fab")
		)
		(pad "1" smd custom
			(at 0 -0.4445 90)
			(size 0.1397 0.1397)
			(layers "F.Cu" "F.Mask" "F.Paste")
			(net "P12V_A")
			(options
				(clearance outline)
				(anchor circle)
			)
			(primitives
				(gr_poly
					(pts
						(arc
							(start -0.1778 -0.2794)
							(mid -0.249642 -0.249642)
							(end -0.2794 -0.1778)
						)
						(arc
							(start -0.2794 0.1778)
							(mid -0.249642 0.249642)
							(end -0.1778 0.2794)
						)
						(arc
							(start 0.1778 0.2794)
							(mid 0.249642 0.249642)
							(end 0.2794 0.1778)
						)
						(arc
							(start 0.2794 -0.1778)
							(mid 0.249642 -0.249642)
							(end 0.1778 -0.2794)
						)
					)
					(width 0)
					(fill yes)
				)
			)
		)
		(pad "2" smd custom
			(at 0 0.4445 90)
			(size 0.1397 0.1397)
			(layers "F.Cu" "F.Mask" "F.Paste")
			(net "SW_HDD_R28")
			(options
				(clearance outline)
				(anchor circle)
			)
			(primitives
				(gr_poly
					(pts
						(arc
							(start -0.1778 -0.2794)
							(mid -0.249642 -0.249642)
							(end -0.2794 -0.1778)
						)
						(arc
							(start -0.2794 0.1778)
							(mid -0.249642 0.249642)
							(end -0.1778 0.2794)
						)
						(arc
							(start 0.1778 0.2794)
							(mid 0.249642 0.249642)
							(end 0.2794 0.1778)
						)
						(arc
							(start 0.2794 -0.1778)
							(mid 0.249642 -0.249642)
							(end 0.1778 -0.2794)
						)
					)
					(width 0)
					(fill yes)
				)
			)
		)
	)
	(footprint ""
		(layer "F.Cu")
		(at 452.642224 -249.875548 90)
		(property "Reference" "C638"
			(at 0 0 90)
			(layer "F.SilkS")
			(hide yes)
			(effects
				(font
					(size 1.27 1.27)
				)
			)
		)
		(property "Value" "SCD1U16V2KX-3GP"
			(at 1.1811 -2.7051 90)
			(unlocked yes)
			(layer "F.Fab")
			(hide yes)
			(effects
				(font
					(size 1.016 1.016)
					(thickness 0.1524)
				)
			)
		)
		(property "Device Type" "C402H22"
			(at 1.1811 -4.2291 90)
			(unlocked yes)
			(layer "F.Fab")
			(hide yes)
			(effects
				(font
					(size 1.016 1.016)
					(thickness 0.1524)
				)
			)
		)
		(duplicate_pad_numbers_are_jumpers no)
		(fp_rect
			(start -0.4318 0.9525)
			(end 0.4318 -0.9525)
			(stroke
				(width 0)
				(type default)
			)
			(fill no)
			(layer "F.CrtYd")
		)
		(fp_rect
			(start -0.4318 0.9525)
			(end 0.4318 -0.9525)
			(stroke
				(width 0)
				(type default)
			)
			(fill no)
			(layer "F.Fab")
		)
		(pad "1" smd custom
			(at 0 -0.4445 90)
			(size 0.1524 0.1524)
			(layers "F.Cu" "F.Mask" "F.Paste")
			(net "P5V_C_VBST_RC")
			(options
				(clearance outline)
				(anchor circle)
			)
			(primitives
				(gr_poly
					(pts
						(arc
							(start 0.3048 -0.2032)
							(mid 0.275042 -0.275042)
							(end 0.2032 -0.3048)
						)
						(arc
							(start -0.2032 -0.3048)
							(mid -0.275042 -0.275042)
							(end -0.3048 -0.2032)
						)
						(arc
							(start -0.3048 0.2032)
							(mid -0.275042 0.275042)
							(end -0.2032 0.3048)
						)
						(arc
							(start 0.2032 0.3048)
							(mid 0.275042 0.275042)
							(end 0.3048 0.2032)
						)
					)
					(width 0)
					(fill yes)
				)
			)
		)
		(pad "2" smd custom
			(at 0 0.4445 90)
			(size 0.1524 0.1524)
			(layers "F.Cu" "F.Mask" "F.Paste")
			(net "P5V_C_LL")
			(options
				(clearance outline)
				(anchor circle)
			)
			(primitives
				(gr_poly
					(pts
						(arc
							(start 0.3048 -0.2032)
							(mid 0.275042 -0.275042)
							(end 0.2032 -0.3048)
						)
						(arc
							(start -0.2032 -0.3048)
							(mid -0.275042 -0.275042)
							(end -0.3048 -0.2032)
						)
						(arc
							(start -0.3048 0.2032)
							(mid -0.275042 0.275042)
							(end -0.2032 0.3048)
						)
						(arc
							(start 0.2032 0.3048)
							(mid 0.275042 0.275042)
							(end 0.3048 0.2032)
						)
					)
					(width 0)
					(fill yes)
				)
			)
		)
	)
	(footprint ""
		(layer "F.Cu")
		(at 161.997898 -291.127942 90)
		(property "Reference" "C98"
			(at 0 0 90)
			(layer "F.SilkS")
			(hide yes)
			(effects
				(font
					(size 1.27 1.27)
				)
			)
		)
		(property "Value" "SCD01U50V2KX-1GP"
			(at 1.1811 -2.7051 90)
			(unlocked yes)
			(layer "F.Fab")
			(hide yes)
			(effects
				(font
					(size 1.016 1.016)
					(thickness 0.1524)
				)
			)
		)
		(property "Device Type" "C402H22"
			(at 1.1811 -4.2291 90)
			(unlocked yes)
			(layer "F.Fab")
			(hide yes)
			(effects
				(font
					(size 1.016 1.016)
					(thickness 0.1524)
				)
			)
		)
		(duplicate_pad_numbers_are_jumpers no)
		(fp_rect
			(start -0.4318 0.9525)
			(end 0.4318 -0.9525)
			(stroke
				(width 0)
				(type default)
			)
			(fill no)
			(layer "F.CrtYd")
		)
		(fp_rect
			(start -0.4318 0.9525)
			(end 0.4318 -0.9525)
			(stroke
				(width 0)
				(type default)
			)
			(fill no)
			(layer "F.Fab")
		)
		(pad "1" smd custom
			(at 0 -0.4445 90)
			(size 0.1524 0.1524)
			(layers "F.Cu" "F.Mask" "F.Paste")
			(net "HDD_PRSNT_4")
			(options
				(clearance outline)
				(anchor circle)
			)
			(primitives
				(gr_poly
					(pts
						(arc
							(start 0.3048 -0.2032)
							(mid 0.275042 -0.275042)
							(end 0.2032 -0.3048)
						)
						(arc
							(start -0.2032 -0.3048)
							(mid -0.275042 -0.275042)
							(end -0.3048 -0.2032)
						)
						(arc
							(start -0.3048 0.2032)
							(mid -0.275042 0.275042)
							(end -0.2032 0.3048)
						)
						(arc
							(start 0.2032 0.3048)
							(mid 0.275042 0.275042)
							(end 0.3048 0.2032)
						)
					)
					(width 0)
					(fill yes)
				)
			)
		)
		(pad "2" smd custom
			(at 0 0.4445 90)
			(size 0.1524 0.1524)
			(layers "F.Cu" "F.Mask" "F.Paste")
			(net "GND")
			(options
				(clearance outline)
				(anchor circle)
			)
			(primitives
				(gr_poly
					(pts
						(arc
							(start 0.3048 -0.2032)
							(mid 0.275042 -0.275042)
							(end 0.2032 -0.3048)
						)
						(arc
							(start -0.2032 -0.3048)
							(mid -0.275042 -0.275042)
							(end -0.3048 -0.2032)
						)
						(arc
							(start -0.3048 0.2032)
							(mid -0.275042 0.275042)
							(end -0.2032 0.3048)
						)
						(arc
							(start 0.2032 0.3048)
							(mid 0.275042 0.275042)
							(end 0.3048 0.2032)
						)
					)
					(width 0)
					(fill yes)
				)
			)
		)
	)
	(footprint ""
		(layer "F.Cu")
		(at 276.2377 15.3162 90)
		(property "Reference" "R632"
			(at 0 0 90)
			(layer "F.SilkS")
			(hide yes)
			(effects
				(font
					(size 1.27 1.27)
				)
			)
		)
		(property "Value" "10KR2F-2-GP"
			(at 0.064008 -3.993896 90)
			(unlocked yes)
			(layer "F.Fab")
			(hide yes)
			(effects
				(font
					(size 1.016 1.016)
					(thickness 0.1524)
				)
			)
		)
		(property "Device Type" "R402H16"
			(at 0.064008 -5.517896 90)
			(unlocked yes)
			(layer "F.Fab")
			(hide yes)
			(effects
				(font
					(size 1.016 1.016)
					(thickness 0.1524)
				)
			)
		)
		(duplicate_pad_numbers_are_jumpers no)
		(fp_line
			(start 0.508 -0.9398)
			(end -0.508 -0.9398)
			(stroke
				(width 0.1524)
				(type default)
			)
			(layer "F.SilkS")
		)
		(fp_line
			(start -0.508 -0.9398)
			(end -0.508 0.9398)
			(stroke
				(width 0.1524)
				(type default)
			)
			(layer "F.SilkS")
		)
		(fp_rect
			(start -0.508 0.9398)
			(end 0.508 -0.9398)
			(stroke
				(width 0)
				(type default)
			)
			(fill no)
			(layer "F.CrtYd")
		)
		(fp_rect
			(start -0.508 0.9398)
			(end 0.508 -0.9398)
			(stroke
				(width 0)
				(type default)
			)
			(fill no)
			(layer "F.Fab")
		)
		(pad "1" smd custom
			(at 0 -0.4445 90)
			(size 0.1397 0.1397)
			(layers "F.Cu" "F.Mask" "F.Paste")
			(net "P3V3_STBY_B")
			(options
				(clearance outline)
				(anchor circle)
			)
			(primitives
				(gr_poly
					(pts
						(arc
							(start -0.1778 -0.2794)
							(mid -0.249642 -0.249642)
							(end -0.2794 -0.1778)
						)
						(arc
							(start -0.2794 0.1778)
							(mid -0.249642 0.249642)
							(end -0.1778 0.2794)
						)
						(arc
							(start 0.1778 0.2794)
							(mid 0.249642 0.249642)
							(end 0.2794 0.1778)
						)
						(arc
							(start 0.2794 -0.1778)
							(mid 0.249642 -0.249642)
							(end 0.1778 -0.2794)
						)
					)
					(width 0)
					(fill yes)
				)
			)
		)
		(pad "2" smd custom
			(at 0 0.4445 90)
			(size 0.1397 0.1397)
			(layers "F.Cu" "F.Mask" "F.Paste")
			(net "IOM_B_PWR_LED")
			(options
				(clearance outline)
				(anchor circle)
			)
			(primitives
				(gr_poly
					(pts
						(arc
							(start -0.1778 -0.2794)
							(mid -0.249642 -0.249642)
							(end -0.2794 -0.1778)
						)
						(arc
							(start -0.2794 0.1778)
							(mid -0.249642 0.249642)
							(end -0.1778 0.2794)
						)
						(arc
							(start 0.1778 0.2794)
							(mid 0.249642 0.249642)
							(end 0.2794 0.1778)
						)
						(arc
							(start 0.2794 -0.1778)
							(mid 0.249642 -0.249642)
							(end 0.1778 -0.2794)
						)
					)
					(width 0)
					(fill yes)
				)
			)
		)
	)
	(footprint ""
		(layer "F.Cu")
		(at 77.892148 -45.633894 90)
		(property "Reference" "R742"
			(at 0 0 90)
			(layer "F.SilkS")
			(hide yes)
			(effects
				(font
					(size 1.27 1.27)
				)
			)
		)
		(property "Value" "4K7R2J-2-GP"
			(at 0.064008 -3.993896 90)
			(unlocked yes)
			(layer "F.Fab")
			(hide yes)
			(effects
				(font
					(size 1.016 1.016)
					(thickness 0.1524)
				)
			)
		)
		(property "Device Type" "R402H16"
			(at 0.064008 -5.517896 90)
			(unlocked yes)
			(layer "F.Fab")
			(hide yes)
			(effects
				(font
					(size 1.016 1.016)
					(thickness 0.1524)
				)
			)
		)
		(duplicate_pad_numbers_are_jumpers no)
		(fp_line
			(start 0.508 -0.9398)
			(end -0.508 -0.9398)
			(stroke
				(width 0.1524)
				(type default)
			)
			(layer "F.SilkS")
		)
		(fp_line
			(start -0.508 -0.9398)
			(end -0.508 0.9398)
			(stroke
				(width 0.1524)
				(type default)
			)
			(layer "F.SilkS")
		)
		(fp_rect
			(start -0.508 0.9398)
			(end 0.508 -0.9398)
			(stroke
				(width 0)
				(type default)
			)
			(fill no)
			(layer "F.CrtYd")
		)
		(fp_rect
			(start -0.508 0.9398)
			(end 0.508 -0.9398)
			(stroke
				(width 0)
				(type default)
			)
			(fill no)
			(layer "F.Fab")
		)
		(pad "1" smd custom
			(at 0 -0.4445 90)
			(size 0.1397 0.1397)
			(layers "F.Cu" "F.Mask" "F.Paste")
			(net "P12V_A")
			(options
				(clearance outline)
				(anchor circle)
			)
			(primitives
				(gr_poly
					(pts
						(arc
							(start -0.1778 -0.2794)
							(mid -0.249642 -0.249642)
							(end -0.2794 -0.1778)
						)
						(arc
							(start -0.2794 0.1778)
							(mid -0.249642 0.249642)
							(end -0.1778 0.2794)
						)
						(arc
							(start 0.1778 0.2794)
							(mid 0.249642 0.249642)
							(end 0.2794 0.1778)
						)
						(arc
							(start 0.2794 -0.1778)
							(mid 0.249642 -0.249642)
							(end 0.1778 -0.2794)
						)
					)
					(width 0)
					(fill yes)
				)
			)
		)
		(pad "2" smd custom
			(at 0 0.4445 90)
			(size 0.1397 0.1397)
			(layers "F.Cu" "F.Mask" "F.Paste")
			(net "SW_HDD_R26")
			(options
				(clearance outline)
				(anchor circle)
			)
			(primitives
				(gr_poly
					(pts
						(arc
							(start -0.1778 -0.2794)
							(mid -0.249642 -0.249642)
							(end -0.2794 -0.1778)
						)
						(arc
							(start -0.2794 0.1778)
							(mid -0.249642 0.249642)
							(end -0.1778 0.2794)
						)
						(arc
							(start 0.1778 0.2794)
							(mid 0.249642 0.249642)
							(end 0.2794 0.1778)
						)
						(arc
							(start 0.2794 -0.1778)
							(mid 0.249642 -0.249642)
							(end 0.1778 -0.2794)
						)
					)
					(width 0)
					(fill yes)
				)
			)
		)
	)
	(footprint ""
		(layer "F.Cu")
		(at 271.4498 -280.3144)
		(property "Reference" "C36"
			(at 0 0 0)
			(layer "F.SilkS")
			(hide yes)
			(effects
				(font
					(size 1.27 1.27)
				)
			)
		)
		(property "Value" "SCD1U16V2KX-3GP"
			(at 1.1811 -2.7051 0)
			(unlocked yes)
			(layer "F.Fab")
			(hide yes)
			(effects
				(font
					(size 1.016 1.016)
					(thickness 0.1524)
				)
			)
		)
		(property "Device Type" "C402H22"
			(at 1.1811 -4.2291 0)
			(unlocked yes)
			(layer "F.Fab")
			(hide yes)
			(effects
				(font
					(size 1.016 1.016)
					(thickness 0.1524)
				)
			)
		)
		(duplicate_pad_numbers_are_jumpers no)
		(fp_rect
			(start -0.4318 0.9525)
			(end 0.4318 -0.9525)
			(stroke
				(width 0)
				(type default)
			)
			(fill no)
			(layer "F.CrtYd")
		)
		(fp_rect
			(start -0.4318 0.9525)
			(end 0.4318 -0.9525)
			(stroke
				(width 0)
				(type default)
			)
			(fill no)
			(layer "F.Fab")
		)
		(pad "1" smd custom
			(at 0 -0.4445)
			(size 0.1524 0.1524)
			(layers "F.Cu" "F.Mask" "F.Paste")
			(net "P3V3_STBY_A")
			(options
				(clearance outline)
				(anchor circle)
			)
			(primitives
				(gr_poly
					(pts
						(arc
							(start 0.3048 -0.2032)
							(mid 0.275042 -0.275042)
							(end 0.2032 -0.3048)
						)
						(arc
							(start -0.2032 -0.3048)
							(mid -0.275042 -0.275042)
							(end -0.3048 -0.2032)
						)
						(arc
							(start -0.3048 0.2032)
							(mid -0.275042 0.275042)
							(end -0.2032 0.3048)
						)
						(arc
							(start 0.2032 0.3048)
							(mid 0.275042 0.275042)
							(end 0.3048 0.2032)
						)
					)
					(width 0)
					(fill yes)
				)
			)
		)
		(pad "2" smd custom
			(at 0 0.4445)
			(size 0.1524 0.1524)
			(layers "F.Cu" "F.Mask" "F.Paste")
			(net "GND")
			(options
				(clearance outline)
				(anchor circle)
			)
			(primitives
				(gr_poly
					(pts
						(arc
							(start 0.3048 -0.2032)
							(mid 0.275042 -0.275042)
							(end 0.2032 -0.3048)
						)
						(arc
							(start -0.2032 -0.3048)
							(mid -0.275042 -0.275042)
							(end -0.3048 -0.2032)
						)
						(arc
							(start -0.3048 0.2032)
							(mid -0.275042 0.275042)
							(end -0.2032 0.3048)
						)
						(arc
							(start 0.2032 0.3048)
							(mid 0.275042 0.275042)
							(end 0.3048 0.2032)
						)
					)
					(width 0)
					(fill yes)
				)
			)
		)
	)
	(footprint ""
		(layer "F.Cu")
		(at 392.91895 -181.842918 180)
		(property "Reference" "C300"
			(at 0 0 180)
			(layer "F.SilkS")
			(hide yes)
			(effects
				(font
					(size 1.27 1.27)
				)
			)
		)
		(property "Value" "SC1U16V3KX-5GP"
			(at 0 -2.8194 180)
			(unlocked yes)
			(layer "F.Fab")
			(hide yes)
			(effects
				(font
					(size 1.016 1.016)
					(thickness 0.1524)
				)
			)
		)
		(property "Device Type" "C603H36"
			(at 0 -4.3434 180)
			(unlocked yes)
			(layer "F.Fab")
			(hide yes)
			(effects
				(font
					(size 1.016 1.016)
					(thickness 0.1524)
				)
			)
		)
		(duplicate_pad_numbers_are_jumpers no)
		(fp_line
			(start 0.508 0)
			(end -0.508 0)
			(stroke
				(width 0.2032)
				(type default)
			)
			(layer "F.SilkS")
		)
		(fp_rect
			(start -0.5842 1.3335)
			(end 0.5842 -1.3335)
			(stroke
				(width 0)
				(type default)
			)
			(fill no)
			(layer "F.CrtYd")
		)
		(fp_rect
			(start -0.5842 1.3335)
			(end 0.5842 -1.3335)
			(stroke
				(width 0)
				(type default)
			)
			(fill no)
			(layer "F.Fab")
		)
		(pad "1" smd custom
			(at 0 -0.762 180)
			(size 0.2159 0.2159)
			(layers "F.Cu" "F.Mask" "F.Paste")
			(net "P5V_HDD20")
			(options
				(clearance outline)
				(anchor circle)
			)
			(primitives
				(gr_poly
					(pts
						(arc
							(start -0.3302 -0.4318)
							(mid -0.402042 -0.402042)
							(end -0.4318 -0.3302)
						)
						(arc
							(start -0.4318 0.3302)
							(mid -0.402042 0.402042)
							(end -0.3302 0.4318)
						)
						(arc
							(start 0.3302 0.4318)
							(mid 0.402042 0.402042)
							(end 0.4318 0.3302)
						)
						(arc
							(start 0.4318 -0.3302)
							(mid 0.402042 -0.402042)
							(end 0.3302 -0.4318)
						)
					)
					(width 0)
					(fill yes)
				)
			)
		)
		(pad "2" smd custom
			(at 0 0.762 180)
			(size 0.2159 0.2159)
			(layers "F.Cu" "F.Mask" "F.Paste")
			(net "GND")
			(options
				(clearance outline)
				(anchor circle)
			)
			(primitives
				(gr_poly
					(pts
						(arc
							(start -0.3302 -0.4318)
							(mid -0.402042 -0.402042)
							(end -0.4318 -0.3302)
						)
						(arc
							(start -0.4318 0.3302)
							(mid -0.402042 0.402042)
							(end -0.3302 0.4318)
						)
						(arc
							(start 0.3302 0.4318)
							(mid 0.402042 0.402042)
							(end 0.4318 0.3302)
						)
						(arc
							(start 0.4318 -0.3302)
							(mid 0.402042 -0.402042)
							(end 0.3302 -0.4318)
						)
					)
					(width 0)
					(fill yes)
				)
			)
		)
	)
	(footprint ""
		(layer "F.Cu")
		(at 113.150396 -160.633918)
		(property "Reference" "R492"
			(at 0 0 0)
			(layer "F.SilkS")
			(hide yes)
			(effects
				(font
					(size 1.27 1.27)
				)
			)
		)
		(property "Value" "0R2J-2-GP"
			(at 0.064008 -3.993896 0)
			(unlocked yes)
			(layer "F.Fab")
			(hide yes)
			(effects
				(font
					(size 1.016 1.016)
					(thickness 0.1524)
				)
			)
		)
		(property "Device Type" "R402H16"
			(at 0.064008 -5.517896 0)
			(unlocked yes)
			(layer "F.Fab")
			(hide yes)
			(effects
				(font
					(size 1.016 1.016)
					(thickness 0.1524)
				)
			)
		)
		(duplicate_pad_numbers_are_jumpers no)
		(fp_line
			(start -0.508 -0.9398)
			(end -0.508 0.9398)
			(stroke
				(width 0.1524)
				(type default)
			)
			(layer "F.SilkS")
		)
		(fp_line
			(start 0.508 -0.9398)
			(end -0.508 -0.9398)
			(stroke
				(width 0.1524)
				(type default)
			)
			(layer "F.SilkS")
		)
		(fp_rect
			(start -0.508 0.9398)
			(end 0.508 -0.9398)
			(stroke
				(width 0)
				(type default)
			)
			(fill no)
			(layer "F.CrtYd")
		)
		(fp_rect
			(start -0.508 0.9398)
			(end 0.508 -0.9398)
			(stroke
				(width 0)
				(type default)
			)
			(fill no)
			(layer "F.Fab")
		)
		(pad "1" smd custom
			(at 0 -0.4445)
			(size 0.1397 0.1397)
			(layers "F.Cu" "F.Mask" "F.Paste")
			(net "SW_HDD_G15")
			(options
				(clearance outline)
				(anchor circle)
			)
			(primitives
				(gr_poly
					(pts
						(arc
							(start -0.1778 -0.2794)
							(mid -0.249642 -0.249642)
							(end -0.2794 -0.1778)
						)
						(arc
							(start -0.2794 0.1778)
							(mid -0.249642 0.249642)
							(end -0.1778 0.2794)
						)
						(arc
							(start 0.1778 0.2794)
							(mid 0.249642 0.249642)
							(end 0.2794 0.1778)
						)
						(arc
							(start 0.2794 -0.1778)
							(mid 0.249642 -0.249642)
							(end 0.1778 -0.2794)
						)
					)
					(width 0)
					(fill yes)
				)
			)
		)
		(pad "2" smd custom
			(at 0 0.4445)
			(size 0.1397 0.1397)
			(layers "F.Cu" "F.Mask" "F.Paste")
			(net "SW_HDD_R15")
			(options
				(clearance outline)
				(anchor circle)
			)
			(primitives
				(gr_poly
					(pts
						(arc
							(start -0.1778 -0.2794)
							(mid -0.249642 -0.249642)
							(end -0.2794 -0.1778)
						)
						(arc
							(start -0.2794 0.1778)
							(mid -0.249642 0.249642)
							(end -0.1778 0.2794)
						)
						(arc
							(start 0.1778 0.2794)
							(mid 0.249642 0.249642)
							(end 0.2794 0.1778)
						)
						(arc
							(start 0.2794 -0.1778)
							(mid 0.249642 -0.249642)
							(end 0.1778 -0.2794)
						)
					)
					(width 0)
					(fill yes)
				)
			)
		)
	)
	(footprint ""
		(layer "F.Cu")
		(at 83.784948 -55.285894 180)
		(property "Reference" "Q155"
			(at 0 0 180)
			(layer "F.SilkS")
			(hide yes)
			(effects
				(font
					(size 1.27 1.27)
				)
			)
		)
		(property "Value" "AO4406AL-GP"
			(at -3.707384 -1.5367 180)
			(unlocked yes)
			(layer "F.Fab")
			(hide yes)
			(effects
				(font
					(size 1.016 1.016)
					(thickness 0.1524)
				)
			)
		)
		(property "Device Type" "SOIC8H69"
			(at -3.707384 -3.0607 180)
			(unlocked yes)
			(layer "F.Fab")
			(hide yes)
			(effects
				(font
					(size 1.016 1.016)
					(thickness 0.1524)
				)
			)
		)
		(duplicate_pad_numbers_are_jumpers no)
		(fp_line
			(start 2.1336 1.4224)
			(end 2.1336 -1.4224)
			(stroke
				(width 0.1524)
				(type default)
			)
			(layer "F.SilkS")
		)
		(fp_line
			(start 2.1336 -1.4224)
			(end -2.7432 -1.4224)
			(stroke
				(width 0.1524)
				(type default)
			)
			(layer "F.SilkS")
		)
		(fp_line
			(start -2.1844 -0.0508)
			(end -2.7178 0.508)
			(stroke
				(width 0.1524)
				(type default)
			)
			(layer "F.SilkS")
		)
		(fp_line
			(start -2.6289 3.4417)
			(end -2.6289 1.4732)
			(stroke
				(width 0.381)
				(type default)
			)
			(layer "F.SilkS")
		)
		(fp_line
			(start -2.7178 -0.508)
			(end -2.1844 -0.0508)
			(stroke
				(width 0.1524)
				(type default)
			)
			(layer "F.SilkS")
		)
		(fp_line
			(start -2.7432 1.4224)
			(end 2.1336 1.4224)
			(stroke
				(width 0.1524)
				(type default)
			)
			(layer "F.SilkS")
		)
		(fp_line
			(start -2.7432 1.4224)
			(end -2.6416 1.4224)
			(stroke
				(width 0.1524)
				(type default)
			)
			(layer "F.SilkS")
		)
		(fp_line
			(start -2.7432 -1.4224)
			(end -2.7432 1.4224)
			(stroke
				(width 0.1524)
				(type default)
			)
			(layer "F.SilkS")
		)
		(fp_poly
			(pts
				(xy -2.2098 -1.4224) (xy -2.2098 1.4224) (xy 2.2098 1.4224) (xy 2.2098 -1.4224)
			)
			(stroke
				(width 0)
				(type default)
			)
			(fill yes)
			(layer "F.SilkS")
		)
		(fp_rect
			(start -2.450084 2.999994)
			(end 2.450084 -2.999994)
			(stroke
				(width 0)
				(type default)
			)
			(fill no)
			(layer "F.CrtYd")
		)
		(fp_poly
			(pts
				(xy -2.8194 3.6322) (xy -2.8194 -3.6322) (xy 2.8194 -3.6322) (xy 2.8194 1.18364) (xy 2.450084 1.18364)
				(xy 2.450084 -2.999994) (xy -2.450084 -2.999994) (xy -2.450084 2.999994) (xy 2.450084 2.999994)
				(xy 2.450084 1.18618) (xy 2.8194 1.18618) (xy 2.8194 3.6322)
			)
			(stroke
				(width 0)
				(type default)
			)
			(fill no)
			(layer "F.CrtYd")
		)
		(fp_rect
			(start -2.8194 3.6322)
			(end 2.8194 -3.6322)
			(stroke
				(width 0)
				(type default)
			)
			(fill no)
			(layer "F.Fab")
		)
		(pad "1" smd rect
			(at -1.905 2.54 180)
			(size 0.635 1.651)
			(layers "F.Cu" "F.Mask" "F.Paste")
			(net "P5V_HDD26")
		)
		(pad "2" smd rect
			(at -0.635 2.54 180)
			(size 0.635 1.651)
			(layers "F.Cu" "F.Mask" "F.Paste")
			(net "P5V_HDD26")
		)
		(pad "3" smd rect
			(at 0.635 2.54 180)
			(size 0.635 1.651)
			(layers "F.Cu" "F.Mask" "F.Paste")
			(net "P5V_HDD26")
		)
		(pad "4" smd rect
			(at 1.905 2.54 180)
			(size 0.635 1.651)
			(layers "F.Cu" "F.Mask" "F.Paste")
			(net "SW_HDD_P26")
		)
		(pad "5" smd rect
			(at 1.905 -2.54 180)
			(size 0.635 1.651)
			(layers "F.Cu" "F.Mask" "F.Paste")
			(net "P5V_A_2")
		)
		(pad "6" smd rect
			(at 0.635 -2.54 180)
			(size 0.635 1.651)
			(layers "F.Cu" "F.Mask" "F.Paste")
			(net "P5V_A_2")
		)
		(pad "7" smd rect
			(at -0.635 -2.54 180)
			(size 0.635 1.651)
			(layers "F.Cu" "F.Mask" "F.Paste")
			(net "P5V_A_2")
		)
		(pad "8" smd rect
			(at -1.905 -2.54 180)
			(size 0.635 1.651)
			(layers "F.Cu" "F.Mask" "F.Paste")
			(net "P5V_A_2")
		)
	)
	(footprint ""
		(layer "F.Cu")
		(at 318.600074 -242.745514 180)
		(property "Reference" "Q233"
			(at 0 0 180)
			(layer "F.SilkS")
			(hide yes)
			(effects
				(font
					(size 1.27 1.27)
				)
			)
		)
		(property "Value" "2N7002K-2-GP"
			(at 0.127 -8.9662 180)
			(unlocked yes)
			(layer "F.Fab")
			(hide yes)
			(effects
				(font
					(size 1.016 1.016)
					(thickness 0.1524)
				)
			)
		)
		(property "Device Type" "SOT23DGS2D4H44"
			(at 0.127 -10.4902 180)
			(unlocked yes)
			(layer "F.Fab")
			(hide yes)
			(effects
				(font
					(size 1.016 1.016)
					(thickness 0.1524)
				)
			)
		)
		(duplicate_pad_numbers_are_jumpers no)
		(fp_line
			(start 1.651 1.778)
			(end 1.651 -1.778)
			(stroke
				(width 0.1524)
				(type default)
			)
			(layer "F.SilkS")
		)
		(fp_line
			(start 1.651 -1.778)
			(end -1.651 -1.778)
			(stroke
				(width 0.1524)
				(type default)
			)
			(layer "F.SilkS")
		)
		(fp_line
			(start -1.651 1.778)
			(end 1.651 1.778)
			(stroke
				(width 0.1524)
				(type default)
			)
			(layer "F.SilkS")
		)
		(fp_line
			(start -1.651 -1.778)
			(end -1.651 1.778)
			(stroke
				(width 0.1524)
				(type default)
			)
			(layer "F.SilkS")
		)
		(fp_poly
			(pts
				(xy -1.778 1.8796) (xy -1.778 -1.8796) (xy 1.778 -1.8796) (xy 1.778 1.8796)
			)
			(stroke
				(width 0)
				(type default)
			)
			(fill no)
			(layer "F.CrtYd")
		)
		(fp_poly
			(pts
				(xy -1.778 1.8796) (xy -1.778 -1.8796) (xy 1.778 -1.8796) (xy 1.778 1.8796)
			)
			(stroke
				(width 0)
				(type default)
			)
			(fill no)
			(layer "F.Fab")
		)
		(pad "D" smd custom
			(at 0 -0.9525 180)
			(size 0.1905 0.1905)
			(layers "F.Cu" "F.Mask" "F.Paste")
			(net "FLT_HDD6_N")
			(options
				(clearance outline)
				(anchor circle)
			)
			(primitives
				(gr_poly
					(pts
						(arc
							(start -0.1778 0.5715)
							(mid -0.321484 0.511984)
							(end -0.381 0.3683)
						)
						(arc
							(start -0.381 -0.3683)
							(mid -0.321484 -0.511984)
							(end -0.1778 -0.5715)
						)
						(arc
							(start 0.1778 -0.5715)
							(mid 0.321484 -0.511984)
							(end 0.381 -0.3683)
						)
						(arc
							(start 0.381 0.3683)
							(mid 0.321484 0.511984)
							(end 0.1778 0.5715)
						)
					)
					(width 0)
					(fill yes)
				)
			)
		)
		(pad "G" smd custom
			(at -0.98425 0.9525 180)
			(size 0.1905 0.1905)
			(layers "F.Cu" "F.Mask" "F.Paste")
			(net "DRIVE_A_6_FLT_LED")
			(options
				(clearance outline)
				(anchor circle)
			)
			(primitives
				(gr_poly
					(pts
						(arc
							(start -0.1778 0.5715)
							(mid -0.321484 0.511984)
							(end -0.381 0.3683)
						)
						(arc
							(start -0.381 -0.3683)
							(mid -0.321484 -0.511984)
							(end -0.1778 -0.5715)
						)
						(arc
							(start 0.1778 -0.5715)
							(mid 0.321484 -0.511984)
							(end 0.381 -0.3683)
						)
						(arc
							(start 0.381 0.3683)
							(mid 0.321484 0.511984)
							(end 0.1778 0.5715)
						)
					)
					(width 0)
					(fill yes)
				)
			)
		)
		(pad "S" smd custom
			(at 0.98425 0.9525 180)
			(size 0.1905 0.1905)
			(layers "F.Cu" "F.Mask" "F.Paste")
			(net "GND")
			(options
				(clearance outline)
				(anchor circle)
			)
			(primitives
				(gr_poly
					(pts
						(arc
							(start -0.1778 0.5715)
							(mid -0.321484 0.511984)
							(end -0.381 0.3683)
						)
						(arc
							(start -0.381 -0.3683)
							(mid -0.321484 -0.511984)
							(end -0.1778 -0.5715)
						)
						(arc
							(start 0.1778 -0.5715)
							(mid 0.321484 -0.511984)
							(end 0.381 -0.3683)
						)
						(arc
							(start 0.381 0.3683)
							(mid 0.321484 0.511984)
							(end 0.1778 0.5715)
						)
					)
					(width 0)
					(fill yes)
				)
			)
		)
	)
	(footprint ""
		(layer "F.Cu")
		(at 222.87103 -357.961438)
		(property "Reference" "R425"
			(at 0 0 0)
			(layer "F.SilkS")
			(hide yes)
			(effects
				(font
					(size 1.27 1.27)
				)
			)
		)
		(property "Value" "1KR2F-3-GP"
			(at 0.064008 -3.993896 0)
			(unlocked yes)
			(layer "F.Fab")
			(hide yes)
			(effects
				(font
					(size 1.016 1.016)
					(thickness 0.1524)
				)
			)
		)
		(property "Device Type" "R402H16"
			(at 0.064008 -5.517896 0)
			(unlocked yes)
			(layer "F.Fab")
			(hide yes)
			(effects
				(font
					(size 1.016 1.016)
					(thickness 0.1524)
				)
			)
		)
		(duplicate_pad_numbers_are_jumpers no)
		(fp_line
			(start -0.508 -0.9398)
			(end -0.508 0.9398)
			(stroke
				(width 0.1524)
				(type default)
			)
			(layer "F.SilkS")
		)
		(fp_line
			(start 0.508 -0.9398)
			(end -0.508 -0.9398)
			(stroke
				(width 0.1524)
				(type default)
			)
			(layer "F.SilkS")
		)
		(fp_rect
			(start -0.508 0.9398)
			(end 0.508 -0.9398)
			(stroke
				(width 0)
				(type default)
			)
			(fill no)
			(layer "F.CrtYd")
		)
		(fp_rect
			(start -0.508 0.9398)
			(end 0.508 -0.9398)
			(stroke
				(width 0)
				(type default)
			)
			(fill no)
			(layer "F.Fab")
		)
		(pad "1" smd custom
			(at 0 -0.4445)
			(size 0.1397 0.1397)
			(layers "F.Cu" "F.Mask" "F.Paste")
			(net "P3V3_STBY_A")
			(options
				(clearance outline)
				(anchor circle)
			)
			(primitives
				(gr_poly
					(pts
						(arc
							(start -0.1778 -0.2794)
							(mid -0.249642 -0.249642)
							(end -0.2794 -0.1778)
						)
						(arc
							(start -0.2794 0.1778)
							(mid -0.249642 0.249642)
							(end -0.1778 0.2794)
						)
						(arc
							(start 0.1778 0.2794)
							(mid 0.249642 0.249642)
							(end 0.2794 0.1778)
						)
						(arc
							(start 0.2794 -0.1778)
							(mid 0.249642 -0.249642)
							(end 0.1778 -0.2794)
						)
					)
					(width 0)
					(fill yes)
				)
			)
		)
		(pad "2" smd custom
			(at 0 0.4445)
			(size 0.1397 0.1397)
			(layers "F.Cu" "F.Mask" "F.Paste")
			(net "I2C_CLIP_A_SDA")
			(options
				(clearance outline)
				(anchor circle)
			)
			(primitives
				(gr_poly
					(pts
						(arc
							(start -0.1778 -0.2794)
							(mid -0.249642 -0.249642)
							(end -0.2794 -0.1778)
						)
						(arc
							(start -0.2794 0.1778)
							(mid -0.249642 0.249642)
							(end -0.1778 0.2794)
						)
						(arc
							(start 0.1778 0.2794)
							(mid 0.249642 0.249642)
							(end 0.2794 0.1778)
						)
						(arc
							(start 0.2794 -0.1778)
							(mid 0.249642 -0.249642)
							(end 0.1778 -0.2794)
						)
					)
					(width 0)
					(fill yes)
				)
			)
		)
	)
	(footprint ""
		(layer "F.Cu")
		(at 402.553932 -130.400298 -90)
		(property "Reference" "R540"
			(at 0 0 270)
			(layer "F.SilkS")
			(hide yes)
			(effects
				(font
					(size 1.27 1.27)
				)
			)
		)
		(property "Value" "4K7R2J-2-GP"
			(at 0.064008 -3.993896 270)
			(unlocked yes)
			(layer "F.Fab")
			(hide yes)
			(effects
				(font
					(size 1.016 1.016)
					(thickness 0.1524)
				)
			)
		)
		(property "Device Type" "R402H16"
			(at 0.064008 -5.517896 270)
			(unlocked yes)
			(layer "F.Fab")
			(hide yes)
			(effects
				(font
					(size 1.016 1.016)
					(thickness 0.1524)
				)
			)
		)
		(duplicate_pad_numbers_are_jumpers no)
		(fp_line
			(start -0.508 -0.9398)
			(end -0.508 0.9398)
			(stroke
				(width 0.1524)
				(type default)
			)
			(layer "F.SilkS")
		)
		(fp_line
			(start 0.508 -0.9398)
			(end -0.508 -0.9398)
			(stroke
				(width 0.1524)
				(type default)
			)
			(layer "F.SilkS")
		)
		(fp_rect
			(start -0.508 0.9398)
			(end 0.508 -0.9398)
			(stroke
				(width 0)
				(type default)
			)
			(fill no)
			(layer "F.CrtYd")
		)
		(fp_rect
			(start -0.508 0.9398)
			(end 0.508 -0.9398)
			(stroke
				(width 0)
				(type default)
			)
			(fill no)
			(layer "F.Fab")
		)
		(pad "1" smd custom
			(at 0 -0.4445 270)
			(size 0.1397 0.1397)
			(layers "F.Cu" "F.Mask" "F.Paste")
			(net "DRIVE_A_21_ACT")
			(options
				(clearance outline)
				(anchor circle)
			)
			(primitives
				(gr_poly
					(pts
						(arc
							(start -0.1778 -0.2794)
							(mid -0.249642 -0.249642)
							(end -0.2794 -0.1778)
						)
						(arc
							(start -0.2794 0.1778)
							(mid -0.249642 0.249642)
							(end -0.1778 0.2794)
						)
						(arc
							(start 0.1778 0.2794)
							(mid 0.249642 0.249642)
							(end 0.2794 0.1778)
						)
						(arc
							(start 0.2794 -0.1778)
							(mid 0.249642 -0.249642)
							(end 0.1778 -0.2794)
						)
					)
					(width 0)
					(fill yes)
				)
			)
		)
		(pad "2" smd custom
			(at 0 0.4445 270)
			(size 0.1397 0.1397)
			(layers "F.Cu" "F.Mask" "F.Paste")
			(net "GND")
			(options
				(clearance outline)
				(anchor circle)
			)
			(primitives
				(gr_poly
					(pts
						(arc
							(start -0.1778 -0.2794)
							(mid -0.249642 -0.249642)
							(end -0.2794 -0.1778)
						)
						(arc
							(start -0.2794 0.1778)
							(mid -0.249642 0.249642)
							(end -0.1778 0.2794)
						)
						(arc
							(start 0.1778 0.2794)
							(mid 0.249642 0.249642)
							(end 0.2794 0.1778)
						)
						(arc
							(start 0.2794 -0.1778)
							(mid 0.249642 -0.249642)
							(end 0.1778 -0.2794)
						)
					)
					(width 0)
					(fill yes)
				)
			)
		)
	)
	(footprint ""
		(layer "F.Cu")
		(at 427.009052 -180.826918 180)
		(property "Reference" "C314"
			(at 0 0 180)
			(layer "F.SilkS")
			(hide yes)
			(effects
				(font
					(size 1.27 1.27)
				)
			)
		)
		(property "Value" "SC10U16V6KX-2GP"
			(at -0.0762 -5.1308 180)
			(unlocked yes)
			(layer "F.Fab")
			(hide yes)
			(effects
				(font
					(size 1.016 1.016)
					(thickness 0.1524)
				)
			)
		)
		(property "Device Type" "C1206H71"
			(at -0.127 -6.6548 180)
			(unlocked yes)
			(layer "F.Fab")
			(hide yes)
			(effects
				(font
					(size 1.016 1.016)
					(thickness 0.1524)
				)
			)
		)
		(duplicate_pad_numbers_are_jumpers no)
		(fp_line
			(start 1.016 2.2352)
			(end -1.016 2.2352)
			(stroke
				(width 0.1524)
				(type default)
			)
			(layer "F.SilkS")
		)
		(fp_line
			(start 1.016 0.8382)
			(end 1.016 2.2352)
			(stroke
				(width 0.1524)
				(type default)
			)
			(layer "F.SilkS")
		)
		(fp_line
			(start 1.016 -2.2352)
			(end 1.016 -0.8382)
			(stroke
				(width 0.1524)
				(type default)
			)
			(layer "F.SilkS")
		)
		(fp_line
			(start -1.016 2.2352)
			(end -1.016 0.8382)
			(stroke
				(width 0.1524)
				(type default)
			)
			(layer "F.SilkS")
		)
		(fp_line
			(start -1.016 -0.8382)
			(end -1.016 -2.2352)
			(stroke
				(width 0.1524)
				(type default)
			)
			(layer "F.SilkS")
		)
		(fp_line
			(start -1.016 -2.2352)
			(end 1.016 -2.2352)
			(stroke
				(width 0.1524)
				(type default)
			)
			(layer "F.SilkS")
		)
		(fp_rect
			(start -1.0922 2.3114)
			(end 1.0922 -2.3114)
			(stroke
				(width 0)
				(type default)
			)
			(fill no)
			(layer "F.CrtYd")
		)
		(fp_poly
			(pts
				(xy 1.0922 -2.3114) (xy 1.0922 2.3114) (xy -1.0922 2.3114) (xy -1.0922 -2.3114)
			)
			(stroke
				(width 0)
				(type default)
			)
			(fill no)
			(layer "F.Fab")
		)
		(pad "1" smd rect
			(at 0 -1.397 180)
			(size 1.651 1.27)
			(layers "F.Cu" "F.Mask" "F.Paste")
			(net "P5V_HDD21")
		)
		(pad "2" smd rect
			(at 0 1.397 180)
			(size 1.651 1.27)
			(layers "F.Cu" "F.Mask" "F.Paste")
			(net "GND")
		)
	)
	(footprint ""
		(layer "F.Cu")
		(at 48.424846 -46.649894 180)
		(property "Reference" "D25"
			(at 0 0 180)
			(layer "F.SilkS")
			(hide yes)
			(effects
				(font
					(size 1.27 1.27)
				)
			)
		)
		(property "Value" "RB551V30-GP"
			(at 0 -6.7818 180)
			(unlocked yes)
			(layer "F.Fab")
			(hide yes)
			(effects
				(font
					(size 1.016 1.016)
					(thickness 0.1524)
				)
			)
		)
		(property "Device Type" "SOD323AKH38"
			(at 0 -8.6868 180)
			(unlocked yes)
			(layer "F.Fab")
			(hide yes)
			(effects
				(font
					(size 1.016 1.016)
					(thickness 0.1524)
				)
			)
		)
		(duplicate_pad_numbers_are_jumpers no)
		(fp_line
			(start 0.889 2.159)
			(end -0.889 2.159)
			(stroke
				(width 0.1524)
				(type default)
			)
			(layer "F.SilkS")
		)
		(fp_line
			(start 0.889 -1.9304)
			(end 0.889 2.159)
			(stroke
				(width 0.1524)
				(type default)
			)
			(layer "F.SilkS")
		)
		(fp_line
			(start 0.762 2.0574)
			(end -0.762 2.0574)
			(stroke
				(width 0.508)
				(type default)
			)
			(layer "F.SilkS")
		)
		(fp_line
			(start -0.889 2.159)
			(end -0.889 -1.9304)
			(stroke
				(width 0.1524)
				(type default)
			)
			(layer "F.SilkS")
		)
		(fp_line
			(start -0.889 -1.9304)
			(end 0.889 -1.9304)
			(stroke
				(width 0.1524)
				(type default)
			)
			(layer "F.SilkS")
		)
		(fp_rect
			(start -1.016 2.3114)
			(end 1.016 -2.0066)
			(stroke
				(width 0)
				(type default)
			)
			(fill no)
			(layer "F.CrtYd")
		)
		(fp_poly
			(pts
				(xy -1.016 -2.0066) (xy 1.016 -2.0066) (xy 1.016 2.3114) (xy -1.016 2.3114)
			)
			(stroke
				(width 0)
				(type default)
			)
			(fill no)
			(layer "F.Fab")
		)
		(pad "A" smd rect
			(at 0 -1.143 180)
			(size 0.5588 1.016)
			(layers "F.Cu" "F.Mask" "F.Paste")
			(net "SW_HDD_R25")
		)
		(pad "K" smd rect
			(at 0 1.143 180)
			(size 0.5588 1.016)
			(layers "F.Cu" "F.Mask" "F.Paste")
			(net "SW_HDD_N25")
		)
	)
	(footprint ""
		(layer "F.Cu")
		(at 333.502 -188.954918 180)
		(property "Reference" "C280"
			(at 0 0 180)
			(layer "F.SilkS")
			(hide yes)
			(effects
				(font
					(size 1.27 1.27)
				)
			)
		)
		(property "Value" "SC4D7U25V5KX-1-GP"
			(at -0.0762 -6.1214 180)
			(unlocked yes)
			(layer "F.Fab")
			(hide yes)
			(effects
				(font
					(size 1.016 1.016)
					(thickness 0.1524)
				)
			)
		)
		(property "Device Type" "C805H58"
			(at -0.0762 -8.1534 180)
			(unlocked yes)
			(layer "F.Fab")
			(hide yes)
			(effects
				(font
					(size 1.016 1.016)
					(thickness 0.1524)
				)
			)
		)
		(duplicate_pad_numbers_are_jumpers no)
		(fp_line
			(start 0.635 0)
			(end -0.635 0)
			(stroke
				(width 0.508)
				(type default)
			)
			(layer "F.SilkS")
		)
		(fp_rect
			(start -0.9652 1.778)
			(end 0.9652 -1.778)
			(stroke
				(width 0)
				(type default)
			)
			(fill no)
			(layer "F.CrtYd")
		)
		(fp_poly
			(pts
				(xy -0.9652 -1.778) (xy 0.9652 -1.778) (xy 0.9652 1.778) (xy -0.9652 1.778)
			)
			(stroke
				(width 0)
				(type default)
			)
			(fill no)
			(layer "F.Fab")
		)
		(pad "1" smd rect
			(at 0 -0.9652 180)
			(size 1.397 1.143)
			(layers "F.Cu" "F.Mask" "F.Paste")
			(net "P12V_HDD18")
		)
		(pad "2" smd rect
			(at 0 0.9652 180)
			(size 1.397 1.143)
			(layers "F.Cu" "F.Mask" "F.Paste")
			(net "GND")
		)
	)
	(footprint ""
		(layer "F.Cu")
		(at 69.619622 -185.06059)
		(property "Reference" "Q265"
			(at 0 0 0)
			(layer "F.SilkS")
			(hide yes)
			(effects
				(font
					(size 1.27 1.27)
				)
			)
		)
		(property "Value" "SSM3K324R-GP"
			(at 0.127 -8.9662 0)
			(unlocked yes)
			(layer "F.Fab")
			(hide yes)
			(effects
				(font
					(size 1.016 1.016)
					(thickness 0.1524)
				)
			)
		)
		(property "Device Type" "SOT23DGS2D4H35"
			(at 0.127 -10.4902 0)
			(unlocked yes)
			(layer "F.Fab")
			(hide yes)
			(effects
				(font
					(size 1.016 1.016)
					(thickness 0.1524)
				)
			)
		)
		(duplicate_pad_numbers_are_jumpers no)
		(fp_line
			(start -1.651 -1.778)
			(end -1.651 1.778)
			(stroke
				(width 0.1524)
				(type default)
			)
			(layer "F.SilkS")
		)
		(fp_line
			(start -1.651 1.778)
			(end 1.651 1.778)
			(stroke
				(width 0.1524)
				(type default)
			)
			(layer "F.SilkS")
		)
		(fp_line
			(start 1.651 -1.778)
			(end -1.651 -1.778)
			(stroke
				(width 0.1524)
				(type default)
			)
			(layer "F.SilkS")
		)
		(fp_line
			(start 1.651 1.778)
			(end 1.651 -1.778)
			(stroke
				(width 0.1524)
				(type default)
			)
			(layer "F.SilkS")
		)
		(fp_poly
			(pts
				(xy -1.778 1.8796) (xy -1.778 -1.8796) (xy 1.778 -1.8796) (xy 1.778 1.8796)
			)
			(stroke
				(width 0)
				(type default)
			)
			(fill no)
			(layer "F.CrtYd")
		)
		(fp_poly
			(pts
				(xy -1.778 1.8796) (xy -1.778 -1.8796) (xy 1.778 -1.8796) (xy 1.778 1.8796)
			)
			(stroke
				(width 0)
				(type default)
			)
			(fill no)
			(layer "F.Fab")
		)
		(pad "D" smd custom
			(at 0 -0.9525)
			(size 0.1905 0.1905)
			(layers "F.Cu" "F.Mask" "F.Paste")
			(net "DRV_ACT_2_N")
			(options
				(clearance outline)
				(anchor circle)
			)
			(primitives
				(gr_poly
					(pts
						(arc
							(start -0.1778 0.5715)
							(mid -0.321484 0.511984)
							(end -0.381 0.3683)
						)
						(arc
							(start -0.381 -0.3683)
							(mid -0.321484 -0.511984)
							(end -0.1778 -0.5715)
						)
						(arc
							(start 0.1778 -0.5715)
							(mid 0.321484 -0.511984)
							(end 0.381 -0.3683)
						)
						(arc
							(start 0.381 0.3683)
							(mid 0.321484 0.511984)
							(end 0.1778 0.5715)
						)
					)
					(width 0)
					(fill yes)
				)
			)
		)
		(pad "G" smd custom
			(at -0.98425 0.9525)
			(size 0.1905 0.1905)
			(layers "F.Cu" "F.Mask" "F.Paste")
			(net "DRIVE_A_2_ACT")
			(options
				(clearance outline)
				(anchor circle)
			)
			(primitives
				(gr_poly
					(pts
						(arc
							(start -0.1778 0.5715)
							(mid -0.321484 0.511984)
							(end -0.381 0.3683)
						)
						(arc
							(start -0.381 -0.3683)
							(mid -0.321484 -0.511984)
							(end -0.1778 -0.5715)
						)
						(arc
							(start 0.1778 -0.5715)
							(mid 0.321484 -0.511984)
							(end 0.381 -0.3683)
						)
						(arc
							(start 0.381 0.3683)
							(mid 0.321484 0.511984)
							(end 0.1778 0.5715)
						)
					)
					(width 0)
					(fill yes)
				)
			)
		)
		(pad "S" smd custom
			(at 0.98425 0.9525)
			(size 0.1905 0.1905)
			(layers "F.Cu" "F.Mask" "F.Paste")
			(net "GND")
			(options
				(clearance outline)
				(anchor circle)
			)
			(primitives
				(gr_poly
					(pts
						(arc
							(start -0.1778 0.5715)
							(mid -0.321484 0.511984)
							(end -0.381 0.3683)
						)
						(arc
							(start -0.381 -0.3683)
							(mid -0.321484 -0.511984)
							(end -0.1778 -0.5715)
						)
						(arc
							(start 0.1778 -0.5715)
							(mid 0.321484 -0.511984)
							(end 0.381 -0.3683)
						)
						(arc
							(start 0.381 0.3683)
							(mid 0.321484 0.511984)
							(end 0.1778 0.5715)
						)
					)
					(width 0)
					(fill yes)
				)
			)
		)
	)
	(footprint ""
		(layer "F.Cu")
		(at 64.013334 -44.219368 90)
		(property "Reference" "C363"
			(at 0 0 90)
			(layer "F.SilkS")
			(hide yes)
			(effects
				(font
					(size 1.27 1.27)
				)
			)
		)
		(property "Value" "SCD01U16V1KX-GP"
			(at -2.8321 -1.7399 90)
			(unlocked yes)
			(layer "F.Fab")
			(hide yes)
			(effects
				(font
					(size 1.016 1.016)
					(thickness 0.1524)
				)
			)
		)
		(property "Device Type" "C0201H13"
			(at -2.8321 -3.2639 90)
			(unlocked yes)
			(layer "F.Fab")
			(hide yes)
			(effects
				(font
					(size 1.016 1.016)
					(thickness 0.1524)
				)
			)
		)
		(duplicate_pad_numbers_are_jumpers no)
		(fp_rect
			(start -0.2794 0.6477)
			(end 0.2794 -0.6477)
			(stroke
				(width 0)
				(type default)
			)
			(fill no)
			(layer "F.CrtYd")
		)
		(fp_rect
			(start -0.2794 0.6477)
			(end 0.2794 -0.6477)
			(stroke
				(width 0)
				(type default)
			)
			(fill no)
			(layer "F.Fab")
		)
		(pad "1" smd custom
			(at 0 -0.2794 90)
			(size 0.0762 0.0762)
			(layers "F.Cu" "F.Mask" "F.Paste")
			(net "SAS_HDD_RX_N25")
			(options
				(clearance outline)
				(anchor circle)
			)
			(primitives
				(gr_poly
					(pts
						(arc
							(start 0.1524 -0.127)
							(mid 0.137521 -0.162921)
							(end 0.1016 -0.1778)
						)
						(arc
							(start -0.1016 -0.1778)
							(mid -0.137521 -0.162921)
							(end -0.1524 -0.127)
						)
						(arc
							(start -0.1524 0.127)
							(mid -0.137521 0.162921)
							(end -0.1016 0.1778)
						)
						(arc
							(start 0.1016 0.1778)
							(mid 0.137521 0.162921)
							(end 0.1524 0.127)
						)
					)
					(width 0)
					(fill yes)
				)
			)
		)
		(pad "2" smd custom
			(at 0 0.2794 90)
			(size 0.0762 0.0762)
			(layers "F.Cu" "F.Mask" "F.Paste")
			(net "PHY_SCC_A_TO_DRV_A_25_DN")
			(options
				(clearance outline)
				(anchor circle)
			)
			(primitives
				(gr_poly
					(pts
						(arc
							(start 0.1524 -0.127)
							(mid 0.137521 -0.162921)
							(end 0.1016 -0.1778)
						)
						(arc
							(start -0.1016 -0.1778)
							(mid -0.137521 -0.162921)
							(end -0.1524 -0.127)
						)
						(arc
							(start -0.1524 0.127)
							(mid -0.137521 0.162921)
							(end -0.1016 0.1778)
						)
						(arc
							(start 0.1016 0.1778)
							(mid 0.137521 0.162921)
							(end 0.1524 0.127)
						)
					)
					(width 0)
					(fill yes)
				)
			)
		)
	)
	(footprint ""
		(layer "F.Cu")
		(at 141.548866 -143.594074 180)
		(property "Reference" "R1040"
			(at 0 0 180)
			(layer "F.SilkS")
			(hide yes)
			(effects
				(font
					(size 1.27 1.27)
				)
			)
		)
		(property "Value" "0R2J-2-GP"
			(at 0.064008 -3.993896 180)
			(unlocked yes)
			(layer "F.Fab")
			(hide yes)
			(effects
				(font
					(size 1.016 1.016)
					(thickness 0.1524)
				)
			)
		)
		(property "Device Type" "R402H16"
			(at 0.064008 -5.517896 180)
			(unlocked yes)
			(layer "F.Fab")
			(hide yes)
			(effects
				(font
					(size 1.016 1.016)
					(thickness 0.1524)
				)
			)
		)
		(duplicate_pad_numbers_are_jumpers no)
		(fp_line
			(start 0.508 -0.9398)
			(end -0.508 -0.9398)
			(stroke
				(width 0.1524)
				(type default)
			)
			(layer "F.SilkS")
		)
		(fp_line
			(start -0.508 -0.9398)
			(end -0.508 0.9398)
			(stroke
				(width 0.1524)
				(type default)
			)
			(layer "F.SilkS")
		)
		(fp_rect
			(start -0.508 0.9398)
			(end 0.508 -0.9398)
			(stroke
				(width 0)
				(type default)
			)
			(fill no)
			(layer "F.CrtYd")
		)
		(fp_rect
			(start -0.508 0.9398)
			(end 0.508 -0.9398)
			(stroke
				(width 0)
				(type default)
			)
			(fill no)
			(layer "F.Fab")
		)
		(pad "1" smd custom
			(at 0 -0.4445 180)
			(size 0.1397 0.1397)
			(layers "F.Cu" "F.Mask" "F.Paste")
			(net "MB0_CM_ADR1_R")
			(options
				(clearance outline)
				(anchor circle)
			)
			(primitives
				(gr_poly
					(pts
						(arc
							(start -0.1778 -0.2794)
							(mid -0.249642 -0.249642)
							(end -0.2794 -0.1778)
						)
						(arc
							(start -0.2794 0.1778)
							(mid -0.249642 0.249642)
							(end -0.1778 0.2794)
						)
						(arc
							(start 0.1778 0.2794)
							(mid 0.249642 0.249642)
							(end 0.2794 0.1778)
						)
						(arc
							(start 0.2794 -0.1778)
							(mid 0.249642 -0.249642)
							(end 0.1778 -0.2794)
						)
					)
					(width 0)
					(fill yes)
				)
			)
		)
		(pad "2" smd custom
			(at 0 0.4445 180)
			(size 0.1397 0.1397)
			(layers "F.Cu" "F.Mask" "F.Paste")
			(net "AGND_CURRENT_MONOA")
			(options
				(clearance outline)
				(anchor circle)
			)
			(primitives
				(gr_poly
					(pts
						(arc
							(start -0.1778 -0.2794)
							(mid -0.249642 -0.249642)
							(end -0.2794 -0.1778)
						)
						(arc
							(start -0.2794 0.1778)
							(mid -0.249642 0.249642)
							(end -0.1778 0.2794)
						)
						(arc
							(start 0.1778 0.2794)
							(mid 0.249642 0.249642)
							(end 0.2794 0.1778)
						)
						(arc
							(start 0.2794 -0.1778)
							(mid 0.249642 -0.249642)
							(end 0.1778 -0.2794)
						)
					)
					(width 0)
					(fill yes)
				)
			)
		)
	)
	(footprint ""
		(layer "F.Cu")
		(at 224.572322 -152.19807 -90)
		(property "Reference" "TP207"
			(at 0 0 270)
			(layer "F.SilkS")
			(hide yes)
			(effects
				(font
					(size 1.27 1.27)
				)
			)
		)
		(property "Value" "TPAD32-GP"
			(at -0.0508 -1.6764 270)
			(unlocked yes)
			(layer "F.Fab")
			(hide yes)
			(effects
				(font
					(size 1.016 1.016)
					(thickness 0.1524)
				)
			)
		)
		(property "Device Type" "TPAD32"
			(at -0.0508 -3.2004 270)
			(unlocked yes)
			(layer "F.Fab")
			(hide yes)
			(effects
				(font
					(size 1.016 1.016)
					(thickness 0.1524)
				)
			)
		)
		(duplicate_pad_numbers_are_jumpers no)
		(fp_poly
			(pts
				(arc
					(start 0 -0.4064)
					(mid 0 0.4064)
					(end 0 -0.4064)
				)
			)
			(stroke
				(width 0)
				(type default)
			)
			(fill no)
			(layer "F.CrtYd")
		)
		(fp_poly
			(pts
				(arc
					(start 0 -0.7112)
					(mid 0 0.7112)
					(end 0 -0.7112)
				)
			)
			(stroke
				(width 0)
				(type default)
			)
			(fill no)
			(layer "F.Fab")
		)
		(pad "1" smd circle
			(at 0 0 270)
			(size 0.8128 0.8128)
			(layers "F.Cu" "F.Mask" "F.Paste")
			(net "TP_COMP_A_KR_P0_RX_DP")
		)
	)
	(footprint ""
		(layer "F.Cu")
		(at 237.561374 -231.659938 90)
		(property "Reference" "R17"
			(at 0 0 90)
			(layer "F.SilkS")
			(hide yes)
			(effects
				(font
					(size 1.27 1.27)
				)
			)
		)
		(property "Value" "100KR2F-L1-GP"
			(at 0.064008 -3.993896 90)
			(unlocked yes)
			(layer "F.Fab")
			(hide yes)
			(effects
				(font
					(size 1.016 1.016)
					(thickness 0.1524)
				)
			)
		)
		(property "Device Type" "R402H16"
			(at 0.064008 -5.517896 90)
			(unlocked yes)
			(layer "F.Fab")
			(hide yes)
			(effects
				(font
					(size 1.016 1.016)
					(thickness 0.1524)
				)
			)
		)
		(duplicate_pad_numbers_are_jumpers no)
		(fp_line
			(start 0.508 -0.9398)
			(end -0.508 -0.9398)
			(stroke
				(width 0.1524)
				(type default)
			)
			(layer "F.SilkS")
		)
		(fp_line
			(start -0.508 -0.9398)
			(end -0.508 0.9398)
			(stroke
				(width 0.1524)
				(type default)
			)
			(layer "F.SilkS")
		)
		(fp_rect
			(start -0.508 0.9398)
			(end 0.508 -0.9398)
			(stroke
				(width 0)
				(type default)
			)
			(fill no)
			(layer "F.CrtYd")
		)
		(fp_rect
			(start -0.508 0.9398)
			(end 0.508 -0.9398)
			(stroke
				(width 0)
				(type default)
			)
			(fill no)
			(layer "F.Fab")
		)
		(pad "1" smd custom
			(at 0 -0.4445 90)
			(size 0.1397 0.1397)
			(layers "F.Cu" "F.Mask" "F.Paste")
			(net "GPIO_VCC_U7")
			(options
				(clearance outline)
				(anchor circle)
			)
			(primitives
				(gr_poly
					(pts
						(arc
							(start -0.1778 -0.2794)
							(mid -0.249642 -0.249642)
							(end -0.2794 -0.1778)
						)
						(arc
							(start -0.2794 0.1778)
							(mid -0.249642 0.249642)
							(end -0.1778 0.2794)
						)
						(arc
							(start 0.1778 0.2794)
							(mid 0.249642 0.249642)
							(end 0.2794 0.1778)
						)
						(arc
							(start 0.2794 -0.1778)
							(mid 0.249642 -0.249642)
							(end 0.1778 -0.2794)
						)
					)
					(width 0)
					(fill yes)
				)
			)
		)
		(pad "2" smd custom
			(at 0 0.4445 90)
			(size 0.1397 0.1397)
			(layers "F.Cu" "F.Mask" "F.Paste")
			(net "GND")
			(options
				(clearance outline)
				(anchor circle)
			)
			(primitives
				(gr_poly
					(pts
						(arc
							(start -0.1778 -0.2794)
							(mid -0.249642 -0.249642)
							(end -0.2794 -0.1778)
						)
						(arc
							(start -0.2794 0.1778)
							(mid -0.249642 0.249642)
							(end -0.1778 0.2794)
						)
						(arc
							(start 0.1778 0.2794)
							(mid 0.249642 0.249642)
							(end 0.2794 0.1778)
						)
						(arc
							(start 0.2794 -0.1778)
							(mid 0.249642 -0.249642)
							(end 0.1778 -0.2794)
						)
					)
					(width 0)
					(fill yes)
				)
			)
		)
	)
	(footprint ""
		(layer "F.Cu")
		(at 338.709 -287.851342 90)
		(property "Reference" "C127"
			(at 0 0 90)
			(layer "F.SilkS")
			(hide yes)
			(effects
				(font
					(size 1.27 1.27)
				)
			)
		)
		(property "Value" "SCD033U25V2KX-GP"
			(at 1.1811 -2.7051 90)
			(unlocked yes)
			(layer "F.Fab")
			(hide yes)
			(effects
				(font
					(size 1.016 1.016)
					(thickness 0.1524)
				)
			)
		)
		(property "Device Type" "C402H22"
			(at 1.1811 -4.2291 90)
			(unlocked yes)
			(layer "F.Fab")
			(hide yes)
			(effects
				(font
					(size 1.016 1.016)
					(thickness 0.1524)
				)
			)
		)
		(duplicate_pad_numbers_are_jumpers no)
		(fp_rect
			(start -0.4318 0.9525)
			(end 0.4318 -0.9525)
			(stroke
				(width 0)
				(type default)
			)
			(fill no)
			(layer "F.CrtYd")
		)
		(fp_rect
			(start -0.4318 0.9525)
			(end 0.4318 -0.9525)
			(stroke
				(width 0)
				(type default)
			)
			(fill no)
			(layer "F.Fab")
		)
		(pad "1" smd custom
			(at 0 -0.4445 90)
			(size 0.1524 0.1524)
			(layers "F.Cu" "F.Mask" "F.Paste")
			(net "P12V_A")
			(options
				(clearance outline)
				(anchor circle)
			)
			(primitives
				(gr_poly
					(pts
						(arc
							(start 0.3048 -0.2032)
							(mid 0.275042 -0.275042)
							(end 0.2032 -0.3048)
						)
						(arc
							(start -0.2032 -0.3048)
							(mid -0.275042 -0.275042)
							(end -0.3048 -0.2032)
						)
						(arc
							(start -0.3048 0.2032)
							(mid -0.275042 0.275042)
							(end -0.2032 0.3048)
						)
						(arc
							(start 0.2032 0.3048)
							(mid 0.275042 0.275042)
							(end 0.3048 0.2032)
						)
					)
					(width 0)
					(fill yes)
				)
			)
		)
		(pad "2" smd custom
			(at 0 0.4445 90)
			(size 0.1524 0.1524)
			(layers "F.Cu" "F.Mask" "F.Paste")
			(net "SW_HDD_N6")
			(options
				(clearance outline)
				(anchor circle)
			)
			(primitives
				(gr_poly
					(pts
						(arc
							(start 0.3048 -0.2032)
							(mid 0.275042 -0.275042)
							(end 0.2032 -0.3048)
						)
						(arc
							(start -0.2032 -0.3048)
							(mid -0.275042 -0.275042)
							(end -0.3048 -0.2032)
						)
						(arc
							(start -0.3048 0.2032)
							(mid -0.275042 0.275042)
							(end -0.2032 0.3048)
						)
						(arc
							(start 0.2032 0.3048)
							(mid 0.275042 0.275042)
							(end 0.3048 0.2032)
						)
					)
					(width 0)
					(fill yes)
				)
			)
		)
	)
	(footprint ""
		(layer "F.Cu")
		(at 284.4038 -272.3134)
		(property "Reference" "R126"
			(at 0 0 0)
			(layer "F.SilkS")
			(hide yes)
			(effects
				(font
					(size 1.27 1.27)
				)
			)
		)
		(property "Value" "4K7R2F-GP"
			(at 0.064008 -3.993896 0)
			(unlocked yes)
			(layer "F.Fab")
			(hide yes)
			(effects
				(font
					(size 1.016 1.016)
					(thickness 0.1524)
				)
			)
		)
		(property "Device Type" "R402H16"
			(at 0.064008 -5.517896 0)
			(unlocked yes)
			(layer "F.Fab")
			(hide yes)
			(effects
				(font
					(size 1.016 1.016)
					(thickness 0.1524)
				)
			)
		)
		(duplicate_pad_numbers_are_jumpers no)
		(fp_line
			(start -0.508 -0.9398)
			(end -0.508 0.9398)
			(stroke
				(width 0.1524)
				(type default)
			)
			(layer "F.SilkS")
		)
		(fp_line
			(start 0.508 -0.9398)
			(end -0.508 -0.9398)
			(stroke
				(width 0.1524)
				(type default)
			)
			(layer "F.SilkS")
		)
		(fp_rect
			(start -0.508 0.9398)
			(end 0.508 -0.9398)
			(stroke
				(width 0)
				(type default)
			)
			(fill no)
			(layer "F.CrtYd")
		)
		(fp_rect
			(start -0.508 0.9398)
			(end 0.508 -0.9398)
			(stroke
				(width 0)
				(type default)
			)
			(fill no)
			(layer "F.Fab")
		)
		(pad "1" smd custom
			(at 0 -0.4445)
			(size 0.1397 0.1397)
			(layers "F.Cu" "F.Mask" "F.Paste")
			(net "IO_EXP2_HDD_FAULT_A1")
			(options
				(clearance outline)
				(anchor circle)
			)
			(primitives
				(gr_poly
					(pts
						(arc
							(start -0.1778 -0.2794)
							(mid -0.249642 -0.249642)
							(end -0.2794 -0.1778)
						)
						(arc
							(start -0.2794 0.1778)
							(mid -0.249642 0.249642)
							(end -0.1778 0.2794)
						)
						(arc
							(start 0.1778 0.2794)
							(mid 0.249642 0.249642)
							(end 0.2794 0.1778)
						)
						(arc
							(start 0.2794 -0.1778)
							(mid 0.249642 -0.249642)
							(end 0.1778 -0.2794)
						)
					)
					(width 0)
					(fill yes)
				)
			)
		)
		(pad "2" smd custom
			(at 0 0.4445)
			(size 0.1397 0.1397)
			(layers "F.Cu" "F.Mask" "F.Paste")
			(net "GND")
			(options
				(clearance outline)
				(anchor circle)
			)
			(primitives
				(gr_poly
					(pts
						(arc
							(start -0.1778 -0.2794)
							(mid -0.249642 -0.249642)
							(end -0.2794 -0.1778)
						)
						(arc
							(start -0.2794 0.1778)
							(mid -0.249642 0.249642)
							(end -0.1778 0.2794)
						)
						(arc
							(start 0.1778 0.2794)
							(mid 0.249642 0.249642)
							(end 0.2794 0.1778)
						)
						(arc
							(start 0.2794 -0.1778)
							(mid 0.249642 -0.249642)
							(end 0.1778 -0.2794)
						)
					)
					(width 0)
					(fill yes)
				)
			)
		)
	)
	(footprint ""
		(layer "F.Cu")
		(at 471.275918 -156.522674)
		(property "Reference" "R671"
			(at 0 0 0)
			(layer "F.SilkS")
			(hide yes)
			(effects
				(font
					(size 1.27 1.27)
				)
			)
		)
		(property "Value" "4K7R2J-2-GP"
			(at 0.064008 -3.993896 0)
			(unlocked yes)
			(layer "F.Fab")
			(hide yes)
			(effects
				(font
					(size 1.016 1.016)
					(thickness 0.1524)
				)
			)
		)
		(property "Device Type" "R402H16"
			(at 0.064008 -5.517896 0)
			(unlocked yes)
			(layer "F.Fab")
			(hide yes)
			(effects
				(font
					(size 1.016 1.016)
					(thickness 0.1524)
				)
			)
		)
		(duplicate_pad_numbers_are_jumpers no)
		(fp_line
			(start -0.508 -0.9398)
			(end -0.508 0.9398)
			(stroke
				(width 0.1524)
				(type default)
			)
			(layer "F.SilkS")
		)
		(fp_line
			(start 0.508 -0.9398)
			(end -0.508 -0.9398)
			(stroke
				(width 0.1524)
				(type default)
			)
			(layer "F.SilkS")
		)
		(fp_rect
			(start -0.508 0.9398)
			(end 0.508 -0.9398)
			(stroke
				(width 0)
				(type default)
			)
			(fill no)
			(layer "F.CrtYd")
		)
		(fp_rect
			(start -0.508 0.9398)
			(end 0.508 -0.9398)
			(stroke
				(width 0)
				(type default)
			)
			(fill no)
			(layer "F.Fab")
		)
		(pad "1" smd custom
			(at 0 -0.4445)
			(size 0.1397 0.1397)
			(layers "F.Cu" "F.Mask" "F.Paste")
			(net "SW_PWR_R_HDD23")
			(options
				(clearance outline)
				(anchor circle)
			)
			(primitives
				(gr_poly
					(pts
						(arc
							(start -0.1778 -0.2794)
							(mid -0.249642 -0.249642)
							(end -0.2794 -0.1778)
						)
						(arc
							(start -0.2794 0.1778)
							(mid -0.249642 0.249642)
							(end -0.1778 0.2794)
						)
						(arc
							(start 0.1778 0.2794)
							(mid 0.249642 0.249642)
							(end 0.2794 0.1778)
						)
						(arc
							(start 0.2794 -0.1778)
							(mid 0.249642 -0.249642)
							(end 0.1778 -0.2794)
						)
					)
					(width 0)
					(fill yes)
				)
			)
		)
		(pad "2" smd custom
			(at 0 0.4445)
			(size 0.1397 0.1397)
			(layers "F.Cu" "F.Mask" "F.Paste")
			(net "GND")
			(options
				(clearance outline)
				(anchor circle)
			)
			(primitives
				(gr_poly
					(pts
						(arc
							(start -0.1778 -0.2794)
							(mid -0.249642 -0.249642)
							(end -0.2794 -0.1778)
						)
						(arc
							(start -0.2794 0.1778)
							(mid -0.249642 0.249642)
							(end -0.1778 0.2794)
						)
						(arc
							(start 0.1778 0.2794)
							(mid 0.249642 0.249642)
							(end 0.2794 0.1778)
						)
						(arc
							(start 0.2794 -0.1778)
							(mid 0.249642 -0.249642)
							(end 0.1778 -0.2794)
						)
					)
					(width 0)
					(fill yes)
				)
			)
		)
	)
	(footprint ""
		(layer "F.Cu")
		(at 20.049998 -176.000918 -90)
		(property "Reference" "C197"
			(at 0 0 270)
			(layer "F.SilkS")
			(hide yes)
			(effects
				(font
					(size 1.27 1.27)
				)
			)
		)
		(property "Value" "SC10U16V6KX-2GP"
			(at -0.0762 -5.1308 270)
			(unlocked yes)
			(layer "F.Fab")
			(hide yes)
			(effects
				(font
					(size 1.016 1.016)
					(thickness 0.1524)
				)
			)
		)
		(property "Device Type" "C1206H71"
			(at -0.127 -6.6548 270)
			(unlocked yes)
			(layer "F.Fab")
			(hide yes)
			(effects
				(font
					(size 1.016 1.016)
					(thickness 0.1524)
				)
			)
		)
		(duplicate_pad_numbers_are_jumpers no)
		(fp_line
			(start -1.016 2.2352)
			(end -1.016 0.8382)
			(stroke
				(width 0.1524)
				(type default)
			)
			(layer "F.SilkS")
		)
		(fp_line
			(start 1.016 2.2352)
			(end -1.016 2.2352)
			(stroke
				(width 0.1524)
				(type default)
			)
			(layer "F.SilkS")
		)
		(fp_line
			(start 1.016 0.8382)
			(end 1.016 2.2352)
			(stroke
				(width 0.1524)
				(type default)
			)
			(layer "F.SilkS")
		)
		(fp_line
			(start -1.016 -0.8382)
			(end -1.016 -2.2352)
			(stroke
				(width 0.1524)
				(type default)
			)
			(layer "F.SilkS")
		)
		(fp_line
			(start -1.016 -2.2352)
			(end 1.016 -2.2352)
			(stroke
				(width 0.1524)
				(type default)
			)
			(layer "F.SilkS")
		)
		(fp_line
			(start 1.016 -2.2352)
			(end 1.016 -0.8382)
			(stroke
				(width 0.1524)
				(type default)
			)
			(layer "F.SilkS")
		)
		(fp_rect
			(start -1.0922 2.3114)
			(end 1.0922 -2.3114)
			(stroke
				(width 0)
				(type default)
			)
			(fill no)
			(layer "F.CrtYd")
		)
		(fp_poly
			(pts
				(xy 1.0922 -2.3114) (xy 1.0922 2.3114) (xy -1.0922 2.3114) (xy -1.0922 -2.3114)
			)
			(stroke
				(width 0)
				(type default)
			)
			(fill no)
			(layer "F.Fab")
		)
		(pad "1" smd rect
			(at 0 -1.397 270)
			(size 1.651 1.27)
			(layers "F.Cu" "F.Mask" "F.Paste")
			(net "P5V_HDD12")
		)
		(pad "2" smd rect
			(at 0 1.397 270)
			(size 1.651 1.27)
			(layers "F.Cu" "F.Mask" "F.Paste")
			(net "GND")
		)
	)
	(footprint ""
		(layer "F.Cu")
		(at 127.15875 -47.749968 -90)
		(property "Reference" "VIA66"
			(at 0 0 270)
			(layer "F.SilkS")
			(hide yes)
			(effects
				(font
					(size 1.27 1.27)
				)
			)
		)
		(property "Value" "100OHM-8L-1D6MM-L18L16-GP"
			(at -3.7211 -4.5085 270)
			(unlocked yes)
			(layer "F.Fab")
			(hide yes)
			(effects
				(font
					(size 1.016 1.016)
					(thickness 0.1524)
				)
			)
		)
		(property "Device Type" "VIA-PCIE-4P-394076"
			(at -3.7211 -6.0325 270)
			(unlocked yes)
			(layer "F.Fab")
			(hide yes)
			(effects
				(font
					(size 1.016 1.016)
					(thickness 0.1524)
				)
			)
		)
		(duplicate_pad_numbers_are_jumpers no)
		(fp_rect
			(start -1.9685 0.381)
			(end 1.9685 -0.381)
			(stroke
				(width 0)
				(type default)
			)
			(fill no)
			(layer "F.CrtYd")
		)
		(fp_rect
			(start -1.9685 0.381)
			(end 1.9685 -0.381)
			(stroke
				(width 0)
				(type default)
			)
			(fill no)
			(layer "F.Fab")
		)
		(pad "1" thru_hole circle
			(at -1.5875 0 270)
			(size 0.508 0.508)
			(drill 0.254)
			(layers "*.Cu" "*.Mask")
			(remove_unused_layers no)
			(net "GND")
			(clearance 0.127)
			(thermal_gap 0.127)
		)
		(pad "2" thru_hole circle
			(at -0.5715 0 270)
			(size 0.508 0.508)
			(drill 0.254)
			(layers "*.Cu" "*.Mask")
			(remove_unused_layers no)
			(net "PHY_DRV_A_TO_SCC_A_27_DP")
			(clearance 0.127)
			(thermal_gap 0.127)
		)
		(pad "3" thru_hole circle
			(at 0.5715 0 270)
			(size 0.508 0.508)
			(drill 0.254)
			(layers "*.Cu" "*.Mask")
			(remove_unused_layers no)
			(net "PHY_DRV_A_TO_SCC_A_27_DN")
			(clearance 0.127)
			(thermal_gap 0.127)
		)
		(pad "4" thru_hole circle
			(at 1.5875 0 270)
			(size 0.508 0.508)
			(drill 0.254)
			(layers "*.Cu" "*.Mask")
			(remove_unused_layers no)
			(net "GND")
			(clearance 0.127)
			(thermal_gap 0.127)
		)
	)
	(footprint ""
		(layer "F.Cu")
		(at 412.477458 -284.022546)
		(property "Reference" "Q296"
			(at 0 0 0)
			(layer "F.SilkS")
			(hide yes)
			(effects
				(font
					(size 1.27 1.27)
				)
			)
		)
		(property "Value" "SSM3K324R-GP"
			(at 0.127 -8.9662 0)
			(unlocked yes)
			(layer "F.Fab")
			(hide yes)
			(effects
				(font
					(size 1.016 1.016)
					(thickness 0.1524)
				)
			)
		)
		(property "Device Type" "SOT23DGS2D4H35"
			(at 0.127 -10.4902 0)
			(unlocked yes)
			(layer "F.Fab")
			(hide yes)
			(effects
				(font
					(size 1.016 1.016)
					(thickness 0.1524)
				)
			)
		)
		(duplicate_pad_numbers_are_jumpers no)
		(fp_line
			(start -1.651 -1.778)
			(end -1.651 1.778)
			(stroke
				(width 0.1524)
				(type default)
			)
			(layer "F.SilkS")
		)
		(fp_line
			(start -1.651 1.778)
			(end 1.651 1.778)
			(stroke
				(width 0.1524)
				(type default)
			)
			(layer "F.SilkS")
		)
		(fp_line
			(start 1.651 -1.778)
			(end -1.651 -1.778)
			(stroke
				(width 0.1524)
				(type default)
			)
			(layer "F.SilkS")
		)
		(fp_line
			(start 1.651 1.778)
			(end 1.651 -1.778)
			(stroke
				(width 0.1524)
				(type default)
			)
			(layer "F.SilkS")
		)
		(fp_poly
			(pts
				(xy -1.778 1.8796) (xy -1.778 -1.8796) (xy 1.778 -1.8796) (xy 1.778 1.8796)
			)
			(stroke
				(width 0)
				(type default)
			)
			(fill no)
			(layer "F.CrtYd")
		)
		(fp_poly
			(pts
				(xy -1.778 1.8796) (xy -1.778 -1.8796) (xy 1.778 -1.8796) (xy 1.778 1.8796)
			)
			(stroke
				(width 0)
				(type default)
			)
			(fill no)
			(layer "F.Fab")
		)
		(pad "D" smd custom
			(at 0 -0.9525)
			(size 0.1905 0.1905)
			(layers "F.Cu" "F.Mask" "F.Paste")
			(net "DRV_ACT_33_N")
			(options
				(clearance outline)
				(anchor circle)
			)
			(primitives
				(gr_poly
					(pts
						(arc
							(start -0.1778 0.5715)
							(mid -0.321484 0.511984)
							(end -0.381 0.3683)
						)
						(arc
							(start -0.381 -0.3683)
							(mid -0.321484 -0.511984)
							(end -0.1778 -0.5715)
						)
						(arc
							(start 0.1778 -0.5715)
							(mid 0.321484 -0.511984)
							(end 0.381 -0.3683)
						)
						(arc
							(start 0.381 0.3683)
							(mid 0.321484 0.511984)
							(end 0.1778 0.5715)
						)
					)
					(width 0)
					(fill yes)
				)
			)
		)
		(pad "G" smd custom
			(at -0.98425 0.9525)
			(size 0.1905 0.1905)
			(layers "F.Cu" "F.Mask" "F.Paste")
			(net "DRIVE_B_33_ACT")
			(options
				(clearance outline)
				(anchor circle)
			)
			(primitives
				(gr_poly
					(pts
						(arc
							(start -0.1778 0.5715)
							(mid -0.321484 0.511984)
							(end -0.381 0.3683)
						)
						(arc
							(start -0.381 -0.3683)
							(mid -0.321484 -0.511984)
							(end -0.1778 -0.5715)
						)
						(arc
							(start 0.1778 -0.5715)
							(mid 0.321484 -0.511984)
							(end 0.381 -0.3683)
						)
						(arc
							(start 0.381 0.3683)
							(mid 0.321484 0.511984)
							(end 0.1778 0.5715)
						)
					)
					(width 0)
					(fill yes)
				)
			)
		)
		(pad "S" smd custom
			(at 0.98425 0.9525)
			(size 0.1905 0.1905)
			(layers "F.Cu" "F.Mask" "F.Paste")
			(net "GND")
			(options
				(clearance outline)
				(anchor circle)
			)
			(primitives
				(gr_poly
					(pts
						(arc
							(start -0.1778 0.5715)
							(mid -0.321484 0.511984)
							(end -0.381 0.3683)
						)
						(arc
							(start -0.381 -0.3683)
							(mid -0.321484 -0.511984)
							(end -0.1778 -0.5715)
						)
						(arc
							(start 0.1778 -0.5715)
							(mid 0.321484 -0.511984)
							(end 0.381 -0.3683)
						)
						(arc
							(start 0.381 0.3683)
							(mid 0.321484 0.511984)
							(end 0.1778 0.5715)
						)
					)
					(width 0)
					(fill yes)
				)
			)
		)
	)
	(footprint ""
		(layer "F.Cu")
		(at 143.074898 -46.649894 180)
		(property "Reference" "D28"
			(at 0 0 180)
			(layer "F.SilkS")
			(hide yes)
			(effects
				(font
					(size 1.27 1.27)
				)
			)
		)
		(property "Value" "RB551V30-GP"
			(at 0 -6.7818 180)
			(unlocked yes)
			(layer "F.Fab")
			(hide yes)
			(effects
				(font
					(size 1.016 1.016)
					(thickness 0.1524)
				)
			)
		)
		(property "Device Type" "SOD323AKH38"
			(at 0 -8.6868 180)
			(unlocked yes)
			(layer "F.Fab")
			(hide yes)
			(effects
				(font
					(size 1.016 1.016)
					(thickness 0.1524)
				)
			)
		)
		(duplicate_pad_numbers_are_jumpers no)
		(fp_line
			(start 0.889 2.159)
			(end -0.889 2.159)
			(stroke
				(width 0.1524)
				(type default)
			)
			(layer "F.SilkS")
		)
		(fp_line
			(start 0.889 -1.9304)
			(end 0.889 2.159)
			(stroke
				(width 0.1524)
				(type default)
			)
			(layer "F.SilkS")
		)
		(fp_line
			(start 0.762 2.0574)
			(end -0.762 2.0574)
			(stroke
				(width 0.508)
				(type default)
			)
			(layer "F.SilkS")
		)
		(fp_line
			(start -0.889 2.159)
			(end -0.889 -1.9304)
			(stroke
				(width 0.1524)
				(type default)
			)
			(layer "F.SilkS")
		)
		(fp_line
			(start -0.889 -1.9304)
			(end 0.889 -1.9304)
			(stroke
				(width 0.1524)
				(type default)
			)
			(layer "F.SilkS")
		)
		(fp_rect
			(start -1.016 2.3114)
			(end 1.016 -2.0066)
			(stroke
				(width 0)
				(type default)
			)
			(fill no)
			(layer "F.CrtYd")
		)
		(fp_poly
			(pts
				(xy -1.016 -2.0066) (xy 1.016 -2.0066) (xy 1.016 2.3114) (xy -1.016 2.3114)
			)
			(stroke
				(width 0)
				(type default)
			)
			(fill no)
			(layer "F.Fab")
		)
		(pad "A" smd rect
			(at 0 -1.143 180)
			(size 0.5588 1.016)
			(layers "F.Cu" "F.Mask" "F.Paste")
			(net "SW_HDD_R28")
		)
		(pad "K" smd rect
			(at 0 1.143 180)
			(size 0.5588 1.016)
			(layers "F.Cu" "F.Mask" "F.Paste")
			(net "SW_HDD_N28")
		)
	)
	(footprint ""
		(layer "F.Cu")
		(at 149.196298 -274.871942 -90)
		(property "Reference" "R234"
			(at 0 0 270)
			(layer "F.SilkS")
			(hide yes)
			(effects
				(font
					(size 1.27 1.27)
				)
			)
		)
		(property "Value" "0R2J-2-GP"
			(at 0.064008 -3.993896 270)
			(unlocked yes)
			(layer "F.Fab")
			(hide yes)
			(effects
				(font
					(size 1.016 1.016)
					(thickness 0.1524)
				)
			)
		)
		(property "Device Type" "R402H16"
			(at 0.064008 -5.517896 270)
			(unlocked yes)
			(layer "F.Fab")
			(hide yes)
			(effects
				(font
					(size 1.016 1.016)
					(thickness 0.1524)
				)
			)
		)
		(duplicate_pad_numbers_are_jumpers no)
		(fp_line
			(start -0.508 -0.9398)
			(end -0.508 0.9398)
			(stroke
				(width 0.1524)
				(type default)
			)
			(layer "F.SilkS")
		)
		(fp_line
			(start 0.508 -0.9398)
			(end -0.508 -0.9398)
			(stroke
				(width 0.1524)
				(type default)
			)
			(layer "F.SilkS")
		)
		(fp_rect
			(start -0.508 0.9398)
			(end 0.508 -0.9398)
			(stroke
				(width 0)
				(type default)
			)
			(fill no)
			(layer "F.CrtYd")
		)
		(fp_rect
			(start -0.508 0.9398)
			(end 0.508 -0.9398)
			(stroke
				(width 0)
				(type default)
			)
			(fill no)
			(layer "F.Fab")
		)
		(pad "1" smd custom
			(at 0 -0.4445 270)
			(size 0.1397 0.1397)
			(layers "F.Cu" "F.Mask" "F.Paste")
			(net "DRIVE_A_4_PWR")
			(options
				(clearance outline)
				(anchor circle)
			)
			(primitives
				(gr_poly
					(pts
						(arc
							(start -0.1778 -0.2794)
							(mid -0.249642 -0.249642)
							(end -0.2794 -0.1778)
						)
						(arc
							(start -0.2794 0.1778)
							(mid -0.249642 0.249642)
							(end -0.1778 0.2794)
						)
						(arc
							(start 0.1778 0.2794)
							(mid 0.249642 0.249642)
							(end 0.2794 0.1778)
						)
						(arc
							(start 0.2794 -0.1778)
							(mid 0.249642 -0.249642)
							(end 0.1778 -0.2794)
						)
					)
					(width 0)
					(fill yes)
				)
			)
		)
		(pad "2" smd custom
			(at 0 0.4445 270)
			(size 0.1397 0.1397)
			(layers "F.Cu" "F.Mask" "F.Paste")
			(net "SW_PWR_R_HDD4")
			(options
				(clearance outline)
				(anchor circle)
			)
			(primitives
				(gr_poly
					(pts
						(arc
							(start -0.1778 -0.2794)
							(mid -0.249642 -0.249642)
							(end -0.2794 -0.1778)
						)
						(arc
							(start -0.2794 0.1778)
							(mid -0.249642 0.249642)
							(end -0.1778 0.2794)
						)
						(arc
							(start 0.1778 0.2794)
							(mid 0.249642 0.249642)
							(end 0.2794 0.1778)
						)
						(arc
							(start 0.2794 -0.1778)
							(mid 0.249642 -0.249642)
							(end 0.1778 -0.2794)
						)
					)
					(width 0)
					(fill yes)
				)
			)
		)
	)
	(footprint ""
		(layer "F.Cu")
		(at 344.026998 -21.142452)
		(property "Reference" "R455"
			(at 0 0 0)
			(layer "F.SilkS")
			(hide yes)
			(effects
				(font
					(size 1.27 1.27)
				)
			)
		)
		(property "Value" "4K7R2F-GP"
			(at 0.064008 -3.993896 0)
			(unlocked yes)
			(layer "F.Fab")
			(hide yes)
			(effects
				(font
					(size 1.016 1.016)
					(thickness 0.1524)
				)
			)
		)
		(property "Device Type" "R402H16"
			(at 0.064008 -5.517896 0)
			(unlocked yes)
			(layer "F.Fab")
			(hide yes)
			(effects
				(font
					(size 1.016 1.016)
					(thickness 0.1524)
				)
			)
		)
		(duplicate_pad_numbers_are_jumpers no)
		(fp_line
			(start -0.508 -0.9398)
			(end -0.508 0.9398)
			(stroke
				(width 0.1524)
				(type default)
			)
			(layer "F.SilkS")
		)
		(fp_line
			(start 0.508 -0.9398)
			(end -0.508 -0.9398)
			(stroke
				(width 0.1524)
				(type default)
			)
			(layer "F.SilkS")
		)
		(fp_rect
			(start -0.508 0.9398)
			(end 0.508 -0.9398)
			(stroke
				(width 0)
				(type default)
			)
			(fill no)
			(layer "F.CrtYd")
		)
		(fp_rect
			(start -0.508 0.9398)
			(end 0.508 -0.9398)
			(stroke
				(width 0)
				(type default)
			)
			(fill no)
			(layer "F.Fab")
		)
		(pad "1" smd custom
			(at 0 -0.4445)
			(size 0.1397 0.1397)
			(layers "F.Cu" "F.Mask" "F.Paste")
			(net "GND")
			(options
				(clearance outline)
				(anchor circle)
			)
			(primitives
				(gr_poly
					(pts
						(arc
							(start -0.1778 -0.2794)
							(mid -0.249642 -0.249642)
							(end -0.2794 -0.1778)
						)
						(arc
							(start -0.2794 0.1778)
							(mid -0.249642 0.249642)
							(end -0.1778 0.2794)
						)
						(arc
							(start 0.1778 0.2794)
							(mid 0.249642 0.249642)
							(end 0.2794 0.1778)
						)
						(arc
							(start 0.2794 -0.1778)
							(mid 0.249642 -0.249642)
							(end 0.1778 -0.2794)
						)
					)
					(width 0)
					(fill yes)
				)
			)
		)
		(pad "2" smd custom
			(at 0 0.4445)
			(size 0.1397 0.1397)
			(layers "F.Cu" "F.Mask" "F.Paste")
			(net "COMP_B_FAST_THROTTLE_N")
			(options
				(clearance outline)
				(anchor circle)
			)
			(primitives
				(gr_poly
					(pts
						(arc
							(start -0.1778 -0.2794)
							(mid -0.249642 -0.249642)
							(end -0.2794 -0.1778)
						)
						(arc
							(start -0.2794 0.1778)
							(mid -0.249642 0.249642)
							(end -0.1778 0.2794)
						)
						(arc
							(start 0.1778 0.2794)
							(mid 0.249642 0.249642)
							(end 0.2794 0.1778)
						)
						(arc
							(start 0.2794 -0.1778)
							(mid 0.249642 -0.249642)
							(end 0.1778 -0.2794)
						)
					)
					(width 0)
					(fill yes)
				)
			)
		)
	)
	(footprint ""
		(layer "F.Cu")
		(at 79.924148 -168.126918 -90)
		(property "Reference" "C230"
			(at 0 0 270)
			(layer "F.SilkS")
			(hide yes)
			(effects
				(font
					(size 1.27 1.27)
				)
			)
		)
		(property "Value" "SCD033U25V2KX-GP"
			(at 1.1811 -2.7051 270)
			(unlocked yes)
			(layer "F.Fab")
			(hide yes)
			(effects
				(font
					(size 1.016 1.016)
					(thickness 0.1524)
				)
			)
		)
		(property "Device Type" "C402H22"
			(at 1.1811 -4.2291 270)
			(unlocked yes)
			(layer "F.Fab")
			(hide yes)
			(effects
				(font
					(size 1.016 1.016)
					(thickness 0.1524)
				)
			)
		)
		(duplicate_pad_numbers_are_jumpers no)
		(fp_rect
			(start -0.4318 0.9525)
			(end 0.4318 -0.9525)
			(stroke
				(width 0)
				(type default)
			)
			(fill no)
			(layer "F.CrtYd")
		)
		(fp_rect
			(start -0.4318 0.9525)
			(end 0.4318 -0.9525)
			(stroke
				(width 0)
				(type default)
			)
			(fill no)
			(layer "F.Fab")
		)
		(pad "1" smd custom
			(at 0 -0.4445 270)
			(size 0.1524 0.1524)
			(layers "F.Cu" "F.Mask" "F.Paste")
			(net "SW_HDD_P14")
			(options
				(clearance outline)
				(anchor circle)
			)
			(primitives
				(gr_poly
					(pts
						(arc
							(start 0.3048 -0.2032)
							(mid 0.275042 -0.275042)
							(end 0.2032 -0.3048)
						)
						(arc
							(start -0.2032 -0.3048)
							(mid -0.275042 -0.275042)
							(end -0.3048 -0.2032)
						)
						(arc
							(start -0.3048 0.2032)
							(mid -0.275042 0.275042)
							(end -0.2032 0.3048)
						)
						(arc
							(start 0.2032 0.3048)
							(mid 0.275042 0.275042)
							(end 0.3048 0.2032)
						)
					)
					(width 0)
					(fill yes)
				)
			)
		)
		(pad "2" smd custom
			(at 0 0.4445 270)
			(size 0.1524 0.1524)
			(layers "F.Cu" "F.Mask" "F.Paste")
			(net "GND")
			(options
				(clearance outline)
				(anchor circle)
			)
			(primitives
				(gr_poly
					(pts
						(arc
							(start 0.3048 -0.2032)
							(mid 0.275042 -0.275042)
							(end 0.2032 -0.3048)
						)
						(arc
							(start -0.2032 -0.3048)
							(mid -0.275042 -0.275042)
							(end -0.3048 -0.2032)
						)
						(arc
							(start -0.3048 0.2032)
							(mid -0.275042 0.275042)
							(end -0.2032 0.3048)
						)
						(arc
							(start 0.2032 0.3048)
							(mid 0.275042 0.275042)
							(end 0.3048 0.2032)
						)
					)
					(width 0)
					(fill yes)
				)
			)
		)
	)
	(footprint ""
		(layer "F.Cu")
		(at 409.800044 -209.399886)
		(property "Reference" "FLED10"
			(at 0 0 0)
			(layer "F.SilkS")
			(hide yes)
			(effects
				(font
					(size 1.27 1.27)
				)
			)
		)
		(property "Value" "LED-BY-19-GP"
			(at -2.132076 1.414018 0)
			(unlocked yes)
			(layer "F.Fab")
			(hide yes)
			(effects
				(font
					(size 1.016 1.016)
					(thickness 0.1524)
				)
			)
		)
		(property "Device Type" "LED-1615-4PH26"
			(at -2.132076 -0.109982 0)
			(unlocked yes)
			(layer "F.Fab")
			(hide yes)
			(effects
				(font
					(size 1.016 1.016)
					(thickness 0.1524)
				)
			)
		)
		(duplicate_pad_numbers_are_jumpers no)
		(fp_line
			(start -1.2954 0.254)
			(end -1.2954 1.6002)
			(stroke
				(width 0.508)
				(type default)
			)
			(layer "F.SilkS")
		)
		(fp_line
			(start -1.2954 1.6002)
			(end 1.2954 1.6002)
			(stroke
				(width 0.508)
				(type default)
			)
			(layer "F.SilkS")
		)
		(fp_line
			(start -1.1176 -1.4224)
			(end 1.1176 -1.4224)
			(stroke
				(width 0.1524)
				(type default)
			)
			(layer "F.SilkS")
		)
		(fp_line
			(start -1.1176 1.4224)
			(end -1.1176 -1.4224)
			(stroke
				(width 0.1524)
				(type default)
			)
			(layer "F.SilkS")
		)
		(fp_line
			(start 1.1176 -1.4224)
			(end 1.1176 1.4224)
			(stroke
				(width 0.1524)
				(type default)
			)
			(layer "F.SilkS")
		)
		(fp_line
			(start 1.1176 1.4224)
			(end -1.1176 1.4224)
			(stroke
				(width 0.1524)
				(type default)
			)
			(layer "F.SilkS")
		)
		(fp_line
			(start 1.2954 1.6002)
			(end 1.2954 0.254)
			(stroke
				(width 0.508)
				(type default)
			)
			(layer "F.SilkS")
		)
		(fp_rect
			(start -0.7493 0.8001)
			(end 0.7493 -0.8001)
			(stroke
				(width 0)
				(type default)
			)
			(fill no)
			(layer "F.CrtYd")
		)
		(fp_poly
			(pts
				(xy -1.3716 1.6764) (xy -1.3716 -1.6764) (xy 1.3716 -1.6764) (xy 1.3716 0.0635) (xy 0.7493 0.0635)
				(xy 0.7493 -0.8001) (xy -0.7493 -0.8001) (xy -0.7493 0.8001) (xy 0.7493 0.8001) (xy 0.7493 0.0762)
				(xy 1.3716 0.0762) (xy 1.3716 1.6764)
			)
			(stroke
				(width 0)
				(type default)
			)
			(fill no)
			(layer "F.CrtYd")
		)
		(fp_rect
			(start -1.3716 1.6764)
			(end 1.3716 -1.6764)
			(stroke
				(width 0)
				(type default)
			)
			(fill no)
			(layer "F.Fab")
		)
		(pad "1" smd rect
			(at 0.50038 -0.73025)
			(size 0.7112 0.8636)
			(layers "F.Cu" "F.Mask" "F.Paste")
			(net "DRV_ACT_9")
		)
		(pad "2" smd rect
			(at -0.50038 -0.73025)
			(size 0.7112 0.8636)
			(layers "F.Cu" "F.Mask" "F.Paste")
			(net "FLT_HDD9")
		)
		(pad "3" smd rect
			(at 0.50038 0.73025)
			(size 0.7112 0.8636)
			(layers "F.Cu" "F.Mask" "F.Paste")
			(net "DRV_ACT_9_N")
		)
		(pad "4" smd rect
			(at -0.50038 0.73025)
			(size 0.7112 0.8636)
			(layers "F.Cu" "F.Mask" "F.Paste")
			(net "FLT_HDD9_N")
		)
	)
	(footprint ""
		(layer "F.Cu")
		(at 372.0338 -146.5834 180)
		(property "Reference" "C560"
			(at 0 0 180)
			(layer "F.SilkS")
			(hide yes)
			(effects
				(font
					(size 1.27 1.27)
				)
			)
		)
		(property "Value" "SC2D2U25V5KX-2-GP"
			(at -0.0762 -6.1214 180)
			(unlocked yes)
			(layer "F.Fab")
			(hide yes)
			(effects
				(font
					(size 1.016 1.016)
					(thickness 0.1524)
				)
			)
		)
		(property "Device Type" "C805H54"
			(at -0.0762 -8.1534 180)
			(unlocked yes)
			(layer "F.Fab")
			(hide yes)
			(effects
				(font
					(size 1.016 1.016)
					(thickness 0.1524)
				)
			)
		)
		(duplicate_pad_numbers_are_jumpers no)
		(fp_line
			(start 0.635 0)
			(end -0.635 0)
			(stroke
				(width 0.508)
				(type default)
			)
			(layer "F.SilkS")
		)
		(fp_rect
			(start -0.9652 1.778)
			(end 0.9652 -1.778)
			(stroke
				(width 0)
				(type default)
			)
			(fill no)
			(layer "F.CrtYd")
		)
		(fp_poly
			(pts
				(xy -0.9652 -1.778) (xy 0.9652 -1.778) (xy 0.9652 1.778) (xy -0.9652 1.778)
			)
			(stroke
				(width 0)
				(type default)
			)
			(fill no)
			(layer "F.Fab")
		)
		(pad "1" smd rect
			(at 0 -0.9652 180)
			(size 1.397 1.143)
			(layers "F.Cu" "F.Mask" "F.Paste")
			(net "COMP_B_PGOOD")
		)
		(pad "2" smd rect
			(at 0 0.9652 180)
			(size 1.397 1.143)
			(layers "F.Cu" "F.Mask" "F.Paste")
			(net "GND")
		)
	)
	(footprint ""
		(layer "F.Cu")
		(at 371.022118 -245.334282 -90)
		(property "Reference" "R484"
			(at 0 0 270)
			(layer "F.SilkS")
			(hide yes)
			(effects
				(font
					(size 1.27 1.27)
				)
			)
		)
		(property "Value" "4K7R2J-2-GP"
			(at 0.064008 -3.993896 270)
			(unlocked yes)
			(layer "F.Fab")
			(hide yes)
			(effects
				(font
					(size 1.016 1.016)
					(thickness 0.1524)
				)
			)
		)
		(property "Device Type" "R402H16"
			(at 0.064008 -5.517896 270)
			(unlocked yes)
			(layer "F.Fab")
			(hide yes)
			(effects
				(font
					(size 1.016 1.016)
					(thickness 0.1524)
				)
			)
		)
		(duplicate_pad_numbers_are_jumpers no)
		(fp_line
			(start -0.508 -0.9398)
			(end -0.508 0.9398)
			(stroke
				(width 0.1524)
				(type default)
			)
			(layer "F.SilkS")
		)
		(fp_line
			(start 0.508 -0.9398)
			(end -0.508 -0.9398)
			(stroke
				(width 0.1524)
				(type default)
			)
			(layer "F.SilkS")
		)
		(fp_rect
			(start -0.508 0.9398)
			(end 0.508 -0.9398)
			(stroke
				(width 0)
				(type default)
			)
			(fill no)
			(layer "F.CrtYd")
		)
		(fp_rect
			(start -0.508 0.9398)
			(end 0.508 -0.9398)
			(stroke
				(width 0)
				(type default)
			)
			(fill no)
			(layer "F.Fab")
		)
		(pad "1" smd custom
			(at 0 -0.4445 270)
			(size 0.1397 0.1397)
			(layers "F.Cu" "F.Mask" "F.Paste")
			(net "DRIVE_A_8_ACT")
			(options
				(clearance outline)
				(anchor circle)
			)
			(primitives
				(gr_poly
					(pts
						(arc
							(start -0.1778 -0.2794)
							(mid -0.249642 -0.249642)
							(end -0.2794 -0.1778)
						)
						(arc
							(start -0.2794 0.1778)
							(mid -0.249642 0.249642)
							(end -0.1778 0.2794)
						)
						(arc
							(start 0.1778 0.2794)
							(mid 0.249642 0.249642)
							(end 0.2794 0.1778)
						)
						(arc
							(start 0.2794 -0.1778)
							(mid 0.249642 -0.249642)
							(end 0.1778 -0.2794)
						)
					)
					(width 0)
					(fill yes)
				)
			)
		)
		(pad "2" smd custom
			(at 0 0.4445 270)
			(size 0.1397 0.1397)
			(layers "F.Cu" "F.Mask" "F.Paste")
			(net "GND")
			(options
				(clearance outline)
				(anchor circle)
			)
			(primitives
				(gr_poly
					(pts
						(arc
							(start -0.1778 -0.2794)
							(mid -0.249642 -0.249642)
							(end -0.2794 -0.1778)
						)
						(arc
							(start -0.2794 0.1778)
							(mid -0.249642 0.249642)
							(end -0.1778 0.2794)
						)
						(arc
							(start 0.1778 0.2794)
							(mid 0.249642 0.249642)
							(end 0.2794 0.1778)
						)
						(arc
							(start 0.2794 -0.1778)
							(mid 0.249642 -0.249642)
							(end 0.1778 -0.2794)
						)
					)
					(width 0)
					(fill yes)
				)
			)
		)
	)
	(footprint ""
		(layer "F.Cu")
		(at 235.761276 -349.211392 180)
		(property "Reference" "C8"
			(at 0 0 180)
			(layer "F.SilkS")
			(hide yes)
			(effects
				(font
					(size 1.27 1.27)
				)
			)
		)
		(property "Value" "SCD1U16V2KX-3GP"
			(at 1.1811 -2.7051 180)
			(unlocked yes)
			(layer "F.Fab")
			(hide yes)
			(effects
				(font
					(size 1.016 1.016)
					(thickness 0.1524)
				)
			)
		)
		(property "Device Type" "C402H22"
			(at 1.1811 -4.2291 180)
			(unlocked yes)
			(layer "F.Fab")
			(hide yes)
			(effects
				(font
					(size 1.016 1.016)
					(thickness 0.1524)
				)
			)
		)
		(duplicate_pad_numbers_are_jumpers no)
		(fp_rect
			(start -0.4318 0.9525)
			(end 0.4318 -0.9525)
			(stroke
				(width 0)
				(type default)
			)
			(fill no)
			(layer "F.CrtYd")
		)
		(fp_rect
			(start -0.4318 0.9525)
			(end 0.4318 -0.9525)
			(stroke
				(width 0)
				(type default)
			)
			(fill no)
			(layer "F.Fab")
		)
		(pad "1" smd custom
			(at 0 -0.4445 180)
			(size 0.1524 0.1524)
			(layers "F.Cu" "F.Mask" "F.Paste")
			(net "P3V3_SENSE")
			(options
				(clearance outline)
				(anchor circle)
			)
			(primitives
				(gr_poly
					(pts
						(arc
							(start 0.3048 -0.2032)
							(mid 0.275042 -0.275042)
							(end 0.2032 -0.3048)
						)
						(arc
							(start -0.2032 -0.3048)
							(mid -0.275042 -0.275042)
							(end -0.3048 -0.2032)
						)
						(arc
							(start -0.3048 0.2032)
							(mid -0.275042 0.275042)
							(end -0.2032 0.3048)
						)
						(arc
							(start 0.2032 0.3048)
							(mid 0.275042 0.275042)
							(end 0.3048 0.2032)
						)
					)
					(width 0)
					(fill yes)
				)
			)
		)
		(pad "2" smd custom
			(at 0 0.4445 180)
			(size 0.1524 0.1524)
			(layers "F.Cu" "F.Mask" "F.Paste")
			(net "GND")
			(options
				(clearance outline)
				(anchor circle)
			)
			(primitives
				(gr_poly
					(pts
						(arc
							(start 0.3048 -0.2032)
							(mid 0.275042 -0.275042)
							(end 0.2032 -0.3048)
						)
						(arc
							(start -0.2032 -0.3048)
							(mid -0.275042 -0.275042)
							(end -0.3048 -0.2032)
						)
						(arc
							(start -0.3048 0.2032)
							(mid -0.275042 0.275042)
							(end -0.2032 0.3048)
						)
						(arc
							(start 0.2032 0.3048)
							(mid 0.275042 0.275042)
							(end 0.3048 0.2032)
						)
					)
					(width 0)
					(fill yes)
				)
			)
		)
	)
	(footprint ""
		(layer "F.Cu")
		(at 255.415034 -2.017522 90)
		(property "Reference" "TP215"
			(at 0 0 90)
			(layer "F.SilkS")
			(hide yes)
			(effects
				(font
					(size 1.27 1.27)
				)
			)
		)
		(property "Value" "TPAD32-GP"
			(at -0.0508 -1.6764 90)
			(unlocked yes)
			(layer "F.Fab")
			(hide yes)
			(effects
				(font
					(size 1.016 1.016)
					(thickness 0.1524)
				)
			)
		)
		(property "Device Type" "TPAD32"
			(at -0.0508 -3.2004 90)
			(unlocked yes)
			(layer "F.Fab")
			(hide yes)
			(effects
				(font
					(size 1.016 1.016)
					(thickness 0.1524)
				)
			)
		)
		(duplicate_pad_numbers_are_jumpers no)
		(fp_poly
			(pts
				(arc
					(start 0 0.4064)
					(mid 0 -0.4064)
					(end 0 0.4064)
				)
			)
			(stroke
				(width 0)
				(type default)
			)
			(fill no)
			(layer "F.CrtYd")
		)
		(fp_poly
			(pts
				(arc
					(start 0 0.7112)
					(mid 0 -0.7112)
					(end 0 0.7112)
				)
			)
			(stroke
				(width 0)
				(type default)
			)
			(fill no)
			(layer "F.Fab")
		)
		(pad "1" smd circle
			(at 0 0 90)
			(size 0.8128 0.8128)
			(layers "F.Cu" "F.Mask" "F.Paste")
			(net "TP_COMP_A_NCSI_RXD0")
		)
	)
	(footprint ""
		(layer "F.Cu")
		(at 233.172 -390.9568 -90)
		(property "Reference" "R1150"
			(at 0 0 270)
			(layer "F.SilkS")
			(hide yes)
			(effects
				(font
					(size 1.27 1.27)
				)
			)
		)
		(property "Value" "0R2J-2-GP"
			(at 0.064008 -3.993896 270)
			(unlocked yes)
			(layer "F.Fab")
			(hide yes)
			(effects
				(font
					(size 1.016 1.016)
					(thickness 0.1524)
				)
			)
		)
		(property "Device Type" "R402H16"
			(at 0.064008 -5.517896 270)
			(unlocked yes)
			(layer "F.Fab")
			(hide yes)
			(effects
				(font
					(size 1.016 1.016)
					(thickness 0.1524)
				)
			)
		)
		(duplicate_pad_numbers_are_jumpers no)
		(fp_line
			(start -0.508 -0.9398)
			(end -0.508 0.9398)
			(stroke
				(width 0.1524)
				(type default)
			)
			(layer "F.SilkS")
		)
		(fp_line
			(start 0.508 -0.9398)
			(end -0.508 -0.9398)
			(stroke
				(width 0.1524)
				(type default)
			)
			(layer "F.SilkS")
		)
		(fp_rect
			(start -0.508 0.9398)
			(end 0.508 -0.9398)
			(stroke
				(width 0)
				(type default)
			)
			(fill no)
			(layer "F.CrtYd")
		)
		(fp_rect
			(start -0.508 0.9398)
			(end 0.508 -0.9398)
			(stroke
				(width 0)
				(type default)
			)
			(fill no)
			(layer "F.Fab")
		)
		(pad "1" smd custom
			(at 0 -0.4445 270)
			(size 0.1397 0.1397)
			(layers "F.Cu" "F.Mask" "F.Paste")
			(net "MB3_SPISS_PD")
			(options
				(clearance outline)
				(anchor circle)
			)
			(primitives
				(gr_poly
					(pts
						(arc
							(start -0.1778 -0.2794)
							(mid -0.249642 -0.249642)
							(end -0.2794 -0.1778)
						)
						(arc
							(start -0.2794 0.1778)
							(mid -0.249642 0.249642)
							(end -0.1778 0.2794)
						)
						(arc
							(start 0.1778 0.2794)
							(mid 0.249642 0.249642)
							(end 0.2794 0.1778)
						)
						(arc
							(start 0.2794 -0.1778)
							(mid 0.249642 -0.249642)
							(end 0.1778 -0.2794)
						)
					)
					(width 0)
					(fill yes)
				)
			)
		)
		(pad "2" smd custom
			(at 0 0.4445 270)
			(size 0.1397 0.1397)
			(layers "F.Cu" "F.Mask" "F.Paste")
			(net "AGND_CURRENT_DPB")
			(options
				(clearance outline)
				(anchor circle)
			)
			(primitives
				(gr_poly
					(pts
						(arc
							(start -0.1778 -0.2794)
							(mid -0.249642 -0.249642)
							(end -0.2794 -0.1778)
						)
						(arc
							(start -0.2794 0.1778)
							(mid -0.249642 0.249642)
							(end -0.1778 0.2794)
						)
						(arc
							(start 0.1778 0.2794)
							(mid 0.249642 0.249642)
							(end 0.2794 0.1778)
						)
						(arc
							(start 0.2794 -0.1778)
							(mid 0.249642 -0.249642)
							(end 0.1778 -0.2794)
						)
					)
					(width 0)
					(fill yes)
				)
			)
		)
	)
	(footprint ""
		(layer "F.Cu")
		(at 469.942926 -53.457094 -90)
		(property "Reference" "R950"
			(at 0 0 270)
			(layer "F.SilkS")
			(hide yes)
			(effects
				(font
					(size 1.27 1.27)
				)
			)
		)
		(property "Value" "300KR2F-GP"
			(at 0.064008 -3.993896 270)
			(unlocked yes)
			(layer "F.Fab")
			(hide yes)
			(effects
				(font
					(size 1.016 1.016)
					(thickness 0.1524)
				)
			)
		)
		(property "Device Type" "R402H16"
			(at 0.064008 -5.517896 270)
			(unlocked yes)
			(layer "F.Fab")
			(hide yes)
			(effects
				(font
					(size 1.016 1.016)
					(thickness 0.1524)
				)
			)
		)
		(duplicate_pad_numbers_are_jumpers no)
		(fp_line
			(start -0.508 -0.9398)
			(end -0.508 0.9398)
			(stroke
				(width 0.1524)
				(type default)
			)
			(layer "F.SilkS")
		)
		(fp_line
			(start 0.508 -0.9398)
			(end -0.508 -0.9398)
			(stroke
				(width 0.1524)
				(type default)
			)
			(layer "F.SilkS")
		)
		(fp_rect
			(start -0.508 0.9398)
			(end 0.508 -0.9398)
			(stroke
				(width 0)
				(type default)
			)
			(fill no)
			(layer "F.CrtYd")
		)
		(fp_rect
			(start -0.508 0.9398)
			(end 0.508 -0.9398)
			(stroke
				(width 0)
				(type default)
			)
			(fill no)
			(layer "F.Fab")
		)
		(pad "1" smd custom
			(at 0 -0.4445 270)
			(size 0.1397 0.1397)
			(layers "F.Cu" "F.Mask" "F.Paste")
			(net "SW_HDD_N35")
			(options
				(clearance outline)
				(anchor circle)
			)
			(primitives
				(gr_poly
					(pts
						(arc
							(start -0.1778 -0.2794)
							(mid -0.249642 -0.249642)
							(end -0.2794 -0.1778)
						)
						(arc
							(start -0.2794 0.1778)
							(mid -0.249642 0.249642)
							(end -0.1778 0.2794)
						)
						(arc
							(start 0.1778 0.2794)
							(mid 0.249642 0.249642)
							(end 0.2794 0.1778)
						)
						(arc
							(start 0.2794 -0.1778)
							(mid 0.249642 -0.249642)
							(end 0.1778 -0.2794)
						)
					)
					(width 0)
					(fill yes)
				)
			)
		)
		(pad "2" smd custom
			(at 0 0.4445 270)
			(size 0.1397 0.1397)
			(layers "F.Cu" "F.Mask" "F.Paste")
			(net "P12V_A")
			(options
				(clearance outline)
				(anchor circle)
			)
			(primitives
				(gr_poly
					(pts
						(arc
							(start -0.1778 -0.2794)
							(mid -0.249642 -0.249642)
							(end -0.2794 -0.1778)
						)
						(arc
							(start -0.2794 0.1778)
							(mid -0.249642 0.249642)
							(end -0.1778 0.2794)
						)
						(arc
							(start 0.1778 0.2794)
							(mid 0.249642 0.249642)
							(end 0.2794 0.1778)
						)
						(arc
							(start 0.2794 -0.1778)
							(mid 0.249642 -0.249642)
							(end 0.1778 -0.2794)
						)
					)
					(width 0)
					(fill yes)
				)
			)
		)
	)
	(footprint ""
		(layer "F.Cu")
		(at 451.527164 -242.250976)
		(property "Reference" "R268"
			(at 0 0 0)
			(layer "F.SilkS")
			(hide yes)
			(effects
				(font
					(size 1.27 1.27)
				)
			)
		)
		(property "Value" "130R3F-GP"
			(at -0.0254 -2.5146 0)
			(unlocked yes)
			(layer "F.Fab")
			(hide yes)
			(effects
				(font
					(size 1.016 1.016)
					(thickness 0.1524)
				)
			)
		)
		(property "Device Type" "R603H22"
			(at -0.0254 -4.0386 0)
			(unlocked yes)
			(layer "F.Fab")
			(hide yes)
			(effects
				(font
					(size 1.016 1.016)
					(thickness 0.1524)
				)
			)
		)
		(duplicate_pad_numbers_are_jumpers no)
		(fp_line
			(start -0.4826 0)
			(end -0.2032 0)
			(stroke
				(width 0.2032)
				(type default)
			)
			(layer "F.SilkS")
		)
		(fp_line
			(start 0.2032 0)
			(end 0.4826 0)
			(stroke
				(width 0.2032)
				(type default)
			)
			(layer "F.SilkS")
		)
		(fp_rect
			(start -0.5842 1.3335)
			(end 0.5842 -1.3335)
			(stroke
				(width 0)
				(type default)
			)
			(fill no)
			(layer "F.CrtYd")
		)
		(fp_rect
			(start -0.5842 1.3335)
			(end 0.5842 -1.3335)
			(stroke
				(width 0)
				(type default)
			)
			(fill no)
			(layer "F.Fab")
		)
		(pad "1" smd custom
			(at 0 -0.762)
			(size 0.2159 0.2159)
			(layers "F.Cu" "F.Mask" "F.Paste")
			(net "P5V_A_3")
			(options
				(clearance outline)
				(anchor circle)
			)
			(primitives
				(gr_poly
					(pts
						(arc
							(start -0.3302 -0.4318)
							(mid -0.402042 -0.402042)
							(end -0.4318 -0.3302)
						)
						(arc
							(start -0.4318 0.3302)
							(mid -0.402042 0.402042)
							(end -0.3302 0.4318)
						)
						(arc
							(start 0.3302 0.4318)
							(mid 0.402042 0.402042)
							(end 0.4318 0.3302)
						)
						(arc
							(start 0.4318 -0.3302)
							(mid 0.402042 -0.402042)
							(end 0.3302 -0.4318)
						)
					)
					(width 0)
					(fill yes)
				)
			)
		)
		(pad "2" smd custom
			(at 0 0.762)
			(size 0.2159 0.2159)
			(layers "F.Cu" "F.Mask" "F.Paste")
			(net "FLT_HDD11")
			(options
				(clearance outline)
				(anchor circle)
			)
			(primitives
				(gr_poly
					(pts
						(arc
							(start -0.3302 -0.4318)
							(mid -0.402042 -0.402042)
							(end -0.4318 -0.3302)
						)
						(arc
							(start -0.4318 0.3302)
							(mid -0.402042 0.402042)
							(end -0.3302 0.4318)
						)
						(arc
							(start 0.3302 0.4318)
							(mid 0.402042 0.402042)
							(end 0.4318 0.3302)
						)
						(arc
							(start 0.4318 -0.3302)
							(mid 0.402042 -0.402042)
							(end 0.3302 -0.4318)
						)
					)
					(width 0)
					(fill yes)
				)
			)
		)
	)
	(footprint ""
		(layer "F.Cu")
		(at 16.824198 -53.177694 -90)
		(property "Reference" "C360"
			(at 0 0 270)
			(layer "F.SilkS")
			(hide yes)
			(effects
				(font
					(size 1.27 1.27)
				)
			)
		)
		(property "Value" "SCD033U25V2KX-GP"
			(at 1.1811 -2.7051 270)
			(unlocked yes)
			(layer "F.Fab")
			(hide yes)
			(effects
				(font
					(size 1.016 1.016)
					(thickness 0.1524)
				)
			)
		)
		(property "Device Type" "C402H22"
			(at 1.1811 -4.2291 270)
			(unlocked yes)
			(layer "F.Fab")
			(hide yes)
			(effects
				(font
					(size 1.016 1.016)
					(thickness 0.1524)
				)
			)
		)
		(duplicate_pad_numbers_are_jumpers no)
		(fp_rect
			(start -0.4318 0.9525)
			(end 0.4318 -0.9525)
			(stroke
				(width 0)
				(type default)
			)
			(fill no)
			(layer "F.CrtYd")
		)
		(fp_rect
			(start -0.4318 0.9525)
			(end 0.4318 -0.9525)
			(stroke
				(width 0)
				(type default)
			)
			(fill no)
			(layer "F.Fab")
		)
		(pad "1" smd custom
			(at 0 -0.4445 270)
			(size 0.1524 0.1524)
			(layers "F.Cu" "F.Mask" "F.Paste")
			(net "SW_HDD_P24")
			(options
				(clearance outline)
				(anchor circle)
			)
			(primitives
				(gr_poly
					(pts
						(arc
							(start 0.3048 -0.2032)
							(mid 0.275042 -0.275042)
							(end 0.2032 -0.3048)
						)
						(arc
							(start -0.2032 -0.3048)
							(mid -0.275042 -0.275042)
							(end -0.3048 -0.2032)
						)
						(arc
							(start -0.3048 0.2032)
							(mid -0.275042 0.275042)
							(end -0.2032 0.3048)
						)
						(arc
							(start 0.2032 0.3048)
							(mid 0.275042 0.275042)
							(end 0.3048 0.2032)
						)
					)
					(width 0)
					(fill yes)
				)
			)
		)
		(pad "2" smd custom
			(at 0 0.4445 270)
			(size 0.1524 0.1524)
			(layers "F.Cu" "F.Mask" "F.Paste")
			(net "GND")
			(options
				(clearance outline)
				(anchor circle)
			)
			(primitives
				(gr_poly
					(pts
						(arc
							(start 0.3048 -0.2032)
							(mid 0.275042 -0.275042)
							(end 0.2032 -0.3048)
						)
						(arc
							(start -0.2032 -0.3048)
							(mid -0.275042 -0.275042)
							(end -0.3048 -0.2032)
						)
						(arc
							(start -0.3048 0.2032)
							(mid -0.275042 0.275042)
							(end -0.2032 0.3048)
						)
						(arc
							(start 0.2032 0.3048)
							(mid 0.275042 0.275042)
							(end 0.3048 0.2032)
						)
					)
					(width 0)
					(fill yes)
				)
			)
		)
	)
	(footprint ""
		(layer "F.Cu")
		(at 15.223998 -47.157894 180)
		(property "Reference" "R698"
			(at 0 0 180)
			(layer "F.SilkS")
			(hide yes)
			(effects
				(font
					(size 1.27 1.27)
				)
			)
		)
		(property "Value" "200KR2F-L-GP"
			(at 0.064008 -3.993896 180)
			(unlocked yes)
			(layer "F.Fab")
			(hide yes)
			(effects
				(font
					(size 1.016 1.016)
					(thickness 0.1524)
				)
			)
		)
		(property "Device Type" "R402H16"
			(at 0.064008 -5.517896 180)
			(unlocked yes)
			(layer "F.Fab")
			(hide yes)
			(effects
				(font
					(size 1.016 1.016)
					(thickness 0.1524)
				)
			)
		)
		(duplicate_pad_numbers_are_jumpers no)
		(fp_line
			(start 0.508 -0.9398)
			(end -0.508 -0.9398)
			(stroke
				(width 0.1524)
				(type default)
			)
			(layer "F.SilkS")
		)
		(fp_line
			(start -0.508 -0.9398)
			(end -0.508 0.9398)
			(stroke
				(width 0.1524)
				(type default)
			)
			(layer "F.SilkS")
		)
		(fp_rect
			(start -0.508 0.9398)
			(end 0.508 -0.9398)
			(stroke
				(width 0)
				(type default)
			)
			(fill no)
			(layer "F.CrtYd")
		)
		(fp_rect
			(start -0.508 0.9398)
			(end 0.508 -0.9398)
			(stroke
				(width 0)
				(type default)
			)
			(fill no)
			(layer "F.Fab")
		)
		(pad "1" smd custom
			(at 0 -0.4445 180)
			(size 0.1397 0.1397)
			(layers "F.Cu" "F.Mask" "F.Paste")
			(net "SW_HDD_R24")
			(options
				(clearance outline)
				(anchor circle)
			)
			(primitives
				(gr_poly
					(pts
						(arc
							(start -0.1778 -0.2794)
							(mid -0.249642 -0.249642)
							(end -0.2794 -0.1778)
						)
						(arc
							(start -0.2794 0.1778)
							(mid -0.249642 0.249642)
							(end -0.1778 0.2794)
						)
						(arc
							(start 0.1778 0.2794)
							(mid 0.249642 0.249642)
							(end 0.2794 0.1778)
						)
						(arc
							(start 0.2794 -0.1778)
							(mid 0.249642 -0.249642)
							(end 0.1778 -0.2794)
						)
					)
					(width 0)
					(fill yes)
				)
			)
		)
		(pad "2" smd custom
			(at 0 0.4445 180)
			(size 0.1397 0.1397)
			(layers "F.Cu" "F.Mask" "F.Paste")
			(net "SW_HDD_N24")
			(options
				(clearance outline)
				(anchor circle)
			)
			(primitives
				(gr_poly
					(pts
						(arc
							(start -0.1778 -0.2794)
							(mid -0.249642 -0.249642)
							(end -0.2794 -0.1778)
						)
						(arc
							(start -0.2794 0.1778)
							(mid -0.249642 0.249642)
							(end -0.1778 0.2794)
						)
						(arc
							(start 0.1778 0.2794)
							(mid 0.249642 0.249642)
							(end 0.2794 0.1778)
						)
						(arc
							(start 0.2794 -0.1778)
							(mid 0.249642 -0.249642)
							(end 0.1778 -0.2794)
						)
					)
					(width 0)
					(fill yes)
				)
			)
		)
	)
	(footprint ""
		(layer "F.Cu")
		(at 270.383 -280.162)
		(property "Reference" "C35"
			(at 0 0 0)
			(layer "F.SilkS")
			(hide yes)
			(effects
				(font
					(size 1.27 1.27)
				)
			)
		)
		(property "Value" "SC1U16V3KX-5GP"
			(at 0 -2.8194 0)
			(unlocked yes)
			(layer "F.Fab")
			(hide yes)
			(effects
				(font
					(size 1.016 1.016)
					(thickness 0.1524)
				)
			)
		)
		(property "Device Type" "C603H36"
			(at 0 -4.3434 0)
			(unlocked yes)
			(layer "F.Fab")
			(hide yes)
			(effects
				(font
					(size 1.016 1.016)
					(thickness 0.1524)
				)
			)
		)
		(duplicate_pad_numbers_are_jumpers no)
		(fp_line
			(start 0.508 0)
			(end -0.508 0)
			(stroke
				(width 0.2032)
				(type default)
			)
			(layer "F.SilkS")
		)
		(fp_rect
			(start -0.5842 1.3335)
			(end 0.5842 -1.3335)
			(stroke
				(width 0)
				(type default)
			)
			(fill no)
			(layer "F.CrtYd")
		)
		(fp_rect
			(start -0.5842 1.3335)
			(end 0.5842 -1.3335)
			(stroke
				(width 0)
				(type default)
			)
			(fill no)
			(layer "F.Fab")
		)
		(pad "1" smd custom
			(at 0 -0.762)
			(size 0.2159 0.2159)
			(layers "F.Cu" "F.Mask" "F.Paste")
			(net "P3V3_STBY_A")
			(options
				(clearance outline)
				(anchor circle)
			)
			(primitives
				(gr_poly
					(pts
						(arc
							(start -0.3302 -0.4318)
							(mid -0.402042 -0.402042)
							(end -0.4318 -0.3302)
						)
						(arc
							(start -0.4318 0.3302)
							(mid -0.402042 0.402042)
							(end -0.3302 0.4318)
						)
						(arc
							(start 0.3302 0.4318)
							(mid 0.402042 0.402042)
							(end 0.4318 0.3302)
						)
						(arc
							(start 0.4318 -0.3302)
							(mid 0.402042 -0.402042)
							(end 0.3302 -0.4318)
						)
					)
					(width 0)
					(fill yes)
				)
			)
		)
		(pad "2" smd custom
			(at 0 0.762)
			(size 0.2159 0.2159)
			(layers "F.Cu" "F.Mask" "F.Paste")
			(net "GND")
			(options
				(clearance outline)
				(anchor circle)
			)
			(primitives
				(gr_poly
					(pts
						(arc
							(start -0.3302 -0.4318)
							(mid -0.402042 -0.402042)
							(end -0.4318 -0.3302)
						)
						(arc
							(start -0.4318 0.3302)
							(mid -0.402042 0.402042)
							(end -0.3302 0.4318)
						)
						(arc
							(start 0.3302 0.4318)
							(mid 0.402042 0.402042)
							(end 0.4318 0.3302)
						)
						(arc
							(start 0.4318 -0.3302)
							(mid 0.402042 -0.402042)
							(end 0.3302 -0.4318)
						)
					)
					(width 0)
					(fill yes)
				)
			)
		)
	)
	(footprint ""
		(layer "F.Cu")
		(at 449.545202 -256.34315 -90)
		(property "Reference" "C637"
			(at 0 0 270)
			(layer "F.SilkS")
			(hide yes)
			(effects
				(font
					(size 1.27 1.27)
				)
			)
		)
		(property "Value" "SC1U16V3KX-5GP"
			(at 0 -2.8194 270)
			(unlocked yes)
			(layer "F.Fab")
			(hide yes)
			(effects
				(font
					(size 1.016 1.016)
					(thickness 0.1524)
				)
			)
		)
		(property "Device Type" "C603H36"
			(at 0 -4.3434 270)
			(unlocked yes)
			(layer "F.Fab")
			(hide yes)
			(effects
				(font
					(size 1.016 1.016)
					(thickness 0.1524)
				)
			)
		)
		(duplicate_pad_numbers_are_jumpers no)
		(fp_line
			(start 0.508 0)
			(end -0.508 0)
			(stroke
				(width 0.2032)
				(type default)
			)
			(layer "F.SilkS")
		)
		(fp_rect
			(start -0.5842 1.3335)
			(end 0.5842 -1.3335)
			(stroke
				(width 0)
				(type default)
			)
			(fill no)
			(layer "F.CrtYd")
		)
		(fp_rect
			(start -0.5842 1.3335)
			(end 0.5842 -1.3335)
			(stroke
				(width 0)
				(type default)
			)
			(fill no)
			(layer "F.Fab")
		)
		(pad "1" smd custom
			(at 0 -0.762 270)
			(size 0.2159 0.2159)
			(layers "F.Cu" "F.Mask" "F.Paste")
			(net "P5V_C_EN_R")
			(options
				(clearance outline)
				(anchor circle)
			)
			(primitives
				(gr_poly
					(pts
						(arc
							(start -0.3302 -0.4318)
							(mid -0.402042 -0.402042)
							(end -0.4318 -0.3302)
						)
						(arc
							(start -0.4318 0.3302)
							(mid -0.402042 0.402042)
							(end -0.3302 0.4318)
						)
						(arc
							(start 0.3302 0.4318)
							(mid 0.402042 0.402042)
							(end 0.4318 0.3302)
						)
						(arc
							(start 0.4318 -0.3302)
							(mid 0.402042 -0.402042)
							(end 0.3302 -0.4318)
						)
					)
					(width 0)
					(fill yes)
				)
			)
		)
		(pad "2" smd custom
			(at 0 0.762 270)
			(size 0.2159 0.2159)
			(layers "F.Cu" "F.Mask" "F.Paste")
			(net "GND")
			(options
				(clearance outline)
				(anchor circle)
			)
			(primitives
				(gr_poly
					(pts
						(arc
							(start -0.3302 -0.4318)
							(mid -0.402042 -0.402042)
							(end -0.4318 -0.3302)
						)
						(arc
							(start -0.4318 0.3302)
							(mid -0.402042 0.402042)
							(end -0.3302 0.4318)
						)
						(arc
							(start 0.3302 0.4318)
							(mid 0.402042 0.402042)
							(end 0.4318 0.3302)
						)
						(arc
							(start 0.4318 -0.3302)
							(mid 0.402042 -0.402042)
							(end 0.3302 -0.4318)
						)
					)
					(width 0)
					(fill yes)
				)
			)
		)
	)
	(footprint ""
		(layer "F.Cu")
		(at 224.536 -127.8382 -90)
		(property "Reference" "TP203"
			(at 0 0 270)
			(layer "F.SilkS")
			(hide yes)
			(effects
				(font
					(size 1.27 1.27)
				)
			)
		)
		(property "Value" "TPAD32-GP"
			(at -0.0508 -1.6764 270)
			(unlocked yes)
			(layer "F.Fab")
			(hide yes)
			(effects
				(font
					(size 1.016 1.016)
					(thickness 0.1524)
				)
			)
		)
		(property "Device Type" "TPAD32"
			(at -0.0508 -3.2004 270)
			(unlocked yes)
			(layer "F.Fab")
			(hide yes)
			(effects
				(font
					(size 1.016 1.016)
					(thickness 0.1524)
				)
			)
		)
		(duplicate_pad_numbers_are_jumpers no)
		(fp_poly
			(pts
				(arc
					(start 0 -0.4064)
					(mid 0 0.4064)
					(end 0 -0.4064)
				)
			)
			(stroke
				(width 0)
				(type default)
			)
			(fill no)
			(layer "F.CrtYd")
		)
		(fp_poly
			(pts
				(arc
					(start 0 -0.7112)
					(mid 0 0.7112)
					(end 0 -0.7112)
				)
			)
			(stroke
				(width 0)
				(type default)
			)
			(fill no)
			(layer "F.Fab")
		)
		(pad "1" smd circle
			(at 0 0 270)
			(size 0.8128 0.8128)
			(layers "F.Cu" "F.Mask" "F.Paste")
			(net "TP_COMP_A_SATA_P0_TX_DP")
		)
	)
	(footprint ""
		(layer "F.Cu")
		(at 456.674982 -92.799916)
		(property "Reference" ""
			(at 0 0 0)
			(layer "F.SilkS")
			(hide yes)
			(effects
				(font
					(size 1.27 1.27)
				)
			)
		)
		(property "Value" "*"
			(at -8.398764 -8.057642 0)
			(unlocked yes)
			(layer "F.Fab")
			(hide yes)
			(effects
				(font
					(size 1.016 1.016)
					(thickness 0.1524)
				)
			)
		)
		(duplicate_pad_numbers_are_jumpers no)
		(fp_poly
			(pts
				(arc
					(start 7.3152 0)
					(mid 0 7.3152)
					(end -7.3152 0)
				)
				(arc
					(start -7.3152 -5.9944)
					(mid 0 -13.3096)
					(end 7.3152 -5.9944)
				)
			)
			(stroke
				(width 0)
				(type default)
			)
			(fill no)
			(layer "B.CrtYd")
		)
		(fp_poly
			(pts
				(arc
					(start 7.3152 0)
					(mid 0 7.3152)
					(end -7.3152 0)
				)
				(arc
					(start -7.3152 -5.9944)
					(mid 0 -13.3096)
					(end 7.3152 -5.9944)
				)
			)
			(stroke
				(width 0)
				(type default)
			)
			(fill no)
			(layer "F.CrtYd")
		)
		(fp_poly
			(pts
				(arc
					(start 7.3152 0)
					(mid 0 7.3152)
					(end -7.3152 0)
				)
				(arc
					(start -7.3152 -5.9944)
					(mid 0 -13.3096)
					(end 7.3152 -5.9944)
				)
			)
			(stroke
				(width 0)
				(type default)
			)
			(fill no)
			(layer "B.Fab")
		)
		(fp_poly
			(pts
				(arc
					(start 7.3152 0)
					(mid 0 7.3152)
					(end -7.3152 0)
				)
				(arc
					(start -7.3152 -5.9944)
					(mid 0 -13.3096)
					(end 7.3152 -5.9944)
				)
			)
			(stroke
				(width 0)
				(type default)
			)
			(fill no)
			(layer "F.Fab")
		)
		(pad "1" thru_hole oval
			(at 0 0)
			(size 14.0208 20.0152)
			(drill 0.0254
				(offset 0 -2.9972)
			)
			(layers "*.Cu" "*.Mask")
			(remove_unused_layers no)
			(net "Net_37")
			(clearance -1.002284)
			(thermal_gap 0.1524)
			(padstack
				(mode front_inner_back)
				(layer "Inner"
					(shape custom)
					(size 2.928012 2.928012)
					(options
						(anchor circle)
					)
					(primitives
						(gr_poly
							(pts
								(arc
									(start 4.571746 -2.084324)
									(mid 0.000333 7.430372)
									(end -4.571492 -2.084324)
								)
								(arc
									(start -4.571492 -2.084324)
									(mid -3.570296 -3.611977)
									(end -2.875026 -5.30098)
								)
								(arc
									(start -2.875026 -5.30098)
									(mid 0.000217 -7.43089)
									(end 2.87528 -5.30098)
								)
								(arc
									(start 2.87528 -5.30098)
									(mid 3.570511 -3.611956)
									(end 4.571746 -2.084324)
								)
							)
							(width 0)
							(fill yes)
						)
					)
					(clearance 0.1524)
				)
				(layer "B.Cu"
					(shape oval)
					(size 14.0208 20.0152)
					(offset 0 -2.9972)
					(clearance -1.002284)
				)
			)
		)
		(zone
			(layers "F.Cu" "B.Cu" "In1.Cu" "In2.Cu" "In3.Cu" "In4.Cu" "In5.Cu" "In6.Cu"
				"In7.Cu" "In8.Cu" "In9.Cu" "In10.Cu"
			)
			(hatch none 0.5)
			(connect_pads
				(clearance 0)
			)
			(min_thickness 0.25)
			(keepout
				(tracks not_allowed)
				(vias allowed)
				(pads allowed)
				(copperpour not_allowed)
				(footprints allowed)
			)
			(placement
				(enabled no)
				(sheetname "")
			)
			(fill
				(thermal_gap 0.5)
				(thermal_bridge_width 0.5)
				(island_removal_mode 0)
			)
			(polygon
				(pts
					(arc
						(start 449.664582 -98.794316)
						(mid 456.674982 -105.804716)
						(end 463.685382 -98.794316)
					)
					(arc
						(start 463.685382 -92.799916)
						(mid 456.674982 -85.789516)
						(end 449.664582 -92.799916)
					)
				)
			)
		)
	)
	(footprint ""
		(layer "F.Cu")
		(at 98.6028 -298.704)
		(property "Reference" "TP12"
			(at 0 0 0)
			(layer "F.SilkS")
			(hide yes)
			(effects
				(font
					(size 1.27 1.27)
				)
			)
		)
		(property "Value" "TPAD32-GP"
			(at -0.0508 -1.6764 0)
			(unlocked yes)
			(layer "F.Fab")
			(hide yes)
			(effects
				(font
					(size 1.016 1.016)
					(thickness 0.1524)
				)
			)
		)
		(property "Device Type" "TPAD32"
			(at -0.0508 -3.2004 0)
			(unlocked yes)
			(layer "F.Fab")
			(hide yes)
			(effects
				(font
					(size 1.016 1.016)
					(thickness 0.1524)
				)
			)
		)
		(duplicate_pad_numbers_are_jumpers no)
		(fp_poly
			(pts
				(arc
					(start 0.4064 0)
					(mid -0.4064 0)
					(end 0.4064 0)
				)
			)
			(stroke
				(width 0)
				(type default)
			)
			(fill no)
			(layer "F.CrtYd")
		)
		(fp_poly
			(pts
				(arc
					(start 0.7112 0)
					(mid -0.7112 0)
					(end 0.7112 0)
				)
			)
			(stroke
				(width 0)
				(type default)
			)
			(fill no)
			(layer "F.Fab")
		)
		(pad "1" smd circle
			(at 0 0)
			(size 0.8128 0.8128)
			(layers "F.Cu" "F.Mask" "F.Paste")
			(net "ACT_HDD_2")
		)
	)
	(footprint ""
		(layer "F.Cu")
		(at 349.812102 -176.127918 -90)
		(property "Reference" "C293"
			(at 0 0 270)
			(layer "F.SilkS")
			(hide yes)
			(effects
				(font
					(size 1.27 1.27)
				)
			)
		)
		(property "Value" "SCD01U50V2KX-1GP"
			(at 1.1811 -2.7051 270)
			(unlocked yes)
			(layer "F.Fab")
			(hide yes)
			(effects
				(font
					(size 1.016 1.016)
					(thickness 0.1524)
				)
			)
		)
		(property "Device Type" "C402H22"
			(at 1.1811 -4.2291 270)
			(unlocked yes)
			(layer "F.Fab")
			(hide yes)
			(effects
				(font
					(size 1.016 1.016)
					(thickness 0.1524)
				)
			)
		)
		(duplicate_pad_numbers_are_jumpers no)
		(fp_rect
			(start -0.4318 0.9525)
			(end 0.4318 -0.9525)
			(stroke
				(width 0)
				(type default)
			)
			(fill no)
			(layer "F.CrtYd")
		)
		(fp_rect
			(start -0.4318 0.9525)
			(end 0.4318 -0.9525)
			(stroke
				(width 0)
				(type default)
			)
			(fill no)
			(layer "F.Fab")
		)
		(pad "1" smd custom
			(at 0 -0.4445 270)
			(size 0.1524 0.1524)
			(layers "F.Cu" "F.Mask" "F.Paste")
			(net "HDD_PRSNT_19")
			(options
				(clearance outline)
				(anchor circle)
			)
			(primitives
				(gr_poly
					(pts
						(arc
							(start 0.3048 -0.2032)
							(mid 0.275042 -0.275042)
							(end 0.2032 -0.3048)
						)
						(arc
							(start -0.2032 -0.3048)
							(mid -0.275042 -0.275042)
							(end -0.3048 -0.2032)
						)
						(arc
							(start -0.3048 0.2032)
							(mid -0.275042 0.275042)
							(end -0.2032 0.3048)
						)
						(arc
							(start 0.2032 0.3048)
							(mid 0.275042 0.275042)
							(end 0.3048 0.2032)
						)
					)
					(width 0)
					(fill yes)
				)
			)
		)
		(pad "2" smd custom
			(at 0 0.4445 270)
			(size 0.1524 0.1524)
			(layers "F.Cu" "F.Mask" "F.Paste")
			(net "GND")
			(options
				(clearance outline)
				(anchor circle)
			)
			(primitives
				(gr_poly
					(pts
						(arc
							(start 0.3048 -0.2032)
							(mid 0.275042 -0.275042)
							(end 0.2032 -0.3048)
						)
						(arc
							(start -0.2032 -0.3048)
							(mid -0.275042 -0.275042)
							(end -0.3048 -0.2032)
						)
						(arc
							(start -0.3048 0.2032)
							(mid -0.275042 0.275042)
							(end -0.2032 0.3048)
						)
						(arc
							(start 0.2032 0.3048)
							(mid 0.275042 0.275042)
							(end 0.3048 0.2032)
						)
					)
					(width 0)
					(fill yes)
				)
			)
		)
	)
	(footprint ""
		(layer "F.Cu")
		(at 98.643948 -68.747894)
		(property "Reference" "TP132"
			(at 0 0 0)
			(layer "F.SilkS")
			(hide yes)
			(effects
				(font
					(size 1.27 1.27)
				)
			)
		)
		(property "Value" "TPAD32-GP"
			(at -0.0508 -1.6764 0)
			(unlocked yes)
			(layer "F.Fab")
			(hide yes)
			(effects
				(font
					(size 1.016 1.016)
					(thickness 0.1524)
				)
			)
		)
		(property "Device Type" "TPAD32"
			(at -0.0508 -3.2004 0)
			(unlocked yes)
			(layer "F.Fab")
			(hide yes)
			(effects
				(font
					(size 1.016 1.016)
					(thickness 0.1524)
				)
			)
		)
		(duplicate_pad_numbers_are_jumpers no)
		(fp_poly
			(pts
				(arc
					(start 0.4064 0)
					(mid -0.4064 0)
					(end 0.4064 0)
				)
			)
			(stroke
				(width 0)
				(type default)
			)
			(fill no)
			(layer "F.CrtYd")
		)
		(fp_poly
			(pts
				(arc
					(start 0.7112 0)
					(mid -0.7112 0)
					(end 0.7112 0)
				)
			)
			(stroke
				(width 0)
				(type default)
			)
			(fill no)
			(layer "F.Fab")
		)
		(pad "1" smd circle
			(at 0 0)
			(size 0.8128 0.8128)
			(layers "F.Cu" "F.Mask" "F.Paste")
			(net "ACT_HDD_26")
		)
	)
	(footprint ""
		(layer "F.Cu")
		(at 85.199728 -159.874966 90)
		(property "Reference" "R463"
			(at 0 0 90)
			(layer "F.SilkS")
			(hide yes)
			(effects
				(font
					(size 1.27 1.27)
				)
			)
		)
		(property "Value" "0R2J-2-GP"
			(at 0.064008 -3.993896 90)
			(unlocked yes)
			(layer "F.Fab")
			(hide yes)
			(effects
				(font
					(size 1.016 1.016)
					(thickness 0.1524)
				)
			)
		)
		(property "Device Type" "R402H16"
			(at 0.064008 -5.517896 90)
			(unlocked yes)
			(layer "F.Fab")
			(hide yes)
			(effects
				(font
					(size 1.016 1.016)
					(thickness 0.1524)
				)
			)
		)
		(duplicate_pad_numbers_are_jumpers no)
		(fp_line
			(start 0.508 -0.9398)
			(end -0.508 -0.9398)
			(stroke
				(width 0.1524)
				(type default)
			)
			(layer "F.SilkS")
		)
		(fp_line
			(start -0.508 -0.9398)
			(end -0.508 0.9398)
			(stroke
				(width 0.1524)
				(type default)
			)
			(layer "F.SilkS")
		)
		(fp_rect
			(start -0.508 0.9398)
			(end 0.508 -0.9398)
			(stroke
				(width 0)
				(type default)
			)
			(fill no)
			(layer "F.CrtYd")
		)
		(fp_rect
			(start -0.508 0.9398)
			(end 0.508 -0.9398)
			(stroke
				(width 0)
				(type default)
			)
			(fill no)
			(layer "F.Fab")
		)
		(pad "1" smd custom
			(at 0 -0.4445 90)
			(size 0.1397 0.1397)
			(layers "F.Cu" "F.Mask" "F.Paste")
			(net "DRIVE_A_14_PWR")
			(options
				(clearance outline)
				(anchor circle)
			)
			(primitives
				(gr_poly
					(pts
						(arc
							(start -0.1778 -0.2794)
							(mid -0.249642 -0.249642)
							(end -0.2794 -0.1778)
						)
						(arc
							(start -0.2794 0.1778)
							(mid -0.249642 0.249642)
							(end -0.1778 0.2794)
						)
						(arc
							(start 0.1778 0.2794)
							(mid 0.249642 0.249642)
							(end 0.2794 0.1778)
						)
						(arc
							(start 0.2794 -0.1778)
							(mid 0.249642 -0.249642)
							(end 0.1778 -0.2794)
						)
					)
					(width 0)
					(fill yes)
				)
			)
		)
		(pad "2" smd custom
			(at 0 0.4445 90)
			(size 0.1397 0.1397)
			(layers "F.Cu" "F.Mask" "F.Paste")
			(net "SW_PWR_R_HDD14")
			(options
				(clearance outline)
				(anchor circle)
			)
			(primitives
				(gr_poly
					(pts
						(arc
							(start -0.1778 -0.2794)
							(mid -0.249642 -0.249642)
							(end -0.2794 -0.1778)
						)
						(arc
							(start -0.2794 0.1778)
							(mid -0.249642 0.249642)
							(end -0.1778 0.2794)
						)
						(arc
							(start 0.1778 0.2794)
							(mid 0.249642 0.249642)
							(end 0.2794 0.1778)
						)
						(arc
							(start 0.2794 -0.1778)
							(mid 0.249642 -0.249642)
							(end 0.1778 -0.2794)
						)
					)
					(width 0)
					(fill yes)
				)
			)
		)
	)
	(footprint ""
		(layer "F.Cu")
		(at 37.354002 -255.32715)
		(property "Reference" "TP256"
			(at 0 0 0)
			(layer "F.SilkS")
			(hide yes)
			(effects
				(font
					(size 1.27 1.27)
				)
			)
		)
		(property "Value" "TPAD32-GP"
			(at -0.0508 -1.6764 0)
			(unlocked yes)
			(layer "F.Fab")
			(hide yes)
			(effects
				(font
					(size 1.016 1.016)
					(thickness 0.1524)
				)
			)
		)
		(property "Device Type" "TPAD32"
			(at -0.0508 -3.2004 0)
			(unlocked yes)
			(layer "F.Fab")
			(hide yes)
			(effects
				(font
					(size 1.016 1.016)
					(thickness 0.1524)
				)
			)
		)
		(duplicate_pad_numbers_are_jumpers no)
		(fp_poly
			(pts
				(arc
					(start 0.4064 0)
					(mid -0.4064 0)
					(end 0.4064 0)
				)
			)
			(stroke
				(width 0)
				(type default)
			)
			(fill no)
			(layer "F.CrtYd")
		)
		(fp_poly
			(pts
				(arc
					(start 0.7112 0)
					(mid -0.7112 0)
					(end 0.7112 0)
				)
			)
			(stroke
				(width 0)
				(type default)
			)
			(fill no)
			(layer "F.Fab")
		)
		(pad "1" smd circle
			(at 0 0)
			(size 0.8128 0.8128)
			(layers "F.Cu" "F.Mask" "F.Paste")
			(net "P5V_A_1_PGOOD")
		)
	)
	(footprint ""
		(layer "F.Cu")
		(at 139.516866 -131.656074 180)
		(property "Reference" "R1045"
			(at 0 0 180)
			(layer "F.SilkS")
			(hide yes)
			(effects
				(font
					(size 1.27 1.27)
				)
			)
		)
		(property "Value" "10KR2J-3-GP"
			(at 0.064008 -3.993896 180)
			(unlocked yes)
			(layer "F.Fab")
			(hide yes)
			(effects
				(font
					(size 1.016 1.016)
					(thickness 0.1524)
				)
			)
		)
		(property "Device Type" "R402H16"
			(at 0.064008 -5.517896 180)
			(unlocked yes)
			(layer "F.Fab")
			(hide yes)
			(effects
				(font
					(size 1.016 1.016)
					(thickness 0.1524)
				)
			)
		)
		(duplicate_pad_numbers_are_jumpers no)
		(fp_line
			(start 0.508 -0.9398)
			(end -0.508 -0.9398)
			(stroke
				(width 0.1524)
				(type default)
			)
			(layer "F.SilkS")
		)
		(fp_line
			(start -0.508 -0.9398)
			(end -0.508 0.9398)
			(stroke
				(width 0.1524)
				(type default)
			)
			(layer "F.SilkS")
		)
		(fp_rect
			(start -0.508 0.9398)
			(end 0.508 -0.9398)
			(stroke
				(width 0)
				(type default)
			)
			(fill no)
			(layer "F.CrtYd")
		)
		(fp_rect
			(start -0.508 0.9398)
			(end 0.508 -0.9398)
			(stroke
				(width 0)
				(type default)
			)
			(fill no)
			(layer "F.Fab")
		)
		(pad "1" smd custom
			(at 0 -0.4445 180)
			(size 0.1397 0.1397)
			(layers "F.Cu" "F.Mask" "F.Paste")
			(net "GND")
			(options
				(clearance outline)
				(anchor circle)
			)
			(primitives
				(gr_poly
					(pts
						(arc
							(start -0.1778 -0.2794)
							(mid -0.249642 -0.249642)
							(end -0.2794 -0.1778)
						)
						(arc
							(start -0.2794 0.1778)
							(mid -0.249642 0.249642)
							(end -0.1778 0.2794)
						)
						(arc
							(start 0.1778 0.2794)
							(mid 0.249642 0.249642)
							(end 0.2794 0.1778)
						)
						(arc
							(start 0.2794 -0.1778)
							(mid 0.249642 -0.249642)
							(end 0.1778 -0.2794)
						)
					)
					(width 0)
					(fill yes)
				)
			)
		)
		(pad "2" smd custom
			(at 0 0.4445 180)
			(size 0.1397 0.1397)
			(layers "F.Cu" "F.Mask" "F.Paste")
			(net "MB0_RETRY_R")
			(options
				(clearance outline)
				(anchor circle)
			)
			(primitives
				(gr_poly
					(pts
						(arc
							(start -0.1778 -0.2794)
							(mid -0.249642 -0.249642)
							(end -0.2794 -0.1778)
						)
						(arc
							(start -0.2794 0.1778)
							(mid -0.249642 0.249642)
							(end -0.1778 0.2794)
						)
						(arc
							(start 0.1778 0.2794)
							(mid 0.249642 0.249642)
							(end 0.2794 0.1778)
						)
						(arc
							(start 0.2794 -0.1778)
							(mid 0.249642 -0.249642)
							(end 0.1778 -0.2794)
						)
					)
					(width 0)
					(fill yes)
				)
			)
		)
	)
	(footprint ""
		(layer "B.Cu")
		(at 474.542104 -232.678986 180)
		(property "Reference" "U27"
			(at 0 0 0)
			(layer "B.SilkS")
			(hide yes)
			(effects
				(font
					(size 1.27 1.27)
				)
				(justify mirror)
			)
		)
		(property "Value" "TPS53319DQPR-GP"
			(at -4.7498 -5.6896 180)
			(unlocked yes)
			(layer "B.Fab")
			(hide yes)
			(effects
				(font
					(size 1.016 1.016)
					(thickness 0.1524)
				)
				(justify mirror)
			)
		)
		(property "Device Type" "QFN22G6050-G6133H60"
			(at -4.7498 -7.2136 180)
			(unlocked yes)
			(layer "B.Fab")
			(hide yes)
			(effects
				(font
					(size 1.016 1.016)
					(thickness 0.1524)
				)
				(justify mirror)
			)
		)
		(duplicate_pad_numbers_are_jumpers no)
		(fp_line
			(start 3.556 3.5179)
			(end 2.286 3.5179)
			(stroke
				(width 0.1524)
				(type default)
			)
			(layer "B.SilkS")
		)
		(fp_line
			(start 3.556 2.2479)
			(end 3.556 3.5179)
			(stroke
				(width 0.1524)
				(type default)
			)
			(layer "B.SilkS")
		)
		(fp_line
			(start 3.556 -3.5179)
			(end 3.556 -2.2479)
			(stroke
				(width 0.1524)
				(type default)
			)
			(layer "B.SilkS")
		)
		(fp_line
			(start 2.286 -3.5179)
			(end 3.556 -3.5179)
			(stroke
				(width 0.1524)
				(type default)
			)
			(layer "B.SilkS")
		)
		(fp_line
			(start 1.999996 -3.262122)
			(end 1.999996 -4.024122)
			(stroke
				(width 0.1524)
				(type default)
			)
			(layer "B.SilkS")
		)
		(fp_line
			(start 0.999998 3.262122)
			(end 0.999998 3.770122)
			(stroke
				(width 0.1524)
				(type default)
			)
			(layer "B.SilkS")
		)
		(fp_line
			(start -0.500126 -3.262122)
			(end -0.500126 -3.770122)
			(stroke
				(width 0.1524)
				(type default)
			)
			(layer "B.SilkS")
		)
		(fp_line
			(start -1.500124 3.262122)
			(end -1.500124 4.024122)
			(stroke
				(width 0.1524)
				(type default)
			)
			(layer "B.SilkS")
		)
		(fp_line
			(start -2.286 3.5179)
			(end -3.556 3.5179)
			(stroke
				(width 0.1524)
				(type default)
			)
			(layer "B.SilkS")
		)
		(fp_line
			(start -3.556 3.5179)
			(end -3.556 2.2479)
			(stroke
				(width 0.1524)
				(type default)
			)
			(layer "B.SilkS")
		)
		(fp_poly
			(pts
				(xy -3.556 -3.5179) (xy -2.5273 -3.5179) (xy -3.556 -2.4892)
			)
			(stroke
				(width 0)
				(type default)
			)
			(fill yes)
			(layer "B.SilkS")
		)
		(fp_rect
			(start 2.9972 2.5019)
			(end -2.9972 -2.5019)
			(stroke
				(width 0)
				(type default)
			)
			(fill no)
			(layer "B.CrtYd")
		)
		(fp_poly
			(pts
				(xy -3.556 -2.5019) (xy 2.9972 -2.5019) (xy 2.9972 2.5019) (xy -2.9972 2.5019) (xy -2.9972 -2.4892)
				(xy -3.556 -2.4892) (xy -3.556 3.5179) (xy 3.556 3.5179) (xy 3.556 -3.5179) (xy -3.556 -3.5179)
			)
			(stroke
				(width 0)
				(type default)
			)
			(fill no)
			(layer "B.CrtYd")
		)
		(fp_rect
			(start 3.556 3.5179)
			(end -3.556 -3.5179)
			(stroke
				(width 0)
				(type default)
			)
			(fill no)
			(layer "B.Fab")
		)
		(pad "1" smd rect
			(at -2.500122 -2.449322)
			(size 0.3048 1.1176)
			(layers "B.Cu" "B.Mask" "B.Paste")
			(net "P5V_D_VFB")
		)
		(pad "2" smd rect
			(at -1.999996 -2.449322)
			(size 0.3048 1.1176)
			(layers "B.Cu" "B.Mask" "B.Paste")
			(net "P5V_D_EN_R")
		)
		(pad "3" smd rect
			(at -1.500124 -2.449322)
			(size 0.3048 1.1176)
			(layers "B.Cu" "B.Mask" "B.Paste")
			(net "P5V_A_4_PGOOD")
		)
		(pad "4" smd rect
			(at -0.999998 -2.449322)
			(size 0.3048 1.1176)
			(layers "B.Cu" "B.Mask" "B.Paste")
			(net "P5V_D_VBST")
		)
		(pad "5" smd rect
			(at -0.500126 -2.449322)
			(size 0.3048 1.1176)
			(layers "B.Cu" "B.Mask" "B.Paste")
			(net "P5V_D_ROVP")
		)
		(pad "6" smd rect
			(at 0 -2.449322)
			(size 0.3048 1.1176)
			(layers "B.Cu" "B.Mask" "B.Paste")
			(net "P5V_D_LL")
		)
		(pad "7" smd rect
			(at 0.500126 -2.449322)
			(size 0.3048 1.1176)
			(layers "B.Cu" "B.Mask" "B.Paste")
			(net "P5V_D_LL")
		)
		(pad "8" smd rect
			(at 0.999998 -2.449322)
			(size 0.3048 1.1176)
			(layers "B.Cu" "B.Mask" "B.Paste")
			(net "P5V_D_LL")
		)
		(pad "9" smd rect
			(at 1.500124 -2.449322)
			(size 0.3048 1.1176)
			(layers "B.Cu" "B.Mask" "B.Paste")
			(net "P5V_D_LL")
		)
		(pad "10" smd rect
			(at 1.999996 -2.449322)
			(size 0.3048 1.1176)
			(layers "B.Cu" "B.Mask" "B.Paste")
			(net "P5V_D_LL")
		)
		(pad "11" smd rect
			(at 2.500122 -2.449322)
			(size 0.3048 1.1176)
			(layers "B.Cu" "B.Mask" "B.Paste")
			(net "P5V_D_LL")
		)
		(pad "12" smd rect
			(at 2.500122 2.449322)
			(size 0.3048 1.1176)
			(layers "B.Cu" "B.Mask" "B.Paste")
			(net "P12V_A_VIN_U27")
		)
		(pad "13" smd rect
			(at 1.999996 2.449322)
			(size 0.3048 1.1176)
			(layers "B.Cu" "B.Mask" "B.Paste")
			(net "P12V_A_VIN_U27")
		)
		(pad "14" smd rect
			(at 1.500124 2.449322)
			(size 0.3048 1.1176)
			(layers "B.Cu" "B.Mask" "B.Paste")
			(net "P12V_A_VIN_U27")
		)
		(pad "15" smd rect
			(at 0.999998 2.449322)
			(size 0.3048 1.1176)
			(layers "B.Cu" "B.Mask" "B.Paste")
			(net "P12V_A_VIN_U27")
		)
		(pad "16" smd rect
			(at 0.500126 2.449322)
			(size 0.3048 1.1176)
			(layers "B.Cu" "B.Mask" "B.Paste")
			(net "P12V_A_VIN_U27")
		)
		(pad "17" smd rect
			(at 0 2.449322)
			(size 0.3048 1.1176)
			(layers "B.Cu" "B.Mask" "B.Paste")
			(net "P12V_A_VIN_U27")
		)
		(pad "18" smd rect
			(at -0.500126 2.449322)
			(size 0.3048 1.1176)
			(layers "B.Cu" "B.Mask" "B.Paste")
			(net "P5V_D_VREG")
		)
		(pad "19" smd rect
			(at -0.999998 2.449322)
			(size 0.3048 1.1176)
			(layers "B.Cu" "B.Mask" "B.Paste")
			(net "P12V_A_VDD_U27")
		)
		(pad "20" smd rect
			(at -1.500124 2.449322)
			(size 0.3048 1.1176)
			(layers "B.Cu" "B.Mask" "B.Paste")
			(net "P5V_D_MODE")
		)
		(pad "21" smd rect
			(at -1.999996 2.449322)
			(size 0.3048 1.1176)
			(layers "B.Cu" "B.Mask" "B.Paste")
			(net "P5V_D_TRIP")
		)
		(pad "22" smd rect
			(at -2.500122 2.449322)
			(size 0.3048 1.1176)
			(layers "B.Cu" "B.Mask" "B.Paste")
			(net "P5V_D_RF")
		)
		(pad "23" smd custom
			(at 0 0)
			(size 0.83185 0.83185)
			(layers "B.Cu" "B.Mask" "B.Paste")
			(net "GND")
			(options
				(clearance outline)
				(anchor circle)
			)
			(primitives
				(gr_poly
					(pts
						(xy -2.7813 -1.6637) (xy -2.7813 -1.2954) (xy -3.048 -1.2954) (xy -3.048 -0.9525) (xy -2.7813 -0.9525)
						(xy -2.7813 0.9525) (xy -3.048 0.9525) (xy -3.048 1.2954) (xy -2.7813 1.2954) (xy -2.7813 1.6637)
						(xy 2.7813 1.6637) (xy 2.7813 1.2954) (xy 3.048 1.2954) (xy 3.048 0.9525) (xy 2.7813 0.9525) (xy 2.7813 -0.9525)
						(xy 3.048 -0.9525) (xy 3.048 -1.2954) (xy 2.7813 -1.2954) (xy 2.7813 -1.6637)
					)
					(width 0)
					(fill yes)
				)
			)
		)
	)
	(footprint ""
		(layer "B.Cu")
		(at 216.535 -123.4948 180)
		(property "Reference" "R355"
			(at 0 0 0)
			(layer "B.SilkS")
			(hide yes)
			(effects
				(font
					(size 1.27 1.27)
				)
				(justify mirror)
			)
		)
		(property "Value" "0R2J-2-GP"
			(at -0.064008 -3.993896 180)
			(unlocked yes)
			(layer "B.Fab")
			(hide yes)
			(effects
				(font
					(size 1.016 1.016)
					(thickness 0.1524)
				)
				(justify mirror)
			)
		)
		(property "Device Type" "R402H16"
			(at -0.064008 -5.517896 180)
			(unlocked yes)
			(layer "B.Fab")
			(hide yes)
			(effects
				(font
					(size 1.016 1.016)
					(thickness 0.1524)
				)
				(justify mirror)
			)
		)
		(duplicate_pad_numbers_are_jumpers no)
		(fp_line
			(start 0.508 -0.9398)
			(end 0.508 0.9398)
			(stroke
				(width 0.1524)
				(type default)
			)
			(layer "B.SilkS")
		)
		(fp_line
			(start -0.508 -0.9398)
			(end 0.508 -0.9398)
			(stroke
				(width 0.1524)
				(type default)
			)
			(layer "B.SilkS")
		)
		(fp_rect
			(start 0.508 0.9398)
			(end -0.508 -0.9398)
			(stroke
				(width 0)
				(type default)
			)
			(fill no)
			(layer "B.CrtYd")
		)
		(fp_rect
			(start 0.508 0.9398)
			(end -0.508 -0.9398)
			(stroke
				(width 0)
				(type default)
			)
			(fill no)
			(layer "B.Fab")
		)
		(pad "1" smd custom
			(at 0 -0.4445)
			(size 0.1397 0.1397)
			(layers "B.Cu" "B.Mask" "B.Paste")
			(net "I2C_BMC_A_COMP_A_SDA")
			(options
				(clearance outline)
				(anchor circle)
			)
			(primitives
				(gr_poly
					(pts
						(arc
							(start -0.1778 0.2794)
							(mid -0.249642 0.249642)
							(end -0.2794 0.1778)
						)
						(arc
							(start -0.2794 -0.1778)
							(mid -0.249642 -0.249642)
							(end -0.1778 -0.2794)
						)
						(arc
							(start 0.1778 -0.2794)
							(mid 0.249642 -0.249642)
							(end 0.2794 -0.1778)
						)
						(arc
							(start 0.2794 0.1778)
							(mid 0.249642 0.249642)
							(end 0.1778 0.2794)
						)
					)
					(width 0)
					(fill yes)
				)
			)
		)
		(pad "2" smd custom
			(at 0 0.4445)
			(size 0.1397 0.1397)
			(layers "B.Cu" "B.Mask" "B.Paste")
			(net "I2C_BMC_A_COMP_A_SDA_R")
			(options
				(clearance outline)
				(anchor circle)
			)
			(primitives
				(gr_poly
					(pts
						(arc
							(start -0.1778 0.2794)
							(mid -0.249642 0.249642)
							(end -0.2794 0.1778)
						)
						(arc
							(start -0.2794 -0.1778)
							(mid -0.249642 -0.249642)
							(end -0.1778 -0.2794)
						)
						(arc
							(start 0.1778 -0.2794)
							(mid 0.249642 -0.249642)
							(end 0.2794 -0.1778)
						)
						(arc
							(start 0.2794 0.1778)
							(mid 0.249642 0.249642)
							(end 0.1778 0.2794)
						)
					)
					(width 0)
					(fill yes)
				)
			)
		)
	)
	(footprint ""
		(layer "B.Cu")
		(at 37.084 -142.1384 180)
		(property "Reference" "C618"
			(at 0 0 0)
			(layer "B.SilkS")
			(hide yes)
			(effects
				(font
					(size 1.27 1.27)
				)
				(justify mirror)
			)
		)
		(property "Value" "SC10U16V5KX-7-GP-U"
			(at 0.0762 -6.1214 180)
			(unlocked yes)
			(layer "B.Fab")
			(hide yes)
			(effects
				(font
					(size 1.016 1.016)
					(thickness 0.1524)
				)
				(justify mirror)
			)
		)
		(property "Device Type" "C805H58"
			(at 0.0762 -8.1534 180)
			(unlocked yes)
			(layer "B.Fab")
			(hide yes)
			(effects
				(font
					(size 1.016 1.016)
					(thickness 0.1524)
				)
				(justify mirror)
			)
		)
		(duplicate_pad_numbers_are_jumpers no)
		(fp_line
			(start -0.635 0)
			(end 0.635 0)
			(stroke
				(width 0.508)
				(type default)
			)
			(layer "B.SilkS")
		)
		(fp_rect
			(start 0.9652 1.778)
			(end -0.9652 -1.778)
			(stroke
				(width 0)
				(type default)
			)
			(fill no)
			(layer "B.CrtYd")
		)
		(fp_poly
			(pts
				(xy 0.9652 -1.778) (xy -0.9652 -1.778) (xy -0.9652 1.778) (xy 0.9652 1.778)
			)
			(stroke
				(width 0)
				(type default)
			)
			(fill no)
			(layer "B.Fab")
		)
		(pad "1" smd rect
			(at 0 -0.9652)
			(size 1.397 1.143)
			(layers "B.Cu" "B.Mask" "B.Paste")
			(net "P12V_A_VIN_U21")
		)
		(pad "2" smd rect
			(at 0 0.9652)
			(size 1.397 1.143)
			(layers "B.Cu" "B.Mask" "B.Paste")
			(net "GND")
		)
	)
	(footprint ""
		(layer "B.Cu")
		(at 32.3342 -253.4158 90)
		(property "Reference" "R1217"
			(at 0 0 90)
			(layer "B.SilkS")
			(hide yes)
			(effects
				(font
					(size 1.27 1.27)
				)
				(justify mirror)
			)
		)
		(property "Value" "71K5R2F-GP"
			(at -0.064008 -3.993896 90)
			(unlocked yes)
			(layer "B.Fab")
			(hide yes)
			(effects
				(font
					(size 1.016 1.016)
					(thickness 0.1524)
				)
				(justify mirror)
			)
		)
		(property "Device Type" "R402H16"
			(at -0.064008 -5.517896 90)
			(unlocked yes)
			(layer "B.Fab")
			(hide yes)
			(effects
				(font
					(size 1.016 1.016)
					(thickness 0.1524)
				)
				(justify mirror)
			)
		)
		(duplicate_pad_numbers_are_jumpers no)
		(fp_line
			(start 0.508 -0.9398)
			(end 0.508 0.9398)
			(stroke
				(width 0.1524)
				(type default)
			)
			(layer "B.SilkS")
		)
		(fp_line
			(start -0.508 -0.9398)
			(end 0.508 -0.9398)
			(stroke
				(width 0.1524)
				(type default)
			)
			(layer "B.SilkS")
		)
		(fp_rect
			(start 0.508 0.9398)
			(end -0.508 -0.9398)
			(stroke
				(width 0)
				(type default)
			)
			(fill no)
			(layer "B.CrtYd")
		)
		(fp_rect
			(start 0.508 0.9398)
			(end -0.508 -0.9398)
			(stroke
				(width 0)
				(type default)
			)
			(fill no)
			(layer "B.Fab")
		)
		(pad "1" smd custom
			(at 0 -0.4445 270)
			(size 0.1397 0.1397)
			(layers "B.Cu" "B.Mask" "B.Paste")
			(net "P5V_A_VFB")
			(options
				(clearance outline)
				(anchor circle)
			)
			(primitives
				(gr_poly
					(pts
						(arc
							(start -0.1778 0.2794)
							(mid -0.249642 0.249642)
							(end -0.2794 0.1778)
						)
						(arc
							(start -0.2794 -0.1778)
							(mid -0.249642 -0.249642)
							(end -0.1778 -0.2794)
						)
						(arc
							(start 0.1778 -0.2794)
							(mid 0.249642 -0.249642)
							(end 0.2794 -0.1778)
						)
						(arc
							(start 0.2794 0.1778)
							(mid 0.249642 0.249642)
							(end 0.1778 0.2794)
						)
					)
					(width 0)
					(fill yes)
				)
			)
		)
		(pad "2" smd custom
			(at 0 0.4445 270)
			(size 0.1397 0.1397)
			(layers "B.Cu" "B.Mask" "B.Paste")
			(net "P5V_A_VFB_R")
			(options
				(clearance outline)
				(anchor circle)
			)
			(primitives
				(gr_poly
					(pts
						(arc
							(start -0.1778 0.2794)
							(mid -0.249642 0.249642)
							(end -0.2794 0.1778)
						)
						(arc
							(start -0.2794 -0.1778)
							(mid -0.249642 -0.249642)
							(end -0.1778 -0.2794)
						)
						(arc
							(start 0.1778 -0.2794)
							(mid 0.249642 -0.249642)
							(end 0.2794 -0.1778)
						)
						(arc
							(start 0.2794 0.1778)
							(mid 0.249642 0.249642)
							(end 0.1778 0.2794)
						)
					)
					(width 0)
					(fill yes)
				)
			)
		)
	)
	(footprint ""
		(layer "B.Cu")
		(at 51.949604 -148.778214 -90)
		(property "Reference" "R1235"
			(at 0 0 90)
			(layer "B.SilkS")
			(hide yes)
			(effects
				(font
					(size 1.27 1.27)
				)
				(justify mirror)
			)
		)
		(property "Value" "10R3F-GP"
			(at 0.0254 -2.5146 270)
			(unlocked yes)
			(layer "B.Fab")
			(hide yes)
			(effects
				(font
					(size 1.016 1.016)
					(thickness 0.1524)
				)
				(justify mirror)
			)
		)
		(property "Device Type" "R603H22"
			(at 0.0254 -4.0386 270)
			(unlocked yes)
			(layer "B.Fab")
			(hide yes)
			(effects
				(font
					(size 1.016 1.016)
					(thickness 0.1524)
				)
				(justify mirror)
			)
		)
		(duplicate_pad_numbers_are_jumpers no)
		(fp_line
			(start -0.2032 0)
			(end -0.4826 0)
			(stroke
				(width 0.2032)
				(type default)
			)
			(layer "B.SilkS")
		)
		(fp_line
			(start 0.4826 0)
			(end 0.2032 0)
			(stroke
				(width 0.2032)
				(type default)
			)
			(layer "B.SilkS")
		)
		(fp_rect
			(start 0.5842 1.3335)
			(end -0.5842 -1.3335)
			(stroke
				(width 0)
				(type default)
			)
			(fill no)
			(layer "B.CrtYd")
		)
		(fp_rect
			(start 0.5842 1.3335)
			(end -0.5842 -1.3335)
			(stroke
				(width 0)
				(type default)
			)
			(fill no)
			(layer "B.Fab")
		)
		(pad "1" smd custom
			(at 0 -0.762 90)
			(size 0.2159 0.2159)
			(layers "B.Cu" "B.Mask" "B.Paste")
			(net "P5V_B_CC")
			(options
				(clearance outline)
				(anchor circle)
			)
			(primitives
				(gr_poly
					(pts
						(arc
							(start -0.3302 0.4318)
							(mid -0.402042 0.402042)
							(end -0.4318 0.3302)
						)
						(arc
							(start -0.4318 -0.3302)
							(mid -0.402042 -0.402042)
							(end -0.3302 -0.4318)
						)
						(arc
							(start 0.3302 -0.4318)
							(mid 0.402042 -0.402042)
							(end 0.4318 -0.3302)
						)
						(arc
							(start 0.4318 0.3302)
							(mid 0.402042 0.402042)
							(end 0.3302 0.4318)
						)
					)
					(width 0)
					(fill yes)
				)
			)
		)
		(pad "2" smd custom
			(at 0 0.762 90)
			(size 0.2159 0.2159)
			(layers "B.Cu" "B.Mask" "B.Paste")
			(net "P5V_B_VFB_R")
			(options
				(clearance outline)
				(anchor circle)
			)
			(primitives
				(gr_poly
					(pts
						(arc
							(start -0.3302 0.4318)
							(mid -0.402042 0.402042)
							(end -0.4318 0.3302)
						)
						(arc
							(start -0.4318 -0.3302)
							(mid -0.402042 -0.402042)
							(end -0.3302 -0.4318)
						)
						(arc
							(start 0.3302 -0.4318)
							(mid 0.402042 -0.402042)
							(end 0.4318 -0.3302)
						)
						(arc
							(start 0.4318 0.3302)
							(mid 0.402042 0.402042)
							(end 0.3302 0.4318)
						)
					)
					(width 0)
					(fill yes)
				)
			)
		)
	)
	(footprint ""
		(layer "B.Cu")
		(at 189.911482 -219.707206 -90)
		(property "Reference" "R1285"
			(at 0 0 90)
			(layer "B.SilkS")
			(hide yes)
			(effects
				(font
					(size 1.27 1.27)
				)
				(justify mirror)
			)
		)
		(property "Value" "33KR2J-3-GP"
			(at -0.064008 -3.993896 270)
			(unlocked yes)
			(layer "B.Fab")
			(hide yes)
			(effects
				(font
					(size 1.016 1.016)
					(thickness 0.1524)
				)
				(justify mirror)
			)
		)
		(property "Device Type" "R402H16"
			(at -0.064008 -5.517896 270)
			(unlocked yes)
			(layer "B.Fab")
			(hide yes)
			(effects
				(font
					(size 1.016 1.016)
					(thickness 0.1524)
				)
				(justify mirror)
			)
		)
		(duplicate_pad_numbers_are_jumpers no)
		(fp_line
			(start -0.508 -0.9398)
			(end 0.508 -0.9398)
			(stroke
				(width 0.1524)
				(type default)
			)
			(layer "B.SilkS")
		)
		(fp_line
			(start 0.508 -0.9398)
			(end 0.508 0.9398)
			(stroke
				(width 0.1524)
				(type default)
			)
			(layer "B.SilkS")
		)
		(fp_rect
			(start 0.508 0.9398)
			(end -0.508 -0.9398)
			(stroke
				(width 0)
				(type default)
			)
			(fill no)
			(layer "B.CrtYd")
		)
		(fp_rect
			(start 0.508 0.9398)
			(end -0.508 -0.9398)
			(stroke
				(width 0)
				(type default)
			)
			(fill no)
			(layer "B.Fab")
		)
		(pad "1" smd custom
			(at 0 -0.4445 90)
			(size 0.1397 0.1397)
			(layers "B.Cu" "B.Mask" "B.Paste")
			(net "P3V3_STBY_CC_R")
			(options
				(clearance outline)
				(anchor circle)
			)
			(primitives
				(gr_poly
					(pts
						(arc
							(start -0.1778 0.2794)
							(mid -0.249642 0.249642)
							(end -0.2794 0.1778)
						)
						(arc
							(start -0.2794 -0.1778)
							(mid -0.249642 -0.249642)
							(end -0.1778 -0.2794)
						)
						(arc
							(start 0.1778 -0.2794)
							(mid 0.249642 -0.249642)
							(end 0.2794 -0.1778)
						)
						(arc
							(start 0.2794 0.1778)
							(mid 0.249642 0.249642)
							(end 0.1778 0.2794)
						)
					)
					(width 0)
					(fill yes)
				)
			)
		)
		(pad "2" smd custom
			(at 0 0.4445 90)
			(size 0.1397 0.1397)
			(layers "B.Cu" "B.Mask" "B.Paste")
			(net "P3V3_STBY_VFB")
			(options
				(clearance outline)
				(anchor circle)
			)
			(primitives
				(gr_poly
					(pts
						(arc
							(start -0.1778 0.2794)
							(mid -0.249642 0.249642)
							(end -0.2794 0.1778)
						)
						(arc
							(start -0.2794 -0.1778)
							(mid -0.249642 -0.249642)
							(end -0.1778 -0.2794)
						)
						(arc
							(start 0.1778 -0.2794)
							(mid 0.249642 -0.249642)
							(end 0.2794 -0.1778)
						)
						(arc
							(start 0.2794 0.1778)
							(mid 0.249642 0.249642)
							(end 0.1778 0.2794)
						)
					)
					(width 0)
					(fill yes)
				)
			)
		)
	)
	(footprint ""
		(layer "B.Cu")
		(at 449.3514 -256.4638 90)
		(property "Reference" "R1256"
			(at 0 0 90)
			(layer "B.SilkS")
			(hide yes)
			(effects
				(font
					(size 1.27 1.27)
				)
				(justify mirror)
			)
		)
		(property "Value" "71K5R2F-GP"
			(at -0.064008 -3.993896 90)
			(unlocked yes)
			(layer "B.Fab")
			(hide yes)
			(effects
				(font
					(size 1.016 1.016)
					(thickness 0.1524)
				)
				(justify mirror)
			)
		)
		(property "Device Type" "R402H16"
			(at -0.064008 -5.517896 90)
			(unlocked yes)
			(layer "B.Fab")
			(hide yes)
			(effects
				(font
					(size 1.016 1.016)
					(thickness 0.1524)
				)
				(justify mirror)
			)
		)
		(duplicate_pad_numbers_are_jumpers no)
		(fp_line
			(start 0.508 -0.9398)
			(end 0.508 0.9398)
			(stroke
				(width 0.1524)
				(type default)
			)
			(layer "B.SilkS")
		)
		(fp_line
			(start -0.508 -0.9398)
			(end 0.508 -0.9398)
			(stroke
				(width 0.1524)
				(type default)
			)
			(layer "B.SilkS")
		)
		(fp_rect
			(start 0.508 0.9398)
			(end -0.508 -0.9398)
			(stroke
				(width 0)
				(type default)
			)
			(fill no)
			(layer "B.CrtYd")
		)
		(fp_rect
			(start 0.508 0.9398)
			(end -0.508 -0.9398)
			(stroke
				(width 0)
				(type default)
			)
			(fill no)
			(layer "B.Fab")
		)
		(pad "1" smd custom
			(at 0 -0.4445 270)
			(size 0.1397 0.1397)
			(layers "B.Cu" "B.Mask" "B.Paste")
			(net "P5V_C_VFB")
			(options
				(clearance outline)
				(anchor circle)
			)
			(primitives
				(gr_poly
					(pts
						(arc
							(start -0.1778 0.2794)
							(mid -0.249642 0.249642)
							(end -0.2794 0.1778)
						)
						(arc
							(start -0.2794 -0.1778)
							(mid -0.249642 -0.249642)
							(end -0.1778 -0.2794)
						)
						(arc
							(start 0.1778 -0.2794)
							(mid 0.249642 -0.249642)
							(end 0.2794 -0.1778)
						)
						(arc
							(start 0.2794 0.1778)
							(mid 0.249642 0.249642)
							(end 0.1778 0.2794)
						)
					)
					(width 0)
					(fill yes)
				)
			)
		)
		(pad "2" smd custom
			(at 0 0.4445 270)
			(size 0.1397 0.1397)
			(layers "B.Cu" "B.Mask" "B.Paste")
			(net "P5V_C_VFB_R")
			(options
				(clearance outline)
				(anchor circle)
			)
			(primitives
				(gr_poly
					(pts
						(arc
							(start -0.1778 0.2794)
							(mid -0.249642 0.249642)
							(end -0.2794 0.1778)
						)
						(arc
							(start -0.2794 -0.1778)
							(mid -0.249642 -0.249642)
							(end -0.1778 -0.2794)
						)
						(arc
							(start 0.1778 -0.2794)
							(mid 0.249642 -0.249642)
							(end 0.2794 -0.1778)
						)
						(arc
							(start 0.2794 0.1778)
							(mid 0.249642 0.249642)
							(end 0.1778 0.2794)
						)
					)
					(width 0)
					(fill yes)
				)
			)
		)
	)
	(footprint ""
		(layer "B.Cu")
		(at 483.859586 -230.0605 -90)
		(property "Reference" "R1273"
			(at 0 0 90)
			(layer "B.SilkS")
			(hide yes)
			(effects
				(font
					(size 1.27 1.27)
				)
				(justify mirror)
			)
		)
		(property "Value" "10R3F-GP"
			(at 0.0254 -2.5146 270)
			(unlocked yes)
			(layer "B.Fab")
			(hide yes)
			(effects
				(font
					(size 1.016 1.016)
					(thickness 0.1524)
				)
				(justify mirror)
			)
		)
		(property "Device Type" "R603H22"
			(at 0.0254 -4.0386 270)
			(unlocked yes)
			(layer "B.Fab")
			(hide yes)
			(effects
				(font
					(size 1.016 1.016)
					(thickness 0.1524)
				)
				(justify mirror)
			)
		)
		(duplicate_pad_numbers_are_jumpers no)
		(fp_line
			(start -0.2032 0)
			(end -0.4826 0)
			(stroke
				(width 0.2032)
				(type default)
			)
			(layer "B.SilkS")
		)
		(fp_line
			(start 0.4826 0)
			(end 0.2032 0)
			(stroke
				(width 0.2032)
				(type default)
			)
			(layer "B.SilkS")
		)
		(fp_rect
			(start 0.5842 1.3335)
			(end -0.5842 -1.3335)
			(stroke
				(width 0)
				(type default)
			)
			(fill no)
			(layer "B.CrtYd")
		)
		(fp_rect
			(start 0.5842 1.3335)
			(end -0.5842 -1.3335)
			(stroke
				(width 0)
				(type default)
			)
			(fill no)
			(layer "B.Fab")
		)
		(pad "1" smd custom
			(at 0 -0.762 90)
			(size 0.2159 0.2159)
			(layers "B.Cu" "B.Mask" "B.Paste")
			(net "P5V_D_CC")
			(options
				(clearance outline)
				(anchor circle)
			)
			(primitives
				(gr_poly
					(pts
						(arc
							(start -0.3302 0.4318)
							(mid -0.402042 0.402042)
							(end -0.4318 0.3302)
						)
						(arc
							(start -0.4318 -0.3302)
							(mid -0.402042 -0.402042)
							(end -0.3302 -0.4318)
						)
						(arc
							(start 0.3302 -0.4318)
							(mid 0.402042 -0.402042)
							(end 0.4318 -0.3302)
						)
						(arc
							(start 0.4318 0.3302)
							(mid 0.402042 0.402042)
							(end 0.3302 0.4318)
						)
					)
					(width 0)
					(fill yes)
				)
			)
		)
		(pad "2" smd custom
			(at 0 0.762 90)
			(size 0.2159 0.2159)
			(layers "B.Cu" "B.Mask" "B.Paste")
			(net "P5V_D_VFB_R")
			(options
				(clearance outline)
				(anchor circle)
			)
			(primitives
				(gr_poly
					(pts
						(arc
							(start -0.3302 0.4318)
							(mid -0.402042 0.402042)
							(end -0.4318 0.3302)
						)
						(arc
							(start -0.4318 -0.3302)
							(mid -0.402042 -0.402042)
							(end -0.3302 -0.4318)
						)
						(arc
							(start 0.3302 -0.4318)
							(mid 0.402042 -0.402042)
							(end 0.4318 -0.3302)
						)
						(arc
							(start 0.4318 0.3302)
							(mid 0.402042 0.402042)
							(end 0.3302 0.4318)
						)
					)
					(width 0)
					(fill yes)
				)
			)
		)
	)
	(footprint ""
		(layer "B.Cu")
		(at 482.219 -234.95 90)
		(property "Reference" "R1278"
			(at 0 0 90)
			(layer "B.SilkS")
			(hide yes)
			(effects
				(font
					(size 1.27 1.27)
				)
				(justify mirror)
			)
		)
		(property "Value" "619KR2F-GP"
			(at -0.064008 -3.993896 90)
			(unlocked yes)
			(layer "B.Fab")
			(hide yes)
			(effects
				(font
					(size 1.016 1.016)
					(thickness 0.1524)
				)
				(justify mirror)
			)
		)
		(property "Device Type" "R402H16"
			(at -0.064008 -5.517896 90)
			(unlocked yes)
			(layer "B.Fab")
			(hide yes)
			(effects
				(font
					(size 1.016 1.016)
					(thickness 0.1524)
				)
				(justify mirror)
			)
		)
		(duplicate_pad_numbers_are_jumpers no)
		(fp_line
			(start 0.508 -0.9398)
			(end 0.508 0.9398)
			(stroke
				(width 0.1524)
				(type default)
			)
			(layer "B.SilkS")
		)
		(fp_line
			(start -0.508 -0.9398)
			(end 0.508 -0.9398)
			(stroke
				(width 0.1524)
				(type default)
			)
			(layer "B.SilkS")
		)
		(fp_rect
			(start 0.508 0.9398)
			(end -0.508 -0.9398)
			(stroke
				(width 0)
				(type default)
			)
			(fill no)
			(layer "B.CrtYd")
		)
		(fp_rect
			(start 0.508 0.9398)
			(end -0.508 -0.9398)
			(stroke
				(width 0)
				(type default)
			)
			(fill no)
			(layer "B.Fab")
		)
		(pad "1" smd custom
			(at 0 -0.4445 270)
			(size 0.1397 0.1397)
			(layers "B.Cu" "B.Mask" "B.Paste")
			(net "P5V_D_RF")
			(options
				(clearance outline)
				(anchor circle)
			)
			(primitives
				(gr_poly
					(pts
						(arc
							(start -0.1778 0.2794)
							(mid -0.249642 0.249642)
							(end -0.2794 0.1778)
						)
						(arc
							(start -0.2794 -0.1778)
							(mid -0.249642 -0.249642)
							(end -0.1778 -0.2794)
						)
						(arc
							(start 0.1778 -0.2794)
							(mid 0.249642 -0.249642)
							(end 0.2794 -0.1778)
						)
						(arc
							(start 0.2794 0.1778)
							(mid 0.249642 0.249642)
							(end 0.1778 0.2794)
						)
					)
					(width 0)
					(fill yes)
				)
			)
		)
		(pad "2" smd custom
			(at 0 0.4445 270)
			(size 0.1397 0.1397)
			(layers "B.Cu" "B.Mask" "B.Paste")
			(net "AGND_P5V_D")
			(options
				(clearance outline)
				(anchor circle)
			)
			(primitives
				(gr_poly
					(pts
						(arc
							(start -0.1778 0.2794)
							(mid -0.249642 0.249642)
							(end -0.2794 0.1778)
						)
						(arc
							(start -0.2794 -0.1778)
							(mid -0.249642 -0.249642)
							(end -0.1778 -0.2794)
						)
						(arc
							(start 0.1778 -0.2794)
							(mid 0.249642 -0.249642)
							(end 0.2794 -0.1778)
						)
						(arc
							(start 0.2794 0.1778)
							(mid 0.249642 0.249642)
							(end 0.1778 0.2794)
						)
					)
					(width 0)
					(fill yes)
				)
			)
		)
	)
	(footprint ""
		(layer "B.Cu")
		(at 478.663 -230.505 180)
		(property "Reference" "R1280"
			(at 0 0 0)
			(layer "B.SilkS")
			(hide yes)
			(effects
				(font
					(size 1.27 1.27)
				)
				(justify mirror)
			)
		)
		(property "Value" "10KR2F-2-GP"
			(at -0.064008 -3.993896 180)
			(unlocked yes)
			(layer "B.Fab")
			(hide yes)
			(effects
				(font
					(size 1.016 1.016)
					(thickness 0.1524)
				)
				(justify mirror)
			)
		)
		(property "Device Type" "R402H16"
			(at -0.064008 -5.517896 180)
			(unlocked yes)
			(layer "B.Fab")
			(hide yes)
			(effects
				(font
					(size 1.016 1.016)
					(thickness 0.1524)
				)
				(justify mirror)
			)
		)
		(duplicate_pad_numbers_are_jumpers no)
		(fp_line
			(start 0.508 -0.9398)
			(end 0.508 0.9398)
			(stroke
				(width 0.1524)
				(type default)
			)
			(layer "B.SilkS")
		)
		(fp_line
			(start -0.508 -0.9398)
			(end 0.508 -0.9398)
			(stroke
				(width 0.1524)
				(type default)
			)
			(layer "B.SilkS")
		)
		(fp_rect
			(start 0.508 0.9398)
			(end -0.508 -0.9398)
			(stroke
				(width 0)
				(type default)
			)
			(fill no)
			(layer "B.CrtYd")
		)
		(fp_rect
			(start 0.508 0.9398)
			(end -0.508 -0.9398)
			(stroke
				(width 0)
				(type default)
			)
			(fill no)
			(layer "B.Fab")
		)
		(pad "1" smd custom
			(at 0 -0.4445)
			(size 0.1397 0.1397)
			(layers "B.Cu" "B.Mask" "B.Paste")
			(net "P5V_D_VFB")
			(options
				(clearance outline)
				(anchor circle)
			)
			(primitives
				(gr_poly
					(pts
						(arc
							(start -0.1778 0.2794)
							(mid -0.249642 0.249642)
							(end -0.2794 0.1778)
						)
						(arc
							(start -0.2794 -0.1778)
							(mid -0.249642 -0.249642)
							(end -0.1778 -0.2794)
						)
						(arc
							(start 0.1778 -0.2794)
							(mid 0.249642 -0.249642)
							(end 0.2794 -0.1778)
						)
						(arc
							(start 0.2794 0.1778)
							(mid 0.249642 0.249642)
							(end 0.1778 0.2794)
						)
					)
					(width 0)
					(fill yes)
				)
			)
		)
		(pad "2" smd custom
			(at 0 0.4445)
			(size 0.1397 0.1397)
			(layers "B.Cu" "B.Mask" "B.Paste")
			(net "AGND_P5V_D")
			(options
				(clearance outline)
				(anchor circle)
			)
			(primitives
				(gr_poly
					(pts
						(arc
							(start -0.1778 0.2794)
							(mid -0.249642 0.249642)
							(end -0.2794 0.1778)
						)
						(arc
							(start -0.2794 -0.1778)
							(mid -0.249642 -0.249642)
							(end -0.1778 -0.2794)
						)
						(arc
							(start 0.1778 -0.2794)
							(mid 0.249642 -0.249642)
							(end 0.2794 -0.1778)
						)
						(arc
							(start 0.2794 0.1778)
							(mid 0.249642 0.249642)
							(end 0.1778 0.2794)
						)
					)
					(width 0)
					(fill yes)
				)
			)
		)
	)
	(footprint ""
		(layer "B.Cu")
		(at 425.174918 -210.799934 180)
		(property "Reference" "SCW2"
			(at 0 0 0)
			(layer "B.SilkS")
			(hide yes)
			(effects
				(font
					(size 1.27 1.27)
				)
				(justify mirror)
			)
		)
		(property "Value" ""
			(at 0 0 0)
			(layer "B.Fab")
			(effects
				(font
					(size 1.27 1.27)
				)
				(justify mirror)
			)
		)
		(duplicate_pad_numbers_are_jumpers no)
		(fp_poly
			(pts
				(arc
					(start -5.4356 0)
					(mid 5.4356 0)
					(end -5.4356 0)
				)
			)
			(stroke
				(width 0)
				(type default)
			)
			(fill no)
			(layer "B.CrtYd")
		)
		(fp_poly
			(pts
				(arc
					(start -5.4356 0)
					(mid 5.4356 0)
					(end -5.4356 0)
				)
			)
			(stroke
				(width 0)
				(type default)
			)
			(fill no)
			(layer "F.CrtYd")
		)
		(fp_poly
			(pts
				(arc
					(start -5.4356 0)
					(mid 5.4356 0)
					(end -5.4356 0)
				)
			)
			(stroke
				(width 0)
				(type default)
			)
			(fill no)
			(layer "B.Fab")
		)
		(fp_poly
			(pts
				(arc
					(start -5.4356 0)
					(mid 5.4356 0)
					(end -5.4356 0)
				)
			)
			(stroke
				(width 0)
				(type default)
			)
			(fill no)
			(layer "F.Fab")
		)
		(pad "" np_thru_hole circle
			(at 0 0)
			(size 0.254 0.254)
			(drill 10.2616)
			(layers "*.Cu" "*.Mask")
			(clearance 5.3594)
			(thermal_gap 5.3594)
		)
		(zone
			(layers "F.Cu" "B.Cu" "In1.Cu" "In2.Cu" "In3.Cu" "In4.Cu" "In5.Cu" "In6.Cu"
				"In7.Cu" "In8.Cu" "In9.Cu" "In10.Cu"
			)
			(hatch none 0.5)
			(connect_pads
				(clearance 0)
			)
			(min_thickness 0.25)
			(keepout
				(tracks not_allowed)
				(vias allowed)
				(pads allowed)
				(copperpour not_allowed)
				(footprints allowed)
			)
			(placement
				(enabled no)
				(sheetname "")
			)
			(fill
				(thermal_gap 0.5)
				(thermal_bridge_width 0.5)
				(island_removal_mode 0)
			)
			(polygon
				(pts
					(arc
						(start 430.610518 -210.799934)
						(mid 419.739318 -210.799934)
						(end 430.610518 -210.799934)
					)
				)
			)
		)
	)
	(footprint ""
		(layer "B.Cu")
		(at 182.656226 -218.174062)
		(property "Reference" "TP260"
			(at 0 0 0)
			(layer "B.SilkS")
			(hide yes)
			(effects
				(font
					(size 1.27 1.27)
				)
				(justify mirror)
			)
		)
		(property "Value" "TPAD32-GP"
			(at 0.0508 -1.6764 0)
			(unlocked yes)
			(layer "B.Fab")
			(hide yes)
			(effects
				(font
					(size 1.016 1.016)
					(thickness 0.1524)
				)
				(justify mirror)
			)
		)
		(property "Device Type" "TPAD32"
			(at 0.0508 -3.2004 0)
			(unlocked yes)
			(layer "B.Fab")
			(hide yes)
			(effects
				(font
					(size 1.016 1.016)
					(thickness 0.1524)
				)
				(justify mirror)
			)
		)
		(duplicate_pad_numbers_are_jumpers no)
		(fp_poly
			(pts
				(arc
					(start 0.4064 0)
					(mid -0.4064 0)
					(end 0.4064 0)
				)
			)
			(stroke
				(width 0)
				(type default)
			)
			(fill no)
			(layer "B.CrtYd")
		)
		(fp_poly
			(pts
				(arc
					(start 0.7112 0)
					(mid -0.7112 0)
					(end 0.7112 0)
				)
			)
			(stroke
				(width 0)
				(type default)
			)
			(fill no)
			(layer "B.Fab")
		)
		(pad "1" smd circle
			(at 0 0 180)
			(size 0.8128 0.8128)
			(layers "B.Cu" "B.Mask" "B.Paste")
			(net "PWRGD_P3V3_STBY")
		)
	)
	(footprint ""
		(layer "B.Cu")
		(at 185.644028 -225.679508 180)
		(property "Reference" "U33"
			(at 0 0 0)
			(layer "B.SilkS")
			(hide yes)
			(effects
				(font
					(size 1.27 1.27)
				)
				(justify mirror)
			)
		)
		(property "Value" "TPS53312RGTR-GP"
			(at -4.9784 -6.9342 180)
			(unlocked yes)
			(layer "B.Fab")
			(hide yes)
			(effects
				(font
					(size 1.016 1.016)
					(thickness 0.1524)
				)
				(justify mirror)
			)
		)
		(property "Device Type" "QFN16G3-G1D7H40"
			(at -4.9784 -8.4582 180)
			(unlocked yes)
			(layer "B.Fab")
			(hide yes)
			(effects
				(font
					(size 1.016 1.016)
					(thickness 0.1524)
				)
				(justify mirror)
			)
		)
		(duplicate_pad_numbers_are_jumpers no)
		(fp_line
			(start 2.5146 2.5146)
			(end 1.2446 2.5146)
			(stroke
				(width 0.1524)
				(type default)
			)
			(layer "B.SilkS")
		)
		(fp_line
			(start 2.5146 1.2446)
			(end 2.5146 2.5146)
			(stroke
				(width 0.1524)
				(type default)
			)
			(layer "B.SilkS")
		)
		(fp_line
			(start 2.5146 -2.5146)
			(end 2.5146 -1.2446)
			(stroke
				(width 0.1524)
				(type default)
			)
			(layer "B.SilkS")
		)
		(fp_line
			(start 2.262124 -0.750062)
			(end 2.770124 -0.750062)
			(stroke
				(width 0.1524)
				(type default)
			)
			(layer "B.SilkS")
		)
		(fp_line
			(start 1.2446 -2.5146)
			(end 2.5146 -2.5146)
			(stroke
				(width 0.1524)
				(type default)
			)
			(layer "B.SilkS")
		)
		(fp_line
			(start 0.249936 2.262124)
			(end 0.249936 3.024124)
			(stroke
				(width 0.1524)
				(type default)
			)
			(layer "B.SilkS")
		)
		(fp_line
			(start -1.2446 2.5146)
			(end -2.5146 2.5146)
			(stroke
				(width 0.1524)
				(type default)
			)
			(layer "B.SilkS")
		)
		(fp_line
			(start -2.262124 -0.249936)
			(end -2.770124 -0.249936)
			(stroke
				(width 0.1524)
				(type default)
			)
			(layer "B.SilkS")
		)
		(fp_line
			(start -2.5146 2.5146)
			(end -2.5146 1.2446)
			(stroke
				(width 0.1524)
				(type default)
			)
			(layer "B.SilkS")
		)
		(fp_poly
			(pts
				(xy -2.5146 -2.5146) (xy -1.2446 -2.5146) (xy -2.5146 -1.2446)
			)
			(stroke
				(width 0)
				(type default)
			)
			(fill yes)
			(layer "B.SilkS")
		)
		(fp_rect
			(start 1.4986 1.4986)
			(end -1.4986 -1.4986)
			(stroke
				(width 0)
				(type default)
			)
			(fill no)
			(layer "B.CrtYd")
		)
		(fp_poly
			(pts
				(xy -2.5146 -1.4986) (xy 1.4986 -1.4986) (xy 1.4986 1.4986) (xy -1.4986 1.4986) (xy -1.4986 -1.4859)
				(xy -2.5146 -1.4859) (xy -2.5146 2.5146) (xy 2.5146 2.5146) (xy 2.5146 -2.5146) (xy -2.5146 -2.5146)
			)
			(stroke
				(width 0)
				(type default)
			)
			(fill no)
			(layer "B.CrtYd")
		)
		(fp_rect
			(start 2.5146 2.5146)
			(end -2.5146 -2.5146)
			(stroke
				(width 0)
				(type default)
			)
			(fill no)
			(layer "B.Fab")
		)
		(pad "1" smd rect
			(at -0.750062 -1.550924)
			(size 0.3048 0.9144)
			(layers "B.Cu" "B.Mask" "B.Paste")
			(net "P3V3_STBY_VFB")
		)
		(pad "2" smd rect
			(at -0.249936 -1.538224)
			(size 0.3048 0.9398)
			(layers "B.Cu" "B.Mask" "B.Paste")
			(net "P3V3_STBY_VRG5")
		)
		(pad "3" smd rect
			(at 0.249936 -1.538224)
			(size 0.3048 0.9398)
			(layers "B.Cu" "B.Mask" "B.Paste")
			(net "P3V3_STBY_SS")
		)
		(pad "4" smd rect
			(at 0.750062 -1.550924)
			(size 0.3048 0.9144)
			(layers "B.Cu" "B.Mask" "B.Paste")
			(net "AGND_P3V3_STBY")
		)
		(pad "5" smd rect
			(at 1.550924 -0.750062)
			(size 0.9144 0.3048)
			(layers "B.Cu" "B.Mask" "B.Paste")
			(net "PWRGD_P3V3_STBY")
		)
		(pad "6" smd rect
			(at 1.538224 -0.249936)
			(size 0.9398 0.3048)
			(layers "B.Cu" "B.Mask" "B.Paste")
			(net "P3V3_STBY_EN_R")
		)
		(pad "7" smd rect
			(at 1.538224 0.249936)
			(size 0.9398 0.3048)
			(layers "B.Cu" "B.Mask" "B.Paste")
			(net "GND")
		)
		(pad "8" smd rect
			(at 1.550924 0.750062)
			(size 0.9144 0.3048)
			(layers "B.Cu" "B.Mask" "B.Paste")
			(net "GND")
		)
		(pad "9" smd rect
			(at 0.750062 1.550924)
			(size 0.3048 0.9144)
			(layers "B.Cu" "B.Mask" "B.Paste")
			(net "P3V3_STBY_SW")
		)
		(pad "10" smd rect
			(at 0.249936 1.538224)
			(size 0.3048 0.9398)
			(layers "B.Cu" "B.Mask" "B.Paste")
			(net "P3V3_STBY_SW")
		)
		(pad "11" smd rect
			(at -0.249936 1.538224)
			(size 0.3048 0.9398)
			(layers "B.Cu" "B.Mask" "B.Paste")
			(net "P3V3_STBY_SW")
		)
		(pad "12" smd rect
			(at -0.750062 1.550924)
			(size 0.3048 0.9144)
			(layers "B.Cu" "B.Mask" "B.Paste")
			(net "P3V3_STBY_VBST")
		)
		(pad "13" smd rect
			(at -1.550924 0.750062)
			(size 0.9144 0.3048)
			(layers "B.Cu" "B.Mask" "B.Paste")
			(net "P3V3_STBY_VIN")
		)
		(pad "14" smd rect
			(at -1.538224 0.249936)
			(size 0.9398 0.3048)
			(layers "B.Cu" "B.Mask" "B.Paste")
			(net "P3V3_STBY_VIN")
		)
		(pad "15" smd rect
			(at -1.538224 -0.249936)
			(size 0.9398 0.3048)
			(layers "B.Cu" "B.Mask" "B.Paste")
			(net "P3V3_STBY_VCC")
		)
		(pad "16" smd rect
			(at -1.550924 -0.750062)
			(size 0.9144 0.3048)
			(layers "B.Cu" "B.Mask" "B.Paste")
			(net "P3V3_STBY_VO")
		)
		(pad "17" smd rect
			(at 0 0)
			(size 1.6764 1.6764)
			(layers "B.Cu" "B.Mask" "B.Paste")
			(net "GND")
		)
	)
	(footprint ""
		(layer "B.Cu")
		(at 246.253 -386.2578 -90)
		(property "Reference" "R1156"
			(at 0 0 90)
			(layer "B.SilkS")
			(hide yes)
			(effects
				(font
					(size 1.27 1.27)
				)
				(justify mirror)
			)
		)
		(property "Value" "10R2F-L-GP"
			(at -0.064008 -3.993896 270)
			(unlocked yes)
			(layer "B.Fab")
			(hide yes)
			(effects
				(font
					(size 1.016 1.016)
					(thickness 0.1524)
				)
				(justify mirror)
			)
		)
		(property "Device Type" "R402H14"
			(at -0.064008 -5.517896 270)
			(unlocked yes)
			(layer "B.Fab")
			(hide yes)
			(effects
				(font
					(size 1.016 1.016)
					(thickness 0.1524)
				)
				(justify mirror)
			)
		)
		(duplicate_pad_numbers_are_jumpers no)
		(fp_line
			(start -0.508 -0.9398)
			(end 0.508 -0.9398)
			(stroke
				(width 0.1524)
				(type default)
			)
			(layer "B.SilkS")
		)
		(fp_line
			(start 0.508 -0.9398)
			(end 0.508 0.9398)
			(stroke
				(width 0.1524)
				(type default)
			)
			(layer "B.SilkS")
		)
		(fp_rect
			(start 0.508 0.9398)
			(end -0.508 -0.9398)
			(stroke
				(width 0)
				(type default)
			)
			(fill no)
			(layer "B.CrtYd")
		)
		(fp_rect
			(start 0.508 0.9398)
			(end -0.508 -0.9398)
			(stroke
				(width 0)
				(type default)
			)
			(fill no)
			(layer "B.Fab")
		)
		(pad "1" smd custom
			(at 0 -0.4445 90)
			(size 0.1397 0.1397)
			(layers "B.Cu" "B.Mask" "B.Paste")
			(net "MB3_CM_SENSE_R1_N")
			(options
				(clearance outline)
				(anchor circle)
			)
			(primitives
				(gr_poly
					(pts
						(arc
							(start -0.1778 0.2794)
							(mid -0.249642 0.249642)
							(end -0.2794 0.1778)
						)
						(arc
							(start -0.2794 -0.1778)
							(mid -0.249642 -0.249642)
							(end -0.1778 -0.2794)
						)
						(arc
							(start 0.1778 -0.2794)
							(mid 0.249642 -0.249642)
							(end 0.2794 -0.1778)
						)
						(arc
							(start 0.2794 0.1778)
							(mid 0.249642 0.249642)
							(end 0.1778 0.2794)
						)
					)
					(width 0)
					(fill yes)
				)
			)
		)
		(pad "2" smd custom
			(at 0 0.4445 90)
			(size 0.1397 0.1397)
			(layers "B.Cu" "B.Mask" "B.Paste")
			(net "MB3_CM_SENSE_N")
			(options
				(clearance outline)
				(anchor circle)
			)
			(primitives
				(gr_poly
					(pts
						(arc
							(start -0.1778 0.2794)
							(mid -0.249642 0.249642)
							(end -0.2794 0.1778)
						)
						(arc
							(start -0.2794 -0.1778)
							(mid -0.249642 -0.249642)
							(end -0.1778 -0.2794)
						)
						(arc
							(start 0.1778 -0.2794)
							(mid 0.249642 -0.249642)
							(end 0.2794 -0.1778)
						)
						(arc
							(start 0.2794 0.1778)
							(mid 0.249642 0.249642)
							(end 0.1778 0.2794)
						)
					)
					(width 0)
					(fill yes)
				)
			)
		)
	)
	(footprint ""
		(layer "B.Cu")
		(at 469.646 -229.616 90)
		(property "Reference" "C656"
			(at 0 0 90)
			(layer "B.SilkS")
			(hide yes)
			(effects
				(font
					(size 1.27 1.27)
				)
				(justify mirror)
			)
		)
		(property "Value" "SCD1U16V2KX-3GP"
			(at -1.1811 -2.7051 90)
			(unlocked yes)
			(layer "B.Fab")
			(hide yes)
			(effects
				(font
					(size 1.016 1.016)
					(thickness 0.1524)
				)
				(justify mirror)
			)
		)
		(property "Device Type" "C402H22"
			(at -1.1811 -4.2291 90)
			(unlocked yes)
			(layer "B.Fab")
			(hide yes)
			(effects
				(font
					(size 1.016 1.016)
					(thickness 0.1524)
				)
				(justify mirror)
			)
		)
		(duplicate_pad_numbers_are_jumpers no)
		(fp_rect
			(start 0.4318 0.9525)
			(end -0.4318 -0.9525)
			(stroke
				(width 0)
				(type default)
			)
			(fill no)
			(layer "B.CrtYd")
		)
		(fp_rect
			(start 0.4318 0.9525)
			(end -0.4318 -0.9525)
			(stroke
				(width 0)
				(type default)
			)
			(fill no)
			(layer "B.Fab")
		)
		(pad "1" smd custom
			(at 0 -0.4445 270)
			(size 0.1524 0.1524)
			(layers "B.Cu" "B.Mask" "B.Paste")
			(net "P5V_D_VBST_RC")
			(options
				(clearance outline)
				(anchor circle)
			)
			(primitives
				(gr_poly
					(pts
						(arc
							(start 0.3048 0.2032)
							(mid 0.275042 0.275042)
							(end 0.2032 0.3048)
						)
						(arc
							(start -0.2032 0.3048)
							(mid -0.275042 0.275042)
							(end -0.3048 0.2032)
						)
						(arc
							(start -0.3048 -0.2032)
							(mid -0.275042 -0.275042)
							(end -0.2032 -0.3048)
						)
						(arc
							(start 0.2032 -0.3048)
							(mid 0.275042 -0.275042)
							(end 0.3048 -0.2032)
						)
					)
					(width 0)
					(fill yes)
				)
			)
		)
		(pad "2" smd custom
			(at 0 0.4445 270)
			(size 0.1524 0.1524)
			(layers "B.Cu" "B.Mask" "B.Paste")
			(net "P5V_D_LL")
			(options
				(clearance outline)
				(anchor circle)
			)
			(primitives
				(gr_poly
					(pts
						(arc
							(start 0.3048 0.2032)
							(mid 0.275042 0.275042)
							(end 0.2032 0.3048)
						)
						(arc
							(start -0.2032 0.3048)
							(mid -0.275042 0.275042)
							(end -0.3048 0.2032)
						)
						(arc
							(start -0.3048 -0.2032)
							(mid -0.275042 -0.275042)
							(end -0.2032 -0.3048)
						)
						(arc
							(start 0.2032 -0.3048)
							(mid 0.275042 -0.275042)
							(end 0.3048 -0.2032)
						)
					)
					(width 0)
					(fill yes)
				)
			)
		)
	)
	(footprint ""
		(layer "B.Cu")
		(at 479.139504 -233.136186 -90)
		(property "Reference" "PG17"
			(at 0 0 90)
			(layer "B.SilkS")
			(hide yes)
			(effects
				(font
					(size 1.27 1.27)
				)
				(justify mirror)
			)
		)
		(property "Value" "COPPER-CLOSE-GP-U"
			(at -0.0762 -2.8702 270)
			(unlocked yes)
			(layer "B.Fab")
			(hide yes)
			(effects
				(font
					(size 1.016 1.016)
					(thickness 0.1524)
				)
				(justify mirror)
			)
		)
		(property "Device Type" "CON2C-U"
			(at -0.0762 -4.3942 270)
			(unlocked yes)
			(layer "B.Fab")
			(hide yes)
			(effects
				(font
					(size 1.016 1.016)
					(thickness 0.1524)
				)
				(justify mirror)
			)
		)
		(duplicate_pad_numbers_are_jumpers no)
		(fp_rect
			(start 0.9398 0.9652)
			(end -0.9398 -0.9652)
			(stroke
				(width 0)
				(type default)
			)
			(fill no)
			(layer "B.CrtYd")
		)
		(fp_rect
			(start 0.9398 0.9652)
			(end -0.9398 -0.9652)
			(stroke
				(width 0)
				(type default)
			)
			(fill no)
			(layer "B.Fab")
		)
		(pad "1" smd custom
			(at 0 -0.5334 90)
			(size 0.17145 0.17145)
			(layers "B.Cu" "B.Mask" "B.Paste")
			(net "AGND_P5V_D")
			(options
				(clearance outline)
				(anchor circle)
			)
			(primitives
				(gr_poly
					(pts
						(xy -0.127 -0.3429) (xy -0.127 -0.1651) (xy -0.635 0.3429) (xy 0.635 0.3429) (xy 0.127 -0.1651)
						(xy 0.127 -0.3429)
					)
					(width 0)
					(fill yes)
				)
			)
		)
		(pad "2" smd custom
			(at 0 0.5334 90)
			(size 0.17145 0.17145)
			(layers "B.Cu" "B.Mask" "B.Paste")
			(net "GND")
			(options
				(clearance outline)
				(anchor circle)
			)
			(primitives
				(gr_poly
					(pts
						(xy -0.635 -0.3429) (xy -0.127 0.1651) (xy -0.127 0.3429) (xy 0.127 0.3429) (xy 0.127 0.1651)
						(xy 0.635 -0.3429)
					)
					(width 0)
					(fill yes)
				)
			)
		)
	)
	(footprint ""
		(layer "B.Cu")
		(at 218.7702 -116.4844 -90)
		(property "Reference" "R619"
			(at 0 0 90)
			(layer "B.SilkS")
			(hide yes)
			(effects
				(font
					(size 1.27 1.27)
				)
				(justify mirror)
			)
		)
		(property "Value" "4K7R2F-GP"
			(at -0.064008 -3.993896 270)
			(unlocked yes)
			(layer "B.Fab")
			(hide yes)
			(effects
				(font
					(size 1.016 1.016)
					(thickness 0.1524)
				)
				(justify mirror)
			)
		)
		(property "Device Type" "R402H16"
			(at -0.064008 -5.517896 270)
			(unlocked yes)
			(layer "B.Fab")
			(hide yes)
			(effects
				(font
					(size 1.016 1.016)
					(thickness 0.1524)
				)
				(justify mirror)
			)
		)
		(duplicate_pad_numbers_are_jumpers no)
		(fp_line
			(start -0.508 -0.9398)
			(end 0.508 -0.9398)
			(stroke
				(width 0.1524)
				(type default)
			)
			(layer "B.SilkS")
		)
		(fp_line
			(start 0.508 -0.9398)
			(end 0.508 0.9398)
			(stroke
				(width 0.1524)
				(type default)
			)
			(layer "B.SilkS")
		)
		(fp_rect
			(start 0.508 0.9398)
			(end -0.508 -0.9398)
			(stroke
				(width 0)
				(type default)
			)
			(fill no)
			(layer "B.CrtYd")
		)
		(fp_rect
			(start 0.508 0.9398)
			(end -0.508 -0.9398)
			(stroke
				(width 0)
				(type default)
			)
			(fill no)
			(layer "B.Fab")
		)
		(pad "1" smd custom
			(at 0 -0.4445 90)
			(size 0.1397 0.1397)
			(layers "B.Cu" "B.Mask" "B.Paste")
			(net "I2C_BMC_A_COMP_A_SCL")
			(options
				(clearance outline)
				(anchor circle)
			)
			(primitives
				(gr_poly
					(pts
						(arc
							(start -0.1778 0.2794)
							(mid -0.249642 0.249642)
							(end -0.2794 0.1778)
						)
						(arc
							(start -0.2794 -0.1778)
							(mid -0.249642 -0.249642)
							(end -0.1778 -0.2794)
						)
						(arc
							(start 0.1778 -0.2794)
							(mid 0.249642 -0.249642)
							(end 0.2794 -0.1778)
						)
						(arc
							(start 0.2794 0.1778)
							(mid 0.249642 0.249642)
							(end 0.1778 0.2794)
						)
					)
					(width 0)
					(fill yes)
				)
			)
		)
		(pad "2" smd custom
			(at 0 0.4445 90)
			(size 0.1397 0.1397)
			(layers "B.Cu" "B.Mask" "B.Paste")
			(net "P3V3_STBY_A")
			(options
				(clearance outline)
				(anchor circle)
			)
			(primitives
				(gr_poly
					(pts
						(arc
							(start -0.1778 0.2794)
							(mid -0.249642 0.249642)
							(end -0.2794 0.1778)
						)
						(arc
							(start -0.2794 -0.1778)
							(mid -0.249642 -0.249642)
							(end -0.1778 -0.2794)
						)
						(arc
							(start 0.1778 -0.2794)
							(mid 0.249642 -0.249642)
							(end 0.2794 -0.1778)
						)
						(arc
							(start 0.2794 0.1778)
							(mid 0.249642 0.249642)
							(end 0.1778 0.2794)
						)
					)
					(width 0)
					(fill yes)
				)
			)
		)
	)
	(footprint ""
		(layer "B.Cu")
		(at 57.674002 -252.02515 -90)
		(property "Reference" "PG10"
			(at 0 0 90)
			(layer "B.SilkS")
			(hide yes)
			(effects
				(font
					(size 1.27 1.27)
				)
				(justify mirror)
			)
		)
		(property "Value" "GAP-CLOSE-PWR-4-GP"
			(at 2.4638 -0.5461 270)
			(unlocked yes)
			(layer "B.Fab")
			(hide yes)
			(effects
				(font
					(size 1.016 1.016)
					(thickness 0.1524)
				)
				(justify mirror)
			)
		)
		(property "Device Type" "GAP-CLOSE-PWR-4"
			(at 2.4638 -2.0701 270)
			(unlocked yes)
			(layer "B.Fab")
			(hide yes)
			(effects
				(font
					(size 1.016 1.016)
					(thickness 0.1524)
				)
				(justify mirror)
			)
		)
		(duplicate_pad_numbers_are_jumpers no)
		(fp_rect
			(start 0.2794 0.254)
			(end -0.2794 -0.254)
			(stroke
				(width 0)
				(type default)
			)
			(fill no)
			(layer "B.CrtYd")
		)
		(fp_rect
			(start 0.2794 0.254)
			(end -0.2794 -0.254)
			(stroke
				(width 0)
				(type default)
			)
			(fill no)
			(layer "B.Fab")
		)
		(pad "1" smd rect
			(at 0.0635 0 90)
			(size 0.1778 0.254)
			(layers "B.Cu" "B.Mask" "B.Paste")
			(net "P5V_A_1")
		)
		(pad "2" smd rect
			(at -0.0635 0 90)
			(size 0.1778 0.254)
			(layers "B.Cu" "B.Mask" "B.Paste")
			(net "P5V_A_CC")
		)
	)
	(footprint ""
		(layer "B.Cu")
		(at 46.355 -144.0688 -90)
		(property "Reference" "U21"
			(at 0 0 90)
			(layer "B.SilkS")
			(hide yes)
			(effects
				(font
					(size 1.27 1.27)
				)
				(justify mirror)
			)
		)
		(property "Value" "TPS53319DQPR-GP"
			(at -4.7498 -5.6896 270)
			(unlocked yes)
			(layer "B.Fab")
			(hide yes)
			(effects
				(font
					(size 1.016 1.016)
					(thickness 0.1524)
				)
				(justify mirror)
			)
		)
		(property "Device Type" "QFN22G6050-G6133H60"
			(at -4.7498 -7.2136 270)
			(unlocked yes)
			(layer "B.Fab")
			(hide yes)
			(effects
				(font
					(size 1.016 1.016)
					(thickness 0.1524)
				)
				(justify mirror)
			)
		)
		(duplicate_pad_numbers_are_jumpers no)
		(fp_line
			(start -3.556 3.5179)
			(end -3.556 2.2479)
			(stroke
				(width 0.1524)
				(type default)
			)
			(layer "B.SilkS")
		)
		(fp_line
			(start -2.286 3.5179)
			(end -3.556 3.5179)
			(stroke
				(width 0.1524)
				(type default)
			)
			(layer "B.SilkS")
		)
		(fp_line
			(start 3.556 3.5179)
			(end 2.286 3.5179)
			(stroke
				(width 0.1524)
				(type default)
			)
			(layer "B.SilkS")
		)
		(fp_line
			(start -1.500124 3.262122)
			(end -1.500124 4.024122)
			(stroke
				(width 0.1524)
				(type default)
			)
			(layer "B.SilkS")
		)
		(fp_line
			(start 0.999998 3.262122)
			(end 0.999998 3.770122)
			(stroke
				(width 0.1524)
				(type default)
			)
			(layer "B.SilkS")
		)
		(fp_line
			(start 3.556 2.2479)
			(end 3.556 3.5179)
			(stroke
				(width 0.1524)
				(type default)
			)
			(layer "B.SilkS")
		)
		(fp_line
			(start -0.500126 -3.262122)
			(end -0.500126 -3.770122)
			(stroke
				(width 0.1524)
				(type default)
			)
			(layer "B.SilkS")
		)
		(fp_line
			(start 1.999996 -3.262122)
			(end 1.999996 -4.024122)
			(stroke
				(width 0.1524)
				(type default)
			)
			(layer "B.SilkS")
		)
		(fp_line
			(start 2.286 -3.5179)
			(end 3.556 -3.5179)
			(stroke
				(width 0.1524)
				(type default)
			)
			(layer "B.SilkS")
		)
		(fp_line
			(start 3.556 -3.5179)
			(end 3.556 -2.2479)
			(stroke
				(width 0.1524)
				(type default)
			)
			(layer "B.SilkS")
		)
		(fp_poly
			(pts
				(xy -3.556 -3.5179) (xy -2.5273 -3.5179) (xy -3.556 -2.4892)
			)
			(stroke
				(width 0)
				(type default)
			)
			(fill yes)
			(layer "B.SilkS")
		)
		(fp_rect
			(start 2.9972 2.5019)
			(end -2.9972 -2.5019)
			(stroke
				(width 0)
				(type default)
			)
			(fill no)
			(layer "B.CrtYd")
		)
		(fp_poly
			(pts
				(xy -3.556 -2.5019) (xy 2.9972 -2.5019) (xy 2.9972 2.5019) (xy -2.9972 2.5019) (xy -2.9972 -2.4892)
				(xy -3.556 -2.4892) (xy -3.556 3.5179) (xy 3.556 3.5179) (xy 3.556 -3.5179) (xy -3.556 -3.5179)
			)
			(stroke
				(width 0)
				(type default)
			)
			(fill no)
			(layer "B.CrtYd")
		)
		(fp_rect
			(start 3.556 3.5179)
			(end -3.556 -3.5179)
			(stroke
				(width 0)
				(type default)
			)
			(fill no)
			(layer "B.Fab")
		)
		(pad "1" smd rect
			(at -2.500122 -2.449322 90)
			(size 0.3048 1.1176)
			(layers "B.Cu" "B.Mask" "B.Paste")
			(net "P5V_B_VFB")
		)
		(pad "2" smd rect
			(at -1.999996 -2.449322 90)
			(size 0.3048 1.1176)
			(layers "B.Cu" "B.Mask" "B.Paste")
			(net "P5V_B_EN_R")
		)
		(pad "3" smd rect
			(at -1.500124 -2.449322 90)
			(size 0.3048 1.1176)
			(layers "B.Cu" "B.Mask" "B.Paste")
			(net "P5V_A_2_PGOOD")
		)
		(pad "4" smd rect
			(at -0.999998 -2.449322 90)
			(size 0.3048 1.1176)
			(layers "B.Cu" "B.Mask" "B.Paste")
			(net "P5V_B_VBST")
		)
		(pad "5" smd rect
			(at -0.500126 -2.449322 90)
			(size 0.3048 1.1176)
			(layers "B.Cu" "B.Mask" "B.Paste")
			(net "P5V_B_ROVP")
		)
		(pad "6" smd rect
			(at 0 -2.449322 90)
			(size 0.3048 1.1176)
			(layers "B.Cu" "B.Mask" "B.Paste")
			(net "P5V_B_LL")
		)
		(pad "7" smd rect
			(at 0.500126 -2.449322 90)
			(size 0.3048 1.1176)
			(layers "B.Cu" "B.Mask" "B.Paste")
			(net "P5V_B_LL")
		)
		(pad "8" smd rect
			(at 0.999998 -2.449322 90)
			(size 0.3048 1.1176)
			(layers "B.Cu" "B.Mask" "B.Paste")
			(net "P5V_B_LL")
		)
		(pad "9" smd rect
			(at 1.500124 -2.449322 90)
			(size 0.3048 1.1176)
			(layers "B.Cu" "B.Mask" "B.Paste")
			(net "P5V_B_LL")
		)
		(pad "10" smd rect
			(at 1.999996 -2.449322 90)
			(size 0.3048 1.1176)
			(layers "B.Cu" "B.Mask" "B.Paste")
			(net "P5V_B_LL")
		)
		(pad "11" smd rect
			(at 2.500122 -2.449322 90)
			(size 0.3048 1.1176)
			(layers "B.Cu" "B.Mask" "B.Paste")
			(net "P5V_B_LL")
		)
		(pad "12" smd rect
			(at 2.500122 2.449322 90)
			(size 0.3048 1.1176)
			(layers "B.Cu" "B.Mask" "B.Paste")
			(net "P12V_A_VIN_U21")
		)
		(pad "13" smd rect
			(at 1.999996 2.449322 90)
			(size 0.3048 1.1176)
			(layers "B.Cu" "B.Mask" "B.Paste")
			(net "P12V_A_VIN_U21")
		)
		(pad "14" smd rect
			(at 1.500124 2.449322 90)
			(size 0.3048 1.1176)
			(layers "B.Cu" "B.Mask" "B.Paste")
			(net "P12V_A_VIN_U21")
		)
		(pad "15" smd rect
			(at 0.999998 2.449322 90)
			(size 0.3048 1.1176)
			(layers "B.Cu" "B.Mask" "B.Paste")
			(net "P12V_A_VIN_U21")
		)
		(pad "16" smd rect
			(at 0.500126 2.449322 90)
			(size 0.3048 1.1176)
			(layers "B.Cu" "B.Mask" "B.Paste")
			(net "P12V_A_VIN_U21")
		)
		(pad "17" smd rect
			(at 0 2.449322 90)
			(size 0.3048 1.1176)
			(layers "B.Cu" "B.Mask" "B.Paste")
			(net "P12V_A_VIN_U21")
		)
		(pad "18" smd rect
			(at -0.500126 2.449322 90)
			(size 0.3048 1.1176)
			(layers "B.Cu" "B.Mask" "B.Paste")
			(net "P5V_B_VREG")
		)
		(pad "19" smd rect
			(at -0.999998 2.449322 90)
			(size 0.3048 1.1176)
			(layers "B.Cu" "B.Mask" "B.Paste")
			(net "P12V_A_VDD_U21")
		)
		(pad "20" smd rect
			(at -1.500124 2.449322 90)
			(size 0.3048 1.1176)
			(layers "B.Cu" "B.Mask" "B.Paste")
			(net "P5V_B_MODE")
		)
		(pad "21" smd rect
			(at -1.999996 2.449322 90)
			(size 0.3048 1.1176)
			(layers "B.Cu" "B.Mask" "B.Paste")
			(net "P5V_B_TRIP")
		)
		(pad "22" smd rect
			(at -2.500122 2.449322 90)
			(size 0.3048 1.1176)
			(layers "B.Cu" "B.Mask" "B.Paste")
			(net "P5V_B_RF")
		)
		(pad "23" smd custom
			(at 0 0 90)
			(size 0.83185 0.83185)
			(layers "B.Cu" "B.Mask" "B.Paste")
			(net "GND")
			(options
				(clearance outline)
				(anchor circle)
			)
			(primitives
				(gr_poly
					(pts
						(xy -2.7813 -1.6637) (xy -2.7813 -1.2954) (xy -3.048 -1.2954) (xy -3.048 -0.9525) (xy -2.7813 -0.9525)
						(xy -2.7813 0.9525) (xy -3.048 0.9525) (xy -3.048 1.2954) (xy -2.7813 1.2954) (xy -2.7813 1.6637)
						(xy 2.7813 1.6637) (xy 2.7813 1.2954) (xy 3.048 1.2954) (xy 3.048 0.9525) (xy 2.7813 0.9525) (xy 2.7813 -0.9525)
						(xy 3.048 -0.9525) (xy 3.048 -1.2954) (xy 2.7813 -1.2954) (xy 2.7813 -1.6637)
					)
					(width 0)
					(fill yes)
				)
			)
		)
	)
	(footprint ""
		(layer "B.Cu")
		(at 189.377828 -240.284508 90)
		(property "Reference" "C681"
			(at 0 0 90)
			(layer "B.SilkS")
			(hide yes)
			(effects
				(font
					(size 1.27 1.27)
				)
				(justify mirror)
			)
		)
		(property "Value" "SC10U6D3V5KX-4GP"
			(at 0.0762 -6.1214 90)
			(unlocked yes)
			(layer "B.Fab")
			(hide yes)
			(effects
				(font
					(size 1.016 1.016)
					(thickness 0.1524)
				)
				(justify mirror)
			)
		)
		(property "Device Type" "C805H58"
			(at 0.0762 -8.1534 90)
			(unlocked yes)
			(layer "B.Fab")
			(hide yes)
			(effects
				(font
					(size 1.016 1.016)
					(thickness 0.1524)
				)
				(justify mirror)
			)
		)
		(duplicate_pad_numbers_are_jumpers no)
		(fp_line
			(start -0.635 0)
			(end 0.635 0)
			(stroke
				(width 0.508)
				(type default)
			)
			(layer "B.SilkS")
		)
		(fp_rect
			(start 0.9652 1.778)
			(end -0.9652 -1.778)
			(stroke
				(width 0)
				(type default)
			)
			(fill no)
			(layer "B.CrtYd")
		)
		(fp_poly
			(pts
				(xy 0.9652 -1.778) (xy -0.9652 -1.778) (xy -0.9652 1.778) (xy 0.9652 1.778)
			)
			(stroke
				(width 0)
				(type default)
			)
			(fill no)
			(layer "B.Fab")
		)
		(pad "1" smd rect
			(at 0 -0.9652 270)
			(size 1.397 1.143)
			(layers "B.Cu" "B.Mask" "B.Paste")
			(net "P3V3_STBY_A")
		)
		(pad "2" smd rect
			(at 0 0.9652 270)
			(size 1.397 1.143)
			(layers "B.Cu" "B.Mask" "B.Paste")
			(net "GND")
		)
	)
	(footprint ""
		(layer "B.Cu")
		(at 484.109522 -228.4095 180)
		(property "Reference" "R1263"
			(at 0 0 0)
			(layer "B.SilkS")
			(hide yes)
			(effects
				(font
					(size 1.27 1.27)
				)
				(justify mirror)
			)
		)
		(property "Value" "0R2J-2-GP"
			(at -0.064008 -3.993896 180)
			(unlocked yes)
			(layer "B.Fab")
			(hide yes)
			(effects
				(font
					(size 1.016 1.016)
					(thickness 0.1524)
				)
				(justify mirror)
			)
		)
		(property "Device Type" "R402H16"
			(at -0.064008 -5.517896 180)
			(unlocked yes)
			(layer "B.Fab")
			(hide yes)
			(effects
				(font
					(size 1.016 1.016)
					(thickness 0.1524)
				)
				(justify mirror)
			)
		)
		(duplicate_pad_numbers_are_jumpers no)
		(fp_line
			(start 0.508 -0.9398)
			(end 0.508 0.9398)
			(stroke
				(width 0.1524)
				(type default)
			)
			(layer "B.SilkS")
		)
		(fp_line
			(start -0.508 -0.9398)
			(end 0.508 -0.9398)
			(stroke
				(width 0.1524)
				(type default)
			)
			(layer "B.SilkS")
		)
		(fp_rect
			(start 0.508 0.9398)
			(end -0.508 -0.9398)
			(stroke
				(width 0)
				(type default)
			)
			(fill no)
			(layer "B.CrtYd")
		)
		(fp_rect
			(start 0.508 0.9398)
			(end -0.508 -0.9398)
			(stroke
				(width 0)
				(type default)
			)
			(fill no)
			(layer "B.Fab")
		)
		(pad "1" smd custom
			(at 0 -0.4445)
			(size 0.1397 0.1397)
			(layers "B.Cu" "B.Mask" "B.Paste")
			(net "P12V_A_PGOOD")
			(options
				(clearance outline)
				(anchor circle)
			)
			(primitives
				(gr_poly
					(pts
						(arc
							(start -0.1778 0.2794)
							(mid -0.249642 0.249642)
							(end -0.2794 0.1778)
						)
						(arc
							(start -0.2794 -0.1778)
							(mid -0.249642 -0.249642)
							(end -0.1778 -0.2794)
						)
						(arc
							(start 0.1778 -0.2794)
							(mid 0.249642 -0.249642)
							(end 0.2794 -0.1778)
						)
						(arc
							(start 0.2794 0.1778)
							(mid 0.249642 0.249642)
							(end 0.1778 0.2794)
						)
					)
					(width 0)
					(fill yes)
				)
			)
		)
		(pad "2" smd custom
			(at 0 0.4445)
			(size 0.1397 0.1397)
			(layers "B.Cu" "B.Mask" "B.Paste")
			(net "P5V_D_EN_R")
			(options
				(clearance outline)
				(anchor circle)
			)
			(primitives
				(gr_poly
					(pts
						(arc
							(start -0.1778 0.2794)
							(mid -0.249642 0.249642)
							(end -0.2794 0.1778)
						)
						(arc
							(start -0.2794 -0.1778)
							(mid -0.249642 -0.249642)
							(end -0.1778 -0.2794)
						)
						(arc
							(start 0.1778 -0.2794)
							(mid 0.249642 -0.249642)
							(end 0.2794 -0.1778)
						)
						(arc
							(start 0.2794 0.1778)
							(mid 0.249642 0.249642)
							(end 0.1778 0.2794)
						)
					)
					(width 0)
					(fill yes)
				)
			)
		)
	)
	(footprint ""
		(layer "B.Cu")
		(at 32.959802 -141.66215 180)
		(property "Reference" "R1226"
			(at 0 0 0)
			(layer "B.SilkS")
			(hide yes)
			(effects
				(font
					(size 1.27 1.27)
				)
				(justify mirror)
			)
		)
		(property "Value" "2D2R3-1-U-GP"
			(at 0.0254 -2.5146 180)
			(unlocked yes)
			(layer "B.Fab")
			(hide yes)
			(effects
				(font
					(size 1.016 1.016)
					(thickness 0.1524)
				)
				(justify mirror)
			)
		)
		(property "Device Type" "R603H22"
			(at 0.0254 -4.0386 180)
			(unlocked yes)
			(layer "B.Fab")
			(hide yes)
			(effects
				(font
					(size 1.016 1.016)
					(thickness 0.1524)
				)
				(justify mirror)
			)
		)
		(duplicate_pad_numbers_are_jumpers no)
		(fp_line
			(start 0.4826 0)
			(end 0.2032 0)
			(stroke
				(width 0.2032)
				(type default)
			)
			(layer "B.SilkS")
		)
		(fp_line
			(start -0.2032 0)
			(end -0.4826 0)
			(stroke
				(width 0.2032)
				(type default)
			)
			(layer "B.SilkS")
		)
		(fp_rect
			(start 0.5842 1.3335)
			(end -0.5842 -1.3335)
			(stroke
				(width 0)
				(type default)
			)
			(fill no)
			(layer "B.CrtYd")
		)
		(fp_rect
			(start 0.5842 1.3335)
			(end -0.5842 -1.3335)
			(stroke
				(width 0)
				(type default)
			)
			(fill no)
			(layer "B.Fab")
		)
		(pad "1" smd custom
			(at 0 -0.762)
			(size 0.2159 0.2159)
			(layers "B.Cu" "B.Mask" "B.Paste")
			(net "P12V_A")
			(options
				(clearance outline)
				(anchor circle)
			)
			(primitives
				(gr_poly
					(pts
						(arc
							(start -0.3302 0.4318)
							(mid -0.402042 0.402042)
							(end -0.4318 0.3302)
						)
						(arc
							(start -0.4318 -0.3302)
							(mid -0.402042 -0.402042)
							(end -0.3302 -0.4318)
						)
						(arc
							(start 0.3302 -0.4318)
							(mid 0.402042 -0.402042)
							(end 0.4318 -0.3302)
						)
						(arc
							(start 0.4318 0.3302)
							(mid 0.402042 0.402042)
							(end 0.3302 0.4318)
						)
					)
					(width 0)
					(fill yes)
				)
			)
		)
		(pad "2" smd custom
			(at 0 0.762)
			(size 0.2159 0.2159)
			(layers "B.Cu" "B.Mask" "B.Paste")
			(net "P12V_A_VDD_U21")
			(options
				(clearance outline)
				(anchor circle)
			)
			(primitives
				(gr_poly
					(pts
						(arc
							(start -0.3302 0.4318)
							(mid -0.402042 0.402042)
							(end -0.4318 0.3302)
						)
						(arc
							(start -0.4318 -0.3302)
							(mid -0.402042 -0.402042)
							(end -0.3302 -0.4318)
						)
						(arc
							(start 0.3302 -0.4318)
							(mid 0.402042 -0.402042)
							(end 0.4318 -0.3302)
						)
						(arc
							(start 0.4318 0.3302)
							(mid 0.402042 0.402042)
							(end 0.3302 0.4318)
						)
					)
					(width 0)
					(fill yes)
				)
			)
		)
	)
	(footprint ""
		(layer "B.Cu")
		(at 469.1888 -252.5522 180)
		(property "Reference" "C647"
			(at 0 0 0)
			(layer "B.SilkS")
			(hide yes)
			(effects
				(font
					(size 1.27 1.27)
				)
				(justify mirror)
			)
		)
		(property "Value" "SC10U16V5KX-7-GP-U"
			(at 0.0762 -6.1214 180)
			(unlocked yes)
			(layer "B.Fab")
			(hide yes)
			(effects
				(font
					(size 1.016 1.016)
					(thickness 0.1524)
				)
				(justify mirror)
			)
		)
		(property "Device Type" "C805H58"
			(at 0.0762 -8.1534 180)
			(unlocked yes)
			(layer "B.Fab")
			(hide yes)
			(effects
				(font
					(size 1.016 1.016)
					(thickness 0.1524)
				)
				(justify mirror)
			)
		)
		(duplicate_pad_numbers_are_jumpers no)
		(fp_line
			(start -0.635 0)
			(end 0.635 0)
			(stroke
				(width 0.508)
				(type default)
			)
			(layer "B.SilkS")
		)
		(fp_rect
			(start 0.9652 1.778)
			(end -0.9652 -1.778)
			(stroke
				(width 0)
				(type default)
			)
			(fill no)
			(layer "B.CrtYd")
		)
		(fp_poly
			(pts
				(xy 0.9652 -1.778) (xy -0.9652 -1.778) (xy -0.9652 1.778) (xy 0.9652 1.778)
			)
			(stroke
				(width 0)
				(type default)
			)
			(fill no)
			(layer "B.Fab")
		)
		(pad "1" smd rect
			(at 0 -0.9652)
			(size 1.397 1.143)
			(layers "B.Cu" "B.Mask" "B.Paste")
			(net "P5V_A_3")
		)
		(pad "2" smd rect
			(at 0 0.9652)
			(size 1.397 1.143)
			(layers "B.Cu" "B.Mask" "B.Paste")
			(net "GND")
		)
	)
	(footprint ""
		(layer "B.Cu")
		(at 28.956 -253.3142)
		(property "Reference" "PG11"
			(at 0 0 0)
			(layer "B.SilkS")
			(hide yes)
			(effects
				(font
					(size 1.27 1.27)
				)
				(justify mirror)
			)
		)
		(property "Value" "COPPER-CLOSE-GP-U"
			(at -0.0762 -2.8702 0)
			(unlocked yes)
			(layer "B.Fab")
			(hide yes)
			(effects
				(font
					(size 1.016 1.016)
					(thickness 0.1524)
				)
				(justify mirror)
			)
		)
		(property "Device Type" "CON2C-U"
			(at -0.0762 -4.3942 0)
			(unlocked yes)
			(layer "B.Fab")
			(hide yes)
			(effects
				(font
					(size 1.016 1.016)
					(thickness 0.1524)
				)
				(justify mirror)
			)
		)
		(duplicate_pad_numbers_are_jumpers no)
		(fp_rect
			(start 0.9398 0.9652)
			(end -0.9398 -0.9652)
			(stroke
				(width 0)
				(type default)
			)
			(fill no)
			(layer "B.CrtYd")
		)
		(fp_rect
			(start 0.9398 0.9652)
			(end -0.9398 -0.9652)
			(stroke
				(width 0)
				(type default)
			)
			(fill no)
			(layer "B.Fab")
		)
		(pad "1" smd custom
			(at 0 -0.5334 180)
			(size 0.17145 0.17145)
			(layers "B.Cu" "B.Mask" "B.Paste")
			(net "AGND_P5V_A")
			(options
				(clearance outline)
				(anchor circle)
			)
			(primitives
				(gr_poly
					(pts
						(xy -0.127 -0.3429) (xy -0.127 -0.1651) (xy -0.635 0.3429) (xy 0.635 0.3429) (xy 0.127 -0.1651)
						(xy 0.127 -0.3429)
					)
					(width 0)
					(fill yes)
				)
			)
		)
		(pad "2" smd custom
			(at 0 0.5334 180)
			(size 0.17145 0.17145)
			(layers "B.Cu" "B.Mask" "B.Paste")
			(net "GND")
			(options
				(clearance outline)
				(anchor circle)
			)
			(primitives
				(gr_poly
					(pts
						(xy -0.635 -0.3429) (xy -0.127 0.1651) (xy -0.127 0.3429) (xy 0.127 0.3429) (xy 0.127 0.1651)
						(xy 0.635 -0.3429)
					)
					(width 0)
					(fill yes)
				)
			)
		)
	)
	(footprint ""
		(layer "B.Cu")
		(at 364.7948 -142.2654)
		(property "Reference" "C559"
			(at 0 0 0)
			(layer "B.SilkS")
			(hide yes)
			(effects
				(font
					(size 1.27 1.27)
				)
				(justify mirror)
			)
		)
		(property "Value" "SCD015U25V2KX-GP"
			(at -1.1811 -2.7051 0)
			(unlocked yes)
			(layer "B.Fab")
			(hide yes)
			(effects
				(font
					(size 1.016 1.016)
					(thickness 0.1524)
				)
				(justify mirror)
			)
		)
		(property "Device Type" "C402H22"
			(at -1.1811 -4.2291 0)
			(unlocked yes)
			(layer "B.Fab")
			(hide yes)
			(effects
				(font
					(size 1.016 1.016)
					(thickness 0.1524)
				)
				(justify mirror)
			)
		)
		(duplicate_pad_numbers_are_jumpers no)
		(fp_rect
			(start 0.4318 0.9525)
			(end -0.4318 -0.9525)
			(stroke
				(width 0)
				(type default)
			)
			(fill no)
			(layer "B.CrtYd")
		)
		(fp_rect
			(start 0.4318 0.9525)
			(end -0.4318 -0.9525)
			(stroke
				(width 0)
				(type default)
			)
			(fill no)
			(layer "B.Fab")
		)
		(pad "1" smd custom
			(at 0 -0.4445 180)
			(size 0.1524 0.1524)
			(layers "B.Cu" "B.Mask" "B.Paste")
			(net "MB1_CM_SENSE_P")
			(options
				(clearance outline)
				(anchor circle)
			)
			(primitives
				(gr_poly
					(pts
						(arc
							(start 0.3048 0.2032)
							(mid 0.275042 0.275042)
							(end 0.2032 0.3048)
						)
						(arc
							(start -0.2032 0.3048)
							(mid -0.275042 0.275042)
							(end -0.3048 0.2032)
						)
						(arc
							(start -0.3048 -0.2032)
							(mid -0.275042 -0.275042)
							(end -0.2032 -0.3048)
						)
						(arc
							(start 0.2032 -0.3048)
							(mid 0.275042 -0.275042)
							(end 0.3048 -0.2032)
						)
					)
					(width 0)
					(fill yes)
				)
			)
		)
		(pad "2" smd custom
			(at 0 0.4445 180)
			(size 0.1524 0.1524)
			(layers "B.Cu" "B.Mask" "B.Paste")
			(net "MB1_CM_SENSE_N")
			(options
				(clearance outline)
				(anchor circle)
			)
			(primitives
				(gr_poly
					(pts
						(arc
							(start 0.3048 0.2032)
							(mid 0.275042 0.275042)
							(end 0.2032 0.3048)
						)
						(arc
							(start -0.2032 0.3048)
							(mid -0.275042 0.275042)
							(end -0.3048 0.2032)
						)
						(arc
							(start -0.3048 -0.2032)
							(mid -0.275042 -0.275042)
							(end -0.2032 -0.3048)
						)
						(arc
							(start 0.2032 -0.3048)
							(mid 0.275042 -0.275042)
							(end 0.3048 -0.2032)
						)
					)
					(width 0)
					(fill yes)
				)
			)
		)
	)
	(footprint ""
		(layer "B.Cu")
		(at 471.885518 -209.33029 -90)
		(property "Reference" "C662"
			(at 0 0 90)
			(layer "B.SilkS")
			(hide yes)
			(effects
				(font
					(size 1.27 1.27)
				)
				(justify mirror)
			)
		)
		(property "Value" "SC10U16V5KX-7-GP-U"
			(at 0.0762 -6.1214 270)
			(unlocked yes)
			(layer "B.Fab")
			(hide yes)
			(effects
				(font
					(size 1.016 1.016)
					(thickness 0.1524)
				)
				(justify mirror)
			)
		)
		(property "Device Type" "C805H58"
			(at 0.0762 -8.1534 270)
			(unlocked yes)
			(layer "B.Fab")
			(hide yes)
			(effects
				(font
					(size 1.016 1.016)
					(thickness 0.1524)
				)
				(justify mirror)
			)
		)
		(duplicate_pad_numbers_are_jumpers no)
		(fp_line
			(start -0.635 0)
			(end 0.635 0)
			(stroke
				(width 0.508)
				(type default)
			)
			(layer "B.SilkS")
		)
		(fp_rect
			(start 0.9652 1.778)
			(end -0.9652 -1.778)
			(stroke
				(width 0)
				(type default)
			)
			(fill no)
			(layer "B.CrtYd")
		)
		(fp_poly
			(pts
				(xy 0.9652 -1.778) (xy -0.9652 -1.778) (xy -0.9652 1.778) (xy 0.9652 1.778)
			)
			(stroke
				(width 0)
				(type default)
			)
			(fill no)
			(layer "B.Fab")
		)
		(pad "1" smd rect
			(at 0 -0.9652 90)
			(size 1.397 1.143)
			(layers "B.Cu" "B.Mask" "B.Paste")
			(net "P5V_A_4")
		)
		(pad "2" smd rect
			(at 0 0.9652 90)
			(size 1.397 1.143)
			(layers "B.Cu" "B.Mask" "B.Paste")
			(net "GND")
		)
	)
	(footprint ""
		(layer "B.Cu")
		(at 42.749978 -164.200078 180)
		(property "Reference" "NUT3"
			(at 0 0 0)
			(layer "B.SilkS")
			(hide yes)
			(effects
				(font
					(size 1.27 1.27)
				)
				(justify mirror)
			)
		)
		(property "Value" "STF256R168H278-GP"
			(at 4.826 0.0508 180)
			(unlocked yes)
			(layer "B.Fab")
			(hide yes)
			(effects
				(font
					(size 1.016 1.016)
					(thickness 0.1524)
				)
				(justify mirror)
			)
		)
		(property "Device Type" "STF256R168H278"
			(at 4.826 -1.4732 180)
			(unlocked yes)
			(layer "B.Fab")
			(hide yes)
			(effects
				(font
					(size 1.016 1.016)
					(thickness 0.1524)
				)
				(justify mirror)
			)
		)
		(duplicate_pad_numbers_are_jumpers no)
		(fp_circle
			(center 0 0)
			(end -3.6068 0)
			(stroke
				(width 0.3048)
				(type default)
			)
			(fill no)
			(layer "B.SilkS")
		)
		(fp_poly
			(pts
				(arc
					(start -2.5019 0)
					(mid 2.5019 0)
					(end -2.5019 0)
				)
			)
			(stroke
				(width 0)
				(type default)
			)
			(fill no)
			(layer "B.CrtYd")
		)
		(fp_poly
			(pts
				(arc
					(start -3.7592 0.00635)
					(mid 3.759205 0)
					(end -3.7592 -0.00635)
				)
				(arc
					(start -2.5019 -0.00635)
					(mid 2.501908 0)
					(end -2.5019 0.00635)
				)
			)
			(stroke
				(width 0)
				(type default)
			)
			(fill no)
			(layer "B.CrtYd")
		)
		(fp_poly
			(pts
				(arc
					(start -3.7592 0)
					(mid 3.7592 0)
					(end -3.7592 0)
				)
			)
			(stroke
				(width 0)
				(type default)
			)
			(fill no)
			(layer "F.CrtYd")
		)
		(fp_poly
			(pts
				(arc
					(start -3.7592 0)
					(mid 3.7592 0)
					(end -3.7592 0)
				)
			)
			(stroke
				(width 0)
				(type default)
			)
			(fill no)
			(layer "B.Fab")
		)
		(fp_poly
			(pts
				(arc
					(start -3.7592 0)
					(mid 3.7592 0)
					(end -3.7592 0)
				)
			)
			(stroke
				(width 0)
				(type default)
			)
			(fill no)
			(layer "F.Fab")
		)
		(pad "1" thru_hole circle
			(at 0 0)
			(size 6.5024 6.5024)
			(drill 4.2672)
			(layers "*.Cu" "*.Mask")
			(remove_unused_layers no)
			(net "Net_13")
			(clearance -0.6096)
			(padstack
				(mode front_inner_back)
				(layer "Inner"
					(shape circle)
					(size 4.6736 4.6736)
					(clearance 0.3048)
				)
				(layer "B.Cu"
					(shape circle)
					(size 6.5024 6.5024)
					(thermal_gap 0.3048)
					(clearance -0.6096)
				)
			)
		)
	)
	(footprint ""
		(layer "B.Cu")
		(at 478.231454 -239.216184 180)
		(property "Reference" "C655"
			(at 0 0 0)
			(layer "B.SilkS")
			(hide yes)
			(effects
				(font
					(size 1.27 1.27)
				)
				(justify mirror)
			)
		)
		(property "Value" "SC4D7U25V5KX-GP"
			(at 0.0762 -6.1214 180)
			(unlocked yes)
			(layer "B.Fab")
			(hide yes)
			(effects
				(font
					(size 1.016 1.016)
					(thickness 0.1524)
				)
				(justify mirror)
			)
		)
		(property "Device Type" "C805H54"
			(at 0.0762 -8.1534 180)
			(unlocked yes)
			(layer "B.Fab")
			(hide yes)
			(effects
				(font
					(size 1.016 1.016)
					(thickness 0.1524)
				)
				(justify mirror)
			)
		)
		(duplicate_pad_numbers_are_jumpers no)
		(fp_line
			(start -0.635 0)
			(end 0.635 0)
			(stroke
				(width 0.508)
				(type default)
			)
			(layer "B.SilkS")
		)
		(fp_rect
			(start 0.9652 1.778)
			(end -0.9652 -1.778)
			(stroke
				(width 0)
				(type default)
			)
			(fill no)
			(layer "B.CrtYd")
		)
		(fp_poly
			(pts
				(xy 0.9652 -1.778) (xy -0.9652 -1.778) (xy -0.9652 1.778) (xy 0.9652 1.778)
			)
			(stroke
				(width 0)
				(type default)
			)
			(fill no)
			(layer "B.Fab")
		)
		(pad "1" smd rect
			(at 0 -0.9652)
			(size 1.397 1.143)
			(layers "B.Cu" "B.Mask" "B.Paste")
			(net "P12V_A_VDD_U27")
		)
		(pad "2" smd rect
			(at 0 0.9652)
			(size 1.397 1.143)
			(layers "B.Cu" "B.Mask" "B.Paste")
			(net "GND")
		)
	)
	(footprint ""
		(layer "B.Cu")
		(at 217.6526 -123.4948)
		(property "Reference" "R639"
			(at 0 0 0)
			(layer "B.SilkS")
			(hide yes)
			(effects
				(font
					(size 1.27 1.27)
				)
				(justify mirror)
			)
		)
		(property "Value" "0R2J-2-GP"
			(at -0.064008 -3.993896 0)
			(unlocked yes)
			(layer "B.Fab")
			(hide yes)
			(effects
				(font
					(size 1.016 1.016)
					(thickness 0.1524)
				)
				(justify mirror)
			)
		)
		(property "Device Type" "R402H16"
			(at -0.064008 -5.517896 0)
			(unlocked yes)
			(layer "B.Fab")
			(hide yes)
			(effects
				(font
					(size 1.016 1.016)
					(thickness 0.1524)
				)
				(justify mirror)
			)
		)
		(duplicate_pad_numbers_are_jumpers no)
		(fp_line
			(start -0.508 -0.9398)
			(end 0.508 -0.9398)
			(stroke
				(width 0.1524)
				(type default)
			)
			(layer "B.SilkS")
		)
		(fp_line
			(start 0.508 -0.9398)
			(end 0.508 0.9398)
			(stroke
				(width 0.1524)
				(type default)
			)
			(layer "B.SilkS")
		)
		(fp_rect
			(start 0.508 0.9398)
			(end -0.508 -0.9398)
			(stroke
				(width 0)
				(type default)
			)
			(fill no)
			(layer "B.CrtYd")
		)
		(fp_rect
			(start 0.508 0.9398)
			(end -0.508 -0.9398)
			(stroke
				(width 0)
				(type default)
			)
			(fill no)
			(layer "B.Fab")
		)
		(pad "1" smd custom
			(at 0 -0.4445 180)
			(size 0.1397 0.1397)
			(layers "B.Cu" "B.Mask" "B.Paste")
			(net "I2C_BMC_A_COMP_A_SDA_R")
			(options
				(clearance outline)
				(anchor circle)
			)
			(primitives
				(gr_poly
					(pts
						(arc
							(start -0.1778 0.2794)
							(mid -0.249642 0.249642)
							(end -0.2794 0.1778)
						)
						(arc
							(start -0.2794 -0.1778)
							(mid -0.249642 -0.249642)
							(end -0.1778 -0.2794)
						)
						(arc
							(start 0.1778 -0.2794)
							(mid 0.249642 -0.249642)
							(end 0.2794 -0.1778)
						)
						(arc
							(start 0.2794 0.1778)
							(mid 0.249642 0.249642)
							(end 0.1778 0.2794)
						)
					)
					(width 0)
					(fill yes)
				)
			)
		)
		(pad "2" smd custom
			(at 0 0.4445 180)
			(size 0.1397 0.1397)
			(layers "B.Cu" "B.Mask" "B.Paste")
			(net "I2C_BMC_A_COMP_A_SDA_BUF")
			(options
				(clearance outline)
				(anchor circle)
			)
			(primitives
				(gr_poly
					(pts
						(arc
							(start -0.1778 0.2794)
							(mid -0.249642 0.249642)
							(end -0.2794 0.1778)
						)
						(arc
							(start -0.2794 -0.1778)
							(mid -0.249642 -0.249642)
							(end -0.1778 -0.2794)
						)
						(arc
							(start 0.1778 -0.2794)
							(mid 0.249642 -0.249642)
							(end 0.2794 -0.1778)
						)
						(arc
							(start 0.2794 0.1778)
							(mid 0.249642 0.249642)
							(end 0.1778 0.2794)
						)
					)
					(width 0)
					(fill yes)
				)
			)
		)
	)
	(footprint ""
		(layer "B.Cu")
		(at 23.257002 -250.88215 -90)
		(property "Reference" "C604"
			(at 0 0 90)
			(layer "B.SilkS")
			(hide yes)
			(effects
				(font
					(size 1.27 1.27)
				)
				(justify mirror)
			)
		)
		(property "Value" "SC4D7U25V5KX-GP"
			(at 0.0762 -6.1214 270)
			(unlocked yes)
			(layer "B.Fab")
			(hide yes)
			(effects
				(font
					(size 1.016 1.016)
					(thickness 0.1524)
				)
				(justify mirror)
			)
		)
		(property "Device Type" "C805H54"
			(at 0.0762 -8.1534 270)
			(unlocked yes)
			(layer "B.Fab")
			(hide yes)
			(effects
				(font
					(size 1.016 1.016)
					(thickness 0.1524)
				)
				(justify mirror)
			)
		)
		(duplicate_pad_numbers_are_jumpers no)
		(fp_line
			(start -0.635 0)
			(end 0.635 0)
			(stroke
				(width 0.508)
				(type default)
			)
			(layer "B.SilkS")
		)
		(fp_rect
			(start 0.9652 1.778)
			(end -0.9652 -1.778)
			(stroke
				(width 0)
				(type default)
			)
			(fill no)
			(layer "B.CrtYd")
		)
		(fp_poly
			(pts
				(xy 0.9652 -1.778) (xy -0.9652 -1.778) (xy -0.9652 1.778) (xy 0.9652 1.778)
			)
			(stroke
				(width 0)
				(type default)
			)
			(fill no)
			(layer "B.Fab")
		)
		(pad "1" smd rect
			(at 0 -0.9652 90)
			(size 1.397 1.143)
			(layers "B.Cu" "B.Mask" "B.Paste")
			(net "P12V_A_VDD_U20")
		)
		(pad "2" smd rect
			(at 0 0.9652 90)
			(size 1.397 1.143)
			(layers "B.Cu" "B.Mask" "B.Paste")
			(net "GND")
		)
	)
	(footprint ""
		(layer "B.Cu")
		(at 480.680522 -228.4095)
		(property "Reference" "R1265"
			(at 0 0 0)
			(layer "B.SilkS")
			(hide yes)
			(effects
				(font
					(size 1.27 1.27)
				)
				(justify mirror)
			)
		)
		(property "Value" "10KR2F-2-GP"
			(at -0.064008 -3.993896 0)
			(unlocked yes)
			(layer "B.Fab")
			(hide yes)
			(effects
				(font
					(size 1.016 1.016)
					(thickness 0.1524)
				)
				(justify mirror)
			)
		)
		(property "Device Type" "R402H16"
			(at -0.064008 -5.517896 0)
			(unlocked yes)
			(layer "B.Fab")
			(hide yes)
			(effects
				(font
					(size 1.016 1.016)
					(thickness 0.1524)
				)
				(justify mirror)
			)
		)
		(duplicate_pad_numbers_are_jumpers no)
		(fp_line
			(start -0.508 -0.9398)
			(end 0.508 -0.9398)
			(stroke
				(width 0.1524)
				(type default)
			)
			(layer "B.SilkS")
		)
		(fp_line
			(start 0.508 -0.9398)
			(end 0.508 0.9398)
			(stroke
				(width 0.1524)
				(type default)
			)
			(layer "B.SilkS")
		)
		(fp_rect
			(start 0.508 0.9398)
			(end -0.508 -0.9398)
			(stroke
				(width 0)
				(type default)
			)
			(fill no)
			(layer "B.CrtYd")
		)
		(fp_rect
			(start 0.508 0.9398)
			(end -0.508 -0.9398)
			(stroke
				(width 0)
				(type default)
			)
			(fill no)
			(layer "B.Fab")
		)
		(pad "1" smd custom
			(at 0 -0.4445 180)
			(size 0.1397 0.1397)
			(layers "B.Cu" "B.Mask" "B.Paste")
			(net "P5V_D_EN_R")
			(options
				(clearance outline)
				(anchor circle)
			)
			(primitives
				(gr_poly
					(pts
						(arc
							(start -0.1778 0.2794)
							(mid -0.249642 0.249642)
							(end -0.2794 0.1778)
						)
						(arc
							(start -0.2794 -0.1778)
							(mid -0.249642 -0.249642)
							(end -0.1778 -0.2794)
						)
						(arc
							(start 0.1778 -0.2794)
							(mid 0.249642 -0.249642)
							(end 0.2794 -0.1778)
						)
						(arc
							(start 0.2794 0.1778)
							(mid 0.249642 0.249642)
							(end 0.1778 0.2794)
						)
					)
					(width 0)
					(fill yes)
				)
			)
		)
		(pad "2" smd custom
			(at 0 0.4445 180)
			(size 0.1397 0.1397)
			(layers "B.Cu" "B.Mask" "B.Paste")
			(net "GND")
			(options
				(clearance outline)
				(anchor circle)
			)
			(primitives
				(gr_poly
					(pts
						(arc
							(start -0.1778 0.2794)
							(mid -0.249642 0.249642)
							(end -0.2794 0.1778)
						)
						(arc
							(start -0.2794 -0.1778)
							(mid -0.249642 -0.249642)
							(end -0.1778 -0.2794)
						)
						(arc
							(start 0.1778 -0.2794)
							(mid 0.249642 -0.249642)
							(end 0.2794 -0.1778)
						)
						(arc
							(start 0.2794 0.1778)
							(mid 0.249642 0.249642)
							(end 0.1778 0.2794)
						)
					)
					(width 0)
					(fill yes)
				)
			)
		)
	)
	(footprint ""
		(layer "B.Cu")
		(at 215.9254 -119.761)
		(property "Reference" "C2"
			(at 0 0 0)
			(layer "B.SilkS")
			(hide yes)
			(effects
				(font
					(size 1.27 1.27)
				)
				(justify mirror)
			)
		)
		(property "Value" "SCD1U16V2KX-3GP"
			(at -1.1811 -2.7051 0)
			(unlocked yes)
			(layer "B.Fab")
			(hide yes)
			(effects
				(font
					(size 1.016 1.016)
					(thickness 0.1524)
				)
				(justify mirror)
			)
		)
		(property "Device Type" "C402H22"
			(at -1.1811 -4.2291 0)
			(unlocked yes)
			(layer "B.Fab")
			(hide yes)
			(effects
				(font
					(size 1.016 1.016)
					(thickness 0.1524)
				)
				(justify mirror)
			)
		)
		(duplicate_pad_numbers_are_jumpers no)
		(fp_poly
			(pts
				(xy 0.4318 0.9525) (xy 0.4318 -0.9525) (xy -0.4318 -0.9525) (xy -0.4318 0.9525)
			)
			(stroke
				(width 0)
				(type default)
			)
			(fill no)
			(layer "B.CrtYd")
		)
		(fp_rect
			(start 0.4318 0.9525)
			(end -0.4318 -0.9525)
			(stroke
				(width 0)
				(type default)
			)
			(fill no)
			(layer "B.Fab")
		)
		(pad "1" smd custom
			(at 0 -0.4445 180)
			(size 0.1524 0.1524)
			(layers "B.Cu" "B.Mask" "B.Paste")
			(net "P3V3_STBY_A")
			(options
				(clearance outline)
				(anchor circle)
			)
			(primitives
				(gr_poly
					(pts
						(arc
							(start 0.3048 0.2032)
							(mid 0.275042 0.275042)
							(end 0.2032 0.3048)
						)
						(arc
							(start -0.2032 0.3048)
							(mid -0.275042 0.275042)
							(end -0.3048 0.2032)
						)
						(arc
							(start -0.3048 -0.2032)
							(mid -0.275042 -0.275042)
							(end -0.2032 -0.3048)
						)
						(arc
							(start 0.2032 -0.3048)
							(mid 0.275042 -0.275042)
							(end 0.3048 -0.2032)
						)
					)
					(width 0)
					(fill yes)
				)
			)
		)
		(pad "2" smd custom
			(at 0 0.4445 180)
			(size 0.1524 0.1524)
			(layers "B.Cu" "B.Mask" "B.Paste")
			(net "GND")
			(options
				(clearance outline)
				(anchor circle)
			)
			(primitives
				(gr_poly
					(pts
						(arc
							(start 0.3048 0.2032)
							(mid 0.275042 0.275042)
							(end 0.2032 0.3048)
						)
						(arc
							(start -0.2032 0.3048)
							(mid -0.275042 0.275042)
							(end -0.3048 0.2032)
						)
						(arc
							(start -0.3048 -0.2032)
							(mid -0.275042 -0.275042)
							(end -0.2032 -0.3048)
						)
						(arc
							(start 0.2032 -0.3048)
							(mid 0.275042 -0.275042)
							(end 0.3048 -0.2032)
						)
					)
					(width 0)
					(fill yes)
				)
			)
		)
	)
	(footprint ""
		(layer "B.Cu")
		(at 7.999984 -224.199958 180)
		(property "Reference" "NUT1"
			(at 0 0 0)
			(layer "B.SilkS")
			(hide yes)
			(effects
				(font
					(size 1.27 1.27)
				)
				(justify mirror)
			)
		)
		(property "Value" "STF256R168H278-GP"
			(at 4.826 0.0508 180)
			(unlocked yes)
			(layer "B.Fab")
			(hide yes)
			(effects
				(font
					(size 1.016 1.016)
					(thickness 0.1524)
				)
				(justify mirror)
			)
		)
		(property "Device Type" "STF256R168H278"
			(at 4.826 -1.4732 180)
			(unlocked yes)
			(layer "B.Fab")
			(hide yes)
			(effects
				(font
					(size 1.016 1.016)
					(thickness 0.1524)
				)
				(justify mirror)
			)
		)
		(duplicate_pad_numbers_are_jumpers no)
		(fp_circle
			(center 0 0)
			(end -3.6068 0)
			(stroke
				(width 0.3048)
				(type default)
			)
			(fill no)
			(layer "B.SilkS")
		)
		(fp_poly
			(pts
				(arc
					(start -2.5019 0)
					(mid 2.5019 0)
					(end -2.5019 0)
				)
			)
			(stroke
				(width 0)
				(type default)
			)
			(fill no)
			(layer "B.CrtYd")
		)
		(fp_poly
			(pts
				(arc
					(start -3.7592 0.00635)
					(mid 3.759205 0)
					(end -3.7592 -0.00635)
				)
				(arc
					(start -2.5019 -0.00635)
					(mid 2.501908 0)
					(end -2.5019 0.00635)
				)
			)
			(stroke
				(width 0)
				(type default)
			)
			(fill no)
			(layer "B.CrtYd")
		)
		(fp_poly
			(pts
				(arc
					(start -3.7592 0)
					(mid 3.7592 0)
					(end -3.7592 0)
				)
			)
			(stroke
				(width 0)
				(type default)
			)
			(fill no)
			(layer "F.CrtYd")
		)
		(fp_poly
			(pts
				(arc
					(start -3.7592 0)
					(mid 3.7592 0)
					(end -3.7592 0)
				)
			)
			(stroke
				(width 0)
				(type default)
			)
			(fill no)
			(layer "B.Fab")
		)
		(fp_poly
			(pts
				(arc
					(start -3.7592 0)
					(mid 3.7592 0)
					(end -3.7592 0)
				)
			)
			(stroke
				(width 0)
				(type default)
			)
			(fill no)
			(layer "F.Fab")
		)
		(pad "1" thru_hole circle
			(at 0 0)
			(size 6.5024 6.5024)
			(drill 4.2672)
			(layers "*.Cu" "*.Mask")
			(remove_unused_layers no)
			(net "Net_15")
			(clearance -0.6096)
			(padstack
				(mode front_inner_back)
				(layer "Inner"
					(shape circle)
					(size 4.6736 4.6736)
					(clearance 0.3048)
				)
				(layer "B.Cu"
					(shape circle)
					(size 6.5024 6.5024)
					(thermal_gap 0.3048)
					(clearance -0.6096)
				)
			)
		)
	)
	(footprint ""
		(layer "B.Cu")
		(at 447.431414 -256.391664 180)
		(property "Reference" "R1259"
			(at 0 0 0)
			(layer "B.SilkS")
			(hide yes)
			(effects
				(font
					(size 1.27 1.27)
				)
				(justify mirror)
			)
		)
		(property "Value" "10KR2F-2-GP"
			(at -0.064008 -3.993896 180)
			(unlocked yes)
			(layer "B.Fab")
			(hide yes)
			(effects
				(font
					(size 1.016 1.016)
					(thickness 0.1524)
				)
				(justify mirror)
			)
		)
		(property "Device Type" "R402H16"
			(at -0.064008 -5.517896 180)
			(unlocked yes)
			(layer "B.Fab")
			(hide yes)
			(effects
				(font
					(size 1.016 1.016)
					(thickness 0.1524)
				)
				(justify mirror)
			)
		)
		(duplicate_pad_numbers_are_jumpers no)
		(fp_line
			(start 0.508 -0.9398)
			(end 0.508 0.9398)
			(stroke
				(width 0.1524)
				(type default)
			)
			(layer "B.SilkS")
		)
		(fp_line
			(start -0.508 -0.9398)
			(end 0.508 -0.9398)
			(stroke
				(width 0.1524)
				(type default)
			)
			(layer "B.SilkS")
		)
		(fp_rect
			(start 0.508 0.9398)
			(end -0.508 -0.9398)
			(stroke
				(width 0)
				(type default)
			)
			(fill no)
			(layer "B.CrtYd")
		)
		(fp_rect
			(start 0.508 0.9398)
			(end -0.508 -0.9398)
			(stroke
				(width 0)
				(type default)
			)
			(fill no)
			(layer "B.Fab")
		)
		(pad "1" smd custom
			(at 0 -0.4445)
			(size 0.1397 0.1397)
			(layers "B.Cu" "B.Mask" "B.Paste")
			(net "P5V_C_VFB")
			(options
				(clearance outline)
				(anchor circle)
			)
			(primitives
				(gr_poly
					(pts
						(arc
							(start -0.1778 0.2794)
							(mid -0.249642 0.249642)
							(end -0.2794 0.1778)
						)
						(arc
							(start -0.2794 -0.1778)
							(mid -0.249642 -0.249642)
							(end -0.1778 -0.2794)
						)
						(arc
							(start 0.1778 -0.2794)
							(mid 0.249642 -0.249642)
							(end 0.2794 -0.1778)
						)
						(arc
							(start 0.2794 0.1778)
							(mid 0.249642 0.249642)
							(end 0.1778 0.2794)
						)
					)
					(width 0)
					(fill yes)
				)
			)
		)
		(pad "2" smd custom
			(at 0 0.4445)
			(size 0.1397 0.1397)
			(layers "B.Cu" "B.Mask" "B.Paste")
			(net "AGND_P5V_C")
			(options
				(clearance outline)
				(anchor circle)
			)
			(primitives
				(gr_poly
					(pts
						(arc
							(start -0.1778 0.2794)
							(mid -0.249642 0.249642)
							(end -0.2794 0.1778)
						)
						(arc
							(start -0.2794 -0.1778)
							(mid -0.249642 -0.249642)
							(end -0.1778 -0.2794)
						)
						(arc
							(start 0.1778 -0.2794)
							(mid 0.249642 -0.249642)
							(end 0.2794 -0.1778)
						)
						(arc
							(start 0.2794 0.1778)
							(mid 0.249642 0.249642)
							(end 0.1778 0.2794)
						)
					)
					(width 0)
					(fill yes)
				)
			)
		)
	)
	(footprint ""
		(layer "B.Cu")
		(at 438.713372 -252.076966 180)
		(property "Reference" "C633"
			(at 0 0 0)
			(layer "B.SilkS")
			(hide yes)
			(effects
				(font
					(size 1.27 1.27)
				)
				(justify mirror)
			)
		)
		(property "Value" "SC10U16V5KX-7-GP-U"
			(at 0.0762 -6.1214 180)
			(unlocked yes)
			(layer "B.Fab")
			(hide yes)
			(effects
				(font
					(size 1.016 1.016)
					(thickness 0.1524)
				)
				(justify mirror)
			)
		)
		(property "Device Type" "C805H58"
			(at 0.0762 -8.1534 180)
			(unlocked yes)
			(layer "B.Fab")
			(hide yes)
			(effects
				(font
					(size 1.016 1.016)
					(thickness 0.1524)
				)
				(justify mirror)
			)
		)
		(duplicate_pad_numbers_are_jumpers no)
		(fp_line
			(start -0.635 0)
			(end 0.635 0)
			(stroke
				(width 0.508)
				(type default)
			)
			(layer "B.SilkS")
		)
		(fp_rect
			(start 0.9652 1.778)
			(end -0.9652 -1.778)
			(stroke
				(width 0)
				(type default)
			)
			(fill no)
			(layer "B.CrtYd")
		)
		(fp_poly
			(pts
				(xy 0.9652 -1.778) (xy -0.9652 -1.778) (xy -0.9652 1.778) (xy 0.9652 1.778)
			)
			(stroke
				(width 0)
				(type default)
			)
			(fill no)
			(layer "B.Fab")
		)
		(pad "1" smd rect
			(at 0 -0.9652)
			(size 1.397 1.143)
			(layers "B.Cu" "B.Mask" "B.Paste")
			(net "P12V_A_VIN_U22")
		)
		(pad "2" smd rect
			(at 0 0.9652)
			(size 1.397 1.143)
			(layers "B.Cu" "B.Mask" "B.Paste")
			(net "GND")
		)
	)
	(footprint ""
		(layer "B.Cu")
		(at 407.100024 -164.200078 180)
		(property "Reference" "NUT6"
			(at 0 0 0)
			(layer "B.SilkS")
			(hide yes)
			(effects
				(font
					(size 1.27 1.27)
				)
				(justify mirror)
			)
		)
		(property "Value" "STF256R168H278-GP"
			(at 4.826 0.0508 180)
			(unlocked yes)
			(layer "B.Fab")
			(hide yes)
			(effects
				(font
					(size 1.016 1.016)
					(thickness 0.1524)
				)
				(justify mirror)
			)
		)
		(property "Device Type" "STF256R168H278"
			(at 4.826 -1.4732 180)
			(unlocked yes)
			(layer "B.Fab")
			(hide yes)
			(effects
				(font
					(size 1.016 1.016)
					(thickness 0.1524)
				)
				(justify mirror)
			)
		)
		(duplicate_pad_numbers_are_jumpers no)
		(fp_circle
			(center 0 0)
			(end -3.6068 0)
			(stroke
				(width 0.3048)
				(type default)
			)
			(fill no)
			(layer "B.SilkS")
		)
		(fp_poly
			(pts
				(arc
					(start -2.5019 0)
					(mid 2.5019 0)
					(end -2.5019 0)
				)
			)
			(stroke
				(width 0)
				(type default)
			)
			(fill no)
			(layer "B.CrtYd")
		)
		(fp_poly
			(pts
				(arc
					(start -3.7592 0.00635)
					(mid 3.759205 0)
					(end -3.7592 -0.00635)
				)
				(arc
					(start -2.5019 -0.00635)
					(mid 2.501908 0)
					(end -2.5019 0.00635)
				)
			)
			(stroke
				(width 0)
				(type default)
			)
			(fill no)
			(layer "B.CrtYd")
		)
		(fp_poly
			(pts
				(arc
					(start -3.7592 0)
					(mid 3.7592 0)
					(end -3.7592 0)
				)
			)
			(stroke
				(width 0)
				(type default)
			)
			(fill no)
			(layer "F.CrtYd")
		)
		(fp_poly
			(pts
				(arc
					(start -3.7592 0)
					(mid 3.7592 0)
					(end -3.7592 0)
				)
			)
			(stroke
				(width 0)
				(type default)
			)
			(fill no)
			(layer "B.Fab")
		)
		(fp_poly
			(pts
				(arc
					(start -3.7592 0)
					(mid 3.7592 0)
					(end -3.7592 0)
				)
			)
			(stroke
				(width 0)
				(type default)
			)
			(fill no)
			(layer "F.Fab")
		)
		(pad "1" thru_hole circle
			(at 0 0)
			(size 6.5024 6.5024)
			(drill 4.2672)
			(layers "*.Cu" "*.Mask")
			(remove_unused_layers no)
			(net "Net_10")
			(clearance -0.6096)
			(padstack
				(mode front_inner_back)
				(layer "Inner"
					(shape circle)
					(size 4.6736 4.6736)
					(clearance 0.3048)
				)
				(layer "B.Cu"
					(shape circle)
					(size 6.5024 6.5024)
					(thermal_gap 0.3048)
					(clearance -0.6096)
				)
			)
		)
	)
	(footprint ""
		(layer "B.Cu")
		(at 246.253 -385.2418 -90)
		(property "Reference" "R1154"
			(at 0 0 90)
			(layer "B.SilkS")
			(hide yes)
			(effects
				(font
					(size 1.27 1.27)
				)
				(justify mirror)
			)
		)
		(property "Value" "10R2F-L-GP"
			(at -0.064008 -3.993896 270)
			(unlocked yes)
			(layer "B.Fab")
			(hide yes)
			(effects
				(font
					(size 1.016 1.016)
					(thickness 0.1524)
				)
				(justify mirror)
			)
		)
		(property "Device Type" "R402H14"
			(at -0.064008 -5.517896 270)
			(unlocked yes)
			(layer "B.Fab")
			(hide yes)
			(effects
				(font
					(size 1.016 1.016)
					(thickness 0.1524)
				)
				(justify mirror)
			)
		)
		(duplicate_pad_numbers_are_jumpers no)
		(fp_line
			(start -0.508 -0.9398)
			(end 0.508 -0.9398)
			(stroke
				(width 0.1524)
				(type default)
			)
			(layer "B.SilkS")
		)
		(fp_line
			(start 0.508 -0.9398)
			(end 0.508 0.9398)
			(stroke
				(width 0.1524)
				(type default)
			)
			(layer "B.SilkS")
		)
		(fp_rect
			(start 0.508 0.9398)
			(end -0.508 -0.9398)
			(stroke
				(width 0)
				(type default)
			)
			(fill no)
			(layer "B.CrtYd")
		)
		(fp_rect
			(start 0.508 0.9398)
			(end -0.508 -0.9398)
			(stroke
				(width 0)
				(type default)
			)
			(fill no)
			(layer "B.Fab")
		)
		(pad "1" smd custom
			(at 0 -0.4445 90)
			(size 0.1397 0.1397)
			(layers "B.Cu" "B.Mask" "B.Paste")
			(net "MB3_CM_SENSE_R1_P")
			(options
				(clearance outline)
				(anchor circle)
			)
			(primitives
				(gr_poly
					(pts
						(arc
							(start -0.1778 0.2794)
							(mid -0.249642 0.249642)
							(end -0.2794 0.1778)
						)
						(arc
							(start -0.2794 -0.1778)
							(mid -0.249642 -0.249642)
							(end -0.1778 -0.2794)
						)
						(arc
							(start 0.1778 -0.2794)
							(mid 0.249642 -0.249642)
							(end 0.2794 -0.1778)
						)
						(arc
							(start 0.2794 0.1778)
							(mid 0.249642 0.249642)
							(end 0.1778 0.2794)
						)
					)
					(width 0)
					(fill yes)
				)
			)
		)
		(pad "2" smd custom
			(at 0 0.4445 90)
			(size 0.1397 0.1397)
			(layers "B.Cu" "B.Mask" "B.Paste")
			(net "MB3_CM_SENSE_P")
			(options
				(clearance outline)
				(anchor circle)
			)
			(primitives
				(gr_poly
					(pts
						(arc
							(start -0.1778 0.2794)
							(mid -0.249642 0.249642)
							(end -0.2794 0.1778)
						)
						(arc
							(start -0.2794 -0.1778)
							(mid -0.249642 -0.249642)
							(end -0.1778 -0.2794)
						)
						(arc
							(start 0.1778 -0.2794)
							(mid 0.249642 -0.249642)
							(end 0.2794 -0.1778)
						)
						(arc
							(start 0.2794 0.1778)
							(mid 0.249642 0.249642)
							(end 0.1778 0.2794)
						)
					)
					(width 0)
					(fill yes)
				)
			)
		)
	)
	(footprint ""
		(layer "B.Cu")
		(at 484.251 -225.679 180)
		(property "Reference" "R1279"
			(at 0 0 0)
			(layer "B.SilkS")
			(hide yes)
			(effects
				(font
					(size 1.27 1.27)
				)
				(justify mirror)
			)
		)
		(property "Value" "0R2J-2-GP"
			(at -0.064008 -3.993896 180)
			(unlocked yes)
			(layer "B.Fab")
			(hide yes)
			(effects
				(font
					(size 1.016 1.016)
					(thickness 0.1524)
				)
				(justify mirror)
			)
		)
		(property "Device Type" "R402H16"
			(at -0.064008 -5.517896 180)
			(unlocked yes)
			(layer "B.Fab")
			(hide yes)
			(effects
				(font
					(size 1.016 1.016)
					(thickness 0.1524)
				)
				(justify mirror)
			)
		)
		(duplicate_pad_numbers_are_jumpers no)
		(fp_line
			(start 0.508 -0.9398)
			(end 0.508 0.9398)
			(stroke
				(width 0.1524)
				(type default)
			)
			(layer "B.SilkS")
		)
		(fp_line
			(start -0.508 -0.9398)
			(end 0.508 -0.9398)
			(stroke
				(width 0.1524)
				(type default)
			)
			(layer "B.SilkS")
		)
		(fp_rect
			(start 0.508 0.9398)
			(end -0.508 -0.9398)
			(stroke
				(width 0)
				(type default)
			)
			(fill no)
			(layer "B.CrtYd")
		)
		(fp_rect
			(start 0.508 0.9398)
			(end -0.508 -0.9398)
			(stroke
				(width 0)
				(type default)
			)
			(fill no)
			(layer "B.Fab")
		)
		(pad "1" smd custom
			(at 0 -0.4445)
			(size 0.1397 0.1397)
			(layers "B.Cu" "B.Mask" "B.Paste")
			(net "P5V_D_ROVP")
			(options
				(clearance outline)
				(anchor circle)
			)
			(primitives
				(gr_poly
					(pts
						(arc
							(start -0.1778 0.2794)
							(mid -0.249642 0.249642)
							(end -0.2794 0.1778)
						)
						(arc
							(start -0.2794 -0.1778)
							(mid -0.249642 -0.249642)
							(end -0.1778 -0.2794)
						)
						(arc
							(start 0.1778 -0.2794)
							(mid 0.249642 -0.249642)
							(end 0.2794 -0.1778)
						)
						(arc
							(start 0.2794 0.1778)
							(mid 0.249642 0.249642)
							(end 0.1778 0.2794)
						)
					)
					(width 0)
					(fill yes)
				)
			)
		)
		(pad "2" smd custom
			(at 0 0.4445)
			(size 0.1397 0.1397)
			(layers "B.Cu" "B.Mask" "B.Paste")
			(net "AGND_P5V_D")
			(options
				(clearance outline)
				(anchor circle)
			)
			(primitives
				(gr_poly
					(pts
						(arc
							(start -0.1778 0.2794)
							(mid -0.249642 0.249642)
							(end -0.2794 0.1778)
						)
						(arc
							(start -0.2794 -0.1778)
							(mid -0.249642 -0.249642)
							(end -0.1778 -0.2794)
						)
						(arc
							(start 0.1778 -0.2794)
							(mid 0.249642 -0.249642)
							(end 0.2794 -0.1778)
						)
						(arc
							(start 0.2794 0.1778)
							(mid 0.249642 0.249642)
							(end 0.1778 0.2794)
						)
					)
					(width 0)
					(fill yes)
				)
			)
		)
	)
	(footprint ""
		(layer "B.Cu")
		(at 222.2246 -120.2182)
		(property "Reference" "R188"
			(at 0 0 0)
			(layer "B.SilkS")
			(hide yes)
			(effects
				(font
					(size 1.27 1.27)
				)
				(justify mirror)
			)
		)
		(property "Value" "4K7R2F-GP"
			(at -0.064008 -3.993896 0)
			(unlocked yes)
			(layer "B.Fab")
			(hide yes)
			(effects
				(font
					(size 1.016 1.016)
					(thickness 0.1524)
				)
				(justify mirror)
			)
		)
		(property "Device Type" "R402H16"
			(at -0.064008 -5.517896 0)
			(unlocked yes)
			(layer "B.Fab")
			(hide yes)
			(effects
				(font
					(size 1.016 1.016)
					(thickness 0.1524)
				)
				(justify mirror)
			)
		)
		(duplicate_pad_numbers_are_jumpers no)
		(fp_line
			(start -0.508 -0.9398)
			(end 0.508 -0.9398)
			(stroke
				(width 0.1524)
				(type default)
			)
			(layer "B.SilkS")
		)
		(fp_line
			(start 0.508 -0.9398)
			(end 0.508 0.9398)
			(stroke
				(width 0.1524)
				(type default)
			)
			(layer "B.SilkS")
		)
		(fp_rect
			(start 0.508 0.9398)
			(end -0.508 -0.9398)
			(stroke
				(width 0)
				(type default)
			)
			(fill no)
			(layer "B.CrtYd")
		)
		(fp_rect
			(start 0.508 0.9398)
			(end -0.508 -0.9398)
			(stroke
				(width 0)
				(type default)
			)
			(fill no)
			(layer "B.Fab")
		)
		(pad "1" smd custom
			(at 0 -0.4445 180)
			(size 0.1397 0.1397)
			(layers "B.Cu" "B.Mask" "B.Paste")
			(net "TXS0102_A_OE")
			(options
				(clearance outline)
				(anchor circle)
			)
			(primitives
				(gr_poly
					(pts
						(arc
							(start -0.1778 0.2794)
							(mid -0.249642 0.249642)
							(end -0.2794 0.1778)
						)
						(arc
							(start -0.2794 -0.1778)
							(mid -0.249642 -0.249642)
							(end -0.1778 -0.2794)
						)
						(arc
							(start 0.1778 -0.2794)
							(mid 0.249642 -0.249642)
							(end 0.2794 -0.1778)
						)
						(arc
							(start 0.2794 0.1778)
							(mid 0.249642 0.249642)
							(end 0.1778 0.2794)
						)
					)
					(width 0)
					(fill yes)
				)
			)
		)
		(pad "2" smd custom
			(at 0 0.4445 180)
			(size 0.1397 0.1397)
			(layers "B.Cu" "B.Mask" "B.Paste")
			(net "P3V3_STBY_A")
			(options
				(clearance outline)
				(anchor circle)
			)
			(primitives
				(gr_poly
					(pts
						(arc
							(start -0.1778 0.2794)
							(mid -0.249642 0.249642)
							(end -0.2794 0.1778)
						)
						(arc
							(start -0.2794 -0.1778)
							(mid -0.249642 -0.249642)
							(end -0.1778 -0.2794)
						)
						(arc
							(start 0.1778 -0.2794)
							(mid 0.249642 -0.249642)
							(end 0.2794 -0.1778)
						)
						(arc
							(start 0.2794 0.1778)
							(mid 0.249642 0.249642)
							(end 0.1778 0.2794)
						)
					)
					(width 0)
					(fill yes)
				)
			)
		)
	)
	(footprint ""
		(layer "B.Cu")
		(at 479.552 -228.092)
		(property "Reference" "C654"
			(at 0 0 0)
			(layer "B.SilkS")
			(hide yes)
			(effects
				(font
					(size 1.27 1.27)
				)
				(justify mirror)
			)
		)
		(property "Value" "SC1U16V3KX-5GP"
			(at 0 -2.8194 0)
			(unlocked yes)
			(layer "B.Fab")
			(hide yes)
			(effects
				(font
					(size 1.016 1.016)
					(thickness 0.1524)
				)
				(justify mirror)
			)
		)
		(property "Device Type" "C603H36"
			(at 0 -4.3434 0)
			(unlocked yes)
			(layer "B.Fab")
			(hide yes)
			(effects
				(font
					(size 1.016 1.016)
					(thickness 0.1524)
				)
				(justify mirror)
			)
		)
		(duplicate_pad_numbers_are_jumpers no)
		(fp_line
			(start -0.508 0)
			(end 0.508 0)
			(stroke
				(width 0.2032)
				(type default)
			)
			(layer "B.SilkS")
		)
		(fp_rect
			(start 0.5842 1.3335)
			(end -0.5842 -1.3335)
			(stroke
				(width 0)
				(type default)
			)
			(fill no)
			(layer "B.CrtYd")
		)
		(fp_rect
			(start 0.5842 1.3335)
			(end -0.5842 -1.3335)
			(stroke
				(width 0)
				(type default)
			)
			(fill no)
			(layer "B.Fab")
		)
		(pad "1" smd custom
			(at 0 -0.762 180)
			(size 0.2159 0.2159)
			(layers "B.Cu" "B.Mask" "B.Paste")
			(net "P5V_D_EN_R")
			(options
				(clearance outline)
				(anchor circle)
			)
			(primitives
				(gr_poly
					(pts
						(arc
							(start -0.3302 0.4318)
							(mid -0.402042 0.402042)
							(end -0.4318 0.3302)
						)
						(arc
							(start -0.4318 -0.3302)
							(mid -0.402042 -0.402042)
							(end -0.3302 -0.4318)
						)
						(arc
							(start 0.3302 -0.4318)
							(mid 0.402042 -0.402042)
							(end 0.4318 -0.3302)
						)
						(arc
							(start 0.4318 0.3302)
							(mid 0.402042 0.402042)
							(end 0.3302 0.4318)
						)
					)
					(width 0)
					(fill yes)
				)
			)
		)
		(pad "2" smd custom
			(at 0 0.762 180)
			(size 0.2159 0.2159)
			(layers "B.Cu" "B.Mask" "B.Paste")
			(net "GND")
			(options
				(clearance outline)
				(anchor circle)
			)
			(primitives
				(gr_poly
					(pts
						(arc
							(start -0.3302 0.4318)
							(mid -0.402042 0.402042)
							(end -0.4318 0.3302)
						)
						(arc
							(start -0.4318 -0.3302)
							(mid -0.402042 -0.402042)
							(end -0.3302 -0.4318)
						)
						(arc
							(start 0.3302 -0.4318)
							(mid 0.402042 -0.402042)
							(end 0.4318 -0.3302)
						)
						(arc
							(start 0.4318 0.3302)
							(mid 0.402042 0.402042)
							(end 0.3302 0.4318)
						)
					)
					(width 0)
					(fill yes)
				)
			)
		)
	)
	(footprint ""
		(layer "B.Cu")
		(at 185.089292 -239.238028 180)
		(property "Reference" "C686"
			(at 0 0 0)
			(layer "B.SilkS")
			(hide yes)
			(effects
				(font
					(size 1.27 1.27)
				)
				(justify mirror)
			)
		)
		(property "Value" "SC10U6D3V5KX-4GP"
			(at 0.0762 -6.1214 180)
			(unlocked yes)
			(layer "B.Fab")
			(hide yes)
			(effects
				(font
					(size 1.016 1.016)
					(thickness 0.1524)
				)
				(justify mirror)
			)
		)
		(property "Device Type" "C805H58"
			(at 0.0762 -8.1534 180)
			(unlocked yes)
			(layer "B.Fab")
			(hide yes)
			(effects
				(font
					(size 1.016 1.016)
					(thickness 0.1524)
				)
				(justify mirror)
			)
		)
		(duplicate_pad_numbers_are_jumpers no)
		(fp_line
			(start -0.635 0)
			(end 0.635 0)
			(stroke
				(width 0.508)
				(type default)
			)
			(layer "B.SilkS")
		)
		(fp_rect
			(start 0.9652 1.778)
			(end -0.9652 -1.778)
			(stroke
				(width 0)
				(type default)
			)
			(fill no)
			(layer "B.CrtYd")
		)
		(fp_poly
			(pts
				(xy 0.9652 -1.778) (xy -0.9652 -1.778) (xy -0.9652 1.778) (xy 0.9652 1.778)
			)
			(stroke
				(width 0)
				(type default)
			)
			(fill no)
			(layer "B.Fab")
		)
		(pad "1" smd rect
			(at 0 -0.9652)
			(size 1.397 1.143)
			(layers "B.Cu" "B.Mask" "B.Paste")
			(net "P3V3_STBY_A")
		)
		(pad "2" smd rect
			(at 0 0.9652)
			(size 1.397 1.143)
			(layers "B.Cu" "B.Mask" "B.Paste")
			(net "GND")
		)
	)
	(footprint ""
		(layer "B.Cu")
		(at 434.750972 -252.076966 180)
		(property "Reference" "C636"
			(at 0 0 0)
			(layer "B.SilkS")
			(hide yes)
			(effects
				(font
					(size 1.27 1.27)
				)
				(justify mirror)
			)
		)
		(property "Value" "SC10U16V5KX-7-GP-U"
			(at 0.0762 -6.1214 180)
			(unlocked yes)
			(layer "B.Fab")
			(hide yes)
			(effects
				(font
					(size 1.016 1.016)
					(thickness 0.1524)
				)
				(justify mirror)
			)
		)
		(property "Device Type" "C805H58"
			(at 0.0762 -8.1534 180)
			(unlocked yes)
			(layer "B.Fab")
			(hide yes)
			(effects
				(font
					(size 1.016 1.016)
					(thickness 0.1524)
				)
				(justify mirror)
			)
		)
		(duplicate_pad_numbers_are_jumpers no)
		(fp_line
			(start -0.635 0)
			(end 0.635 0)
			(stroke
				(width 0.508)
				(type default)
			)
			(layer "B.SilkS")
		)
		(fp_rect
			(start 0.9652 1.778)
			(end -0.9652 -1.778)
			(stroke
				(width 0)
				(type default)
			)
			(fill no)
			(layer "B.CrtYd")
		)
		(fp_poly
			(pts
				(xy 0.9652 -1.778) (xy -0.9652 -1.778) (xy -0.9652 1.778) (xy 0.9652 1.778)
			)
			(stroke
				(width 0)
				(type default)
			)
			(fill no)
			(layer "B.Fab")
		)
		(pad "1" smd rect
			(at 0 -0.9652)
			(size 1.397 1.143)
			(layers "B.Cu" "B.Mask" "B.Paste")
			(net "P12V_A_VIN_U22")
		)
		(pad "2" smd rect
			(at 0 0.9652)
			(size 1.397 1.143)
			(layers "B.Cu" "B.Mask" "B.Paste")
			(net "GND")
		)
	)
	(footprint ""
		(layer "B.Cu")
		(at 456.5396 -248.9454 90)
		(property "Reference" "L6"
			(at 0 0 90)
			(layer "B.SilkS")
			(hide yes)
			(effects
				(font
					(size 1.27 1.27)
				)
				(justify mirror)
			)
		)
		(property "Value" "IND-1UH-191-GP"
			(at 6.7818 -2.1082 90)
			(unlocked yes)
			(layer "B.Fab")
			(hide yes)
			(effects
				(font
					(size 1.016 1.016)
					(thickness 0.1524)
				)
				(justify mirror)
			)
		)
		(property "Device Type" "L109100-2430-UH119"
			(at 6.7818 -3.6322 90)
			(unlocked yes)
			(layer "B.Fab")
			(hide yes)
			(effects
				(font
					(size 1.016 1.016)
					(thickness 0.1524)
				)
				(justify mirror)
			)
		)
		(duplicate_pad_numbers_are_jumpers no)
		(fp_line
			(start 5.2578 -6.4262)
			(end -5.2578 -6.4262)
			(stroke
				(width 0.1524)
				(type default)
			)
			(layer "B.SilkS")
		)
		(fp_line
			(start -5.2578 -6.4262)
			(end -5.2578 6.4262)
			(stroke
				(width 0.1524)
				(type default)
			)
			(layer "B.SilkS")
		)
		(fp_line
			(start 5.2578 6.4262)
			(end 5.2578 -6.4262)
			(stroke
				(width 0.1524)
				(type default)
			)
			(layer "B.SilkS")
		)
		(fp_line
			(start -5.2578 6.4262)
			(end 5.2578 6.4262)
			(stroke
				(width 0.1524)
				(type default)
			)
			(layer "B.SilkS")
		)
		(fp_rect
			(start 5.0038 5.4229)
			(end -5.0038 -5.4229)
			(stroke
				(width 0)
				(type default)
			)
			(fill no)
			(layer "B.CrtYd")
		)
		(fp_poly
			(pts
				(xy 5.5118 6.5024) (xy 5.5118 -6.5024) (xy -5.5118 -6.5024) (xy -5.5118 -0.8509) (xy -5.0038 -0.8509)
				(xy -5.0038 -5.4229) (xy 5.0038 -5.4229) (xy 5.0038 5.4229) (xy -5.0038 5.4229) (xy -5.0038 -0.8382)
				(xy -5.5118 -0.8382) (xy -5.5118 6.5024)
			)
			(stroke
				(width 0)
				(type default)
			)
			(fill no)
			(layer "B.CrtYd")
		)
		(fp_rect
			(start 5.5118 6.5024)
			(end -5.5118 -6.5024)
			(stroke
				(width 0)
				(type default)
			)
			(fill no)
			(layer "B.Fab")
		)
		(pad "1" smd rect
			(at 0 -4.396994 270)
			(size 3.5052 3.556)
			(layers "B.Cu" "B.Mask" "B.Paste")
			(net "P5V_C_LL")
		)
		(pad "2" smd rect
			(at 0 4.396994 270)
			(size 3.5052 3.556)
			(layers "B.Cu" "B.Mask" "B.Paste")
			(net "P5V_A_3")
		)
	)
	(footprint ""
		(layer "B.Cu")
		(at 143.34998 -30.550104 180)
		(property "Reference" "IO1"
			(at 0 0 0)
			(layer "B.SilkS")
			(hide yes)
			(effects
				(font
					(size 1.27 1.27)
				)
				(justify mirror)
			)
		)
		(property "Value" "DM-AMP-CONN200-13R-6-GP-01"
			(at 47.5488 -16.5862 180)
			(unlocked yes)
			(layer "B.Fab")
			(hide yes)
			(effects
				(font
					(size 1.016 1.016)
					(thickness 0.1524)
				)
				(justify mirror)
			)
		)
		(property "Device Type" "DMFIT-200P-384346H577-01"
			(at 47.5488 -18.1102 180)
			(unlocked yes)
			(layer "B.Fab")
			(hide yes)
			(effects
				(font
					(size 1.016 1.016)
					(thickness 0.1524)
				)
				(justify mirror)
			)
		)
		(duplicate_pad_numbers_are_jumpers no)
		(fp_line
			(start 36.703 3.9878)
			(end 36.703 -15.54988)
			(stroke
				(width 0.1524)
				(type default)
			)
			(layer "B.SilkS")
		)
		(fp_line
			(start 36.703 -15.54988)
			(end -2.2098 -15.54988)
			(stroke
				(width 0.1524)
				(type default)
			)
			(layer "B.SilkS")
		)
		(fp_line
			(start -2.2098 3.9878)
			(end 36.703 3.9878)
			(stroke
				(width 0.1524)
				(type default)
			)
			(layer "B.SilkS")
		)
		(fp_line
			(start -2.2098 -15.54988)
			(end -2.2098 3.9878)
			(stroke
				(width 0.1524)
				(type default)
			)
			(layer "B.SilkS")
		)
		(fp_poly
			(pts
				(xy 36.703 3.9878) (xy 36.703 -15.54988) (xy -2.2098 -15.54988) (xy -2.2098 3.9878) (xy 11.9634 3.9878)
				(xy 11.9634 2.2098) (xy -0.5842 2.2098) (xy -0.5842 -14.884146) (xy 34.784284 -14.884146) (xy 34.784284 2.2098)
				(xy 22.3774 2.2098) (xy 22.3774 3.9878)
			)
			(stroke
				(width 0)
				(type default)
			)
			(fill yes)
			(layer "B.SilkS")
		)
		(fp_poly
			(pts
				(arc
					(start 33.947862 1.778)
					(mid 34.201862 2.032)
					(end 34.455862 1.778)
				)
				(arc
					(start 34.455862 1.016)
					(mid 34.201862 0.762)
					(end 33.947862 1.016)
				)
			)
			(stroke
				(width 0)
				(type default)
			)
			(fill yes)
			(layer "B.SilkS")
		)
		(fp_poly
			(pts
				(arc
					(start 32.147764 1.778)
					(mid 32.401764 2.032)
					(end 32.655764 1.778)
				)
				(arc
					(start 32.655764 1.016)
					(mid 32.401764 0.762)
					(end 32.147764 1.016)
				)
			)
			(stroke
				(width 0)
				(type default)
			)
			(fill yes)
			(layer "B.SilkS")
		)
		(fp_poly
			(pts
				(arc
					(start 30.347666 1.778)
					(mid 30.601666 2.032)
					(end 30.855666 1.778)
				)
				(arc
					(start 30.855666 1.016)
					(mid 30.601666 0.762)
					(end 30.347666 1.016)
				)
			)
			(stroke
				(width 0)
				(type default)
			)
			(fill yes)
			(layer "B.SilkS")
		)
		(fp_poly
			(pts
				(arc
					(start 28.547568 1.778)
					(mid 28.801568 2.032)
					(end 29.055568 1.778)
				)
				(arc
					(start 29.055568 1.016)
					(mid 28.801568 0.762)
					(end 28.547568 1.016)
				)
			)
			(stroke
				(width 0)
				(type default)
			)
			(fill yes)
			(layer "B.SilkS")
		)
		(fp_poly
			(pts
				(arc
					(start 26.74747 1.778)
					(mid 27.00147 2.032)
					(end 27.25547 1.778)
				)
				(arc
					(start 27.25547 1.016)
					(mid 27.00147 0.762)
					(end 26.74747 1.016)
				)
			)
			(stroke
				(width 0)
				(type default)
			)
			(fill yes)
			(layer "B.SilkS")
		)
		(fp_poly
			(pts
				(arc
					(start 24.947372 1.778)
					(mid 25.201372 2.032)
					(end 25.455372 1.778)
				)
				(arc
					(start 25.455372 1.016)
					(mid 25.201372 0.762)
					(end 24.947372 1.016)
				)
			)
			(stroke
				(width 0)
				(type default)
			)
			(fill yes)
			(layer "B.SilkS")
		)
		(fp_poly
			(pts
				(arc
					(start 23.147274 1.778)
					(mid 23.401274 2.032)
					(end 23.655274 1.778)
				)
				(arc
					(start 23.655274 1.016)
					(mid 23.401274 0.762)
					(end 23.147274 1.016)
				)
			)
			(stroke
				(width 0)
				(type default)
			)
			(fill yes)
			(layer "B.SilkS")
		)
		(fp_poly
			(pts
				(arc
					(start 21.347176 1.778)
					(mid 21.601176 2.032)
					(end 21.855176 1.778)
				)
				(arc
					(start 21.855176 1.016)
					(mid 21.601176 0.762)
					(end 21.347176 1.016)
				)
			)
			(stroke
				(width 0)
				(type default)
			)
			(fill yes)
			(layer "B.SilkS")
		)
		(fp_poly
			(pts
				(arc
					(start 12.346686 1.778)
					(mid 12.600686 2.032)
					(end 12.854686 1.778)
				)
				(arc
					(start 12.854686 1.016)
					(mid 12.600686 0.762)
					(end 12.346686 1.016)
				)
			)
			(stroke
				(width 0)
				(type default)
			)
			(fill yes)
			(layer "B.SilkS")
		)
		(fp_poly
			(pts
				(arc
					(start 10.546588 1.778)
					(mid 10.800588 2.032)
					(end 11.054588 1.778)
				)
				(arc
					(start 11.054588 1.016)
					(mid 10.800588 0.762)
					(end 10.546588 1.016)
				)
			)
			(stroke
				(width 0)
				(type default)
			)
			(fill yes)
			(layer "B.SilkS")
		)
		(fp_poly
			(pts
				(arc
					(start 8.74649 1.778)
					(mid 9.00049 2.032)
					(end 9.25449 1.778)
				)
				(arc
					(start 9.25449 1.016)
					(mid 9.00049 0.762)
					(end 8.74649 1.016)
				)
			)
			(stroke
				(width 0)
				(type default)
			)
			(fill yes)
			(layer "B.SilkS")
		)
		(fp_poly
			(pts
				(arc
					(start 6.946392 1.778)
					(mid 7.200392 2.032)
					(end 7.454392 1.778)
				)
				(arc
					(start 7.454392 1.016)
					(mid 7.200392 0.762)
					(end 6.946392 1.016)
				)
			)
			(stroke
				(width 0)
				(type default)
			)
			(fill yes)
			(layer "B.SilkS")
		)
		(fp_poly
			(pts
				(arc
					(start 5.146294 1.778)
					(mid 5.400294 2.032)
					(end 5.654294 1.778)
				)
				(arc
					(start 5.654294 1.016)
					(mid 5.400294 0.762)
					(end 5.146294 1.016)
				)
			)
			(stroke
				(width 0)
				(type default)
			)
			(fill yes)
			(layer "B.SilkS")
		)
		(fp_poly
			(pts
				(arc
					(start 3.346196 1.778)
					(mid 3.600196 2.032)
					(end 3.854196 1.778)
				)
				(arc
					(start 3.854196 1.016)
					(mid 3.600196 0.762)
					(end 3.346196 1.016)
				)
			)
			(stroke
				(width 0)
				(type default)
			)
			(fill yes)
			(layer "B.SilkS")
		)
		(fp_poly
			(pts
				(arc
					(start 1.546098 1.778)
					(mid 1.800098 2.032)
					(end 2.054098 1.778)
				)
				(arc
					(start 2.054098 1.016)
					(mid 1.800098 0.762)
					(end 1.546098 1.016)
				)
			)
			(stroke
				(width 0)
				(type default)
			)
			(fill yes)
			(layer "B.SilkS")
		)
		(fp_poly
			(pts
				(arc
					(start -0.254 1.778)
					(mid 0 2.032)
					(end 0.254 1.778)
				)
				(arc
					(start 0.254 1.016)
					(mid 0 0.762)
					(end -0.254 1.016)
				)
			)
			(stroke
				(width 0)
				(type default)
			)
			(fill yes)
			(layer "B.SilkS")
		)
		(fp_rect
			(start 36.449 3.7338)
			(end -1.9558 -30.861)
			(stroke
				(width 0)
				(type default)
			)
			(fill no)
			(layer "B.CrtYd")
		)
		(fp_poly
			(pts
				(xy 41.4528 8.7376) (xy 41.4528 -35.8648) (xy -6.9596 -35.8648) (xy -6.9596 -0.00635) (xy -2.4638 -0.00635)
				(xy -2.4638 -31.369) (xy 36.957 -31.369) (xy 36.957 4.2418) (xy -2.4638 4.2418) (xy -2.4638 0.00635)
				(xy -6.9596 0.00635) (xy -6.9596 8.7376)
			)
			(stroke
				(width 0)
				(type default)
			)
			(fill no)
			(layer "B.CrtYd")
		)
		(fp_poly
			(pts
				(xy 36.957 4.2418) (xy 36.957 -31.369) (xy -2.4638 -31.369) (xy -2.4638 -0.00635) (xy -1.9558 -0.00635)
				(xy -1.9558 -30.861) (xy 36.449 -30.861) (xy 36.449 3.7338) (xy -1.9558 3.7338) (xy -1.9558 0.00635)
				(xy -2.4638 0.00635) (xy -2.4638 4.2418)
			)
			(stroke
				(width 0)
				(type default)
			)
			(fill no)
			(layer "B.CrtYd")
		)
		(fp_rect
			(start 39.5986 5.4864)
			(end -5.3848 -19.685)
			(stroke
				(width 0)
				(type default)
			)
			(fill no)
			(layer "F.CrtYd")
		)
		(fp_rect
			(start 46.4566 13.7414)
			(end -11.9634 -40.8686)
			(stroke
				(width 0)
				(type default)
			)
			(fill no)
			(layer "B.Fab")
		)
		(fp_rect
			(start 41.4528 8.7376)
			(end -6.9596 -35.8648)
			(stroke
				(width 0)
				(type default)
			)
			(fill no)
			(layer "B.Fab")
		)
		(fp_rect
			(start 36.957 4.2418)
			(end -2.4638 -31.369)
			(stroke
				(width 0)
				(type default)
			)
			(fill no)
			(layer "B.Fab")
		)
		(fp_rect
			(start 44.6024 10.4902)
			(end -10.3886 -24.6888)
			(stroke
				(width 0)
				(type default)
			)
			(fill no)
			(layer "F.Fab")
		)
		(fp_rect
			(start 39.5986 5.4864)
			(end -5.3848 -19.685)
			(stroke
				(width 0)
				(type default)
			)
			(fill no)
			(layer "F.Fab")
		)
		(fp_text user "Press Fit"
			(at 22.2504 3.1242 180)
			(unlocked yes)
			(layer "B.SilkS")
			(effects
				(font
					(size 1.016 1.016)
					(thickness 0.1524)
				)
				(justify left mirror)
			)
		)
		(fp_text user "Slit"
			(at 19.27987 -18.071846 180)
			(unlocked yes)
			(layer "B.SilkS")
			(effects
				(font
					(size 1.016 1.016)
					(thickness 0.1524)
				)
				(justify left mirror)
			)
		)
		(fp_text user "Can not place BGA,CSP,Wave Solder Component"
			(at 42.5704 -39.1922 180)
			(unlocked yes)
			(layer "B.Fab")
			(effects
				(font
					(size 1.016 1.016)
					(thickness 0.1524)
				)
				(justify left mirror)
			)
		)
		(fp_text user "High Limit 2mm"
			(at 24.6126 -34.5694 180)
			(unlocked yes)
			(layer "B.Fab")
			(effects
				(font
					(size 1.016 1.016)
					(thickness 0.1524)
				)
				(justify left mirror)
			)
		)
		(fp_text user "Can not place BGA,CSP,Wave Solder Component"
			(at 42.3418 -23.4442 180)
			(unlocked yes)
			(layer "F.Fab")
			(effects
				(font
					(size 1.016 1.016)
					(thickness 0.1524)
				)
				(justify left mirror)
			)
		)
		(pad "" np_thru_hole circle
			(at 17.200118 -9.99998)
			(size 0.254 0.254)
			(drill 2.3876)
			(layers "*.Cu" "*.Mask")
			(clearance 1.4224)
			(thermal_gap 1.4224)
		)
		(pad "" np_thru_hole circle
			(at 17.200118 -2.469896)
			(size 0.254 0.254)
			(drill 2.4638)
			(layers "*.Cu" "*.Mask")
			(clearance 1.4605)
			(thermal_gap 1.4605)
		)
		(pad "A1" thru_hole circle
			(at 0 0)
			(size 0.762 0.762)
			(drill 0.359918)
			(layers "*.Cu" "*.Mask")
			(remove_unused_layers no)
			(net "PCIE_COMP_A_TO_IOM_A_CLK_2_DN")
			(clearance 0.1651)
			(thermal_gap 0.1651)
		)
		(pad "A2" thru_hole circle
			(at 1.800098 -0.999998)
			(size 0.762 0.762)
			(drill 0.359918)
			(layers "*.Cu" "*.Mask")
			(remove_unused_layers no)
			(net "I2C_BMC_A_MISC_SDA")
			(clearance 0.1651)
			(thermal_gap 0.1651)
		)
		(pad "A3" thru_hole circle
			(at 3.599942 0)
			(size 0.762 0.762)
			(drill 0.359918)
			(layers "*.Cu" "*.Mask")
			(remove_unused_layers no)
			(net "BMC_A_HEARTBEAT")
			(clearance 0.1651)
			(thermal_gap 0.1651)
		)
		(pad "A4" thru_hole circle
			(at 5.40004 -0.999998)
			(size 0.762 0.762)
			(drill 0.359918)
			(layers "*.Cu" "*.Mask")
			(remove_unused_layers no)
			(net "SCC_B_FULL_PWR_EN")
			(clearance 0.1651)
			(thermal_gap 0.1651)
		)
		(pad "A5" thru_hole circle
			(at 7.199884 0)
			(size 0.762 0.762)
			(drill 0.359918)
			(layers "*.Cu" "*.Mask")
			(remove_unused_layers no)
			(net "PCIE_COMP_A_TO_IOM_A_CLK_3_DN")
			(clearance 0.1651)
			(thermal_gap 0.1651)
		)
		(pad "A6" thru_hole circle
			(at 8.999982 -0.999998)
			(size 0.762 0.762)
			(drill 0.359918)
			(layers "*.Cu" "*.Mask")
			(remove_unused_layers no)
			(net "I2C_BMC_A_EXP_A_SDA")
			(clearance 0.1651)
			(thermal_gap 0.1651)
		)
		(pad "A7" thru_hole circle
			(at 10.80008 0)
			(size 0.762 0.762)
			(drill 0.359918)
			(layers "*.Cu" "*.Mask")
			(remove_unused_layers no)
			(net "P12V_A")
			(clearance 0.1651)
			(thermal_gap 0.1651)
		)
		(pad "A8" thru_hole circle
			(at 12.599924 -0.999998)
			(size 0.762 0.762)
			(drill 0.359918)
			(layers "*.Cu" "*.Mask")
			(remove_unused_layers no)
			(net "P12V_A")
			(clearance 0.1651)
			(thermal_gap 0.1651)
		)
		(pad "A9" thru_hole circle
			(at 21.599906 0)
			(size 0.762 0.762)
			(drill 0.359918)
			(layers "*.Cu" "*.Mask")
			(remove_unused_layers no)
			(net "PCIE_COMP_A_TO_IOM_A_CLK_4_DN")
			(clearance 0.1651)
			(thermal_gap 0.1651)
		)
		(pad "A10" thru_hole circle
			(at 23.400004 -0.999998)
			(size 0.762 0.762)
			(drill 0.359918)
			(layers "*.Cu" "*.Mask")
			(remove_unused_layers no)
			(net "IOM_A_SLOT_ID_1")
			(clearance 0.1651)
			(thermal_gap 0.1651)
		)
		(pad "A11" thru_hole circle
			(at 25.200102 0)
			(size 0.762 0.762)
			(drill 0.359918)
			(layers "*.Cu" "*.Mask")
			(remove_unused_layers no)
			(net "BMC_A_TO_EXP_A_RESET_N")
			(clearance 0.1651)
			(thermal_gap 0.1651)
		)
		(pad "A12" thru_hole circle
			(at 26.999946 -0.999998)
			(size 0.762 0.762)
			(drill 0.359918)
			(layers "*.Cu" "*.Mask")
			(remove_unused_layers no)
			(net "USB_COMP_A_DN")
			(clearance 0.1651)
			(thermal_gap 0.1651)
		)
		(pad "A13" thru_hole circle
			(at 28.800044 0)
			(size 0.762 0.762)
			(drill 0.359918)
			(layers "*.Cu" "*.Mask")
			(remove_unused_layers no)
			(net "COMP_A_TO_BMC_A_RESET_N")
			(clearance 0.1651)
			(thermal_gap 0.1651)
		)
		(pad "A14" thru_hole circle
			(at 30.599888 -0.999998)
			(size 0.762 0.762)
			(drill 0.359918)
			(layers "*.Cu" "*.Mask")
			(remove_unused_layers no)
			(net "I2C_DPB_A_SDA")
			(clearance 0.1651)
			(thermal_gap 0.1651)
		)
		(pad "A15" thru_hole circle
			(at 32.399986 0)
			(size 0.762 0.762)
			(drill 0.359918)
			(layers "*.Cu" "*.Mask")
			(remove_unused_layers no)
			(net "BMC_A_EXP_A_SPARE_1")
			(clearance 0.1651)
			(thermal_gap 0.1651)
		)
		(pad "A16" thru_hole circle
			(at 34.200084 -0.999998)
			(size 0.762 0.762)
			(drill 0.359918)
			(layers "*.Cu" "*.Mask")
			(remove_unused_layers no)
			(net "COMP_A_BMC_A_SPARE_1")
			(clearance 0.1651)
			(thermal_gap 0.1651)
		)
		(pad "B1" thru_hole circle
			(at 0 -1.400048)
			(size 0.762 0.762)
			(drill 0.359918)
			(layers "*.Cu" "*.Mask")
			(remove_unused_layers no)
			(net "PCIE_COMP_A_TO_IOM_A_CLK_2_DP")
			(clearance 0.1651)
			(thermal_gap 0.1651)
		)
		(pad "B2" thru_hole circle
			(at 1.800098 -2.400046)
			(size 0.762 0.762)
			(drill 0.359918)
			(layers "*.Cu" "*.Mask")
			(remove_unused_layers no)
			(net "I2C_BMC_A_MISC_SCL")
			(clearance 0.1651)
			(thermal_gap 0.1651)
		)
		(pad "B3" thru_hole circle
			(at 3.599942 -1.400048)
			(size 0.762 0.762)
			(drill 0.359918)
			(layers "*.Cu" "*.Mask")
			(remove_unused_layers no)
			(net "BMC_B_HEARTBEAT")
			(clearance 0.1651)
			(thermal_gap 0.1651)
		)
		(pad "B4" thru_hole circle
			(at 5.40004 -2.400046)
			(size 0.762 0.762)
			(drill 0.359918)
			(layers "*.Cu" "*.Mask")
			(remove_unused_layers no)
			(net "SCC_A_FULL_PWR_EN")
			(clearance 0.1651)
			(thermal_gap 0.1651)
		)
		(pad "B5" thru_hole circle
			(at 7.199884 -1.400048)
			(size 0.762 0.762)
			(drill 0.359918)
			(layers "*.Cu" "*.Mask")
			(remove_unused_layers no)
			(net "PCIE_COMP_A_TO_IOM_A_CLK_3_DP")
			(clearance 0.1651)
			(thermal_gap 0.1651)
		)
		(pad "B6" thru_hole circle
			(at 8.999982 -2.400046)
			(size 0.762 0.762)
			(drill 0.359918)
			(layers "*.Cu" "*.Mask")
			(remove_unused_layers no)
			(net "I2C_BMC_A_EXP_A_SCL")
			(clearance 0.1651)
			(thermal_gap 0.1651)
		)
		(pad "B7" thru_hole circle
			(at 10.80008 -1.400048)
			(size 0.762 0.762)
			(drill 0.359918)
			(layers "*.Cu" "*.Mask")
			(remove_unused_layers no)
			(net "P12V_A_PGOOD")
			(clearance 0.1651)
			(thermal_gap 0.1651)
		)
		(pad "B8" thru_hole circle
			(at 12.599924 -2.400046)
			(size 0.762 0.762)
			(drill 0.359918)
			(layers "*.Cu" "*.Mask")
			(remove_unused_layers no)
			(net "P12V_A")
			(clearance 0.1651)
			(thermal_gap 0.1651)
		)
		(pad "B9" thru_hole circle
			(at 21.599906 -1.400048)
			(size 0.762 0.762)
			(drill 0.359918)
			(layers "*.Cu" "*.Mask")
			(remove_unused_layers no)
			(net "PCIE_COMP_A_TO_IOM_A_CLK_4_DP")
			(clearance 0.1651)
			(thermal_gap 0.1651)
		)
		(pad "B10" thru_hole circle
			(at 23.400004 -2.400046)
			(size 0.762 0.762)
			(drill 0.359918)
			(layers "*.Cu" "*.Mask")
			(remove_unused_layers no)
			(net "IOM_A_SLOT_ID_0")
			(clearance 0.1651)
			(thermal_gap 0.1651)
		)
		(pad "B11" thru_hole circle
			(at 25.200102 -1.400048)
			(size 0.762 0.762)
			(drill 0.359918)
			(layers "*.Cu" "*.Mask")
			(remove_unused_layers no)
			(net "BMC_A_MISC_ALERT_N")
			(clearance 0.1651)
			(thermal_gap 0.1651)
		)
		(pad "B12" thru_hole circle
			(at 26.999946 -2.400046)
			(size 0.762 0.762)
			(drill 0.359918)
			(layers "*.Cu" "*.Mask")
			(remove_unused_layers no)
			(net "USB_COMP_A_DP")
			(clearance 0.1651)
			(thermal_gap 0.1651)
		)
		(pad "B13" thru_hole circle
			(at 28.800044 -1.400048)
			(size 0.762 0.762)
			(drill 0.359918)
			(layers "*.Cu" "*.Mask")
			(remove_unused_layers no)
			(net "SYS_A_RESET_N")
			(clearance 0.1651)
			(thermal_gap 0.1651)
		)
		(pad "B14" thru_hole circle
			(at 30.599888 -2.400046)
			(size 0.762 0.762)
			(drill 0.359918)
			(layers "*.Cu" "*.Mask")
			(remove_unused_layers no)
			(net "I2C_DPB_A_SCL")
			(clearance 0.1651)
			(thermal_gap 0.1651)
		)
		(pad "B15" thru_hole circle
			(at 32.399986 -1.400048)
			(size 0.762 0.762)
			(drill 0.359918)
			(layers "*.Cu" "*.Mask")
			(remove_unused_layers no)
			(net "BMC_A_EXP_A_SPARE_0")
			(clearance 0.1651)
			(thermal_gap 0.1651)
		)
		(pad "B16" thru_hole circle
			(at 34.200084 -2.400046)
			(size 0.762 0.762)
			(drill 0.359918)
			(layers "*.Cu" "*.Mask")
			(remove_unused_layers no)
			(net "COMP_A_BMC_A_SPARE_0")
			(clearance 0.1651)
			(thermal_gap 0.1651)
		)
		(pad "C1" thru_hole circle
			(at 0 -3.599942)
			(size 0.762 0.762)
			(drill 0.359918)
			(layers "*.Cu" "*.Mask")
			(remove_unused_layers no)
			(net "IOM_A_MATED_N")
			(clearance 0.1651)
			(thermal_gap 0.1651)
		)
		(pad "C2" thru_hole circle
			(at 1.800098 -4.59994)
			(size 0.762 0.762)
			(drill 0.359918)
			(layers "*.Cu" "*.Mask")
			(remove_unused_layers no)
			(net "I2C_SCC_A_SDA")
			(clearance 0.1651)
			(thermal_gap 0.1651)
		)
		(pad "C3" thru_hole circle
			(at 3.599942 -3.599942)
			(size 0.762 0.762)
			(drill 0.359918)
			(layers "*.Cu" "*.Mask")
			(remove_unused_layers no)
			(net "SCC_B_HEARTBEAT")
			(clearance 0.1651)
			(thermal_gap 0.1651)
		)
		(pad "C4" thru_hole circle
			(at 5.40004 -4.59994)
			(size 0.762 0.762)
			(drill 0.359918)
			(layers "*.Cu" "*.Mask")
			(remove_unused_layers no)
			(net "IOM_A_PWR_LED")
			(clearance 0.1651)
			(thermal_gap 0.1651)
		)
		(pad "C5" thru_hole circle
			(at 7.199884 -3.599942)
			(size 0.762 0.762)
			(drill 0.359918)
			(layers "*.Cu" "*.Mask")
			(remove_unused_layers no)
			(net "IOM_A_INS_N")
			(clearance 0.1651)
			(thermal_gap 0.1651)
		)
		(pad "C6" thru_hole circle
			(at 8.999982 -4.59994)
			(size 0.762 0.762)
			(drill 0.359918)
			(layers "*.Cu" "*.Mask")
			(remove_unused_layers no)
			(net "I2C_BMC_A_EXP_B_SDA")
			(clearance 0.1651)
			(thermal_gap 0.1651)
		)
		(pad "C7" thru_hole circle
			(at 10.80008 -3.599942)
			(size 0.762 0.762)
			(drill 0.359918)
			(layers "*.Cu" "*.Mask")
			(remove_unused_layers no)
			(net "UART_SDB_A_RX")
			(clearance 0.1651)
			(thermal_gap 0.1651)
		)
		(pad "C8" thru_hole circle
			(at 12.599924 -4.59994)
			(size 0.762 0.762)
			(drill 0.359918)
			(layers "*.Cu" "*.Mask")
			(remove_unused_layers no)
			(net "P12V_A")
			(clearance 0.1651)
			(thermal_gap 0.1651)
		)
		(pad "C9" thru_hole circle
			(at 21.599906 -3.599942)
			(size 0.762 0.762)
			(drill 0.359918)
			(layers "*.Cu" "*.Mask")
			(remove_unused_layers no)
			(net "COMP_A_BMC_A_ALERT_N")
			(clearance 0.1651)
			(thermal_gap 0.1651)
		)
		(pad "C10" thru_hole circle
			(at 23.400004 -4.59994)
			(size 0.762 0.762)
			(drill 0.359918)
			(layers "*.Cu" "*.Mask")
			(remove_unused_layers no)
			(net "I2C_BMC_A_COMP_A_SDA_BUF")
			(clearance 0.1651)
			(thermal_gap 0.1651)
		)
		(pad "C11" thru_hole circle
			(at 25.200102 -3.599942)
			(size 0.762 0.762)
			(drill 0.359918)
			(layers "*.Cu" "*.Mask")
			(remove_unused_layers no)
			(net "UART_COMP_A_RX")
			(clearance 0.1651)
			(thermal_gap 0.1651)
		)
		(pad "C12" thru_hole circle
			(at 26.999946 -4.59994)
			(size 0.762 0.762)
			(drill 0.359918)
			(layers "*.Cu" "*.Mask")
			(remove_unused_layers no)
			(net "COMP_A_PWR_EN")
			(clearance 0.1651)
			(thermal_gap 0.1651)
		)
		(pad "C13" thru_hole circle
			(at 28.800044 -3.599942)
			(size 0.762 0.762)
			(drill 0.359918)
			(layers "*.Cu" "*.Mask")
			(remove_unused_layers no)
			(net "COMP_A_POWER_FAIL_N")
			(clearance 0.1651)
			(thermal_gap 0.1651)
		)
		(pad "C14" thru_hole circle
			(at 30.599888 -4.59994)
			(size 0.762 0.762)
			(drill 0.359918)
			(layers "*.Cu" "*.Mask")
			(remove_unused_layers no)
			(net "Net_18")
			(clearance 0.1651)
			(thermal_gap 0.1651)
		)
		(pad "C15" thru_hole circle
			(at 32.399986 -3.599942)
			(size 0.762 0.762)
			(drill 0.359918)
			(layers "*.Cu" "*.Mask")
			(remove_unused_layers no)
			(net "Net_19")
			(clearance 0.1651)
			(thermal_gap 0.1651)
		)
		(pad "C16" thru_hole circle
			(at 34.200084 -4.59994)
			(size 0.762 0.762)
			(drill 0.359918)
			(layers "*.Cu" "*.Mask")
			(remove_unused_layers no)
			(net "PWM_BMC_A_ZONE_C")
			(clearance 0.1651)
			(thermal_gap 0.1651)
		)
		(pad "D1" thru_hole circle
			(at 0 -4.99999)
			(size 0.762 0.762)
			(drill 0.359918)
			(layers "*.Cu" "*.Mask")
			(remove_unused_layers no)
			(net "PCIE_COMP_A_TO_IOM_A_RST_2")
			(clearance 0.1651)
			(thermal_gap 0.1651)
		)
		(pad "D2" thru_hole circle
			(at 1.800098 -5.999988)
			(size 0.762 0.762)
			(drill 0.359918)
			(layers "*.Cu" "*.Mask")
			(remove_unused_layers no)
			(net "I2C_SCC_A_SCL")
			(clearance 0.1651)
			(thermal_gap 0.1651)
		)
		(pad "D3" thru_hole circle
			(at 3.599942 -4.99999)
			(size 0.762 0.762)
			(drill 0.359918)
			(layers "*.Cu" "*.Mask")
			(remove_unused_layers no)
			(net "SCC_A_HEARTBEAT")
			(clearance 0.1651)
			(thermal_gap 0.1651)
		)
		(pad "D4" thru_hole circle
			(at 5.40004 -5.999988)
			(size 0.762 0.762)
			(drill 0.359918)
			(layers "*.Cu" "*.Mask")
			(remove_unused_layers no)
			(net "SCC_A_STBY_PWR_EN")
			(clearance 0.1651)
			(thermal_gap 0.1651)
		)
		(pad "D5" thru_hole circle
			(at 7.199884 -4.99999)
			(size 0.762 0.762)
			(drill 0.359918)
			(layers "*.Cu" "*.Mask")
			(remove_unused_layers no)
			(net "PCIE_COMP_A_TO_IOM_A_RST_3")
			(clearance 0.1651)
			(thermal_gap 0.1651)
		)
		(pad "D6" thru_hole circle
			(at 8.999982 -5.999988)
			(size 0.762 0.762)
			(drill 0.359918)
			(layers "*.Cu" "*.Mask")
			(remove_unused_layers no)
			(net "I2C_BMC_A_EXP_B_SCL")
			(clearance 0.1651)
			(thermal_gap 0.1651)
		)
		(pad "D7" thru_hole circle
			(at 10.80008 -4.99999)
			(size 0.762 0.762)
			(drill 0.359918)
			(layers "*.Cu" "*.Mask")
			(remove_unused_layers no)
			(net "UART_SDB_A_TX")
			(clearance 0.1651)
			(thermal_gap 0.1651)
		)
		(pad "D8" thru_hole circle
			(at 12.599924 -5.999988)
			(size 0.762 0.762)
			(drill 0.359918)
			(layers "*.Cu" "*.Mask")
			(remove_unused_layers no)
			(net "P12V_A")
			(clearance 0.1651)
			(thermal_gap 0.1651)
		)
		(pad "D9" thru_hole circle
			(at 21.599906 -4.99999)
			(size 0.762 0.762)
			(drill 0.359918)
			(layers "*.Cu" "*.Mask")
			(remove_unused_layers no)
			(net "PCIE_COMP_A_TO_IOM_A_RST_4")
			(clearance 0.1651)
			(thermal_gap 0.1651)
		)
		(pad "D10" thru_hole circle
			(at 23.400004 -5.999988)
			(size 0.762 0.762)
			(drill 0.359918)
			(layers "*.Cu" "*.Mask")
			(remove_unused_layers no)
			(net "I2C_BMC_A_COMP_A_SCL_BUF")
			(clearance 0.1651)
			(thermal_gap 0.1651)
		)
		(pad "D11" thru_hole circle
			(at 25.200102 -4.99999)
			(size 0.762 0.762)
			(drill 0.359918)
			(layers "*.Cu" "*.Mask")
			(remove_unused_layers no)
			(net "UART_COMP_A_TX")
			(clearance 0.1651)
			(thermal_gap 0.1651)
		)
		(pad "D12" thru_hole circle
			(at 26.999946 -5.999988)
			(size 0.762 0.762)
			(drill 0.359918)
			(layers "*.Cu" "*.Mask")
			(remove_unused_layers no)
			(net "SCC_B_TYPE_0")
			(clearance 0.1651)
			(thermal_gap 0.1651)
		)
		(pad "D13" thru_hole circle
			(at 28.800044 -4.99999)
			(size 0.762 0.762)
			(drill 0.359918)
			(layers "*.Cu" "*.Mask")
			(remove_unused_layers no)
			(net "COMP_A_FAST_THROTTLE_N")
			(clearance 0.1651)
			(thermal_gap 0.1651)
		)
		(pad "D14" thru_hole circle
			(at 30.599888 -5.999988)
			(size 0.762 0.762)
			(drill 0.359918)
			(layers "*.Cu" "*.Mask")
			(remove_unused_layers no)
			(net "COMP_A_PWR_BTN_N")
			(clearance 0.1651)
			(thermal_gap 0.1651)
		)
		(pad "D15" thru_hole circle
			(at 32.399986 -4.99999)
			(size 0.762 0.762)
			(drill 0.359918)
			(layers "*.Cu" "*.Mask")
			(remove_unused_layers no)
			(net "IOM_A_FAULT_LED")
			(clearance 0.1651)
			(thermal_gap 0.1651)
		)
		(pad "D16" thru_hole circle
			(at 34.200084 -5.999988)
			(size 0.762 0.762)
			(drill 0.359918)
			(layers "*.Cu" "*.Mask")
			(remove_unused_layers no)
			(net "PWM_BMC_A_ZONE_D")
			(clearance 0.1651)
			(thermal_gap 0.1651)
		)
		(pad "E1" thru_hole circle
			(at 0 -7.199884)
			(size 0.664718 0.664718)
			(drill 0.359918)
			(layers "*.Cu" "*.Mask")
			(remove_unused_layers no)
			(net "PCIE_IOM_A_TO_COMP_A_8_DN")
			(clearance 0.264414)
			(padstack
				(mode custom)
				(layer "In1.Cu"
					(shape circle)
					(size 0.664718 0.664718)
					(clearance 0.264414)
				)
				(layer "In2.Cu"
					(shape circle)
					(size 0.664718 0.664718)
					(clearance 0.264414)
				)
				(layer "In3.Cu"
					(shape circle)
					(size 0.664718 0.664718)
					(clearance 0.264414)
				)
				(layer "In4.Cu"
					(shape circle)
					(size 0.664718 0.664718)
					(clearance 0.264414)
				)
				(layer "In5.Cu"
					(shape circle)
					(size 0.664718 0.664718)
					(clearance 0.264414)
				)
				(layer "In6.Cu"
					(shape circle)
					(size 0.762 0.762)
					(clearance 0.1651)
				)
				(layer "In7.Cu"
					(shape circle)
					(size 0.762 0.762)
					(clearance 0.1651)
				)
				(layer "In8.Cu"
					(shape circle)
					(size 0.762 0.762)
					(clearance 0.1651)
				)
				(layer "In9.Cu"
					(shape circle)
					(size 0.762 0.762)
					(clearance 0.1651)
				)
				(layer "In10.Cu"
					(shape circle)
					(size 0.762 0.762)
					(clearance 0.1651)
				)
				(layer "B.Cu"
					(shape circle)
					(size 0.762 0.762)
					(thermal_gap 0.1651)
					(clearance 0.1651)
				)
			)
		)
		(pad "E2" thru_hole circle
			(at 1.800098 -8.199882)
			(size 0.664718 0.664718)
			(drill 0.359918)
			(layers "*.Cu" "*.Mask")
			(remove_unused_layers no)
			(net "PCIE_IOM_A_TO_COMP_A_9_DN")
			(clearance 0.264414)
			(padstack
				(mode custom)
				(layer "In1.Cu"
					(shape circle)
					(size 0.664718 0.664718)
					(clearance 0.264414)
				)
				(layer "In2.Cu"
					(shape circle)
					(size 0.664718 0.664718)
					(clearance 0.264414)
				)
				(layer "In3.Cu"
					(shape circle)
					(size 0.664718 0.664718)
					(clearance 0.264414)
				)
				(layer "In4.Cu"
					(shape circle)
					(size 0.664718 0.664718)
					(clearance 0.264414)
				)
				(layer "In5.Cu"
					(shape circle)
					(size 0.664718 0.664718)
					(clearance 0.264414)
				)
				(layer "In6.Cu"
					(shape circle)
					(size 0.762 0.762)
					(clearance 0.1651)
				)
				(layer "In7.Cu"
					(shape circle)
					(size 0.762 0.762)
					(clearance 0.1651)
				)
				(layer "In8.Cu"
					(shape circle)
					(size 0.762 0.762)
					(clearance 0.1651)
				)
				(layer "In9.Cu"
					(shape circle)
					(size 0.762 0.762)
					(clearance 0.1651)
				)
				(layer "In10.Cu"
					(shape circle)
					(size 0.762 0.762)
					(clearance 0.1651)
				)
				(layer "B.Cu"
					(shape circle)
					(size 0.762 0.762)
					(thermal_gap 0.1651)
					(clearance 0.1651)
				)
			)
		)
		(pad "E3" thru_hole circle
			(at 3.599942 -7.199884)
			(size 0.664718 0.664718)
			(drill 0.359918)
			(layers "*.Cu" "*.Mask")
			(remove_unused_layers no)
			(net "PCIE_IOM_A_TO_COMP_A_10_DN")
			(clearance 0.264414)
			(padstack
				(mode custom)
				(layer "In1.Cu"
					(shape circle)
					(size 0.664718 0.664718)
					(clearance 0.264414)
				)
				(layer "In2.Cu"
					(shape circle)
					(size 0.664718 0.664718)
					(clearance 0.264414)
				)
				(layer "In3.Cu"
					(shape circle)
					(size 0.664718 0.664718)
					(clearance 0.264414)
				)
				(layer "In4.Cu"
					(shape circle)
					(size 0.664718 0.664718)
					(clearance 0.264414)
				)
				(layer "In5.Cu"
					(shape circle)
					(size 0.664718 0.664718)
					(clearance 0.264414)
				)
				(layer "In6.Cu"
					(shape circle)
					(size 0.762 0.762)
					(clearance 0.1651)
				)
				(layer "In7.Cu"
					(shape circle)
					(size 0.762 0.762)
					(clearance 0.1651)
				)
				(layer "In8.Cu"
					(shape circle)
					(size 0.762 0.762)
					(clearance 0.1651)
				)
				(layer "In9.Cu"
					(shape circle)
					(size 0.762 0.762)
					(clearance 0.1651)
				)
				(layer "In10.Cu"
					(shape circle)
					(size 0.762 0.762)
					(clearance 0.1651)
				)
				(layer "B.Cu"
					(shape circle)
					(size 0.762 0.762)
					(thermal_gap 0.1651)
					(clearance 0.1651)
				)
			)
		)
		(pad "E4" thru_hole circle
			(at 5.40004 -8.199882)
			(size 0.664718 0.664718)
			(drill 0.359918)
			(layers "*.Cu" "*.Mask")
			(remove_unused_layers no)
			(net "PCIE_IOM_A_TO_COMP_A_11_DN")
			(clearance 0.264414)
			(padstack
				(mode custom)
				(layer "In1.Cu"
					(shape circle)
					(size 0.664718 0.664718)
					(clearance 0.264414)
				)
				(layer "In2.Cu"
					(shape circle)
					(size 0.664718 0.664718)
					(clearance 0.264414)
				)
				(layer "In3.Cu"
					(shape circle)
					(size 0.664718 0.664718)
					(clearance 0.264414)
				)
				(layer "In4.Cu"
					(shape circle)
					(size 0.664718 0.664718)
					(clearance 0.264414)
				)
				(layer "In5.Cu"
					(shape circle)
					(size 0.664718 0.664718)
					(clearance 0.264414)
				)
				(layer "In6.Cu"
					(shape circle)
					(size 0.762 0.762)
					(clearance 0.1651)
				)
				(layer "In7.Cu"
					(shape circle)
					(size 0.762 0.762)
					(clearance 0.1651)
				)
				(layer "In8.Cu"
					(shape circle)
					(size 0.762 0.762)
					(clearance 0.1651)
				)
				(layer "In9.Cu"
					(shape circle)
					(size 0.762 0.762)
					(clearance 0.1651)
				)
				(layer "In10.Cu"
					(shape circle)
					(size 0.762 0.762)
					(clearance 0.1651)
				)
				(layer "B.Cu"
					(shape circle)
					(size 0.762 0.762)
					(thermal_gap 0.1651)
					(clearance 0.1651)
				)
			)
		)
		(pad "E5" thru_hole circle
			(at 7.199884 -7.199884)
			(size 0.664718 0.664718)
			(drill 0.359918)
			(layers "*.Cu" "*.Mask")
			(remove_unused_layers no)
			(net "PCIE_IOM_A_TO_COMP_A_12_DN")
			(clearance 0.264414)
			(padstack
				(mode custom)
				(layer "In1.Cu"
					(shape circle)
					(size 0.664718 0.664718)
					(clearance 0.264414)
				)
				(layer "In2.Cu"
					(shape circle)
					(size 0.664718 0.664718)
					(clearance 0.264414)
				)
				(layer "In3.Cu"
					(shape circle)
					(size 0.664718 0.664718)
					(clearance 0.264414)
				)
				(layer "In4.Cu"
					(shape circle)
					(size 0.664718 0.664718)
					(clearance 0.264414)
				)
				(layer "In5.Cu"
					(shape circle)
					(size 0.664718 0.664718)
					(clearance 0.264414)
				)
				(layer "In6.Cu"
					(shape circle)
					(size 0.762 0.762)
					(clearance 0.1651)
				)
				(layer "In7.Cu"
					(shape circle)
					(size 0.762 0.762)
					(clearance 0.1651)
				)
				(layer "In8.Cu"
					(shape circle)
					(size 0.762 0.762)
					(clearance 0.1651)
				)
				(layer "In9.Cu"
					(shape circle)
					(size 0.762 0.762)
					(clearance 0.1651)
				)
				(layer "In10.Cu"
					(shape circle)
					(size 0.762 0.762)
					(clearance 0.1651)
				)
				(layer "B.Cu"
					(shape circle)
					(size 0.762 0.762)
					(thermal_gap 0.1651)
					(clearance 0.1651)
				)
			)
		)
		(pad "E6" thru_hole circle
			(at 8.999982 -8.199882)
			(size 0.664718 0.664718)
			(drill 0.359918)
			(layers "*.Cu" "*.Mask")
			(remove_unused_layers no)
			(net "PCIE_IOM_A_TO_COMP_A_13_DN")
			(clearance 0.264414)
			(padstack
				(mode custom)
				(layer "In1.Cu"
					(shape circle)
					(size 0.664718 0.664718)
					(clearance 0.264414)
				)
				(layer "In2.Cu"
					(shape circle)
					(size 0.664718 0.664718)
					(clearance 0.264414)
				)
				(layer "In3.Cu"
					(shape circle)
					(size 0.664718 0.664718)
					(clearance 0.264414)
				)
				(layer "In4.Cu"
					(shape circle)
					(size 0.664718 0.664718)
					(clearance 0.264414)
				)
				(layer "In5.Cu"
					(shape circle)
					(size 0.664718 0.664718)
					(clearance 0.264414)
				)
				(layer "In6.Cu"
					(shape circle)
					(size 0.762 0.762)
					(clearance 0.1651)
				)
				(layer "In7.Cu"
					(shape circle)
					(size 0.762 0.762)
					(clearance 0.1651)
				)
				(layer "In8.Cu"
					(shape circle)
					(size 0.762 0.762)
					(clearance 0.1651)
				)
				(layer "In9.Cu"
					(shape circle)
					(size 0.762 0.762)
					(clearance 0.1651)
				)
				(layer "In10.Cu"
					(shape circle)
					(size 0.762 0.762)
					(clearance 0.1651)
				)
				(layer "B.Cu"
					(shape circle)
					(size 0.762 0.762)
					(thermal_gap 0.1651)
					(clearance 0.1651)
				)
			)
		)
		(pad "E7" thru_hole circle
			(at 10.80008 -7.199884)
			(size 0.664718 0.664718)
			(drill 0.359918)
			(layers "*.Cu" "*.Mask")
			(remove_unused_layers no)
			(net "PCIE_IOM_A_TO_COMP_A_14_DN")
			(clearance 0.264414)
			(padstack
				(mode custom)
				(layer "In1.Cu"
					(shape circle)
					(size 0.664718 0.664718)
					(clearance 0.264414)
				)
				(layer "In2.Cu"
					(shape circle)
					(size 0.664718 0.664718)
					(clearance 0.264414)
				)
				(layer "In3.Cu"
					(shape circle)
					(size 0.664718 0.664718)
					(clearance 0.264414)
				)
				(layer "In4.Cu"
					(shape circle)
					(size 0.664718 0.664718)
					(clearance 0.264414)
				)
				(layer "In5.Cu"
					(shape circle)
					(size 0.664718 0.664718)
					(clearance 0.264414)
				)
				(layer "In6.Cu"
					(shape circle)
					(size 0.762 0.762)
					(clearance 0.1651)
				)
				(layer "In7.Cu"
					(shape circle)
					(size 0.762 0.762)
					(clearance 0.1651)
				)
				(layer "In8.Cu"
					(shape circle)
					(size 0.762 0.762)
					(clearance 0.1651)
				)
				(layer "In9.Cu"
					(shape circle)
					(size 0.762 0.762)
					(clearance 0.1651)
				)
				(layer "In10.Cu"
					(shape circle)
					(size 0.762 0.762)
					(clearance 0.1651)
				)
				(layer "B.Cu"
					(shape circle)
					(size 0.762 0.762)
					(thermal_gap 0.1651)
					(clearance 0.1651)
				)
			)
		)
		(pad "E8" thru_hole circle
			(at 12.599924 -8.199882)
			(size 0.664718 0.664718)
			(drill 0.359918)
			(layers "*.Cu" "*.Mask")
			(remove_unused_layers no)
			(net "PCIE_IOM_A_TO_COMP_A_15_DN")
			(clearance 0.264414)
			(padstack
				(mode custom)
				(layer "In1.Cu"
					(shape circle)
					(size 0.664718 0.664718)
					(clearance 0.264414)
				)
				(layer "In2.Cu"
					(shape circle)
					(size 0.664718 0.664718)
					(clearance 0.264414)
				)
				(layer "In3.Cu"
					(shape circle)
					(size 0.664718 0.664718)
					(clearance 0.264414)
				)
				(layer "In4.Cu"
					(shape circle)
					(size 0.664718 0.664718)
					(clearance 0.264414)
				)
				(layer "In5.Cu"
					(shape circle)
					(size 0.664718 0.664718)
					(clearance 0.264414)
				)
				(layer "In6.Cu"
					(shape circle)
					(size 0.762 0.762)
					(clearance 0.1651)
				)
				(layer "In7.Cu"
					(shape circle)
					(size 0.762 0.762)
					(clearance 0.1651)
				)
				(layer "In8.Cu"
					(shape circle)
					(size 0.762 0.762)
					(clearance 0.1651)
				)
				(layer "In9.Cu"
					(shape circle)
					(size 0.762 0.762)
					(clearance 0.1651)
				)
				(layer "In10.Cu"
					(shape circle)
					(size 0.762 0.762)
					(clearance 0.1651)
				)
				(layer "B.Cu"
					(shape circle)
					(size 0.762 0.762)
					(thermal_gap 0.1651)
					(clearance 0.1651)
				)
			)
		)
		(pad "E9" thru_hole circle
			(at 21.599906 -7.199884)
			(size 0.664718 0.664718)
			(drill 0.359918)
			(layers "*.Cu" "*.Mask")
			(remove_unused_layers no)
			(net "PCIE_IOM_A_TO_COMP_A_16_DN")
			(clearance 0.264414)
			(padstack
				(mode custom)
				(layer "In1.Cu"
					(shape circle)
					(size 0.664718 0.664718)
					(clearance 0.264414)
				)
				(layer "In2.Cu"
					(shape circle)
					(size 0.664718 0.664718)
					(clearance 0.264414)
				)
				(layer "In3.Cu"
					(shape circle)
					(size 0.664718 0.664718)
					(clearance 0.264414)
				)
				(layer "In4.Cu"
					(shape circle)
					(size 0.664718 0.664718)
					(clearance 0.264414)
				)
				(layer "In5.Cu"
					(shape circle)
					(size 0.664718 0.664718)
					(clearance 0.264414)
				)
				(layer "In6.Cu"
					(shape circle)
					(size 0.762 0.762)
					(clearance 0.1651)
				)
				(layer "In7.Cu"
					(shape circle)
					(size 0.762 0.762)
					(clearance 0.1651)
				)
				(layer "In8.Cu"
					(shape circle)
					(size 0.762 0.762)
					(clearance 0.1651)
				)
				(layer "In9.Cu"
					(shape circle)
					(size 0.762 0.762)
					(clearance 0.1651)
				)
				(layer "In10.Cu"
					(shape circle)
					(size 0.762 0.762)
					(clearance 0.1651)
				)
				(layer "B.Cu"
					(shape circle)
					(size 0.762 0.762)
					(thermal_gap 0.1651)
					(clearance 0.1651)
				)
			)
		)
		(pad "E10" thru_hole circle
			(at 23.400004 -8.199882)
			(size 0.664718 0.664718)
			(drill 0.359918)
			(layers "*.Cu" "*.Mask")
			(remove_unused_layers no)
			(net "PCIE_IOM_A_TO_COMP_A_17_DN")
			(clearance 0.264414)
			(padstack
				(mode custom)
				(layer "In1.Cu"
					(shape circle)
					(size 0.664718 0.664718)
					(clearance 0.264414)
				)
				(layer "In2.Cu"
					(shape circle)
					(size 0.664718 0.664718)
					(clearance 0.264414)
				)
				(layer "In3.Cu"
					(shape circle)
					(size 0.664718 0.664718)
					(clearance 0.264414)
				)
				(layer "In4.Cu"
					(shape circle)
					(size 0.664718 0.664718)
					(clearance 0.264414)
				)
				(layer "In5.Cu"
					(shape circle)
					(size 0.664718 0.664718)
					(clearance 0.264414)
				)
				(layer "In6.Cu"
					(shape circle)
					(size 0.762 0.762)
					(clearance 0.1651)
				)
				(layer "In7.Cu"
					(shape circle)
					(size 0.762 0.762)
					(clearance 0.1651)
				)
				(layer "In8.Cu"
					(shape circle)
					(size 0.762 0.762)
					(clearance 0.1651)
				)
				(layer "In9.Cu"
					(shape circle)
					(size 0.762 0.762)
					(clearance 0.1651)
				)
				(layer "In10.Cu"
					(shape circle)
					(size 0.762 0.762)
					(clearance 0.1651)
				)
				(layer "B.Cu"
					(shape circle)
					(size 0.762 0.762)
					(thermal_gap 0.1651)
					(clearance 0.1651)
				)
			)
		)
		(pad "E11" thru_hole circle
			(at 25.200102 -7.199884)
			(size 0.664718 0.664718)
			(drill 0.359918)
			(layers "*.Cu" "*.Mask")
			(remove_unused_layers no)
			(net "PCIE_IOM_A_TO_COMP_A_18_DN")
			(clearance 0.264414)
			(padstack
				(mode custom)
				(layer "In1.Cu"
					(shape circle)
					(size 0.664718 0.664718)
					(clearance 0.264414)
				)
				(layer "In2.Cu"
					(shape circle)
					(size 0.664718 0.664718)
					(clearance 0.264414)
				)
				(layer "In3.Cu"
					(shape circle)
					(size 0.664718 0.664718)
					(clearance 0.264414)
				)
				(layer "In4.Cu"
					(shape circle)
					(size 0.664718 0.664718)
					(clearance 0.264414)
				)
				(layer "In5.Cu"
					(shape circle)
					(size 0.664718 0.664718)
					(clearance 0.264414)
				)
				(layer "In6.Cu"
					(shape circle)
					(size 0.762 0.762)
					(clearance 0.1651)
				)
				(layer "In7.Cu"
					(shape circle)
					(size 0.762 0.762)
					(clearance 0.1651)
				)
				(layer "In8.Cu"
					(shape circle)
					(size 0.762 0.762)
					(clearance 0.1651)
				)
				(layer "In9.Cu"
					(shape circle)
					(size 0.762 0.762)
					(clearance 0.1651)
				)
				(layer "In10.Cu"
					(shape circle)
					(size 0.762 0.762)
					(clearance 0.1651)
				)
				(layer "B.Cu"
					(shape circle)
					(size 0.762 0.762)
					(thermal_gap 0.1651)
					(clearance 0.1651)
				)
			)
		)
		(pad "E12" thru_hole circle
			(at 26.999946 -8.199882)
			(size 0.664718 0.664718)
			(drill 0.359918)
			(layers "*.Cu" "*.Mask")
			(remove_unused_layers no)
			(net "PCIE_IOM_A_TO_COMP_A_19_DN")
			(clearance 0.264414)
			(padstack
				(mode custom)
				(layer "In1.Cu"
					(shape circle)
					(size 0.664718 0.664718)
					(clearance 0.264414)
				)
				(layer "In2.Cu"
					(shape circle)
					(size 0.664718 0.664718)
					(clearance 0.264414)
				)
				(layer "In3.Cu"
					(shape circle)
					(size 0.664718 0.664718)
					(clearance 0.264414)
				)
				(layer "In4.Cu"
					(shape circle)
					(size 0.664718 0.664718)
					(clearance 0.264414)
				)
				(layer "In5.Cu"
					(shape circle)
					(size 0.664718 0.664718)
					(clearance 0.264414)
				)
				(layer "In6.Cu"
					(shape circle)
					(size 0.762 0.762)
					(clearance 0.1651)
				)
				(layer "In7.Cu"
					(shape circle)
					(size 0.762 0.762)
					(clearance 0.1651)
				)
				(layer "In8.Cu"
					(shape circle)
					(size 0.762 0.762)
					(clearance 0.1651)
				)
				(layer "In9.Cu"
					(shape circle)
					(size 0.762 0.762)
					(clearance 0.1651)
				)
				(layer "In10.Cu"
					(shape circle)
					(size 0.762 0.762)
					(clearance 0.1651)
				)
				(layer "B.Cu"
					(shape circle)
					(size 0.762 0.762)
					(thermal_gap 0.1651)
					(clearance 0.1651)
				)
			)
		)
		(pad "E13" thru_hole circle
			(at 28.800044 -7.199884)
			(size 0.664718 0.664718)
			(drill 0.359918)
			(layers "*.Cu" "*.Mask")
			(remove_unused_layers no)
			(net "PCIE_IOM_A_TO_COMP_A_20_DN")
			(clearance 0.264414)
			(padstack
				(mode custom)
				(layer "In1.Cu"
					(shape circle)
					(size 0.664718 0.664718)
					(clearance 0.264414)
				)
				(layer "In2.Cu"
					(shape circle)
					(size 0.664718 0.664718)
					(clearance 0.264414)
				)
				(layer "In3.Cu"
					(shape circle)
					(size 0.664718 0.664718)
					(clearance 0.264414)
				)
				(layer "In4.Cu"
					(shape circle)
					(size 0.664718 0.664718)
					(clearance 0.264414)
				)
				(layer "In5.Cu"
					(shape circle)
					(size 0.664718 0.664718)
					(clearance 0.264414)
				)
				(layer "In6.Cu"
					(shape circle)
					(size 0.762 0.762)
					(clearance 0.1651)
				)
				(layer "In7.Cu"
					(shape circle)
					(size 0.762 0.762)
					(clearance 0.1651)
				)
				(layer "In8.Cu"
					(shape circle)
					(size 0.762 0.762)
					(clearance 0.1651)
				)
				(layer "In9.Cu"
					(shape circle)
					(size 0.762 0.762)
					(clearance 0.1651)
				)
				(layer "In10.Cu"
					(shape circle)
					(size 0.762 0.762)
					(clearance 0.1651)
				)
				(layer "B.Cu"
					(shape circle)
					(size 0.762 0.762)
					(thermal_gap 0.1651)
					(clearance 0.1651)
				)
			)
		)
		(pad "E14" thru_hole circle
			(at 30.599888 -8.199882)
			(size 0.664718 0.664718)
			(drill 0.359918)
			(layers "*.Cu" "*.Mask")
			(remove_unused_layers no)
			(net "PCIE_IOM_A_TO_COMP_A_21_DN")
			(clearance 0.264414)
			(padstack
				(mode custom)
				(layer "In1.Cu"
					(shape circle)
					(size 0.664718 0.664718)
					(clearance 0.264414)
				)
				(layer "In2.Cu"
					(shape circle)
					(size 0.664718 0.664718)
					(clearance 0.264414)
				)
				(layer "In3.Cu"
					(shape circle)
					(size 0.664718 0.664718)
					(clearance 0.264414)
				)
				(layer "In4.Cu"
					(shape circle)
					(size 0.664718 0.664718)
					(clearance 0.264414)
				)
				(layer "In5.Cu"
					(shape circle)
					(size 0.664718 0.664718)
					(clearance 0.264414)
				)
				(layer "In6.Cu"
					(shape circle)
					(size 0.762 0.762)
					(clearance 0.1651)
				)
				(layer "In7.Cu"
					(shape circle)
					(size 0.762 0.762)
					(clearance 0.1651)
				)
				(layer "In8.Cu"
					(shape circle)
					(size 0.762 0.762)
					(clearance 0.1651)
				)
				(layer "In9.Cu"
					(shape circle)
					(size 0.762 0.762)
					(clearance 0.1651)
				)
				(layer "In10.Cu"
					(shape circle)
					(size 0.762 0.762)
					(clearance 0.1651)
				)
				(layer "B.Cu"
					(shape circle)
					(size 0.762 0.762)
					(thermal_gap 0.1651)
					(clearance 0.1651)
				)
			)
		)
		(pad "E15" thru_hole circle
			(at 32.399986 -7.199884)
			(size 0.664718 0.664718)
			(drill 0.359918)
			(layers "*.Cu" "*.Mask")
			(remove_unused_layers no)
			(net "PCIE_IOM_A_TO_COMP_A_22_DN")
			(clearance 0.264414)
			(padstack
				(mode custom)
				(layer "In1.Cu"
					(shape circle)
					(size 0.664718 0.664718)
					(clearance 0.264414)
				)
				(layer "In2.Cu"
					(shape circle)
					(size 0.664718 0.664718)
					(clearance 0.264414)
				)
				(layer "In3.Cu"
					(shape circle)
					(size 0.664718 0.664718)
					(clearance 0.264414)
				)
				(layer "In4.Cu"
					(shape circle)
					(size 0.664718 0.664718)
					(clearance 0.264414)
				)
				(layer "In5.Cu"
					(shape circle)
					(size 0.664718 0.664718)
					(clearance 0.264414)
				)
				(layer "In6.Cu"
					(shape circle)
					(size 0.762 0.762)
					(clearance 0.1651)
				)
				(layer "In7.Cu"
					(shape circle)
					(size 0.762 0.762)
					(clearance 0.1651)
				)
				(layer "In8.Cu"
					(shape circle)
					(size 0.762 0.762)
					(clearance 0.1651)
				)
				(layer "In9.Cu"
					(shape circle)
					(size 0.762 0.762)
					(clearance 0.1651)
				)
				(layer "In10.Cu"
					(shape circle)
					(size 0.762 0.762)
					(clearance 0.1651)
				)
				(layer "B.Cu"
					(shape circle)
					(size 0.762 0.762)
					(thermal_gap 0.1651)
					(clearance 0.1651)
				)
			)
		)
		(pad "E16" thru_hole circle
			(at 34.200084 -8.199882)
			(size 0.664718 0.664718)
			(drill 0.359918)
			(layers "*.Cu" "*.Mask")
			(remove_unused_layers no)
			(net "PCIE_IOM_A_TO_COMP_A_23_DN")
			(clearance 0.264414)
			(padstack
				(mode custom)
				(layer "In1.Cu"
					(shape circle)
					(size 0.664718 0.664718)
					(clearance 0.264414)
				)
				(layer "In2.Cu"
					(shape circle)
					(size 0.664718 0.664718)
					(clearance 0.264414)
				)
				(layer "In3.Cu"
					(shape circle)
					(size 0.664718 0.664718)
					(clearance 0.264414)
				)
				(layer "In4.Cu"
					(shape circle)
					(size 0.664718 0.664718)
					(clearance 0.264414)
				)
				(layer "In5.Cu"
					(shape circle)
					(size 0.664718 0.664718)
					(clearance 0.264414)
				)
				(layer "In6.Cu"
					(shape circle)
					(size 0.762 0.762)
					(clearance 0.1651)
				)
				(layer "In7.Cu"
					(shape circle)
					(size 0.762 0.762)
					(clearance 0.1651)
				)
				(layer "In8.Cu"
					(shape circle)
					(size 0.762 0.762)
					(clearance 0.1651)
				)
				(layer "In9.Cu"
					(shape circle)
					(size 0.762 0.762)
					(clearance 0.1651)
				)
				(layer "In10.Cu"
					(shape circle)
					(size 0.762 0.762)
					(clearance 0.1651)
				)
				(layer "B.Cu"
					(shape circle)
					(size 0.762 0.762)
					(thermal_gap 0.1651)
					(clearance 0.1651)
				)
			)
		)
		(pad "F1" thru_hole circle
			(at 0 -8.599932)
			(size 0.664718 0.664718)
			(drill 0.359918)
			(layers "*.Cu" "*.Mask")
			(remove_unused_layers no)
			(net "PCIE_IOM_A_TO_COMP_A_8_DP")
			(clearance 0.264414)
			(padstack
				(mode custom)
				(layer "In1.Cu"
					(shape circle)
					(size 0.664718 0.664718)
					(clearance 0.264414)
				)
				(layer "In2.Cu"
					(shape circle)
					(size 0.664718 0.664718)
					(clearance 0.264414)
				)
				(layer "In3.Cu"
					(shape circle)
					(size 0.664718 0.664718)
					(clearance 0.264414)
				)
				(layer "In4.Cu"
					(shape circle)
					(size 0.664718 0.664718)
					(clearance 0.264414)
				)
				(layer "In5.Cu"
					(shape circle)
					(size 0.664718 0.664718)
					(clearance 0.264414)
				)
				(layer "In6.Cu"
					(shape circle)
					(size 0.762 0.762)
					(clearance 0.1651)
				)
				(layer "In7.Cu"
					(shape circle)
					(size 0.762 0.762)
					(clearance 0.1651)
				)
				(layer "In8.Cu"
					(shape circle)
					(size 0.762 0.762)
					(clearance 0.1651)
				)
				(layer "In9.Cu"
					(shape circle)
					(size 0.762 0.762)
					(clearance 0.1651)
				)
				(layer "In10.Cu"
					(shape circle)
					(size 0.762 0.762)
					(clearance 0.1651)
				)
				(layer "B.Cu"
					(shape circle)
					(size 0.762 0.762)
					(thermal_gap 0.1651)
					(clearance 0.1651)
				)
			)
		)
		(pad "F2" thru_hole circle
			(at 1.800098 -9.59993)
			(size 0.664718 0.664718)
			(drill 0.359918)
			(layers "*.Cu" "*.Mask")
			(remove_unused_layers no)
			(net "PCIE_IOM_A_TO_COMP_A_9_DP")
			(clearance 0.264414)
			(padstack
				(mode custom)
				(layer "In1.Cu"
					(shape circle)
					(size 0.664718 0.664718)
					(clearance 0.264414)
				)
				(layer "In2.Cu"
					(shape circle)
					(size 0.664718 0.664718)
					(clearance 0.264414)
				)
				(layer "In3.Cu"
					(shape circle)
					(size 0.664718 0.664718)
					(clearance 0.264414)
				)
				(layer "In4.Cu"
					(shape circle)
					(size 0.664718 0.664718)
					(clearance 0.264414)
				)
				(layer "In5.Cu"
					(shape circle)
					(size 0.664718 0.664718)
					(clearance 0.264414)
				)
				(layer "In6.Cu"
					(shape circle)
					(size 0.762 0.762)
					(clearance 0.1651)
				)
				(layer "In7.Cu"
					(shape circle)
					(size 0.762 0.762)
					(clearance 0.1651)
				)
				(layer "In8.Cu"
					(shape circle)
					(size 0.762 0.762)
					(clearance 0.1651)
				)
				(layer "In9.Cu"
					(shape circle)
					(size 0.762 0.762)
					(clearance 0.1651)
				)
				(layer "In10.Cu"
					(shape circle)
					(size 0.762 0.762)
					(clearance 0.1651)
				)
				(layer "B.Cu"
					(shape circle)
					(size 0.762 0.762)
					(thermal_gap 0.1651)
					(clearance 0.1651)
				)
			)
		)
		(pad "F3" thru_hole circle
			(at 3.599942 -8.599932)
			(size 0.664718 0.664718)
			(drill 0.359918)
			(layers "*.Cu" "*.Mask")
			(remove_unused_layers no)
			(net "PCIE_IOM_A_TO_COMP_A_10_DP")
			(clearance 0.264414)
			(padstack
				(mode custom)
				(layer "In1.Cu"
					(shape circle)
					(size 0.664718 0.664718)
					(clearance 0.264414)
				)
				(layer "In2.Cu"
					(shape circle)
					(size 0.664718 0.664718)
					(clearance 0.264414)
				)
				(layer "In3.Cu"
					(shape circle)
					(size 0.664718 0.664718)
					(clearance 0.264414)
				)
				(layer "In4.Cu"
					(shape circle)
					(size 0.664718 0.664718)
					(clearance 0.264414)
				)
				(layer "In5.Cu"
					(shape circle)
					(size 0.664718 0.664718)
					(clearance 0.264414)
				)
				(layer "In6.Cu"
					(shape circle)
					(size 0.762 0.762)
					(clearance 0.1651)
				)
				(layer "In7.Cu"
					(shape circle)
					(size 0.762 0.762)
					(clearance 0.1651)
				)
				(layer "In8.Cu"
					(shape circle)
					(size 0.762 0.762)
					(clearance 0.1651)
				)
				(layer "In9.Cu"
					(shape circle)
					(size 0.762 0.762)
					(clearance 0.1651)
				)
				(layer "In10.Cu"
					(shape circle)
					(size 0.762 0.762)
					(clearance 0.1651)
				)
				(layer "B.Cu"
					(shape circle)
					(size 0.762 0.762)
					(thermal_gap 0.1651)
					(clearance 0.1651)
				)
			)
		)
		(pad "F4" thru_hole circle
			(at 5.40004 -9.59993)
			(size 0.664718 0.664718)
			(drill 0.359918)
			(layers "*.Cu" "*.Mask")
			(remove_unused_layers no)
			(net "PCIE_IOM_A_TO_COMP_A_11_DP")
			(clearance 0.264414)
			(padstack
				(mode custom)
				(layer "In1.Cu"
					(shape circle)
					(size 0.664718 0.664718)
					(clearance 0.264414)
				)
				(layer "In2.Cu"
					(shape circle)
					(size 0.664718 0.664718)
					(clearance 0.264414)
				)
				(layer "In3.Cu"
					(shape circle)
					(size 0.664718 0.664718)
					(clearance 0.264414)
				)
				(layer "In4.Cu"
					(shape circle)
					(size 0.664718 0.664718)
					(clearance 0.264414)
				)
				(layer "In5.Cu"
					(shape circle)
					(size 0.664718 0.664718)
					(clearance 0.264414)
				)
				(layer "In6.Cu"
					(shape circle)
					(size 0.762 0.762)
					(clearance 0.1651)
				)
				(layer "In7.Cu"
					(shape circle)
					(size 0.762 0.762)
					(clearance 0.1651)
				)
				(layer "In8.Cu"
					(shape circle)
					(size 0.762 0.762)
					(clearance 0.1651)
				)
				(layer "In9.Cu"
					(shape circle)
					(size 0.762 0.762)
					(clearance 0.1651)
				)
				(layer "In10.Cu"
					(shape circle)
					(size 0.762 0.762)
					(clearance 0.1651)
				)
				(layer "B.Cu"
					(shape circle)
					(size 0.762 0.762)
					(thermal_gap 0.1651)
					(clearance 0.1651)
				)
			)
		)
		(pad "F5" thru_hole circle
			(at 7.199884 -8.599932)
			(size 0.664718 0.664718)
			(drill 0.359918)
			(layers "*.Cu" "*.Mask")
			(remove_unused_layers no)
			(net "PCIE_IOM_A_TO_COMP_A_12_DP")
			(clearance 0.264414)
			(padstack
				(mode custom)
				(layer "In1.Cu"
					(shape circle)
					(size 0.664718 0.664718)
					(clearance 0.264414)
				)
				(layer "In2.Cu"
					(shape circle)
					(size 0.664718 0.664718)
					(clearance 0.264414)
				)
				(layer "In3.Cu"
					(shape circle)
					(size 0.664718 0.664718)
					(clearance 0.264414)
				)
				(layer "In4.Cu"
					(shape circle)
					(size 0.664718 0.664718)
					(clearance 0.264414)
				)
				(layer "In5.Cu"
					(shape circle)
					(size 0.664718 0.664718)
					(clearance 0.264414)
				)
				(layer "In6.Cu"
					(shape circle)
					(size 0.762 0.762)
					(clearance 0.1651)
				)
				(layer "In7.Cu"
					(shape circle)
					(size 0.762 0.762)
					(clearance 0.1651)
				)
				(layer "In8.Cu"
					(shape circle)
					(size 0.762 0.762)
					(clearance 0.1651)
				)
				(layer "In9.Cu"
					(shape circle)
					(size 0.762 0.762)
					(clearance 0.1651)
				)
				(layer "In10.Cu"
					(shape circle)
					(size 0.762 0.762)
					(clearance 0.1651)
				)
				(layer "B.Cu"
					(shape circle)
					(size 0.762 0.762)
					(thermal_gap 0.1651)
					(clearance 0.1651)
				)
			)
		)
		(pad "F6" thru_hole circle
			(at 8.999982 -9.59993)
			(size 0.664718 0.664718)
			(drill 0.359918)
			(layers "*.Cu" "*.Mask")
			(remove_unused_layers no)
			(net "PCIE_IOM_A_TO_COMP_A_13_DP")
			(clearance 0.264414)
			(padstack
				(mode custom)
				(layer "In1.Cu"
					(shape circle)
					(size 0.664718 0.664718)
					(clearance 0.264414)
				)
				(layer "In2.Cu"
					(shape circle)
					(size 0.664718 0.664718)
					(clearance 0.264414)
				)
				(layer "In3.Cu"
					(shape circle)
					(size 0.664718 0.664718)
					(clearance 0.264414)
				)
				(layer "In4.Cu"
					(shape circle)
					(size 0.664718 0.664718)
					(clearance 0.264414)
				)
				(layer "In5.Cu"
					(shape circle)
					(size 0.664718 0.664718)
					(clearance 0.264414)
				)
				(layer "In6.Cu"
					(shape circle)
					(size 0.762 0.762)
					(clearance 0.1651)
				)
				(layer "In7.Cu"
					(shape circle)
					(size 0.762 0.762)
					(clearance 0.1651)
				)
				(layer "In8.Cu"
					(shape circle)
					(size 0.762 0.762)
					(clearance 0.1651)
				)
				(layer "In9.Cu"
					(shape circle)
					(size 0.762 0.762)
					(clearance 0.1651)
				)
				(layer "In10.Cu"
					(shape circle)
					(size 0.762 0.762)
					(clearance 0.1651)
				)
				(layer "B.Cu"
					(shape circle)
					(size 0.762 0.762)
					(thermal_gap 0.1651)
					(clearance 0.1651)
				)
			)
		)
		(pad "F7" thru_hole circle
			(at 10.80008 -8.599932)
			(size 0.664718 0.664718)
			(drill 0.359918)
			(layers "*.Cu" "*.Mask")
			(remove_unused_layers no)
			(net "PCIE_IOM_A_TO_COMP_A_14_DP")
			(clearance 0.264414)
			(padstack
				(mode custom)
				(layer "In1.Cu"
					(shape circle)
					(size 0.664718 0.664718)
					(clearance 0.264414)
				)
				(layer "In2.Cu"
					(shape circle)
					(size 0.664718 0.664718)
					(clearance 0.264414)
				)
				(layer "In3.Cu"
					(shape circle)
					(size 0.664718 0.664718)
					(clearance 0.264414)
				)
				(layer "In4.Cu"
					(shape circle)
					(size 0.664718 0.664718)
					(clearance 0.264414)
				)
				(layer "In5.Cu"
					(shape circle)
					(size 0.664718 0.664718)
					(clearance 0.264414)
				)
				(layer "In6.Cu"
					(shape circle)
					(size 0.762 0.762)
					(clearance 0.1651)
				)
				(layer "In7.Cu"
					(shape circle)
					(size 0.762 0.762)
					(clearance 0.1651)
				)
				(layer "In8.Cu"
					(shape circle)
					(size 0.762 0.762)
					(clearance 0.1651)
				)
				(layer "In9.Cu"
					(shape circle)
					(size 0.762 0.762)
					(clearance 0.1651)
				)
				(layer "In10.Cu"
					(shape circle)
					(size 0.762 0.762)
					(clearance 0.1651)
				)
				(layer "B.Cu"
					(shape circle)
					(size 0.762 0.762)
					(thermal_gap 0.1651)
					(clearance 0.1651)
				)
			)
		)
		(pad "F8" thru_hole circle
			(at 12.599924 -9.59993)
			(size 0.664718 0.664718)
			(drill 0.359918)
			(layers "*.Cu" "*.Mask")
			(remove_unused_layers no)
			(net "PCIE_IOM_A_TO_COMP_A_15_DP")
			(clearance 0.264414)
			(padstack
				(mode custom)
				(layer "In1.Cu"
					(shape circle)
					(size 0.664718 0.664718)
					(clearance 0.264414)
				)
				(layer "In2.Cu"
					(shape circle)
					(size 0.664718 0.664718)
					(clearance 0.264414)
				)
				(layer "In3.Cu"
					(shape circle)
					(size 0.664718 0.664718)
					(clearance 0.264414)
				)
				(layer "In4.Cu"
					(shape circle)
					(size 0.664718 0.664718)
					(clearance 0.264414)
				)
				(layer "In5.Cu"
					(shape circle)
					(size 0.664718 0.664718)
					(clearance 0.264414)
				)
				(layer "In6.Cu"
					(shape circle)
					(size 0.762 0.762)
					(clearance 0.1651)
				)
				(layer "In7.Cu"
					(shape circle)
					(size 0.762 0.762)
					(clearance 0.1651)
				)
				(layer "In8.Cu"
					(shape circle)
					(size 0.762 0.762)
					(clearance 0.1651)
				)
				(layer "In9.Cu"
					(shape circle)
					(size 0.762 0.762)
					(clearance 0.1651)
				)
				(layer "In10.Cu"
					(shape circle)
					(size 0.762 0.762)
					(clearance 0.1651)
				)
				(layer "B.Cu"
					(shape circle)
					(size 0.762 0.762)
					(thermal_gap 0.1651)
					(clearance 0.1651)
				)
			)
		)
		(pad "F9" thru_hole circle
			(at 21.599906 -8.599932)
			(size 0.664718 0.664718)
			(drill 0.359918)
			(layers "*.Cu" "*.Mask")
			(remove_unused_layers no)
			(net "PCIE_IOM_A_TO_COMP_A_16_DP")
			(clearance 0.264414)
			(padstack
				(mode custom)
				(layer "In1.Cu"
					(shape circle)
					(size 0.664718 0.664718)
					(clearance 0.264414)
				)
				(layer "In2.Cu"
					(shape circle)
					(size 0.664718 0.664718)
					(clearance 0.264414)
				)
				(layer "In3.Cu"
					(shape circle)
					(size 0.664718 0.664718)
					(clearance 0.264414)
				)
				(layer "In4.Cu"
					(shape circle)
					(size 0.664718 0.664718)
					(clearance 0.264414)
				)
				(layer "In5.Cu"
					(shape circle)
					(size 0.664718 0.664718)
					(clearance 0.264414)
				)
				(layer "In6.Cu"
					(shape circle)
					(size 0.762 0.762)
					(clearance 0.1651)
				)
				(layer "In7.Cu"
					(shape circle)
					(size 0.762 0.762)
					(clearance 0.1651)
				)
				(layer "In8.Cu"
					(shape circle)
					(size 0.762 0.762)
					(clearance 0.1651)
				)
				(layer "In9.Cu"
					(shape circle)
					(size 0.762 0.762)
					(clearance 0.1651)
				)
				(layer "In10.Cu"
					(shape circle)
					(size 0.762 0.762)
					(clearance 0.1651)
				)
				(layer "B.Cu"
					(shape circle)
					(size 0.762 0.762)
					(thermal_gap 0.1651)
					(clearance 0.1651)
				)
			)
		)
		(pad "F10" thru_hole circle
			(at 23.400004 -9.59993)
			(size 0.664718 0.664718)
			(drill 0.359918)
			(layers "*.Cu" "*.Mask")
			(remove_unused_layers no)
			(net "PCIE_IOM_A_TO_COMP_A_17_DP")
			(clearance 0.264414)
			(padstack
				(mode custom)
				(layer "In1.Cu"
					(shape circle)
					(size 0.664718 0.664718)
					(clearance 0.264414)
				)
				(layer "In2.Cu"
					(shape circle)
					(size 0.664718 0.664718)
					(clearance 0.264414)
				)
				(layer "In3.Cu"
					(shape circle)
					(size 0.664718 0.664718)
					(clearance 0.264414)
				)
				(layer "In4.Cu"
					(shape circle)
					(size 0.664718 0.664718)
					(clearance 0.264414)
				)
				(layer "In5.Cu"
					(shape circle)
					(size 0.664718 0.664718)
					(clearance 0.264414)
				)
				(layer "In6.Cu"
					(shape circle)
					(size 0.762 0.762)
					(clearance 0.1651)
				)
				(layer "In7.Cu"
					(shape circle)
					(size 0.762 0.762)
					(clearance 0.1651)
				)
				(layer "In8.Cu"
					(shape circle)
					(size 0.762 0.762)
					(clearance 0.1651)
				)
				(layer "In9.Cu"
					(shape circle)
					(size 0.762 0.762)
					(clearance 0.1651)
				)
				(layer "In10.Cu"
					(shape circle)
					(size 0.762 0.762)
					(clearance 0.1651)
				)
				(layer "B.Cu"
					(shape circle)
					(size 0.762 0.762)
					(thermal_gap 0.1651)
					(clearance 0.1651)
				)
			)
		)
		(pad "F11" thru_hole circle
			(at 25.200102 -8.599932)
			(size 0.664718 0.664718)
			(drill 0.359918)
			(layers "*.Cu" "*.Mask")
			(remove_unused_layers no)
			(net "PCIE_IOM_A_TO_COMP_A_18_DP")
			(clearance 0.264414)
			(padstack
				(mode custom)
				(layer "In1.Cu"
					(shape circle)
					(size 0.664718 0.664718)
					(clearance 0.264414)
				)
				(layer "In2.Cu"
					(shape circle)
					(size 0.664718 0.664718)
					(clearance 0.264414)
				)
				(layer "In3.Cu"
					(shape circle)
					(size 0.664718 0.664718)
					(clearance 0.264414)
				)
				(layer "In4.Cu"
					(shape circle)
					(size 0.664718 0.664718)
					(clearance 0.264414)
				)
				(layer "In5.Cu"
					(shape circle)
					(size 0.664718 0.664718)
					(clearance 0.264414)
				)
				(layer "In6.Cu"
					(shape circle)
					(size 0.762 0.762)
					(clearance 0.1651)
				)
				(layer "In7.Cu"
					(shape circle)
					(size 0.762 0.762)
					(clearance 0.1651)
				)
				(layer "In8.Cu"
					(shape circle)
					(size 0.762 0.762)
					(clearance 0.1651)
				)
				(layer "In9.Cu"
					(shape circle)
					(size 0.762 0.762)
					(clearance 0.1651)
				)
				(layer "In10.Cu"
					(shape circle)
					(size 0.762 0.762)
					(clearance 0.1651)
				)
				(layer "B.Cu"
					(shape circle)
					(size 0.762 0.762)
					(thermal_gap 0.1651)
					(clearance 0.1651)
				)
			)
		)
		(pad "F12" thru_hole circle
			(at 26.999946 -9.59993)
			(size 0.664718 0.664718)
			(drill 0.359918)
			(layers "*.Cu" "*.Mask")
			(remove_unused_layers no)
			(net "PCIE_IOM_A_TO_COMP_A_19_DP")
			(clearance 0.264414)
			(padstack
				(mode custom)
				(layer "In1.Cu"
					(shape circle)
					(size 0.664718 0.664718)
					(clearance 0.264414)
				)
				(layer "In2.Cu"
					(shape circle)
					(size 0.664718 0.664718)
					(clearance 0.264414)
				)
				(layer "In3.Cu"
					(shape circle)
					(size 0.664718 0.664718)
					(clearance 0.264414)
				)
				(layer "In4.Cu"
					(shape circle)
					(size 0.664718 0.664718)
					(clearance 0.264414)
				)
				(layer "In5.Cu"
					(shape circle)
					(size 0.664718 0.664718)
					(clearance 0.264414)
				)
				(layer "In6.Cu"
					(shape circle)
					(size 0.762 0.762)
					(clearance 0.1651)
				)
				(layer "In7.Cu"
					(shape circle)
					(size 0.762 0.762)
					(clearance 0.1651)
				)
				(layer "In8.Cu"
					(shape circle)
					(size 0.762 0.762)
					(clearance 0.1651)
				)
				(layer "In9.Cu"
					(shape circle)
					(size 0.762 0.762)
					(clearance 0.1651)
				)
				(layer "In10.Cu"
					(shape circle)
					(size 0.762 0.762)
					(clearance 0.1651)
				)
				(layer "B.Cu"
					(shape circle)
					(size 0.762 0.762)
					(thermal_gap 0.1651)
					(clearance 0.1651)
				)
			)
		)
		(pad "F13" thru_hole circle
			(at 28.800044 -8.599932)
			(size 0.664718 0.664718)
			(drill 0.359918)
			(layers "*.Cu" "*.Mask")
			(remove_unused_layers no)
			(net "PCIE_IOM_A_TO_COMP_A_20_DP")
			(clearance 0.264414)
			(padstack
				(mode custom)
				(layer "In1.Cu"
					(shape circle)
					(size 0.664718 0.664718)
					(clearance 0.264414)
				)
				(layer "In2.Cu"
					(shape circle)
					(size 0.664718 0.664718)
					(clearance 0.264414)
				)
				(layer "In3.Cu"
					(shape circle)
					(size 0.664718 0.664718)
					(clearance 0.264414)
				)
				(layer "In4.Cu"
					(shape circle)
					(size 0.664718 0.664718)
					(clearance 0.264414)
				)
				(layer "In5.Cu"
					(shape circle)
					(size 0.664718 0.664718)
					(clearance 0.264414)
				)
				(layer "In6.Cu"
					(shape circle)
					(size 0.762 0.762)
					(clearance 0.1651)
				)
				(layer "In7.Cu"
					(shape circle)
					(size 0.762 0.762)
					(clearance 0.1651)
				)
				(layer "In8.Cu"
					(shape circle)
					(size 0.762 0.762)
					(clearance 0.1651)
				)
				(layer "In9.Cu"
					(shape circle)
					(size 0.762 0.762)
					(clearance 0.1651)
				)
				(layer "In10.Cu"
					(shape circle)
					(size 0.762 0.762)
					(clearance 0.1651)
				)
				(layer "B.Cu"
					(shape circle)
					(size 0.762 0.762)
					(thermal_gap 0.1651)
					(clearance 0.1651)
				)
			)
		)
		(pad "F14" thru_hole circle
			(at 30.599888 -9.59993)
			(size 0.664718 0.664718)
			(drill 0.359918)
			(layers "*.Cu" "*.Mask")
			(remove_unused_layers no)
			(net "PCIE_IOM_A_TO_COMP_A_21_DP")
			(clearance 0.264414)
			(padstack
				(mode custom)
				(layer "In1.Cu"
					(shape circle)
					(size 0.664718 0.664718)
					(clearance 0.264414)
				)
				(layer "In2.Cu"
					(shape circle)
					(size 0.664718 0.664718)
					(clearance 0.264414)
				)
				(layer "In3.Cu"
					(shape circle)
					(size 0.664718 0.664718)
					(clearance 0.264414)
				)
				(layer "In4.Cu"
					(shape circle)
					(size 0.664718 0.664718)
					(clearance 0.264414)
				)
				(layer "In5.Cu"
					(shape circle)
					(size 0.664718 0.664718)
					(clearance 0.264414)
				)
				(layer "In6.Cu"
					(shape circle)
					(size 0.762 0.762)
					(clearance 0.1651)
				)
				(layer "In7.Cu"
					(shape circle)
					(size 0.762 0.762)
					(clearance 0.1651)
				)
				(layer "In8.Cu"
					(shape circle)
					(size 0.762 0.762)
					(clearance 0.1651)
				)
				(layer "In9.Cu"
					(shape circle)
					(size 0.762 0.762)
					(clearance 0.1651)
				)
				(layer "In10.Cu"
					(shape circle)
					(size 0.762 0.762)
					(clearance 0.1651)
				)
				(layer "B.Cu"
					(shape circle)
					(size 0.762 0.762)
					(thermal_gap 0.1651)
					(clearance 0.1651)
				)
			)
		)
		(pad "F15" thru_hole circle
			(at 32.399986 -8.599932)
			(size 0.664718 0.664718)
			(drill 0.359918)
			(layers "*.Cu" "*.Mask")
			(remove_unused_layers no)
			(net "PCIE_IOM_A_TO_COMP_A_22_DP")
			(clearance 0.264414)
			(padstack
				(mode custom)
				(layer "In1.Cu"
					(shape circle)
					(size 0.664718 0.664718)
					(clearance 0.264414)
				)
				(layer "In2.Cu"
					(shape circle)
					(size 0.664718 0.664718)
					(clearance 0.264414)
				)
				(layer "In3.Cu"
					(shape circle)
					(size 0.664718 0.664718)
					(clearance 0.264414)
				)
				(layer "In4.Cu"
					(shape circle)
					(size 0.664718 0.664718)
					(clearance 0.264414)
				)
				(layer "In5.Cu"
					(shape circle)
					(size 0.664718 0.664718)
					(clearance 0.264414)
				)
				(layer "In6.Cu"
					(shape circle)
					(size 0.762 0.762)
					(clearance 0.1651)
				)
				(layer "In7.Cu"
					(shape circle)
					(size 0.762 0.762)
					(clearance 0.1651)
				)
				(layer "In8.Cu"
					(shape circle)
					(size 0.762 0.762)
					(clearance 0.1651)
				)
				(layer "In9.Cu"
					(shape circle)
					(size 0.762 0.762)
					(clearance 0.1651)
				)
				(layer "In10.Cu"
					(shape circle)
					(size 0.762 0.762)
					(clearance 0.1651)
				)
				(layer "B.Cu"
					(shape circle)
					(size 0.762 0.762)
					(thermal_gap 0.1651)
					(clearance 0.1651)
				)
			)
		)
		(pad "F16" thru_hole circle
			(at 34.200084 -9.59993)
			(size 0.664718 0.664718)
			(drill 0.359918)
			(layers "*.Cu" "*.Mask")
			(remove_unused_layers no)
			(net "PCIE_IOM_A_TO_COMP_A_23_DP")
			(clearance 0.264414)
			(padstack
				(mode custom)
				(layer "In1.Cu"
					(shape circle)
					(size 0.664718 0.664718)
					(clearance 0.264414)
				)
				(layer "In2.Cu"
					(shape circle)
					(size 0.664718 0.664718)
					(clearance 0.264414)
				)
				(layer "In3.Cu"
					(shape circle)
					(size 0.664718 0.664718)
					(clearance 0.264414)
				)
				(layer "In4.Cu"
					(shape circle)
					(size 0.664718 0.664718)
					(clearance 0.264414)
				)
				(layer "In5.Cu"
					(shape circle)
					(size 0.664718 0.664718)
					(clearance 0.264414)
				)
				(layer "In6.Cu"
					(shape circle)
					(size 0.762 0.762)
					(clearance 0.1651)
				)
				(layer "In7.Cu"
					(shape circle)
					(size 0.762 0.762)
					(clearance 0.1651)
				)
				(layer "In8.Cu"
					(shape circle)
					(size 0.762 0.762)
					(clearance 0.1651)
				)
				(layer "In9.Cu"
					(shape circle)
					(size 0.762 0.762)
					(clearance 0.1651)
				)
				(layer "In10.Cu"
					(shape circle)
					(size 0.762 0.762)
					(clearance 0.1651)
				)
				(layer "B.Cu"
					(shape circle)
					(size 0.762 0.762)
					(thermal_gap 0.1651)
					(clearance 0.1651)
				)
			)
		)
		(pad "G1" thru_hole circle
			(at 0 -10.80008)
			(size 0.664718 0.664718)
			(drill 0.359918)
			(layers "*.Cu" "*.Mask")
			(remove_unused_layers no)
			(net "PCIE_COMP_A_TO_IOM_A_8_DN")
			(clearance 0.264414)
			(padstack
				(mode custom)
				(layer "In1.Cu"
					(shape circle)
					(size 0.664718 0.664718)
					(clearance 0.264414)
				)
				(layer "In2.Cu"
					(shape circle)
					(size 0.664718 0.664718)
					(clearance 0.264414)
				)
				(layer "In3.Cu"
					(shape circle)
					(size 0.664718 0.664718)
					(clearance 0.264414)
				)
				(layer "In4.Cu"
					(shape circle)
					(size 0.664718 0.664718)
					(clearance 0.264414)
				)
				(layer "In5.Cu"
					(shape circle)
					(size 0.664718 0.664718)
					(clearance 0.264414)
				)
				(layer "In6.Cu"
					(shape circle)
					(size 0.762 0.762)
					(clearance 0.1651)
				)
				(layer "In7.Cu"
					(shape circle)
					(size 0.762 0.762)
					(clearance 0.1651)
				)
				(layer "In8.Cu"
					(shape circle)
					(size 0.762 0.762)
					(clearance 0.1651)
				)
				(layer "In9.Cu"
					(shape circle)
					(size 0.762 0.762)
					(clearance 0.1651)
				)
				(layer "In10.Cu"
					(shape circle)
					(size 0.762 0.762)
					(clearance 0.1651)
				)
				(layer "B.Cu"
					(shape circle)
					(size 0.762 0.762)
					(thermal_gap 0.1651)
					(clearance 0.1651)
				)
			)
		)
		(pad "G2" thru_hole circle
			(at 1.800098 -11.800078)
			(size 0.664718 0.664718)
			(drill 0.359918)
			(layers "*.Cu" "*.Mask")
			(remove_unused_layers no)
			(net "PCIE_COMP_A_TO_IOM_A_9_DN")
			(clearance 0.264414)
			(padstack
				(mode custom)
				(layer "In1.Cu"
					(shape circle)
					(size 0.664718 0.664718)
					(clearance 0.264414)
				)
				(layer "In2.Cu"
					(shape circle)
					(size 0.664718 0.664718)
					(clearance 0.264414)
				)
				(layer "In3.Cu"
					(shape circle)
					(size 0.664718 0.664718)
					(clearance 0.264414)
				)
				(layer "In4.Cu"
					(shape circle)
					(size 0.664718 0.664718)
					(clearance 0.264414)
				)
				(layer "In5.Cu"
					(shape circle)
					(size 0.664718 0.664718)
					(clearance 0.264414)
				)
				(layer "In6.Cu"
					(shape circle)
					(size 0.762 0.762)
					(clearance 0.1651)
				)
				(layer "In7.Cu"
					(shape circle)
					(size 0.762 0.762)
					(clearance 0.1651)
				)
				(layer "In8.Cu"
					(shape circle)
					(size 0.762 0.762)
					(clearance 0.1651)
				)
				(layer "In9.Cu"
					(shape circle)
					(size 0.762 0.762)
					(clearance 0.1651)
				)
				(layer "In10.Cu"
					(shape circle)
					(size 0.762 0.762)
					(clearance 0.1651)
				)
				(layer "B.Cu"
					(shape circle)
					(size 0.762 0.762)
					(thermal_gap 0.1651)
					(clearance 0.1651)
				)
			)
		)
		(pad "G3" thru_hole circle
			(at 3.599942 -10.80008)
			(size 0.664718 0.664718)
			(drill 0.359918)
			(layers "*.Cu" "*.Mask")
			(remove_unused_layers no)
			(net "PCIE_COMP_A_TO_IOM_A_10_DN")
			(clearance 0.264414)
			(padstack
				(mode custom)
				(layer "In1.Cu"
					(shape circle)
					(size 0.664718 0.664718)
					(clearance 0.264414)
				)
				(layer "In2.Cu"
					(shape circle)
					(size 0.664718 0.664718)
					(clearance 0.264414)
				)
				(layer "In3.Cu"
					(shape circle)
					(size 0.664718 0.664718)
					(clearance 0.264414)
				)
				(layer "In4.Cu"
					(shape circle)
					(size 0.664718 0.664718)
					(clearance 0.264414)
				)
				(layer "In5.Cu"
					(shape circle)
					(size 0.664718 0.664718)
					(clearance 0.264414)
				)
				(layer "In6.Cu"
					(shape circle)
					(size 0.762 0.762)
					(clearance 0.1651)
				)
				(layer "In7.Cu"
					(shape circle)
					(size 0.762 0.762)
					(clearance 0.1651)
				)
				(layer "In8.Cu"
					(shape circle)
					(size 0.762 0.762)
					(clearance 0.1651)
				)
				(layer "In9.Cu"
					(shape circle)
					(size 0.762 0.762)
					(clearance 0.1651)
				)
				(layer "In10.Cu"
					(shape circle)
					(size 0.762 0.762)
					(clearance 0.1651)
				)
				(layer "B.Cu"
					(shape circle)
					(size 0.762 0.762)
					(thermal_gap 0.1651)
					(clearance 0.1651)
				)
			)
		)
		(pad "G4" thru_hole circle
			(at 5.40004 -11.800078)
			(size 0.664718 0.664718)
			(drill 0.359918)
			(layers "*.Cu" "*.Mask")
			(remove_unused_layers no)
			(net "PCIE_COMP_A_TO_IOM_A_11_DN")
			(clearance 0.264414)
			(padstack
				(mode custom)
				(layer "In1.Cu"
					(shape circle)
					(size 0.664718 0.664718)
					(clearance 0.264414)
				)
				(layer "In2.Cu"
					(shape circle)
					(size 0.664718 0.664718)
					(clearance 0.264414)
				)
				(layer "In3.Cu"
					(shape circle)
					(size 0.664718 0.664718)
					(clearance 0.264414)
				)
				(layer "In4.Cu"
					(shape circle)
					(size 0.664718 0.664718)
					(clearance 0.264414)
				)
				(layer "In5.Cu"
					(shape circle)
					(size 0.664718 0.664718)
					(clearance 0.264414)
				)
				(layer "In6.Cu"
					(shape circle)
					(size 0.762 0.762)
					(clearance 0.1651)
				)
				(layer "In7.Cu"
					(shape circle)
					(size 0.762 0.762)
					(clearance 0.1651)
				)
				(layer "In8.Cu"
					(shape circle)
					(size 0.762 0.762)
					(clearance 0.1651)
				)
				(layer "In9.Cu"
					(shape circle)
					(size 0.762 0.762)
					(clearance 0.1651)
				)
				(layer "In10.Cu"
					(shape circle)
					(size 0.762 0.762)
					(clearance 0.1651)
				)
				(layer "B.Cu"
					(shape circle)
					(size 0.762 0.762)
					(thermal_gap 0.1651)
					(clearance 0.1651)
				)
			)
		)
		(pad "G5" thru_hole circle
			(at 7.199884 -10.80008)
			(size 0.664718 0.664718)
			(drill 0.359918)
			(layers "*.Cu" "*.Mask")
			(remove_unused_layers no)
			(net "PCIE_COMP_A_TO_IOM_A_12_DN")
			(clearance 0.264414)
			(padstack
				(mode custom)
				(layer "In1.Cu"
					(shape circle)
					(size 0.664718 0.664718)
					(clearance 0.264414)
				)
				(layer "In2.Cu"
					(shape circle)
					(size 0.664718 0.664718)
					(clearance 0.264414)
				)
				(layer "In3.Cu"
					(shape circle)
					(size 0.664718 0.664718)
					(clearance 0.264414)
				)
				(layer "In4.Cu"
					(shape circle)
					(size 0.664718 0.664718)
					(clearance 0.264414)
				)
				(layer "In5.Cu"
					(shape circle)
					(size 0.664718 0.664718)
					(clearance 0.264414)
				)
				(layer "In6.Cu"
					(shape circle)
					(size 0.762 0.762)
					(clearance 0.1651)
				)
				(layer "In7.Cu"
					(shape circle)
					(size 0.762 0.762)
					(clearance 0.1651)
				)
				(layer "In8.Cu"
					(shape circle)
					(size 0.762 0.762)
					(clearance 0.1651)
				)
				(layer "In9.Cu"
					(shape circle)
					(size 0.762 0.762)
					(clearance 0.1651)
				)
				(layer "In10.Cu"
					(shape circle)
					(size 0.762 0.762)
					(clearance 0.1651)
				)
				(layer "B.Cu"
					(shape circle)
					(size 0.762 0.762)
					(thermal_gap 0.1651)
					(clearance 0.1651)
				)
			)
		)
		(pad "G6" thru_hole circle
			(at 8.999982 -11.800078)
			(size 0.664718 0.664718)
			(drill 0.359918)
			(layers "*.Cu" "*.Mask")
			(remove_unused_layers no)
			(net "PCIE_COMP_A_TO_IOM_A_13_DN")
			(clearance 0.264414)
			(padstack
				(mode custom)
				(layer "In1.Cu"
					(shape circle)
					(size 0.664718 0.664718)
					(clearance 0.264414)
				)
				(layer "In2.Cu"
					(shape circle)
					(size 0.664718 0.664718)
					(clearance 0.264414)
				)
				(layer "In3.Cu"
					(shape circle)
					(size 0.664718 0.664718)
					(clearance 0.264414)
				)
				(layer "In4.Cu"
					(shape circle)
					(size 0.664718 0.664718)
					(clearance 0.264414)
				)
				(layer "In5.Cu"
					(shape circle)
					(size 0.664718 0.664718)
					(clearance 0.264414)
				)
				(layer "In6.Cu"
					(shape circle)
					(size 0.762 0.762)
					(clearance 0.1651)
				)
				(layer "In7.Cu"
					(shape circle)
					(size 0.762 0.762)
					(clearance 0.1651)
				)
				(layer "In8.Cu"
					(shape circle)
					(size 0.762 0.762)
					(clearance 0.1651)
				)
				(layer "In9.Cu"
					(shape circle)
					(size 0.762 0.762)
					(clearance 0.1651)
				)
				(layer "In10.Cu"
					(shape circle)
					(size 0.762 0.762)
					(clearance 0.1651)
				)
				(layer "B.Cu"
					(shape circle)
					(size 0.762 0.762)
					(thermal_gap 0.1651)
					(clearance 0.1651)
				)
			)
		)
		(pad "G7" thru_hole circle
			(at 10.80008 -10.80008)
			(size 0.664718 0.664718)
			(drill 0.359918)
			(layers "*.Cu" "*.Mask")
			(remove_unused_layers no)
			(net "PCIE_COMP_A_TO_IOM_A_14_DN")
			(clearance 0.264414)
			(padstack
				(mode custom)
				(layer "In1.Cu"
					(shape circle)
					(size 0.664718 0.664718)
					(clearance 0.264414)
				)
				(layer "In2.Cu"
					(shape circle)
					(size 0.664718 0.664718)
					(clearance 0.264414)
				)
				(layer "In3.Cu"
					(shape circle)
					(size 0.664718 0.664718)
					(clearance 0.264414)
				)
				(layer "In4.Cu"
					(shape circle)
					(size 0.664718 0.664718)
					(clearance 0.264414)
				)
				(layer "In5.Cu"
					(shape circle)
					(size 0.664718 0.664718)
					(clearance 0.264414)
				)
				(layer "In6.Cu"
					(shape circle)
					(size 0.762 0.762)
					(clearance 0.1651)
				)
				(layer "In7.Cu"
					(shape circle)
					(size 0.762 0.762)
					(clearance 0.1651)
				)
				(layer "In8.Cu"
					(shape circle)
					(size 0.762 0.762)
					(clearance 0.1651)
				)
				(layer "In9.Cu"
					(shape circle)
					(size 0.762 0.762)
					(clearance 0.1651)
				)
				(layer "In10.Cu"
					(shape circle)
					(size 0.762 0.762)
					(clearance 0.1651)
				)
				(layer "B.Cu"
					(shape circle)
					(size 0.762 0.762)
					(thermal_gap 0.1651)
					(clearance 0.1651)
				)
			)
		)
		(pad "G8" thru_hole circle
			(at 12.599924 -11.800078)
			(size 0.664718 0.664718)
			(drill 0.359918)
			(layers "*.Cu" "*.Mask")
			(remove_unused_layers no)
			(net "PCIE_COMP_A_TO_IOM_A_15_DN")
			(clearance 0.264414)
			(padstack
				(mode custom)
				(layer "In1.Cu"
					(shape circle)
					(size 0.664718 0.664718)
					(clearance 0.264414)
				)
				(layer "In2.Cu"
					(shape circle)
					(size 0.664718 0.664718)
					(clearance 0.264414)
				)
				(layer "In3.Cu"
					(shape circle)
					(size 0.664718 0.664718)
					(clearance 0.264414)
				)
				(layer "In4.Cu"
					(shape circle)
					(size 0.664718 0.664718)
					(clearance 0.264414)
				)
				(layer "In5.Cu"
					(shape circle)
					(size 0.664718 0.664718)
					(clearance 0.264414)
				)
				(layer "In6.Cu"
					(shape circle)
					(size 0.762 0.762)
					(clearance 0.1651)
				)
				(layer "In7.Cu"
					(shape circle)
					(size 0.762 0.762)
					(clearance 0.1651)
				)
				(layer "In8.Cu"
					(shape circle)
					(size 0.762 0.762)
					(clearance 0.1651)
				)
				(layer "In9.Cu"
					(shape circle)
					(size 0.762 0.762)
					(clearance 0.1651)
				)
				(layer "In10.Cu"
					(shape circle)
					(size 0.762 0.762)
					(clearance 0.1651)
				)
				(layer "B.Cu"
					(shape circle)
					(size 0.762 0.762)
					(thermal_gap 0.1651)
					(clearance 0.1651)
				)
			)
		)
		(pad "G9" thru_hole circle
			(at 21.599906 -10.80008)
			(size 0.664718 0.664718)
			(drill 0.359918)
			(layers "*.Cu" "*.Mask")
			(remove_unused_layers no)
			(net "PCIE_COMP_A_TO_IOM_A_16_DN")
			(clearance 0.264414)
			(padstack
				(mode custom)
				(layer "In1.Cu"
					(shape circle)
					(size 0.664718 0.664718)
					(clearance 0.264414)
				)
				(layer "In2.Cu"
					(shape circle)
					(size 0.664718 0.664718)
					(clearance 0.264414)
				)
				(layer "In3.Cu"
					(shape circle)
					(size 0.664718 0.664718)
					(clearance 0.264414)
				)
				(layer "In4.Cu"
					(shape circle)
					(size 0.664718 0.664718)
					(clearance 0.264414)
				)
				(layer "In5.Cu"
					(shape circle)
					(size 0.664718 0.664718)
					(clearance 0.264414)
				)
				(layer "In6.Cu"
					(shape circle)
					(size 0.762 0.762)
					(clearance 0.1651)
				)
				(layer "In7.Cu"
					(shape circle)
					(size 0.762 0.762)
					(clearance 0.1651)
				)
				(layer "In8.Cu"
					(shape circle)
					(size 0.762 0.762)
					(clearance 0.1651)
				)
				(layer "In9.Cu"
					(shape circle)
					(size 0.762 0.762)
					(clearance 0.1651)
				)
				(layer "In10.Cu"
					(shape circle)
					(size 0.762 0.762)
					(clearance 0.1651)
				)
				(layer "B.Cu"
					(shape circle)
					(size 0.762 0.762)
					(thermal_gap 0.1651)
					(clearance 0.1651)
				)
			)
		)
		(pad "G10" thru_hole circle
			(at 23.400004 -11.800078)
			(size 0.664718 0.664718)
			(drill 0.359918)
			(layers "*.Cu" "*.Mask")
			(remove_unused_layers no)
			(net "PCIE_COMP_A_TO_IOM_A_17_DN")
			(clearance 0.264414)
			(padstack
				(mode custom)
				(layer "In1.Cu"
					(shape circle)
					(size 0.664718 0.664718)
					(clearance 0.264414)
				)
				(layer "In2.Cu"
					(shape circle)
					(size 0.664718 0.664718)
					(clearance 0.264414)
				)
				(layer "In3.Cu"
					(shape circle)
					(size 0.664718 0.664718)
					(clearance 0.264414)
				)
				(layer "In4.Cu"
					(shape circle)
					(size 0.664718 0.664718)
					(clearance 0.264414)
				)
				(layer "In5.Cu"
					(shape circle)
					(size 0.664718 0.664718)
					(clearance 0.264414)
				)
				(layer "In6.Cu"
					(shape circle)
					(size 0.762 0.762)
					(clearance 0.1651)
				)
				(layer "In7.Cu"
					(shape circle)
					(size 0.762 0.762)
					(clearance 0.1651)
				)
				(layer "In8.Cu"
					(shape circle)
					(size 0.762 0.762)
					(clearance 0.1651)
				)
				(layer "In9.Cu"
					(shape circle)
					(size 0.762 0.762)
					(clearance 0.1651)
				)
				(layer "In10.Cu"
					(shape circle)
					(size 0.762 0.762)
					(clearance 0.1651)
				)
				(layer "B.Cu"
					(shape circle)
					(size 0.762 0.762)
					(thermal_gap 0.1651)
					(clearance 0.1651)
				)
			)
		)
		(pad "G11" thru_hole circle
			(at 25.200102 -10.80008)
			(size 0.664718 0.664718)
			(drill 0.359918)
			(layers "*.Cu" "*.Mask")
			(remove_unused_layers no)
			(net "PCIE_COMP_A_TO_IOM_A_18_DN")
			(clearance 0.264414)
			(padstack
				(mode custom)
				(layer "In1.Cu"
					(shape circle)
					(size 0.664718 0.664718)
					(clearance 0.264414)
				)
				(layer "In2.Cu"
					(shape circle)
					(size 0.664718 0.664718)
					(clearance 0.264414)
				)
				(layer "In3.Cu"
					(shape circle)
					(size 0.664718 0.664718)
					(clearance 0.264414)
				)
				(layer "In4.Cu"
					(shape circle)
					(size 0.664718 0.664718)
					(clearance 0.264414)
				)
				(layer "In5.Cu"
					(shape circle)
					(size 0.664718 0.664718)
					(clearance 0.264414)
				)
				(layer "In6.Cu"
					(shape circle)
					(size 0.762 0.762)
					(clearance 0.1651)
				)
				(layer "In7.Cu"
					(shape circle)
					(size 0.762 0.762)
					(clearance 0.1651)
				)
				(layer "In8.Cu"
					(shape circle)
					(size 0.762 0.762)
					(clearance 0.1651)
				)
				(layer "In9.Cu"
					(shape circle)
					(size 0.762 0.762)
					(clearance 0.1651)
				)
				(layer "In10.Cu"
					(shape circle)
					(size 0.762 0.762)
					(clearance 0.1651)
				)
				(layer "B.Cu"
					(shape circle)
					(size 0.762 0.762)
					(thermal_gap 0.1651)
					(clearance 0.1651)
				)
			)
		)
		(pad "G12" thru_hole circle
			(at 26.999946 -11.800078)
			(size 0.664718 0.664718)
			(drill 0.359918)
			(layers "*.Cu" "*.Mask")
			(remove_unused_layers no)
			(net "PCIE_COMP_A_TO_IOM_A_19_DN")
			(clearance 0.264414)
			(padstack
				(mode custom)
				(layer "In1.Cu"
					(shape circle)
					(size 0.664718 0.664718)
					(clearance 0.264414)
				)
				(layer "In2.Cu"
					(shape circle)
					(size 0.664718 0.664718)
					(clearance 0.264414)
				)
				(layer "In3.Cu"
					(shape circle)
					(size 0.664718 0.664718)
					(clearance 0.264414)
				)
				(layer "In4.Cu"
					(shape circle)
					(size 0.664718 0.664718)
					(clearance 0.264414)
				)
				(layer "In5.Cu"
					(shape circle)
					(size 0.664718 0.664718)
					(clearance 0.264414)
				)
				(layer "In6.Cu"
					(shape circle)
					(size 0.762 0.762)
					(clearance 0.1651)
				)
				(layer "In7.Cu"
					(shape circle)
					(size 0.762 0.762)
					(clearance 0.1651)
				)
				(layer "In8.Cu"
					(shape circle)
					(size 0.762 0.762)
					(clearance 0.1651)
				)
				(layer "In9.Cu"
					(shape circle)
					(size 0.762 0.762)
					(clearance 0.1651)
				)
				(layer "In10.Cu"
					(shape circle)
					(size 0.762 0.762)
					(clearance 0.1651)
				)
				(layer "B.Cu"
					(shape circle)
					(size 0.762 0.762)
					(thermal_gap 0.1651)
					(clearance 0.1651)
				)
			)
		)
		(pad "G13" thru_hole circle
			(at 28.800044 -10.80008)
			(size 0.664718 0.664718)
			(drill 0.359918)
			(layers "*.Cu" "*.Mask")
			(remove_unused_layers no)
			(net "PCIE_COMP_A_TO_IOM_A_20_DN")
			(clearance 0.264414)
			(padstack
				(mode custom)
				(layer "In1.Cu"
					(shape circle)
					(size 0.664718 0.664718)
					(clearance 0.264414)
				)
				(layer "In2.Cu"
					(shape circle)
					(size 0.664718 0.664718)
					(clearance 0.264414)
				)
				(layer "In3.Cu"
					(shape circle)
					(size 0.664718 0.664718)
					(clearance 0.264414)
				)
				(layer "In4.Cu"
					(shape circle)
					(size 0.664718 0.664718)
					(clearance 0.264414)
				)
				(layer "In5.Cu"
					(shape circle)
					(size 0.664718 0.664718)
					(clearance 0.264414)
				)
				(layer "In6.Cu"
					(shape circle)
					(size 0.762 0.762)
					(clearance 0.1651)
				)
				(layer "In7.Cu"
					(shape circle)
					(size 0.762 0.762)
					(clearance 0.1651)
				)
				(layer "In8.Cu"
					(shape circle)
					(size 0.762 0.762)
					(clearance 0.1651)
				)
				(layer "In9.Cu"
					(shape circle)
					(size 0.762 0.762)
					(clearance 0.1651)
				)
				(layer "In10.Cu"
					(shape circle)
					(size 0.762 0.762)
					(clearance 0.1651)
				)
				(layer "B.Cu"
					(shape circle)
					(size 0.762 0.762)
					(thermal_gap 0.1651)
					(clearance 0.1651)
				)
			)
		)
		(pad "G14" thru_hole circle
			(at 30.599888 -11.800078)
			(size 0.664718 0.664718)
			(drill 0.359918)
			(layers "*.Cu" "*.Mask")
			(remove_unused_layers no)
			(net "PCIE_COMP_A_TO_IOM_A_21_DN")
			(clearance 0.264414)
			(padstack
				(mode custom)
				(layer "In1.Cu"
					(shape circle)
					(size 0.664718 0.664718)
					(clearance 0.264414)
				)
				(layer "In2.Cu"
					(shape circle)
					(size 0.664718 0.664718)
					(clearance 0.264414)
				)
				(layer "In3.Cu"
					(shape circle)
					(size 0.664718 0.664718)
					(clearance 0.264414)
				)
				(layer "In4.Cu"
					(shape circle)
					(size 0.664718 0.664718)
					(clearance 0.264414)
				)
				(layer "In5.Cu"
					(shape circle)
					(size 0.664718 0.664718)
					(clearance 0.264414)
				)
				(layer "In6.Cu"
					(shape circle)
					(size 0.762 0.762)
					(clearance 0.1651)
				)
				(layer "In7.Cu"
					(shape circle)
					(size 0.762 0.762)
					(clearance 0.1651)
				)
				(layer "In8.Cu"
					(shape circle)
					(size 0.762 0.762)
					(clearance 0.1651)
				)
				(layer "In9.Cu"
					(shape circle)
					(size 0.762 0.762)
					(clearance 0.1651)
				)
				(layer "In10.Cu"
					(shape circle)
					(size 0.762 0.762)
					(clearance 0.1651)
				)
				(layer "B.Cu"
					(shape circle)
					(size 0.762 0.762)
					(thermal_gap 0.1651)
					(clearance 0.1651)
				)
			)
		)
		(pad "G15" thru_hole circle
			(at 32.399986 -10.80008)
			(size 0.664718 0.664718)
			(drill 0.359918)
			(layers "*.Cu" "*.Mask")
			(remove_unused_layers no)
			(net "PCIE_COMP_A_TO_IOM_A_22_DN")
			(clearance 0.264414)
			(padstack
				(mode custom)
				(layer "In1.Cu"
					(shape circle)
					(size 0.664718 0.664718)
					(clearance 0.264414)
				)
				(layer "In2.Cu"
					(shape circle)
					(size 0.664718 0.664718)
					(clearance 0.264414)
				)
				(layer "In3.Cu"
					(shape circle)
					(size 0.664718 0.664718)
					(clearance 0.264414)
				)
				(layer "In4.Cu"
					(shape circle)
					(size 0.664718 0.664718)
					(clearance 0.264414)
				)
				(layer "In5.Cu"
					(shape circle)
					(size 0.664718 0.664718)
					(clearance 0.264414)
				)
				(layer "In6.Cu"
					(shape circle)
					(size 0.762 0.762)
					(clearance 0.1651)
				)
				(layer "In7.Cu"
					(shape circle)
					(size 0.762 0.762)
					(clearance 0.1651)
				)
				(layer "In8.Cu"
					(shape circle)
					(size 0.762 0.762)
					(clearance 0.1651)
				)
				(layer "In9.Cu"
					(shape circle)
					(size 0.762 0.762)
					(clearance 0.1651)
				)
				(layer "In10.Cu"
					(shape circle)
					(size 0.762 0.762)
					(clearance 0.1651)
				)
				(layer "B.Cu"
					(shape circle)
					(size 0.762 0.762)
					(thermal_gap 0.1651)
					(clearance 0.1651)
				)
			)
		)
		(pad "G16" thru_hole circle
			(at 34.200084 -11.800078)
			(size 0.664718 0.664718)
			(drill 0.359918)
			(layers "*.Cu" "*.Mask")
			(remove_unused_layers no)
			(net "PCIE_COMP_A_TO_IOM_A_23_DN")
			(clearance 0.264414)
			(padstack
				(mode custom)
				(layer "In1.Cu"
					(shape circle)
					(size 0.664718 0.664718)
					(clearance 0.264414)
				)
				(layer "In2.Cu"
					(shape circle)
					(size 0.664718 0.664718)
					(clearance 0.264414)
				)
				(layer "In3.Cu"
					(shape circle)
					(size 0.664718 0.664718)
					(clearance 0.264414)
				)
				(layer "In4.Cu"
					(shape circle)
					(size 0.664718 0.664718)
					(clearance 0.264414)
				)
				(layer "In5.Cu"
					(shape circle)
					(size 0.664718 0.664718)
					(clearance 0.264414)
				)
				(layer "In6.Cu"
					(shape circle)
					(size 0.762 0.762)
					(clearance 0.1651)
				)
				(layer "In7.Cu"
					(shape circle)
					(size 0.762 0.762)
					(clearance 0.1651)
				)
				(layer "In8.Cu"
					(shape circle)
					(size 0.762 0.762)
					(clearance 0.1651)
				)
				(layer "In9.Cu"
					(shape circle)
					(size 0.762 0.762)
					(clearance 0.1651)
				)
				(layer "In10.Cu"
					(shape circle)
					(size 0.762 0.762)
					(clearance 0.1651)
				)
				(layer "B.Cu"
					(shape circle)
					(size 0.762 0.762)
					(thermal_gap 0.1651)
					(clearance 0.1651)
				)
			)
		)
		(pad "GND1" thru_hole circle
			(at 0 -2.500122)
			(size 0.762 0.762)
			(drill 0.359918)
			(layers "*.Cu" "*.Mask")
			(remove_unused_layers no)
			(net "GND")
			(clearance 0.1651)
			(thermal_gap 0.1651)
		)
		(pad "GND2" thru_hole circle
			(at 0 -6.100064)
			(size 0.762 0.762)
			(drill 0.359918)
			(layers "*.Cu" "*.Mask")
			(remove_unused_layers no)
			(net "GND")
			(clearance 0.1651)
			(thermal_gap 0.1651)
		)
		(pad "GND3" thru_hole circle
			(at 0 -9.700006)
			(size 0.762 0.762)
			(drill 0.359918)
			(layers "*.Cu" "*.Mask")
			(remove_unused_layers no)
			(net "GND")
			(clearance 0.1651)
			(thermal_gap 0.1651)
		)
		(pad "GND4" thru_hole circle
			(at 0 -13.299948)
			(size 0.762 0.762)
			(drill 0.359918)
			(layers "*.Cu" "*.Mask")
			(remove_unused_layers no)
			(net "GND")
			(clearance 0.1651)
			(thermal_gap 0.1651)
		)
		(pad "GND5" thru_hole circle
			(at 1.800098 0.100076)
			(size 0.762 0.762)
			(drill 0.359918)
			(layers "*.Cu" "*.Mask")
			(remove_unused_layers no)
			(net "GND")
			(clearance 0.1651)
			(thermal_gap 0.1651)
		)
		(pad "GND6" thru_hole circle
			(at 1.800098 -3.50012)
			(size 0.762 0.762)
			(drill 0.359918)
			(layers "*.Cu" "*.Mask")
			(remove_unused_layers no)
			(net "GND")
			(clearance 0.1651)
			(thermal_gap 0.1651)
		)
		(pad "GND7" thru_hole circle
			(at 1.800098 -7.100062)
			(size 0.762 0.762)
			(drill 0.359918)
			(layers "*.Cu" "*.Mask")
			(remove_unused_layers no)
			(net "GND")
			(clearance 0.1651)
			(thermal_gap 0.1651)
		)
		(pad "GND8" thru_hole circle
			(at 1.800098 -10.700004)
			(size 0.762 0.762)
			(drill 0.359918)
			(layers "*.Cu" "*.Mask")
			(remove_unused_layers no)
			(net "GND")
			(clearance 0.1651)
			(thermal_gap 0.1651)
		)
		(pad "GND9" thru_hole circle
			(at 1.800098 -14.299946)
			(size 0.762 0.762)
			(drill 0.359918)
			(layers "*.Cu" "*.Mask")
			(remove_unused_layers no)
			(net "GND")
			(clearance 0.1651)
			(thermal_gap 0.1651)
		)
		(pad "GND10" thru_hole circle
			(at 3.599942 -2.500122)
			(size 0.762 0.762)
			(drill 0.359918)
			(layers "*.Cu" "*.Mask")
			(remove_unused_layers no)
			(net "GND")
			(clearance 0.1651)
			(thermal_gap 0.1651)
		)
		(pad "GND11" thru_hole circle
			(at 3.599942 -6.100064)
			(size 0.762 0.762)
			(drill 0.359918)
			(layers "*.Cu" "*.Mask")
			(remove_unused_layers no)
			(net "GND")
			(clearance 0.1651)
			(thermal_gap 0.1651)
		)
		(pad "GND12" thru_hole circle
			(at 3.599942 -9.700006)
			(size 0.762 0.762)
			(drill 0.359918)
			(layers "*.Cu" "*.Mask")
			(remove_unused_layers no)
			(net "GND")
			(clearance 0.1651)
			(thermal_gap 0.1651)
		)
		(pad "GND13" thru_hole circle
			(at 3.599942 -13.299948)
			(size 0.762 0.762)
			(drill 0.359918)
			(layers "*.Cu" "*.Mask")
			(remove_unused_layers no)
			(net "GND")
			(clearance 0.1651)
			(thermal_gap 0.1651)
		)
		(pad "GND14" thru_hole circle
			(at 5.40004 0.100076)
			(size 0.762 0.762)
			(drill 0.359918)
			(layers "*.Cu" "*.Mask")
			(remove_unused_layers no)
			(net "GND")
			(clearance 0.1651)
			(thermal_gap 0.1651)
		)
		(pad "GND15" thru_hole circle
			(at 5.40004 -3.50012)
			(size 0.762 0.762)
			(drill 0.359918)
			(layers "*.Cu" "*.Mask")
			(remove_unused_layers no)
			(net "GND")
			(clearance 0.1651)
			(thermal_gap 0.1651)
		)
		(pad "GND16" thru_hole circle
			(at 5.40004 -7.100062)
			(size 0.762 0.762)
			(drill 0.359918)
			(layers "*.Cu" "*.Mask")
			(remove_unused_layers no)
			(net "GND")
			(clearance 0.1651)
			(thermal_gap 0.1651)
		)
		(pad "GND17" thru_hole circle
			(at 5.40004 -10.700004)
			(size 0.762 0.762)
			(drill 0.359918)
			(layers "*.Cu" "*.Mask")
			(remove_unused_layers no)
			(net "GND")
			(clearance 0.1651)
			(thermal_gap 0.1651)
		)
		(pad "GND18" thru_hole circle
			(at 5.40004 -14.299946)
			(size 0.762 0.762)
			(drill 0.359918)
			(layers "*.Cu" "*.Mask")
			(remove_unused_layers no)
			(net "GND")
			(clearance 0.1651)
			(thermal_gap 0.1651)
		)
		(pad "GND19" thru_hole circle
			(at 7.199884 -2.500122)
			(size 0.762 0.762)
			(drill 0.359918)
			(layers "*.Cu" "*.Mask")
			(remove_unused_layers no)
			(net "GND")
			(clearance 0.1651)
			(thermal_gap 0.1651)
		)
		(pad "GND20" thru_hole circle
			(at 7.199884 -6.100064)
			(size 0.762 0.762)
			(drill 0.359918)
			(layers "*.Cu" "*.Mask")
			(remove_unused_layers no)
			(net "GND")
			(clearance 0.1651)
			(thermal_gap 0.1651)
		)
		(pad "GND21" thru_hole circle
			(at 7.199884 -9.700006)
			(size 0.762 0.762)
			(drill 0.359918)
			(layers "*.Cu" "*.Mask")
			(remove_unused_layers no)
			(net "GND")
			(clearance 0.1651)
			(thermal_gap 0.1651)
		)
		(pad "GND22" thru_hole circle
			(at 7.199884 -13.299948)
			(size 0.762 0.762)
			(drill 0.359918)
			(layers "*.Cu" "*.Mask")
			(remove_unused_layers no)
			(net "GND")
			(clearance 0.1651)
			(thermal_gap 0.1651)
		)
		(pad "GND23" thru_hole circle
			(at 8.999982 0.100076)
			(size 0.762 0.762)
			(drill 0.359918)
			(layers "*.Cu" "*.Mask")
			(remove_unused_layers no)
			(net "GND")
			(clearance 0.1651)
			(thermal_gap 0.1651)
		)
		(pad "GND24" thru_hole circle
			(at 8.999982 -3.50012)
			(size 0.762 0.762)
			(drill 0.359918)
			(layers "*.Cu" "*.Mask")
			(remove_unused_layers no)
			(net "GND")
			(clearance 0.1651)
			(thermal_gap 0.1651)
		)
		(pad "GND25" thru_hole circle
			(at 8.999982 -7.100062)
			(size 0.762 0.762)
			(drill 0.359918)
			(layers "*.Cu" "*.Mask")
			(remove_unused_layers no)
			(net "GND")
			(clearance 0.1651)
			(thermal_gap 0.1651)
		)
		(pad "GND26" thru_hole circle
			(at 8.999982 -10.700004)
			(size 0.762 0.762)
			(drill 0.359918)
			(layers "*.Cu" "*.Mask")
			(remove_unused_layers no)
			(net "GND")
			(clearance 0.1651)
			(thermal_gap 0.1651)
		)
		(pad "GND27" thru_hole circle
			(at 8.999982 -14.299946)
			(size 0.762 0.762)
			(drill 0.359918)
			(layers "*.Cu" "*.Mask")
			(remove_unused_layers no)
			(net "GND")
			(clearance 0.1651)
			(thermal_gap 0.1651)
		)
		(pad "GND28" thru_hole circle
			(at 10.80008 -2.500122)
			(size 0.762 0.762)
			(drill 0.359918)
			(layers "*.Cu" "*.Mask")
			(remove_unused_layers no)
			(net "GND")
			(clearance 0.1651)
			(thermal_gap 0.1651)
		)
		(pad "GND29" thru_hole circle
			(at 10.80008 -6.100064)
			(size 0.762 0.762)
			(drill 0.359918)
			(layers "*.Cu" "*.Mask")
			(remove_unused_layers no)
			(net "GND")
			(clearance 0.1651)
			(thermal_gap 0.1651)
		)
		(pad "GND30" thru_hole circle
			(at 10.80008 -9.700006)
			(size 0.762 0.762)
			(drill 0.359918)
			(layers "*.Cu" "*.Mask")
			(remove_unused_layers no)
			(net "GND")
			(clearance 0.1651)
			(thermal_gap 0.1651)
		)
		(pad "GND31" thru_hole circle
			(at 10.80008 -13.299948)
			(size 0.762 0.762)
			(drill 0.359918)
			(layers "*.Cu" "*.Mask")
			(remove_unused_layers no)
			(net "GND")
			(clearance 0.1651)
			(thermal_gap 0.1651)
		)
		(pad "GND32" thru_hole circle
			(at 12.599924 0.100076)
			(size 0.762 0.762)
			(drill 0.359918)
			(layers "*.Cu" "*.Mask")
			(remove_unused_layers no)
			(net "GND")
			(clearance 0.1651)
			(thermal_gap 0.1651)
		)
		(pad "GND33" thru_hole circle
			(at 12.599924 -3.50012)
			(size 0.762 0.762)
			(drill 0.359918)
			(layers "*.Cu" "*.Mask")
			(remove_unused_layers no)
			(net "GND")
			(clearance 0.1651)
			(thermal_gap 0.1651)
		)
		(pad "GND34" thru_hole circle
			(at 12.599924 -7.100062)
			(size 0.762 0.762)
			(drill 0.359918)
			(layers "*.Cu" "*.Mask")
			(remove_unused_layers no)
			(net "GND")
			(clearance 0.1651)
			(thermal_gap 0.1651)
		)
		(pad "GND35" thru_hole circle
			(at 12.599924 -10.700004)
			(size 0.762 0.762)
			(drill 0.359918)
			(layers "*.Cu" "*.Mask")
			(remove_unused_layers no)
			(net "GND")
			(clearance 0.1651)
			(thermal_gap 0.1651)
		)
		(pad "GND36" thru_hole circle
			(at 12.599924 -14.299946)
			(size 0.762 0.762)
			(drill 0.359918)
			(layers "*.Cu" "*.Mask")
			(remove_unused_layers no)
			(net "GND")
			(clearance 0.1651)
			(thermal_gap 0.1651)
		)
		(pad "GND37" thru_hole circle
			(at 21.599906 -2.500122)
			(size 0.762 0.762)
			(drill 0.359918)
			(layers "*.Cu" "*.Mask")
			(remove_unused_layers no)
			(net "GND")
			(clearance 0.1651)
			(thermal_gap 0.1651)
		)
		(pad "GND38" thru_hole circle
			(at 21.599906 -6.100064)
			(size 0.762 0.762)
			(drill 0.359918)
			(layers "*.Cu" "*.Mask")
			(remove_unused_layers no)
			(net "GND")
			(clearance 0.1651)
			(thermal_gap 0.1651)
		)
		(pad "GND39" thru_hole circle
			(at 21.599906 -9.700006)
			(size 0.762 0.762)
			(drill 0.359918)
			(layers "*.Cu" "*.Mask")
			(remove_unused_layers no)
			(net "GND")
			(clearance 0.1651)
			(thermal_gap 0.1651)
		)
		(pad "GND40" thru_hole circle
			(at 21.599906 -13.299948)
			(size 0.762 0.762)
			(drill 0.359918)
			(layers "*.Cu" "*.Mask")
			(remove_unused_layers no)
			(net "GND")
			(clearance 0.1651)
			(thermal_gap 0.1651)
		)
		(pad "GND41" thru_hole circle
			(at 23.400004 0.100076)
			(size 0.762 0.762)
			(drill 0.359918)
			(layers "*.Cu" "*.Mask")
			(remove_unused_layers no)
			(net "GND")
			(clearance 0.1651)
			(thermal_gap 0.1651)
		)
		(pad "GND42" thru_hole circle
			(at 23.400004 -3.50012)
			(size 0.762 0.762)
			(drill 0.359918)
			(layers "*.Cu" "*.Mask")
			(remove_unused_layers no)
			(net "GND")
			(clearance 0.1651)
			(thermal_gap 0.1651)
		)
		(pad "GND43" thru_hole circle
			(at 23.400004 -7.100062)
			(size 0.762 0.762)
			(drill 0.359918)
			(layers "*.Cu" "*.Mask")
			(remove_unused_layers no)
			(net "GND")
			(clearance 0.1651)
			(thermal_gap 0.1651)
		)
		(pad "GND44" thru_hole circle
			(at 23.400004 -10.700004)
			(size 0.762 0.762)
			(drill 0.359918)
			(layers "*.Cu" "*.Mask")
			(remove_unused_layers no)
			(net "GND")
			(clearance 0.1651)
			(thermal_gap 0.1651)
		)
		(pad "GND45" thru_hole circle
			(at 23.400004 -14.299946)
			(size 0.762 0.762)
			(drill 0.359918)
			(layers "*.Cu" "*.Mask")
			(remove_unused_layers no)
			(net "GND")
			(clearance 0.1651)
			(thermal_gap 0.1651)
		)
		(pad "GND46" thru_hole circle
			(at 25.200102 -2.500122)
			(size 0.762 0.762)
			(drill 0.359918)
			(layers "*.Cu" "*.Mask")
			(remove_unused_layers no)
			(net "GND")
			(clearance 0.1651)
			(thermal_gap 0.1651)
		)
		(pad "GND47" thru_hole circle
			(at 25.200102 -6.100064)
			(size 0.762 0.762)
			(drill 0.359918)
			(layers "*.Cu" "*.Mask")
			(remove_unused_layers no)
			(net "GND")
			(clearance 0.1651)
			(thermal_gap 0.1651)
		)
		(pad "GND48" thru_hole circle
			(at 25.200102 -9.700006)
			(size 0.762 0.762)
			(drill 0.359918)
			(layers "*.Cu" "*.Mask")
			(remove_unused_layers no)
			(net "GND")
			(clearance 0.1651)
			(thermal_gap 0.1651)
		)
		(pad "GND49" thru_hole circle
			(at 25.200102 -13.299948)
			(size 0.762 0.762)
			(drill 0.359918)
			(layers "*.Cu" "*.Mask")
			(remove_unused_layers no)
			(net "GND")
			(clearance 0.1651)
			(thermal_gap 0.1651)
		)
		(pad "GND50" thru_hole circle
			(at 26.999946 0.100076)
			(size 0.762 0.762)
			(drill 0.359918)
			(layers "*.Cu" "*.Mask")
			(remove_unused_layers no)
			(net "GND")
			(clearance 0.1651)
			(thermal_gap 0.1651)
		)
		(pad "GND51" thru_hole circle
			(at 26.999946 -3.50012)
			(size 0.762 0.762)
			(drill 0.359918)
			(layers "*.Cu" "*.Mask")
			(remove_unused_layers no)
			(net "GND")
			(clearance 0.1651)
			(thermal_gap 0.1651)
		)
		(pad "GND52" thru_hole circle
			(at 26.999946 -7.100062)
			(size 0.762 0.762)
			(drill 0.359918)
			(layers "*.Cu" "*.Mask")
			(remove_unused_layers no)
			(net "GND")
			(clearance 0.1651)
			(thermal_gap 0.1651)
		)
		(pad "GND53" thru_hole circle
			(at 26.999946 -10.700004)
			(size 0.762 0.762)
			(drill 0.359918)
			(layers "*.Cu" "*.Mask")
			(remove_unused_layers no)
			(net "GND")
			(clearance 0.1651)
			(thermal_gap 0.1651)
		)
		(pad "GND54" thru_hole circle
			(at 26.999946 -14.299946)
			(size 0.762 0.762)
			(drill 0.359918)
			(layers "*.Cu" "*.Mask")
			(remove_unused_layers no)
			(net "GND")
			(clearance 0.1651)
			(thermal_gap 0.1651)
		)
		(pad "GND55" thru_hole circle
			(at 28.800044 -2.500122)
			(size 0.762 0.762)
			(drill 0.359918)
			(layers "*.Cu" "*.Mask")
			(remove_unused_layers no)
			(net "GND")
			(clearance 0.1651)
			(thermal_gap 0.1651)
		)
		(pad "GND56" thru_hole circle
			(at 28.800044 -6.100064)
			(size 0.762 0.762)
			(drill 0.359918)
			(layers "*.Cu" "*.Mask")
			(remove_unused_layers no)
			(net "GND")
			(clearance 0.1651)
			(thermal_gap 0.1651)
		)
		(pad "GND57" thru_hole circle
			(at 28.800044 -9.700006)
			(size 0.762 0.762)
			(drill 0.359918)
			(layers "*.Cu" "*.Mask")
			(remove_unused_layers no)
			(net "GND")
			(clearance 0.1651)
			(thermal_gap 0.1651)
		)
		(pad "GND58" thru_hole circle
			(at 28.800044 -13.299948)
			(size 0.762 0.762)
			(drill 0.359918)
			(layers "*.Cu" "*.Mask")
			(remove_unused_layers no)
			(net "GND")
			(clearance 0.1651)
			(thermal_gap 0.1651)
		)
		(pad "GND59" thru_hole circle
			(at 30.599888 0.100076)
			(size 0.762 0.762)
			(drill 0.359918)
			(layers "*.Cu" "*.Mask")
			(remove_unused_layers no)
			(net "GND")
			(clearance 0.1651)
			(thermal_gap 0.1651)
		)
		(pad "GND60" thru_hole circle
			(at 30.599888 -3.50012)
			(size 0.762 0.762)
			(drill 0.359918)
			(layers "*.Cu" "*.Mask")
			(remove_unused_layers no)
			(net "GND")
			(clearance 0.1651)
			(thermal_gap 0.1651)
		)
		(pad "GND61" thru_hole circle
			(at 30.599888 -7.100062)
			(size 0.762 0.762)
			(drill 0.359918)
			(layers "*.Cu" "*.Mask")
			(remove_unused_layers no)
			(net "GND")
			(clearance 0.1651)
			(thermal_gap 0.1651)
		)
		(pad "GND62" thru_hole circle
			(at 30.599888 -10.700004)
			(size 0.762 0.762)
			(drill 0.359918)
			(layers "*.Cu" "*.Mask")
			(remove_unused_layers no)
			(net "GND")
			(clearance 0.1651)
			(thermal_gap 0.1651)
		)
		(pad "GND63" thru_hole circle
			(at 30.599888 -14.299946)
			(size 0.762 0.762)
			(drill 0.359918)
			(layers "*.Cu" "*.Mask")
			(remove_unused_layers no)
			(net "GND")
			(clearance 0.1651)
			(thermal_gap 0.1651)
		)
		(pad "GND64" thru_hole circle
			(at 32.399986 -2.500122)
			(size 0.762 0.762)
			(drill 0.359918)
			(layers "*.Cu" "*.Mask")
			(remove_unused_layers no)
			(net "GND")
			(clearance 0.1651)
			(thermal_gap 0.1651)
		)
		(pad "GND65" thru_hole circle
			(at 32.399986 -6.100064)
			(size 0.762 0.762)
			(drill 0.359918)
			(layers "*.Cu" "*.Mask")
			(remove_unused_layers no)
			(net "GND")
			(clearance 0.1651)
			(thermal_gap 0.1651)
		)
		(pad "GND66" thru_hole circle
			(at 32.399986 -9.700006)
			(size 0.762 0.762)
			(drill 0.359918)
			(layers "*.Cu" "*.Mask")
			(remove_unused_layers no)
			(net "GND")
			(clearance 0.1651)
			(thermal_gap 0.1651)
		)
		(pad "GND67" thru_hole circle
			(at 32.399986 -13.299948)
			(size 0.762 0.762)
			(drill 0.359918)
			(layers "*.Cu" "*.Mask")
			(remove_unused_layers no)
			(net "GND")
			(clearance 0.1651)
			(thermal_gap 0.1651)
		)
		(pad "GND68" thru_hole circle
			(at 34.200084 0.100076)
			(size 0.762 0.762)
			(drill 0.359918)
			(layers "*.Cu" "*.Mask")
			(remove_unused_layers no)
			(net "GND")
			(clearance 0.1651)
			(thermal_gap 0.1651)
		)
		(pad "GND69" thru_hole circle
			(at 34.200084 -3.50012)
			(size 0.762 0.762)
			(drill 0.359918)
			(layers "*.Cu" "*.Mask")
			(remove_unused_layers no)
			(net "GND")
			(clearance 0.1651)
			(thermal_gap 0.1651)
		)
		(pad "GND70" thru_hole circle
			(at 34.200084 -7.100062)
			(size 0.762 0.762)
			(drill 0.359918)
			(layers "*.Cu" "*.Mask")
			(remove_unused_layers no)
			(net "GND")
			(clearance 0.1651)
			(thermal_gap 0.1651)
		)
		(pad "GND71" thru_hole circle
			(at 34.200084 -10.700004)
			(size 0.762 0.762)
			(drill 0.359918)
			(layers "*.Cu" "*.Mask")
			(remove_unused_layers no)
			(net "GND")
			(clearance 0.1651)
			(thermal_gap 0.1651)
		)
		(pad "GND72" thru_hole circle
			(at 34.200084 -14.299946)
			(size 0.762 0.762)
			(drill 0.359918)
			(layers "*.Cu" "*.Mask")
			(remove_unused_layers no)
			(net "GND")
			(clearance 0.1651)
			(thermal_gap 0.1651)
		)
		(pad "H1" thru_hole circle
			(at 0 -12.199874)
			(size 0.664718 0.664718)
			(drill 0.359918)
			(layers "*.Cu" "*.Mask")
			(remove_unused_layers no)
			(net "PCIE_COMP_A_TO_IOM_A_8_DP")
			(clearance 0.264414)
			(padstack
				(mode custom)
				(layer "In1.Cu"
					(shape circle)
					(size 0.664718 0.664718)
					(clearance 0.264414)
				)
				(layer "In2.Cu"
					(shape circle)
					(size 0.664718 0.664718)
					(clearance 0.264414)
				)
				(layer "In3.Cu"
					(shape circle)
					(size 0.664718 0.664718)
					(clearance 0.264414)
				)
				(layer "In4.Cu"
					(shape circle)
					(size 0.664718 0.664718)
					(clearance 0.264414)
				)
				(layer "In5.Cu"
					(shape circle)
					(size 0.664718 0.664718)
					(clearance 0.264414)
				)
				(layer "In6.Cu"
					(shape circle)
					(size 0.762 0.762)
					(clearance 0.1651)
				)
				(layer "In7.Cu"
					(shape circle)
					(size 0.762 0.762)
					(clearance 0.1651)
				)
				(layer "In8.Cu"
					(shape circle)
					(size 0.762 0.762)
					(clearance 0.1651)
				)
				(layer "In9.Cu"
					(shape circle)
					(size 0.762 0.762)
					(clearance 0.1651)
				)
				(layer "In10.Cu"
					(shape circle)
					(size 0.762 0.762)
					(clearance 0.1651)
				)
				(layer "B.Cu"
					(shape circle)
					(size 0.762 0.762)
					(thermal_gap 0.1651)
					(clearance 0.1651)
				)
			)
		)
		(pad "H2" thru_hole circle
			(at 1.800098 -13.200126)
			(size 0.664718 0.664718)
			(drill 0.359918)
			(layers "*.Cu" "*.Mask")
			(remove_unused_layers no)
			(net "PCIE_COMP_A_TO_IOM_A_9_DP")
			(clearance 0.264414)
			(padstack
				(mode custom)
				(layer "In1.Cu"
					(shape circle)
					(size 0.664718 0.664718)
					(clearance 0.264414)
				)
				(layer "In2.Cu"
					(shape circle)
					(size 0.664718 0.664718)
					(clearance 0.264414)
				)
				(layer "In3.Cu"
					(shape circle)
					(size 0.664718 0.664718)
					(clearance 0.264414)
				)
				(layer "In4.Cu"
					(shape circle)
					(size 0.664718 0.664718)
					(clearance 0.264414)
				)
				(layer "In5.Cu"
					(shape circle)
					(size 0.664718 0.664718)
					(clearance 0.264414)
				)
				(layer "In6.Cu"
					(shape circle)
					(size 0.762 0.762)
					(clearance 0.1651)
				)
				(layer "In7.Cu"
					(shape circle)
					(size 0.762 0.762)
					(clearance 0.1651)
				)
				(layer "In8.Cu"
					(shape circle)
					(size 0.762 0.762)
					(clearance 0.1651)
				)
				(layer "In9.Cu"
					(shape circle)
					(size 0.762 0.762)
					(clearance 0.1651)
				)
				(layer "In10.Cu"
					(shape circle)
					(size 0.762 0.762)
					(clearance 0.1651)
				)
				(layer "B.Cu"
					(shape circle)
					(size 0.762 0.762)
					(thermal_gap 0.1651)
					(clearance 0.1651)
				)
			)
		)
		(pad "H3" thru_hole circle
			(at 3.599942 -12.199874)
			(size 0.664718 0.664718)
			(drill 0.359918)
			(layers "*.Cu" "*.Mask")
			(remove_unused_layers no)
			(net "PCIE_COMP_A_TO_IOM_A_10_DP")
			(clearance 0.264414)
			(padstack
				(mode custom)
				(layer "In1.Cu"
					(shape circle)
					(size 0.664718 0.664718)
					(clearance 0.264414)
				)
				(layer "In2.Cu"
					(shape circle)
					(size 0.664718 0.664718)
					(clearance 0.264414)
				)
				(layer "In3.Cu"
					(shape circle)
					(size 0.664718 0.664718)
					(clearance 0.264414)
				)
				(layer "In4.Cu"
					(shape circle)
					(size 0.664718 0.664718)
					(clearance 0.264414)
				)
				(layer "In5.Cu"
					(shape circle)
					(size 0.664718 0.664718)
					(clearance 0.264414)
				)
				(layer "In6.Cu"
					(shape circle)
					(size 0.762 0.762)
					(clearance 0.1651)
				)
				(layer "In7.Cu"
					(shape circle)
					(size 0.762 0.762)
					(clearance 0.1651)
				)
				(layer "In8.Cu"
					(shape circle)
					(size 0.762 0.762)
					(clearance 0.1651)
				)
				(layer "In9.Cu"
					(shape circle)
					(size 0.762 0.762)
					(clearance 0.1651)
				)
				(layer "In10.Cu"
					(shape circle)
					(size 0.762 0.762)
					(clearance 0.1651)
				)
				(layer "B.Cu"
					(shape circle)
					(size 0.762 0.762)
					(thermal_gap 0.1651)
					(clearance 0.1651)
				)
			)
		)
		(pad "H4" thru_hole circle
			(at 5.40004 -13.200126)
			(size 0.664718 0.664718)
			(drill 0.359918)
			(layers "*.Cu" "*.Mask")
			(remove_unused_layers no)
			(net "PCIE_COMP_A_TO_IOM_A_11_DP")
			(clearance 0.264414)
			(padstack
				(mode custom)
				(layer "In1.Cu"
					(shape circle)
					(size 0.664718 0.664718)
					(clearance 0.264414)
				)
				(layer "In2.Cu"
					(shape circle)
					(size 0.664718 0.664718)
					(clearance 0.264414)
				)
				(layer "In3.Cu"
					(shape circle)
					(size 0.664718 0.664718)
					(clearance 0.264414)
				)
				(layer "In4.Cu"
					(shape circle)
					(size 0.664718 0.664718)
					(clearance 0.264414)
				)
				(layer "In5.Cu"
					(shape circle)
					(size 0.664718 0.664718)
					(clearance 0.264414)
				)
				(layer "In6.Cu"
					(shape circle)
					(size 0.762 0.762)
					(clearance 0.1651)
				)
				(layer "In7.Cu"
					(shape circle)
					(size 0.762 0.762)
					(clearance 0.1651)
				)
				(layer "In8.Cu"
					(shape circle)
					(size 0.762 0.762)
					(clearance 0.1651)
				)
				(layer "In9.Cu"
					(shape circle)
					(size 0.762 0.762)
					(clearance 0.1651)
				)
				(layer "In10.Cu"
					(shape circle)
					(size 0.762 0.762)
					(clearance 0.1651)
				)
				(layer "B.Cu"
					(shape circle)
					(size 0.762 0.762)
					(thermal_gap 0.1651)
					(clearance 0.1651)
				)
			)
		)
		(pad "H5" thru_hole circle
			(at 7.199884 -12.199874)
			(size 0.664718 0.664718)
			(drill 0.359918)
			(layers "*.Cu" "*.Mask")
			(remove_unused_layers no)
			(net "PCIE_COMP_A_TO_IOM_A_12_DP")
			(clearance 0.264414)
			(padstack
				(mode custom)
				(layer "In1.Cu"
					(shape circle)
					(size 0.664718 0.664718)
					(clearance 0.264414)
				)
				(layer "In2.Cu"
					(shape circle)
					(size 0.664718 0.664718)
					(clearance 0.264414)
				)
				(layer "In3.Cu"
					(shape circle)
					(size 0.664718 0.664718)
					(clearance 0.264414)
				)
				(layer "In4.Cu"
					(shape circle)
					(size 0.664718 0.664718)
					(clearance 0.264414)
				)
				(layer "In5.Cu"
					(shape circle)
					(size 0.664718 0.664718)
					(clearance 0.264414)
				)
				(layer "In6.Cu"
					(shape circle)
					(size 0.762 0.762)
					(clearance 0.1651)
				)
				(layer "In7.Cu"
					(shape circle)
					(size 0.762 0.762)
					(clearance 0.1651)
				)
				(layer "In8.Cu"
					(shape circle)
					(size 0.762 0.762)
					(clearance 0.1651)
				)
				(layer "In9.Cu"
					(shape circle)
					(size 0.762 0.762)
					(clearance 0.1651)
				)
				(layer "In10.Cu"
					(shape circle)
					(size 0.762 0.762)
					(clearance 0.1651)
				)
				(layer "B.Cu"
					(shape circle)
					(size 0.762 0.762)
					(thermal_gap 0.1651)
					(clearance 0.1651)
				)
			)
		)
		(pad "H6" thru_hole circle
			(at 8.999982 -13.200126)
			(size 0.664718 0.664718)
			(drill 0.359918)
			(layers "*.Cu" "*.Mask")
			(remove_unused_layers no)
			(net "PCIE_COMP_A_TO_IOM_A_13_DP")
			(clearance 0.264414)
			(padstack
				(mode custom)
				(layer "In1.Cu"
					(shape circle)
					(size 0.664718 0.664718)
					(clearance 0.264414)
				)
				(layer "In2.Cu"
					(shape circle)
					(size 0.664718 0.664718)
					(clearance 0.264414)
				)
				(layer "In3.Cu"
					(shape circle)
					(size 0.664718 0.664718)
					(clearance 0.264414)
				)
				(layer "In4.Cu"
					(shape circle)
					(size 0.664718 0.664718)
					(clearance 0.264414)
				)
				(layer "In5.Cu"
					(shape circle)
					(size 0.664718 0.664718)
					(clearance 0.264414)
				)
				(layer "In6.Cu"
					(shape circle)
					(size 0.762 0.762)
					(clearance 0.1651)
				)
				(layer "In7.Cu"
					(shape circle)
					(size 0.762 0.762)
					(clearance 0.1651)
				)
				(layer "In8.Cu"
					(shape circle)
					(size 0.762 0.762)
					(clearance 0.1651)
				)
				(layer "In9.Cu"
					(shape circle)
					(size 0.762 0.762)
					(clearance 0.1651)
				)
				(layer "In10.Cu"
					(shape circle)
					(size 0.762 0.762)
					(clearance 0.1651)
				)
				(layer "B.Cu"
					(shape circle)
					(size 0.762 0.762)
					(thermal_gap 0.1651)
					(clearance 0.1651)
				)
			)
		)
		(pad "H7" thru_hole circle
			(at 10.80008 -12.199874)
			(size 0.664718 0.664718)
			(drill 0.359918)
			(layers "*.Cu" "*.Mask")
			(remove_unused_layers no)
			(net "PCIE_COMP_A_TO_IOM_A_14_DP")
			(clearance 0.264414)
			(padstack
				(mode custom)
				(layer "In1.Cu"
					(shape circle)
					(size 0.664718 0.664718)
					(clearance 0.264414)
				)
				(layer "In2.Cu"
					(shape circle)
					(size 0.664718 0.664718)
					(clearance 0.264414)
				)
				(layer "In3.Cu"
					(shape circle)
					(size 0.664718 0.664718)
					(clearance 0.264414)
				)
				(layer "In4.Cu"
					(shape circle)
					(size 0.664718 0.664718)
					(clearance 0.264414)
				)
				(layer "In5.Cu"
					(shape circle)
					(size 0.664718 0.664718)
					(clearance 0.264414)
				)
				(layer "In6.Cu"
					(shape circle)
					(size 0.762 0.762)
					(clearance 0.1651)
				)
				(layer "In7.Cu"
					(shape circle)
					(size 0.762 0.762)
					(clearance 0.1651)
				)
				(layer "In8.Cu"
					(shape circle)
					(size 0.762 0.762)
					(clearance 0.1651)
				)
				(layer "In9.Cu"
					(shape circle)
					(size 0.762 0.762)
					(clearance 0.1651)
				)
				(layer "In10.Cu"
					(shape circle)
					(size 0.762 0.762)
					(clearance 0.1651)
				)
				(layer "B.Cu"
					(shape circle)
					(size 0.762 0.762)
					(thermal_gap 0.1651)
					(clearance 0.1651)
				)
			)
		)
		(pad "H8" thru_hole circle
			(at 12.599924 -13.200126)
			(size 0.664718 0.664718)
			(drill 0.359918)
			(layers "*.Cu" "*.Mask")
			(remove_unused_layers no)
			(net "PCIE_COMP_A_TO_IOM_A_15_DP")
			(clearance 0.264414)
			(padstack
				(mode custom)
				(layer "In1.Cu"
					(shape circle)
					(size 0.664718 0.664718)
					(clearance 0.264414)
				)
				(layer "In2.Cu"
					(shape circle)
					(size 0.664718 0.664718)
					(clearance 0.264414)
				)
				(layer "In3.Cu"
					(shape circle)
					(size 0.664718 0.664718)
					(clearance 0.264414)
				)
				(layer "In4.Cu"
					(shape circle)
					(size 0.664718 0.664718)
					(clearance 0.264414)
				)
				(layer "In5.Cu"
					(shape circle)
					(size 0.664718 0.664718)
					(clearance 0.264414)
				)
				(layer "In6.Cu"
					(shape circle)
					(size 0.762 0.762)
					(clearance 0.1651)
				)
				(layer "In7.Cu"
					(shape circle)
					(size 0.762 0.762)
					(clearance 0.1651)
				)
				(layer "In8.Cu"
					(shape circle)
					(size 0.762 0.762)
					(clearance 0.1651)
				)
				(layer "In9.Cu"
					(shape circle)
					(size 0.762 0.762)
					(clearance 0.1651)
				)
				(layer "In10.Cu"
					(shape circle)
					(size 0.762 0.762)
					(clearance 0.1651)
				)
				(layer "B.Cu"
					(shape circle)
					(size 0.762 0.762)
					(thermal_gap 0.1651)
					(clearance 0.1651)
				)
			)
		)
		(pad "H9" thru_hole circle
			(at 21.599906 -12.199874)
			(size 0.664718 0.664718)
			(drill 0.359918)
			(layers "*.Cu" "*.Mask")
			(remove_unused_layers no)
			(net "PCIE_COMP_A_TO_IOM_A_16_DP")
			(clearance 0.264414)
			(padstack
				(mode custom)
				(layer "In1.Cu"
					(shape circle)
					(size 0.664718 0.664718)
					(clearance 0.264414)
				)
				(layer "In2.Cu"
					(shape circle)
					(size 0.664718 0.664718)
					(clearance 0.264414)
				)
				(layer "In3.Cu"
					(shape circle)
					(size 0.664718 0.664718)
					(clearance 0.264414)
				)
				(layer "In4.Cu"
					(shape circle)
					(size 0.664718 0.664718)
					(clearance 0.264414)
				)
				(layer "In5.Cu"
					(shape circle)
					(size 0.664718 0.664718)
					(clearance 0.264414)
				)
				(layer "In6.Cu"
					(shape circle)
					(size 0.762 0.762)
					(clearance 0.1651)
				)
				(layer "In7.Cu"
					(shape circle)
					(size 0.762 0.762)
					(clearance 0.1651)
				)
				(layer "In8.Cu"
					(shape circle)
					(size 0.762 0.762)
					(clearance 0.1651)
				)
				(layer "In9.Cu"
					(shape circle)
					(size 0.762 0.762)
					(clearance 0.1651)
				)
				(layer "In10.Cu"
					(shape circle)
					(size 0.762 0.762)
					(clearance 0.1651)
				)
				(layer "B.Cu"
					(shape circle)
					(size 0.762 0.762)
					(thermal_gap 0.1651)
					(clearance 0.1651)
				)
			)
		)
		(pad "H10" thru_hole circle
			(at 23.400004 -13.200126)
			(size 0.664718 0.664718)
			(drill 0.359918)
			(layers "*.Cu" "*.Mask")
			(remove_unused_layers no)
			(net "PCIE_COMP_A_TO_IOM_A_17_DP")
			(clearance 0.264414)
			(padstack
				(mode custom)
				(layer "In1.Cu"
					(shape circle)
					(size 0.664718 0.664718)
					(clearance 0.264414)
				)
				(layer "In2.Cu"
					(shape circle)
					(size 0.664718 0.664718)
					(clearance 0.264414)
				)
				(layer "In3.Cu"
					(shape circle)
					(size 0.664718 0.664718)
					(clearance 0.264414)
				)
				(layer "In4.Cu"
					(shape circle)
					(size 0.664718 0.664718)
					(clearance 0.264414)
				)
				(layer "In5.Cu"
					(shape circle)
					(size 0.664718 0.664718)
					(clearance 0.264414)
				)
				(layer "In6.Cu"
					(shape circle)
					(size 0.762 0.762)
					(clearance 0.1651)
				)
				(layer "In7.Cu"
					(shape circle)
					(size 0.762 0.762)
					(clearance 0.1651)
				)
				(layer "In8.Cu"
					(shape circle)
					(size 0.762 0.762)
					(clearance 0.1651)
				)
				(layer "In9.Cu"
					(shape circle)
					(size 0.762 0.762)
					(clearance 0.1651)
				)
				(layer "In10.Cu"
					(shape circle)
					(size 0.762 0.762)
					(clearance 0.1651)
				)
				(layer "B.Cu"
					(shape circle)
					(size 0.762 0.762)
					(thermal_gap 0.1651)
					(clearance 0.1651)
				)
			)
		)
		(pad "H11" thru_hole circle
			(at 25.200102 -12.199874)
			(size 0.664718 0.664718)
			(drill 0.359918)
			(layers "*.Cu" "*.Mask")
			(remove_unused_layers no)
			(net "PCIE_COMP_A_TO_IOM_A_18_DP")
			(clearance 0.264414)
			(padstack
				(mode custom)
				(layer "In1.Cu"
					(shape circle)
					(size 0.664718 0.664718)
					(clearance 0.264414)
				)
				(layer "In2.Cu"
					(shape circle)
					(size 0.664718 0.664718)
					(clearance 0.264414)
				)
				(layer "In3.Cu"
					(shape circle)
					(size 0.664718 0.664718)
					(clearance 0.264414)
				)
				(layer "In4.Cu"
					(shape circle)
					(size 0.664718 0.664718)
					(clearance 0.264414)
				)
				(layer "In5.Cu"
					(shape circle)
					(size 0.664718 0.664718)
					(clearance 0.264414)
				)
				(layer "In6.Cu"
					(shape circle)
					(size 0.762 0.762)
					(clearance 0.1651)
				)
				(layer "In7.Cu"
					(shape circle)
					(size 0.762 0.762)
					(clearance 0.1651)
				)
				(layer "In8.Cu"
					(shape circle)
					(size 0.762 0.762)
					(clearance 0.1651)
				)
				(layer "In9.Cu"
					(shape circle)
					(size 0.762 0.762)
					(clearance 0.1651)
				)
				(layer "In10.Cu"
					(shape circle)
					(size 0.762 0.762)
					(clearance 0.1651)
				)
				(layer "B.Cu"
					(shape circle)
					(size 0.762 0.762)
					(thermal_gap 0.1651)
					(clearance 0.1651)
				)
			)
		)
		(pad "H12" thru_hole circle
			(at 26.999946 -13.200126)
			(size 0.664718 0.664718)
			(drill 0.359918)
			(layers "*.Cu" "*.Mask")
			(remove_unused_layers no)
			(net "PCIE_COMP_A_TO_IOM_A_19_DP")
			(clearance 0.264414)
			(padstack
				(mode custom)
				(layer "In1.Cu"
					(shape circle)
					(size 0.664718 0.664718)
					(clearance 0.264414)
				)
				(layer "In2.Cu"
					(shape circle)
					(size 0.664718 0.664718)
					(clearance 0.264414)
				)
				(layer "In3.Cu"
					(shape circle)
					(size 0.664718 0.664718)
					(clearance 0.264414)
				)
				(layer "In4.Cu"
					(shape circle)
					(size 0.664718 0.664718)
					(clearance 0.264414)
				)
				(layer "In5.Cu"
					(shape circle)
					(size 0.664718 0.664718)
					(clearance 0.264414)
				)
				(layer "In6.Cu"
					(shape circle)
					(size 0.762 0.762)
					(clearance 0.1651)
				)
				(layer "In7.Cu"
					(shape circle)
					(size 0.762 0.762)
					(clearance 0.1651)
				)
				(layer "In8.Cu"
					(shape circle)
					(size 0.762 0.762)
					(clearance 0.1651)
				)
				(layer "In9.Cu"
					(shape circle)
					(size 0.762 0.762)
					(clearance 0.1651)
				)
				(layer "In10.Cu"
					(shape circle)
					(size 0.762 0.762)
					(clearance 0.1651)
				)
				(layer "B.Cu"
					(shape circle)
					(size 0.762 0.762)
					(thermal_gap 0.1651)
					(clearance 0.1651)
				)
			)
		)
		(pad "H13" thru_hole circle
			(at 28.800044 -12.199874)
			(size 0.664718 0.664718)
			(drill 0.359918)
			(layers "*.Cu" "*.Mask")
			(remove_unused_layers no)
			(net "PCIE_COMP_A_TO_IOM_A_20_DP")
			(clearance 0.264414)
			(padstack
				(mode custom)
				(layer "In1.Cu"
					(shape circle)
					(size 0.664718 0.664718)
					(clearance 0.264414)
				)
				(layer "In2.Cu"
					(shape circle)
					(size 0.664718 0.664718)
					(clearance 0.264414)
				)
				(layer "In3.Cu"
					(shape circle)
					(size 0.664718 0.664718)
					(clearance 0.264414)
				)
				(layer "In4.Cu"
					(shape circle)
					(size 0.664718 0.664718)
					(clearance 0.264414)
				)
				(layer "In5.Cu"
					(shape circle)
					(size 0.664718 0.664718)
					(clearance 0.264414)
				)
				(layer "In6.Cu"
					(shape circle)
					(size 0.762 0.762)
					(clearance 0.1651)
				)
				(layer "In7.Cu"
					(shape circle)
					(size 0.762 0.762)
					(clearance 0.1651)
				)
				(layer "In8.Cu"
					(shape circle)
					(size 0.762 0.762)
					(clearance 0.1651)
				)
				(layer "In9.Cu"
					(shape circle)
					(size 0.762 0.762)
					(clearance 0.1651)
				)
				(layer "In10.Cu"
					(shape circle)
					(size 0.762 0.762)
					(clearance 0.1651)
				)
				(layer "B.Cu"
					(shape circle)
					(size 0.762 0.762)
					(thermal_gap 0.1651)
					(clearance 0.1651)
				)
			)
		)
		(pad "H14" thru_hole circle
			(at 30.599888 -13.200126)
			(size 0.664718 0.664718)
			(drill 0.359918)
			(layers "*.Cu" "*.Mask")
			(remove_unused_layers no)
			(net "PCIE_COMP_A_TO_IOM_A_21_DP")
			(clearance 0.264414)
			(padstack
				(mode custom)
				(layer "In1.Cu"
					(shape circle)
					(size 0.664718 0.664718)
					(clearance 0.264414)
				)
				(layer "In2.Cu"
					(shape circle)
					(size 0.664718 0.664718)
					(clearance 0.264414)
				)
				(layer "In3.Cu"
					(shape circle)
					(size 0.664718 0.664718)
					(clearance 0.264414)
				)
				(layer "In4.Cu"
					(shape circle)
					(size 0.664718 0.664718)
					(clearance 0.264414)
				)
				(layer "In5.Cu"
					(shape circle)
					(size 0.664718 0.664718)
					(clearance 0.264414)
				)
				(layer "In6.Cu"
					(shape circle)
					(size 0.762 0.762)
					(clearance 0.1651)
				)
				(layer "In7.Cu"
					(shape circle)
					(size 0.762 0.762)
					(clearance 0.1651)
				)
				(layer "In8.Cu"
					(shape circle)
					(size 0.762 0.762)
					(clearance 0.1651)
				)
				(layer "In9.Cu"
					(shape circle)
					(size 0.762 0.762)
					(clearance 0.1651)
				)
				(layer "In10.Cu"
					(shape circle)
					(size 0.762 0.762)
					(clearance 0.1651)
				)
				(layer "B.Cu"
					(shape circle)
					(size 0.762 0.762)
					(thermal_gap 0.1651)
					(clearance 0.1651)
				)
			)
		)
		(pad "H15" thru_hole circle
			(at 32.399986 -12.199874)
			(size 0.664718 0.664718)
			(drill 0.359918)
			(layers "*.Cu" "*.Mask")
			(remove_unused_layers no)
			(net "PCIE_COMP_A_TO_IOM_A_22_DP")
			(clearance 0.264414)
			(padstack
				(mode custom)
				(layer "In1.Cu"
					(shape circle)
					(size 0.664718 0.664718)
					(clearance 0.264414)
				)
				(layer "In2.Cu"
					(shape circle)
					(size 0.664718 0.664718)
					(clearance 0.264414)
				)
				(layer "In3.Cu"
					(shape circle)
					(size 0.664718 0.664718)
					(clearance 0.264414)
				)
				(layer "In4.Cu"
					(shape circle)
					(size 0.664718 0.664718)
					(clearance 0.264414)
				)
				(layer "In5.Cu"
					(shape circle)
					(size 0.664718 0.664718)
					(clearance 0.264414)
				)
				(layer "In6.Cu"
					(shape circle)
					(size 0.762 0.762)
					(clearance 0.1651)
				)
				(layer "In7.Cu"
					(shape circle)
					(size 0.762 0.762)
					(clearance 0.1651)
				)
				(layer "In8.Cu"
					(shape circle)
					(size 0.762 0.762)
					(clearance 0.1651)
				)
				(layer "In9.Cu"
					(shape circle)
					(size 0.762 0.762)
					(clearance 0.1651)
				)
				(layer "In10.Cu"
					(shape circle)
					(size 0.762 0.762)
					(clearance 0.1651)
				)
				(layer "B.Cu"
					(shape circle)
					(size 0.762 0.762)
					(thermal_gap 0.1651)
					(clearance 0.1651)
				)
			)
		)
		(pad "H16" thru_hole circle
			(at 34.200084 -13.200126)
			(size 0.664718 0.664718)
			(drill 0.359918)
			(layers "*.Cu" "*.Mask")
			(remove_unused_layers no)
			(net "PCIE_COMP_A_TO_IOM_A_23_DP")
			(clearance 0.264414)
			(padstack
				(mode custom)
				(layer "In1.Cu"
					(shape circle)
					(size 0.664718 0.664718)
					(clearance 0.264414)
				)
				(layer "In2.Cu"
					(shape circle)
					(size 0.664718 0.664718)
					(clearance 0.264414)
				)
				(layer "In3.Cu"
					(shape circle)
					(size 0.664718 0.664718)
					(clearance 0.264414)
				)
				(layer "In4.Cu"
					(shape circle)
					(size 0.664718 0.664718)
					(clearance 0.264414)
				)
				(layer "In5.Cu"
					(shape circle)
					(size 0.664718 0.664718)
					(clearance 0.264414)
				)
				(layer "In6.Cu"
					(shape circle)
					(size 0.762 0.762)
					(clearance 0.1651)
				)
				(layer "In7.Cu"
					(shape circle)
					(size 0.762 0.762)
					(clearance 0.1651)
				)
				(layer "In8.Cu"
					(shape circle)
					(size 0.762 0.762)
					(clearance 0.1651)
				)
				(layer "In9.Cu"
					(shape circle)
					(size 0.762 0.762)
					(clearance 0.1651)
				)
				(layer "In10.Cu"
					(shape circle)
					(size 0.762 0.762)
					(clearance 0.1651)
				)
				(layer "B.Cu"
					(shape circle)
					(size 0.762 0.762)
					(thermal_gap 0.1651)
					(clearance 0.1651)
				)
			)
		)
		(zone
			(layer "F.Cu")
			(hatch none 0.5)
			(connect_pads
				(clearance 0)
			)
			(min_thickness 0.25)
			(keepout
				(tracks allowed)
				(vias not_allowed)
				(pads allowed)
				(copperpour not_allowed)
				(footprints allowed)
			)
			(placement
				(enabled no)
				(sheetname "")
			)
			(fill
				(thermal_gap 0.5)
				(thermal_bridge_width 0.5)
				(island_removal_mode 0)
			)
			(polygon
				(pts
					(arc
						(start 109.746796 -22.350222)
						(mid 108.552996 -22.350222)
						(end 109.746796 -22.350222)
					)
				)
			)
		)
		(zone
			(layer "F.Cu")
			(hatch none 0.5)
			(connect_pads
				(clearance 0)
			)
			(min_thickness 0.25)
			(keepout
				(tracks not_allowed)
				(vias allowed)
				(pads allowed)
				(copperpour not_allowed)
				(footprints allowed)
			)
			(placement
				(enabled no)
				(sheetname "")
			)
			(fill
				(thermal_gap 0.5)
				(thermal_bridge_width 0.5)
				(island_removal_mode 0)
			)
			(polygon
				(pts
					(arc
						(start 109.746796 -22.350222)
						(mid 108.552996 -22.350222)
						(end 109.746796 -22.350222)
					)
				)
			)
		)
		(zone
			(layer "F.Cu")
			(hatch none 0.5)
			(connect_pads
				(clearance 0)
			)
			(min_thickness 0.25)
			(keepout
				(tracks allowed)
				(vias not_allowed)
				(pads allowed)
				(copperpour not_allowed)
				(footprints allowed)
			)
			(placement
				(enabled no)
				(sheetname "")
			)
			(fill
				(thermal_gap 0.5)
				(thermal_bridge_width 0.5)
				(island_removal_mode 0)
			)
			(polygon
				(pts
					(arc
						(start 109.746796 -20.950174)
						(mid 108.552996 -20.950174)
						(end 109.746796 -20.950174)
					)
				)
			)
		)
		(zone
			(layer "F.Cu")
			(hatch none 0.5)
			(connect_pads
				(clearance 0)
			)
			(min_thickness 0.25)
			(keepout
				(tracks not_allowed)
				(vias allowed)
				(pads allowed)
				(copperpour not_allowed)
				(footprints allowed)
			)
			(placement
				(enabled no)
				(sheetname "")
			)
			(fill
				(thermal_gap 0.5)
				(thermal_bridge_width 0.5)
				(island_removal_mode 0)
			)
			(polygon
				(pts
					(arc
						(start 109.746796 -20.950174)
						(mid 108.552996 -20.950174)
						(end 109.746796 -20.950174)
					)
				)
			)
		)
		(zone
			(layer "F.Cu")
			(hatch none 0.5)
			(connect_pads
				(clearance 0)
			)
			(min_thickness 0.25)
			(keepout
				(tracks not_allowed)
				(vias allowed)
				(pads allowed)
				(copperpour not_allowed)
				(footprints allowed)
			)
			(placement
				(enabled no)
				(sheetname "")
			)
			(fill
				(thermal_gap 0.5)
				(thermal_bridge_width 0.5)
				(island_removal_mode 0)
			)
			(polygon
				(pts
					(arc
						(start 109.746796 -18.750026)
						(mid 108.552996 -18.750026)
						(end 109.746796 -18.750026)
					)
				)
			)
		)
		(zone
			(layer "F.Cu")
			(hatch none 0.5)
			(connect_pads
				(clearance 0)
			)
			(min_thickness 0.25)
			(keepout
				(tracks allowed)
				(vias not_allowed)
				(pads allowed)
				(copperpour not_allowed)
				(footprints allowed)
			)
			(placement
				(enabled no)
				(sheetname "")
			)
			(fill
				(thermal_gap 0.5)
				(thermal_bridge_width 0.5)
				(island_removal_mode 0)
			)
			(polygon
				(pts
					(arc
						(start 109.746796 -18.750026)
						(mid 108.552996 -18.750026)
						(end 109.746796 -18.750026)
					)
				)
			)
		)
		(zone
			(layer "F.Cu")
			(hatch none 0.5)
			(connect_pads
				(clearance 0)
			)
			(min_thickness 0.25)
			(keepout
				(tracks allowed)
				(vias not_allowed)
				(pads allowed)
				(copperpour not_allowed)
				(footprints allowed)
			)
			(placement
				(enabled no)
				(sheetname "")
			)
			(fill
				(thermal_gap 0.5)
				(thermal_bridge_width 0.5)
				(island_removal_mode 0)
			)
			(polygon
				(pts
					(arc
						(start 109.746796 -17.349978)
						(mid 108.552996 -17.349978)
						(end 109.746796 -17.349978)
					)
				)
			)
		)
		(zone
			(layer "F.Cu")
			(hatch none 0.5)
			(connect_pads
				(clearance 0)
			)
			(min_thickness 0.25)
			(keepout
				(tracks not_allowed)
				(vias allowed)
				(pads allowed)
				(copperpour not_allowed)
				(footprints allowed)
			)
			(placement
				(enabled no)
				(sheetname "")
			)
			(fill
				(thermal_gap 0.5)
				(thermal_bridge_width 0.5)
				(island_removal_mode 0)
			)
			(polygon
				(pts
					(arc
						(start 109.746796 -17.349978)
						(mid 108.552996 -17.349978)
						(end 109.746796 -17.349978)
					)
				)
			)
		)
		(zone
			(layer "F.Cu")
			(hatch none 0.5)
			(connect_pads
				(clearance 0)
			)
			(min_thickness 0.25)
			(keepout
				(tracks allowed)
				(vias not_allowed)
				(pads allowed)
				(copperpour not_allowed)
				(footprints allowed)
			)
			(placement
				(enabled no)
				(sheetname "")
			)
			(fill
				(thermal_gap 0.5)
				(thermal_bridge_width 0.5)
				(island_removal_mode 0)
			)
			(polygon
				(pts
					(arc
						(start 111.546894 -23.35022)
						(mid 110.353094 -23.35022)
						(end 111.546894 -23.35022)
					)
				)
			)
		)
		(zone
			(layer "F.Cu")
			(hatch none 0.5)
			(connect_pads
				(clearance 0)
			)
			(min_thickness 0.25)
			(keepout
				(tracks not_allowed)
				(vias allowed)
				(pads allowed)
				(copperpour not_allowed)
				(footprints allowed)
			)
			(placement
				(enabled no)
				(sheetname "")
			)
			(fill
				(thermal_gap 0.5)
				(thermal_bridge_width 0.5)
				(island_removal_mode 0)
			)
			(polygon
				(pts
					(arc
						(start 111.546894 -23.35022)
						(mid 110.353094 -23.35022)
						(end 111.546894 -23.35022)
					)
				)
			)
		)
		(zone
			(layer "F.Cu")
			(hatch none 0.5)
			(connect_pads
				(clearance 0)
			)
			(min_thickness 0.25)
			(keepout
				(tracks not_allowed)
				(vias allowed)
				(pads allowed)
				(copperpour not_allowed)
				(footprints allowed)
			)
			(placement
				(enabled no)
				(sheetname "")
			)
			(fill
				(thermal_gap 0.5)
				(thermal_bridge_width 0.5)
				(island_removal_mode 0)
			)
			(polygon
				(pts
					(arc
						(start 111.546894 -21.950172)
						(mid 110.353094 -21.950172)
						(end 111.546894 -21.950172)
					)
				)
			)
		)
		(zone
			(layer "F.Cu")
			(hatch none 0.5)
			(connect_pads
				(clearance 0)
			)
			(min_thickness 0.25)
			(keepout
				(tracks allowed)
				(vias not_allowed)
				(pads allowed)
				(copperpour not_allowed)
				(footprints allowed)
			)
			(placement
				(enabled no)
				(sheetname "")
			)
			(fill
				(thermal_gap 0.5)
				(thermal_bridge_width 0.5)
				(island_removal_mode 0)
			)
			(polygon
				(pts
					(arc
						(start 111.546894 -21.950172)
						(mid 110.353094 -21.950172)
						(end 111.546894 -21.950172)
					)
				)
			)
		)
		(zone
			(layer "F.Cu")
			(hatch none 0.5)
			(connect_pads
				(clearance 0)
			)
			(min_thickness 0.25)
			(keepout
				(tracks allowed)
				(vias not_allowed)
				(pads allowed)
				(copperpour not_allowed)
				(footprints allowed)
			)
			(placement
				(enabled no)
				(sheetname "")
			)
			(fill
				(thermal_gap 0.5)
				(thermal_bridge_width 0.5)
				(island_removal_mode 0)
			)
			(polygon
				(pts
					(arc
						(start 111.546894 -19.750024)
						(mid 110.353094 -19.750024)
						(end 111.546894 -19.750024)
					)
				)
			)
		)
		(zone
			(layer "F.Cu")
			(hatch none 0.5)
			(connect_pads
				(clearance 0)
			)
			(min_thickness 0.25)
			(keepout
				(tracks not_allowed)
				(vias allowed)
				(pads allowed)
				(copperpour not_allowed)
				(footprints allowed)
			)
			(placement
				(enabled no)
				(sheetname "")
			)
			(fill
				(thermal_gap 0.5)
				(thermal_bridge_width 0.5)
				(island_removal_mode 0)
			)
			(polygon
				(pts
					(arc
						(start 111.546894 -19.750024)
						(mid 110.353094 -19.750024)
						(end 111.546894 -19.750024)
					)
				)
			)
		)
		(zone
			(layer "F.Cu")
			(hatch none 0.5)
			(connect_pads
				(clearance 0)
			)
			(min_thickness 0.25)
			(keepout
				(tracks allowed)
				(vias not_allowed)
				(pads allowed)
				(copperpour not_allowed)
				(footprints allowed)
			)
			(placement
				(enabled no)
				(sheetname "")
			)
			(fill
				(thermal_gap 0.5)
				(thermal_bridge_width 0.5)
				(island_removal_mode 0)
			)
			(polygon
				(pts
					(arc
						(start 111.546894 -18.35023)
						(mid 110.353094 -18.35023)
						(end 111.546894 -18.35023)
					)
				)
			)
		)
		(zone
			(layer "F.Cu")
			(hatch none 0.5)
			(connect_pads
				(clearance 0)
			)
			(min_thickness 0.25)
			(keepout
				(tracks not_allowed)
				(vias allowed)
				(pads allowed)
				(copperpour not_allowed)
				(footprints allowed)
			)
			(placement
				(enabled no)
				(sheetname "")
			)
			(fill
				(thermal_gap 0.5)
				(thermal_bridge_width 0.5)
				(island_removal_mode 0)
			)
			(polygon
				(pts
					(arc
						(start 111.546894 -18.35023)
						(mid 110.353094 -18.35023)
						(end 111.546894 -18.35023)
					)
				)
			)
		)
		(zone
			(layer "F.Cu")
			(hatch none 0.5)
			(connect_pads
				(clearance 0)
			)
			(min_thickness 0.25)
			(keepout
				(tracks allowed)
				(vias not_allowed)
				(pads allowed)
				(copperpour not_allowed)
				(footprints allowed)
			)
			(placement
				(enabled no)
				(sheetname "")
			)
			(fill
				(thermal_gap 0.5)
				(thermal_bridge_width 0.5)
				(island_removal_mode 0)
			)
			(polygon
				(pts
					(arc
						(start 113.346992 -22.350222)
						(mid 112.153192 -22.350222)
						(end 113.346992 -22.350222)
					)
				)
			)
		)
		(zone
			(layer "F.Cu")
			(hatch none 0.5)
			(connect_pads
				(clearance 0)
			)
			(min_thickness 0.25)
			(keepout
				(tracks not_allowed)
				(vias allowed)
				(pads allowed)
				(copperpour not_allowed)
				(footprints allowed)
			)
			(placement
				(enabled no)
				(sheetname "")
			)
			(fill
				(thermal_gap 0.5)
				(thermal_bridge_width 0.5)
				(island_removal_mode 0)
			)
			(polygon
				(pts
					(arc
						(start 113.346992 -22.350222)
						(mid 112.153192 -22.350222)
						(end 113.346992 -22.350222)
					)
				)
			)
		)
		(zone
			(layer "F.Cu")
			(hatch none 0.5)
			(connect_pads
				(clearance 0)
			)
			(min_thickness 0.25)
			(keepout
				(tracks not_allowed)
				(vias allowed)
				(pads allowed)
				(copperpour not_allowed)
				(footprints allowed)
			)
			(placement
				(enabled no)
				(sheetname "")
			)
			(fill
				(thermal_gap 0.5)
				(thermal_bridge_width 0.5)
				(island_removal_mode 0)
			)
			(polygon
				(pts
					(arc
						(start 113.346992 -20.950174)
						(mid 112.153192 -20.950174)
						(end 113.346992 -20.950174)
					)
				)
			)
		)
		(zone
			(layer "F.Cu")
			(hatch none 0.5)
			(connect_pads
				(clearance 0)
			)
			(min_thickness 0.25)
			(keepout
				(tracks allowed)
				(vias not_allowed)
				(pads allowed)
				(copperpour not_allowed)
				(footprints allowed)
			)
			(placement
				(enabled no)
				(sheetname "")
			)
			(fill
				(thermal_gap 0.5)
				(thermal_bridge_width 0.5)
				(island_removal_mode 0)
			)
			(polygon
				(pts
					(arc
						(start 113.346992 -20.950174)
						(mid 112.153192 -20.950174)
						(end 113.346992 -20.950174)
					)
				)
			)
		)
		(zone
			(layer "F.Cu")
			(hatch none 0.5)
			(connect_pads
				(clearance 0)
			)
			(min_thickness 0.25)
			(keepout
				(tracks not_allowed)
				(vias allowed)
				(pads allowed)
				(copperpour not_allowed)
				(footprints allowed)
			)
			(placement
				(enabled no)
				(sheetname "")
			)
			(fill
				(thermal_gap 0.5)
				(thermal_bridge_width 0.5)
				(island_removal_mode 0)
			)
			(polygon
				(pts
					(arc
						(start 113.346992 -18.750026)
						(mid 112.153192 -18.750026)
						(end 113.346992 -18.750026)
					)
				)
			)
		)
		(zone
			(layer "F.Cu")
			(hatch none 0.5)
			(connect_pads
				(clearance 0)
			)
			(min_thickness 0.25)
			(keepout
				(tracks allowed)
				(vias not_allowed)
				(pads allowed)
				(copperpour not_allowed)
				(footprints allowed)
			)
			(placement
				(enabled no)
				(sheetname "")
			)
			(fill
				(thermal_gap 0.5)
				(thermal_bridge_width 0.5)
				(island_removal_mode 0)
			)
			(polygon
				(pts
					(arc
						(start 113.346992 -18.750026)
						(mid 112.153192 -18.750026)
						(end 113.346992 -18.750026)
					)
				)
			)
		)
		(zone
			(layer "F.Cu")
			(hatch none 0.5)
			(connect_pads
				(clearance 0)
			)
			(min_thickness 0.25)
			(keepout
				(tracks not_allowed)
				(vias allowed)
				(pads allowed)
				(copperpour not_allowed)
				(footprints allowed)
			)
			(placement
				(enabled no)
				(sheetname "")
			)
			(fill
				(thermal_gap 0.5)
				(thermal_bridge_width 0.5)
				(island_removal_mode 0)
			)
			(polygon
				(pts
					(arc
						(start 113.346992 -17.349978)
						(mid 112.153192 -17.349978)
						(end 113.346992 -17.349978)
					)
				)
			)
		)
		(zone
			(layer "F.Cu")
			(hatch none 0.5)
			(connect_pads
				(clearance 0)
			)
			(min_thickness 0.25)
			(keepout
				(tracks allowed)
				(vias not_allowed)
				(pads allowed)
				(copperpour not_allowed)
				(footprints allowed)
			)
			(placement
				(enabled no)
				(sheetname "")
			)
			(fill
				(thermal_gap 0.5)
				(thermal_bridge_width 0.5)
				(island_removal_mode 0)
			)
			(polygon
				(pts
					(arc
						(start 113.346992 -17.349978)
						(mid 112.153192 -17.349978)
						(end 113.346992 -17.349978)
					)
				)
			)
		)
		(zone
			(layer "F.Cu")
			(hatch none 0.5)
			(connect_pads
				(clearance 0)
			)
			(min_thickness 0.25)
			(keepout
				(tracks allowed)
				(vias not_allowed)
				(pads allowed)
				(copperpour not_allowed)
				(footprints allowed)
			)
			(placement
				(enabled no)
				(sheetname "")
			)
			(fill
				(thermal_gap 0.5)
				(thermal_bridge_width 0.5)
				(island_removal_mode 0)
			)
			(polygon
				(pts
					(arc
						(start 115.146836 -23.35022)
						(mid 113.953036 -23.35022)
						(end 115.146836 -23.35022)
					)
				)
			)
		)
		(zone
			(layer "F.Cu")
			(hatch none 0.5)
			(connect_pads
				(clearance 0)
			)
			(min_thickness 0.25)
			(keepout
				(tracks not_allowed)
				(vias allowed)
				(pads allowed)
				(copperpour not_allowed)
				(footprints allowed)
			)
			(placement
				(enabled no)
				(sheetname "")
			)
			(fill
				(thermal_gap 0.5)
				(thermal_bridge_width 0.5)
				(island_removal_mode 0)
			)
			(polygon
				(pts
					(arc
						(start 115.146836 -23.35022)
						(mid 113.953036 -23.35022)
						(end 115.146836 -23.35022)
					)
				)
			)
		)
		(zone
			(layer "F.Cu")
			(hatch none 0.5)
			(connect_pads
				(clearance 0)
			)
			(min_thickness 0.25)
			(keepout
				(tracks not_allowed)
				(vias allowed)
				(pads allowed)
				(copperpour not_allowed)
				(footprints allowed)
			)
			(placement
				(enabled no)
				(sheetname "")
			)
			(fill
				(thermal_gap 0.5)
				(thermal_bridge_width 0.5)
				(island_removal_mode 0)
			)
			(polygon
				(pts
					(arc
						(start 115.146836 -21.950172)
						(mid 113.953036 -21.950172)
						(end 115.146836 -21.950172)
					)
				)
			)
		)
		(zone
			(layer "F.Cu")
			(hatch none 0.5)
			(connect_pads
				(clearance 0)
			)
			(min_thickness 0.25)
			(keepout
				(tracks allowed)
				(vias not_allowed)
				(pads allowed)
				(copperpour not_allowed)
				(footprints allowed)
			)
			(placement
				(enabled no)
				(sheetname "")
			)
			(fill
				(thermal_gap 0.5)
				(thermal_bridge_width 0.5)
				(island_removal_mode 0)
			)
			(polygon
				(pts
					(arc
						(start 115.146836 -21.950172)
						(mid 113.953036 -21.950172)
						(end 115.146836 -21.950172)
					)
				)
			)
		)
		(zone
			(layer "F.Cu")
			(hatch none 0.5)
			(connect_pads
				(clearance 0)
			)
			(min_thickness 0.25)
			(keepout
				(tracks allowed)
				(vias not_allowed)
				(pads allowed)
				(copperpour not_allowed)
				(footprints allowed)
			)
			(placement
				(enabled no)
				(sheetname "")
			)
			(fill
				(thermal_gap 0.5)
				(thermal_bridge_width 0.5)
				(island_removal_mode 0)
			)
			(polygon
				(pts
					(arc
						(start 115.146836 -19.750024)
						(mid 113.953036 -19.750024)
						(end 115.146836 -19.750024)
					)
				)
			)
		)
		(zone
			(layer "F.Cu")
			(hatch none 0.5)
			(connect_pads
				(clearance 0)
			)
			(min_thickness 0.25)
			(keepout
				(tracks not_allowed)
				(vias allowed)
				(pads allowed)
				(copperpour not_allowed)
				(footprints allowed)
			)
			(placement
				(enabled no)
				(sheetname "")
			)
			(fill
				(thermal_gap 0.5)
				(thermal_bridge_width 0.5)
				(island_removal_mode 0)
			)
			(polygon
				(pts
					(arc
						(start 115.146836 -19.750024)
						(mid 113.953036 -19.750024)
						(end 115.146836 -19.750024)
					)
				)
			)
		)
		(zone
			(layer "F.Cu")
			(hatch none 0.5)
			(connect_pads
				(clearance 0)
			)
			(min_thickness 0.25)
			(keepout
				(tracks not_allowed)
				(vias allowed)
				(pads allowed)
				(copperpour not_allowed)
				(footprints allowed)
			)
			(placement
				(enabled no)
				(sheetname "")
			)
			(fill
				(thermal_gap 0.5)
				(thermal_bridge_width 0.5)
				(island_removal_mode 0)
			)
			(polygon
				(pts
					(arc
						(start 115.146836 -18.35023)
						(mid 113.953036 -18.35023)
						(end 115.146836 -18.35023)
					)
				)
			)
		)
		(zone
			(layer "F.Cu")
			(hatch none 0.5)
			(connect_pads
				(clearance 0)
			)
			(min_thickness 0.25)
			(keepout
				(tracks allowed)
				(vias not_allowed)
				(pads allowed)
				(copperpour not_allowed)
				(footprints allowed)
			)
			(placement
				(enabled no)
				(sheetname "")
			)
			(fill
				(thermal_gap 0.5)
				(thermal_bridge_width 0.5)
				(island_removal_mode 0)
			)
			(polygon
				(pts
					(arc
						(start 115.146836 -18.35023)
						(mid 113.953036 -18.35023)
						(end 115.146836 -18.35023)
					)
				)
			)
		)
		(zone
			(layer "F.Cu")
			(hatch none 0.5)
			(connect_pads
				(clearance 0)
			)
			(min_thickness 0.25)
			(keepout
				(tracks allowed)
				(vias not_allowed)
				(pads allowed)
				(copperpour not_allowed)
				(footprints allowed)
			)
			(placement
				(enabled no)
				(sheetname "")
			)
			(fill
				(thermal_gap 0.5)
				(thermal_bridge_width 0.5)
				(island_removal_mode 0)
			)
			(polygon
				(pts
					(arc
						(start 116.946934 -22.350222)
						(mid 115.753134 -22.350222)
						(end 116.946934 -22.350222)
					)
				)
			)
		)
		(zone
			(layer "F.Cu")
			(hatch none 0.5)
			(connect_pads
				(clearance 0)
			)
			(min_thickness 0.25)
			(keepout
				(tracks not_allowed)
				(vias allowed)
				(pads allowed)
				(copperpour not_allowed)
				(footprints allowed)
			)
			(placement
				(enabled no)
				(sheetname "")
			)
			(fill
				(thermal_gap 0.5)
				(thermal_bridge_width 0.5)
				(island_removal_mode 0)
			)
			(polygon
				(pts
					(arc
						(start 116.946934 -22.350222)
						(mid 115.753134 -22.350222)
						(end 116.946934 -22.350222)
					)
				)
			)
		)
		(zone
			(layer "F.Cu")
			(hatch none 0.5)
			(connect_pads
				(clearance 0)
			)
			(min_thickness 0.25)
			(keepout
				(tracks allowed)
				(vias not_allowed)
				(pads allowed)
				(copperpour not_allowed)
				(footprints allowed)
			)
			(placement
				(enabled no)
				(sheetname "")
			)
			(fill
				(thermal_gap 0.5)
				(thermal_bridge_width 0.5)
				(island_removal_mode 0)
			)
			(polygon
				(pts
					(arc
						(start 116.946934 -20.950174)
						(mid 115.753134 -20.950174)
						(end 116.946934 -20.950174)
					)
				)
			)
		)
		(zone
			(layer "F.Cu")
			(hatch none 0.5)
			(connect_pads
				(clearance 0)
			)
			(min_thickness 0.25)
			(keepout
				(tracks not_allowed)
				(vias allowed)
				(pads allowed)
				(copperpour not_allowed)
				(footprints allowed)
			)
			(placement
				(enabled no)
				(sheetname "")
			)
			(fill
				(thermal_gap 0.5)
				(thermal_bridge_width 0.5)
				(island_removal_mode 0)
			)
			(polygon
				(pts
					(arc
						(start 116.946934 -20.950174)
						(mid 115.753134 -20.950174)
						(end 116.946934 -20.950174)
					)
				)
			)
		)
		(zone
			(layer "F.Cu")
			(hatch none 0.5)
			(connect_pads
				(clearance 0)
			)
			(min_thickness 0.25)
			(keepout
				(tracks not_allowed)
				(vias allowed)
				(pads allowed)
				(copperpour not_allowed)
				(footprints allowed)
			)
			(placement
				(enabled no)
				(sheetname "")
			)
			(fill
				(thermal_gap 0.5)
				(thermal_bridge_width 0.5)
				(island_removal_mode 0)
			)
			(polygon
				(pts
					(arc
						(start 116.946934 -18.750026)
						(mid 115.753134 -18.750026)
						(end 116.946934 -18.750026)
					)
				)
			)
		)
		(zone
			(layer "F.Cu")
			(hatch none 0.5)
			(connect_pads
				(clearance 0)
			)
			(min_thickness 0.25)
			(keepout
				(tracks allowed)
				(vias not_allowed)
				(pads allowed)
				(copperpour not_allowed)
				(footprints allowed)
			)
			(placement
				(enabled no)
				(sheetname "")
			)
			(fill
				(thermal_gap 0.5)
				(thermal_bridge_width 0.5)
				(island_removal_mode 0)
			)
			(polygon
				(pts
					(arc
						(start 116.946934 -18.750026)
						(mid 115.753134 -18.750026)
						(end 116.946934 -18.750026)
					)
				)
			)
		)
		(zone
			(layer "F.Cu")
			(hatch none 0.5)
			(connect_pads
				(clearance 0)
			)
			(min_thickness 0.25)
			(keepout
				(tracks allowed)
				(vias not_allowed)
				(pads allowed)
				(copperpour not_allowed)
				(footprints allowed)
			)
			(placement
				(enabled no)
				(sheetname "")
			)
			(fill
				(thermal_gap 0.5)
				(thermal_bridge_width 0.5)
				(island_removal_mode 0)
			)
			(polygon
				(pts
					(arc
						(start 116.946934 -17.349978)
						(mid 115.753134 -17.349978)
						(end 116.946934 -17.349978)
					)
				)
			)
		)
		(zone
			(layer "F.Cu")
			(hatch none 0.5)
			(connect_pads
				(clearance 0)
			)
			(min_thickness 0.25)
			(keepout
				(tracks not_allowed)
				(vias allowed)
				(pads allowed)
				(copperpour not_allowed)
				(footprints allowed)
			)
			(placement
				(enabled no)
				(sheetname "")
			)
			(fill
				(thermal_gap 0.5)
				(thermal_bridge_width 0.5)
				(island_removal_mode 0)
			)
			(polygon
				(pts
					(arc
						(start 116.946934 -17.349978)
						(mid 115.753134 -17.349978)
						(end 116.946934 -17.349978)
					)
				)
			)
		)
		(zone
			(layer "F.Cu")
			(hatch none 0.5)
			(connect_pads
				(clearance 0)
			)
			(min_thickness 0.25)
			(keepout
				(tracks not_allowed)
				(vias allowed)
				(pads allowed)
				(copperpour not_allowed)
				(footprints allowed)
			)
			(placement
				(enabled no)
				(sheetname "")
			)
			(fill
				(thermal_gap 0.5)
				(thermal_bridge_width 0.5)
				(island_removal_mode 0)
			)
			(polygon
				(pts
					(arc
						(start 118.746778 -23.35022)
						(mid 117.552978 -23.35022)
						(end 118.746778 -23.35022)
					)
				)
			)
		)
		(zone
			(layer "F.Cu")
			(hatch none 0.5)
			(connect_pads
				(clearance 0)
			)
			(min_thickness 0.25)
			(keepout
				(tracks allowed)
				(vias not_allowed)
				(pads allowed)
				(copperpour not_allowed)
				(footprints allowed)
			)
			(placement
				(enabled no)
				(sheetname "")
			)
			(fill
				(thermal_gap 0.5)
				(thermal_bridge_width 0.5)
				(island_removal_mode 0)
			)
			(polygon
				(pts
					(arc
						(start 118.746778 -23.35022)
						(mid 117.552978 -23.35022)
						(end 118.746778 -23.35022)
					)
				)
			)
		)
		(zone
			(layer "F.Cu")
			(hatch none 0.5)
			(connect_pads
				(clearance 0)
			)
			(min_thickness 0.25)
			(keepout
				(tracks allowed)
				(vias not_allowed)
				(pads allowed)
				(copperpour not_allowed)
				(footprints allowed)
			)
			(placement
				(enabled no)
				(sheetname "")
			)
			(fill
				(thermal_gap 0.5)
				(thermal_bridge_width 0.5)
				(island_removal_mode 0)
			)
			(polygon
				(pts
					(arc
						(start 118.746778 -21.950172)
						(mid 117.552978 -21.950172)
						(end 118.746778 -21.950172)
					)
				)
			)
		)
		(zone
			(layer "F.Cu")
			(hatch none 0.5)
			(connect_pads
				(clearance 0)
			)
			(min_thickness 0.25)
			(keepout
				(tracks not_allowed)
				(vias allowed)
				(pads allowed)
				(copperpour not_allowed)
				(footprints allowed)
			)
			(placement
				(enabled no)
				(sheetname "")
			)
			(fill
				(thermal_gap 0.5)
				(thermal_bridge_width 0.5)
				(island_removal_mode 0)
			)
			(polygon
				(pts
					(arc
						(start 118.746778 -21.950172)
						(mid 117.552978 -21.950172)
						(end 118.746778 -21.950172)
					)
				)
			)
		)
		(zone
			(layer "F.Cu")
			(hatch none 0.5)
			(connect_pads
				(clearance 0)
			)
			(min_thickness 0.25)
			(keepout
				(tracks allowed)
				(vias not_allowed)
				(pads allowed)
				(copperpour not_allowed)
				(footprints allowed)
			)
			(placement
				(enabled no)
				(sheetname "")
			)
			(fill
				(thermal_gap 0.5)
				(thermal_bridge_width 0.5)
				(island_removal_mode 0)
			)
			(polygon
				(pts
					(arc
						(start 118.746778 -19.750024)
						(mid 117.552978 -19.750024)
						(end 118.746778 -19.750024)
					)
				)
			)
		)
		(zone
			(layer "F.Cu")
			(hatch none 0.5)
			(connect_pads
				(clearance 0)
			)
			(min_thickness 0.25)
			(keepout
				(tracks not_allowed)
				(vias allowed)
				(pads allowed)
				(copperpour not_allowed)
				(footprints allowed)
			)
			(placement
				(enabled no)
				(sheetname "")
			)
			(fill
				(thermal_gap 0.5)
				(thermal_bridge_width 0.5)
				(island_removal_mode 0)
			)
			(polygon
				(pts
					(arc
						(start 118.746778 -19.750024)
						(mid 117.552978 -19.750024)
						(end 118.746778 -19.750024)
					)
				)
			)
		)
		(zone
			(layer "F.Cu")
			(hatch none 0.5)
			(connect_pads
				(clearance 0)
			)
			(min_thickness 0.25)
			(keepout
				(tracks allowed)
				(vias not_allowed)
				(pads allowed)
				(copperpour not_allowed)
				(footprints allowed)
			)
			(placement
				(enabled no)
				(sheetname "")
			)
			(fill
				(thermal_gap 0.5)
				(thermal_bridge_width 0.5)
				(island_removal_mode 0)
			)
			(polygon
				(pts
					(arc
						(start 118.746778 -18.35023)
						(mid 117.552978 -18.35023)
						(end 118.746778 -18.35023)
					)
				)
			)
		)
		(zone
			(layer "F.Cu")
			(hatch none 0.5)
			(connect_pads
				(clearance 0)
			)
			(min_thickness 0.25)
			(keepout
				(tracks not_allowed)
				(vias allowed)
				(pads allowed)
				(copperpour not_allowed)
				(footprints allowed)
			)
			(placement
				(enabled no)
				(sheetname "")
			)
			(fill
				(thermal_gap 0.5)
				(thermal_bridge_width 0.5)
				(island_removal_mode 0)
			)
			(polygon
				(pts
					(arc
						(start 118.746778 -18.35023)
						(mid 117.552978 -18.35023)
						(end 118.746778 -18.35023)
					)
				)
			)
		)
		(zone
			(layer "F.Cu")
			(hatch none 0.5)
			(connect_pads
				(clearance 0)
			)
			(min_thickness 0.25)
			(keepout
				(tracks not_allowed)
				(vias allowed)
				(pads allowed)
				(copperpour not_allowed)
				(footprints allowed)
			)
			(placement
				(enabled no)
				(sheetname "")
			)
			(fill
				(thermal_gap 0.5)
				(thermal_bridge_width 0.5)
				(island_removal_mode 0)
			)
			(polygon
				(pts
					(arc
						(start 120.546876 -22.350222)
						(mid 119.353076 -22.350222)
						(end 120.546876 -22.350222)
					)
				)
			)
		)
		(zone
			(layer "F.Cu")
			(hatch none 0.5)
			(connect_pads
				(clearance 0)
			)
			(min_thickness 0.25)
			(keepout
				(tracks allowed)
				(vias not_allowed)
				(pads allowed)
				(copperpour not_allowed)
				(footprints allowed)
			)
			(placement
				(enabled no)
				(sheetname "")
			)
			(fill
				(thermal_gap 0.5)
				(thermal_bridge_width 0.5)
				(island_removal_mode 0)
			)
			(polygon
				(pts
					(arc
						(start 120.546876 -22.350222)
						(mid 119.353076 -22.350222)
						(end 120.546876 -22.350222)
					)
				)
			)
		)
		(zone
			(layer "F.Cu")
			(hatch none 0.5)
			(connect_pads
				(clearance 0)
			)
			(min_thickness 0.25)
			(keepout
				(tracks allowed)
				(vias not_allowed)
				(pads allowed)
				(copperpour not_allowed)
				(footprints allowed)
			)
			(placement
				(enabled no)
				(sheetname "")
			)
			(fill
				(thermal_gap 0.5)
				(thermal_bridge_width 0.5)
				(island_removal_mode 0)
			)
			(polygon
				(pts
					(arc
						(start 120.546876 -20.950174)
						(mid 119.353076 -20.950174)
						(end 120.546876 -20.950174)
					)
				)
			)
		)
		(zone
			(layer "F.Cu")
			(hatch none 0.5)
			(connect_pads
				(clearance 0)
			)
			(min_thickness 0.25)
			(keepout
				(tracks not_allowed)
				(vias allowed)
				(pads allowed)
				(copperpour not_allowed)
				(footprints allowed)
			)
			(placement
				(enabled no)
				(sheetname "")
			)
			(fill
				(thermal_gap 0.5)
				(thermal_bridge_width 0.5)
				(island_removal_mode 0)
			)
			(polygon
				(pts
					(arc
						(start 120.546876 -20.950174)
						(mid 119.353076 -20.950174)
						(end 120.546876 -20.950174)
					)
				)
			)
		)
		(zone
			(layer "F.Cu")
			(hatch none 0.5)
			(connect_pads
				(clearance 0)
			)
			(min_thickness 0.25)
			(keepout
				(tracks allowed)
				(vias not_allowed)
				(pads allowed)
				(copperpour not_allowed)
				(footprints allowed)
			)
			(placement
				(enabled no)
				(sheetname "")
			)
			(fill
				(thermal_gap 0.5)
				(thermal_bridge_width 0.5)
				(island_removal_mode 0)
			)
			(polygon
				(pts
					(arc
						(start 120.546876 -18.750026)
						(mid 119.353076 -18.750026)
						(end 120.546876 -18.750026)
					)
				)
			)
		)
		(zone
			(layer "F.Cu")
			(hatch none 0.5)
			(connect_pads
				(clearance 0)
			)
			(min_thickness 0.25)
			(keepout
				(tracks not_allowed)
				(vias allowed)
				(pads allowed)
				(copperpour not_allowed)
				(footprints allowed)
			)
			(placement
				(enabled no)
				(sheetname "")
			)
			(fill
				(thermal_gap 0.5)
				(thermal_bridge_width 0.5)
				(island_removal_mode 0)
			)
			(polygon
				(pts
					(arc
						(start 120.546876 -18.750026)
						(mid 119.353076 -18.750026)
						(end 120.546876 -18.750026)
					)
				)
			)
		)
		(zone
			(layer "F.Cu")
			(hatch none 0.5)
			(connect_pads
				(clearance 0)
			)
			(min_thickness 0.25)
			(keepout
				(tracks allowed)
				(vias not_allowed)
				(pads allowed)
				(copperpour not_allowed)
				(footprints allowed)
			)
			(placement
				(enabled no)
				(sheetname "")
			)
			(fill
				(thermal_gap 0.5)
				(thermal_bridge_width 0.5)
				(island_removal_mode 0)
			)
			(polygon
				(pts
					(arc
						(start 120.546876 -17.349978)
						(mid 119.353076 -17.349978)
						(end 120.546876 -17.349978)
					)
				)
			)
		)
		(zone
			(layer "F.Cu")
			(hatch none 0.5)
			(connect_pads
				(clearance 0)
			)
			(min_thickness 0.25)
			(keepout
				(tracks not_allowed)
				(vias allowed)
				(pads allowed)
				(copperpour not_allowed)
				(footprints allowed)
			)
			(placement
				(enabled no)
				(sheetname "")
			)
			(fill
				(thermal_gap 0.5)
				(thermal_bridge_width 0.5)
				(island_removal_mode 0)
			)
			(polygon
				(pts
					(arc
						(start 120.546876 -17.349978)
						(mid 119.353076 -17.349978)
						(end 120.546876 -17.349978)
					)
				)
			)
		)
		(zone
			(layer "F.Cu")
			(hatch none 0.5)
			(connect_pads
				(clearance 0)
			)
			(min_thickness 0.25)
			(keepout
				(tracks allowed)
				(vias not_allowed)
				(pads allowed)
				(copperpour not_allowed)
				(footprints allowed)
			)
			(placement
				(enabled no)
				(sheetname "")
			)
			(fill
				(thermal_gap 0.5)
				(thermal_bridge_width 0.5)
				(island_removal_mode 0)
			)
			(polygon
				(pts
					(arc
						(start 122.346974 -23.35022)
						(mid 121.153174 -23.35022)
						(end 122.346974 -23.35022)
					)
				)
			)
		)
		(zone
			(layer "F.Cu")
			(hatch none 0.5)
			(connect_pads
				(clearance 0)
			)
			(min_thickness 0.25)
			(keepout
				(tracks not_allowed)
				(vias allowed)
				(pads allowed)
				(copperpour not_allowed)
				(footprints allowed)
			)
			(placement
				(enabled no)
				(sheetname "")
			)
			(fill
				(thermal_gap 0.5)
				(thermal_bridge_width 0.5)
				(island_removal_mode 0)
			)
			(polygon
				(pts
					(arc
						(start 122.346974 -23.35022)
						(mid 121.153174 -23.35022)
						(end 122.346974 -23.35022)
					)
				)
			)
		)
		(zone
			(layer "F.Cu")
			(hatch none 0.5)
			(connect_pads
				(clearance 0)
			)
			(min_thickness 0.25)
			(keepout
				(tracks not_allowed)
				(vias allowed)
				(pads allowed)
				(copperpour not_allowed)
				(footprints allowed)
			)
			(placement
				(enabled no)
				(sheetname "")
			)
			(fill
				(thermal_gap 0.5)
				(thermal_bridge_width 0.5)
				(island_removal_mode 0)
			)
			(polygon
				(pts
					(arc
						(start 122.346974 -21.950172)
						(mid 121.153174 -21.950172)
						(end 122.346974 -21.950172)
					)
				)
			)
		)
		(zone
			(layer "F.Cu")
			(hatch none 0.5)
			(connect_pads
				(clearance 0)
			)
			(min_thickness 0.25)
			(keepout
				(tracks allowed)
				(vias not_allowed)
				(pads allowed)
				(copperpour not_allowed)
				(footprints allowed)
			)
			(placement
				(enabled no)
				(sheetname "")
			)
			(fill
				(thermal_gap 0.5)
				(thermal_bridge_width 0.5)
				(island_removal_mode 0)
			)
			(polygon
				(pts
					(arc
						(start 122.346974 -21.950172)
						(mid 121.153174 -21.950172)
						(end 122.346974 -21.950172)
					)
				)
			)
		)
		(zone
			(layer "F.Cu")
			(hatch none 0.5)
			(connect_pads
				(clearance 0)
			)
			(min_thickness 0.25)
			(keepout
				(tracks allowed)
				(vias not_allowed)
				(pads allowed)
				(copperpour not_allowed)
				(footprints allowed)
			)
			(placement
				(enabled no)
				(sheetname "")
			)
			(fill
				(thermal_gap 0.5)
				(thermal_bridge_width 0.5)
				(island_removal_mode 0)
			)
			(polygon
				(pts
					(arc
						(start 122.346974 -19.750024)
						(mid 121.153174 -19.750024)
						(end 122.346974 -19.750024)
					)
				)
			)
		)
		(zone
			(layer "F.Cu")
			(hatch none 0.5)
			(connect_pads
				(clearance 0)
			)
			(min_thickness 0.25)
			(keepout
				(tracks not_allowed)
				(vias allowed)
				(pads allowed)
				(copperpour not_allowed)
				(footprints allowed)
			)
			(placement
				(enabled no)
				(sheetname "")
			)
			(fill
				(thermal_gap 0.5)
				(thermal_bridge_width 0.5)
				(island_removal_mode 0)
			)
			(polygon
				(pts
					(arc
						(start 122.346974 -19.750024)
						(mid 121.153174 -19.750024)
						(end 122.346974 -19.750024)
					)
				)
			)
		)
		(zone
			(layer "F.Cu")
			(hatch none 0.5)
			(connect_pads
				(clearance 0)
			)
			(min_thickness 0.25)
			(keepout
				(tracks allowed)
				(vias not_allowed)
				(pads allowed)
				(copperpour not_allowed)
				(footprints allowed)
			)
			(placement
				(enabled no)
				(sheetname "")
			)
			(fill
				(thermal_gap 0.5)
				(thermal_bridge_width 0.5)
				(island_removal_mode 0)
			)
			(polygon
				(pts
					(arc
						(start 122.346974 -18.35023)
						(mid 121.153174 -18.35023)
						(end 122.346974 -18.35023)
					)
				)
			)
		)
		(zone
			(layer "F.Cu")
			(hatch none 0.5)
			(connect_pads
				(clearance 0)
			)
			(min_thickness 0.25)
			(keepout
				(tracks not_allowed)
				(vias allowed)
				(pads allowed)
				(copperpour not_allowed)
				(footprints allowed)
			)
			(placement
				(enabled no)
				(sheetname "")
			)
			(fill
				(thermal_gap 0.5)
				(thermal_bridge_width 0.5)
				(island_removal_mode 0)
			)
			(polygon
				(pts
					(arc
						(start 122.346974 -18.35023)
						(mid 121.153174 -18.35023)
						(end 122.346974 -18.35023)
					)
				)
			)
		)
		(zone
			(layer "F.Cu")
			(hatch none 0.5)
			(connect_pads
				(clearance 0)
			)
			(min_thickness 0.25)
			(keepout
				(tracks not_allowed)
				(vias allowed)
				(pads allowed)
				(copperpour not_allowed)
				(footprints allowed)
			)
			(placement
				(enabled no)
				(sheetname "")
			)
			(fill
				(thermal_gap 0.5)
				(thermal_bridge_width 0.5)
				(island_removal_mode 0)
			)
			(polygon
				(pts
					(arc
						(start 131.346956 -22.350222)
						(mid 130.153156 -22.350222)
						(end 131.346956 -22.350222)
					)
				)
			)
		)
		(zone
			(layer "F.Cu")
			(hatch none 0.5)
			(connect_pads
				(clearance 0)
			)
			(min_thickness 0.25)
			(keepout
				(tracks allowed)
				(vias not_allowed)
				(pads allowed)
				(copperpour not_allowed)
				(footprints allowed)
			)
			(placement
				(enabled no)
				(sheetname "")
			)
			(fill
				(thermal_gap 0.5)
				(thermal_bridge_width 0.5)
				(island_removal_mode 0)
			)
			(polygon
				(pts
					(arc
						(start 131.346956 -22.350222)
						(mid 130.153156 -22.350222)
						(end 131.346956 -22.350222)
					)
				)
			)
		)
		(zone
			(layer "F.Cu")
			(hatch none 0.5)
			(connect_pads
				(clearance 0)
			)
			(min_thickness 0.25)
			(keepout
				(tracks not_allowed)
				(vias allowed)
				(pads allowed)
				(copperpour not_allowed)
				(footprints allowed)
			)
			(placement
				(enabled no)
				(sheetname "")
			)
			(fill
				(thermal_gap 0.5)
				(thermal_bridge_width 0.5)
				(island_removal_mode 0)
			)
			(polygon
				(pts
					(arc
						(start 131.346956 -20.950174)
						(mid 130.153156 -20.950174)
						(end 131.346956 -20.950174)
					)
				)
			)
		)
		(zone
			(layer "F.Cu")
			(hatch none 0.5)
			(connect_pads
				(clearance 0)
			)
			(min_thickness 0.25)
			(keepout
				(tracks allowed)
				(vias not_allowed)
				(pads allowed)
				(copperpour not_allowed)
				(footprints allowed)
			)
			(placement
				(enabled no)
				(sheetname "")
			)
			(fill
				(thermal_gap 0.5)
				(thermal_bridge_width 0.5)
				(island_removal_mode 0)
			)
			(polygon
				(pts
					(arc
						(start 131.346956 -20.950174)
						(mid 130.153156 -20.950174)
						(end 131.346956 -20.950174)
					)
				)
			)
		)
		(zone
			(layer "F.Cu")
			(hatch none 0.5)
			(connect_pads
				(clearance 0)
			)
			(min_thickness 0.25)
			(keepout
				(tracks not_allowed)
				(vias allowed)
				(pads allowed)
				(copperpour not_allowed)
				(footprints allowed)
			)
			(placement
				(enabled no)
				(sheetname "")
			)
			(fill
				(thermal_gap 0.5)
				(thermal_bridge_width 0.5)
				(island_removal_mode 0)
			)
			(polygon
				(pts
					(arc
						(start 131.346956 -18.750026)
						(mid 130.153156 -18.750026)
						(end 131.346956 -18.750026)
					)
				)
			)
		)
		(zone
			(layer "F.Cu")
			(hatch none 0.5)
			(connect_pads
				(clearance 0)
			)
			(min_thickness 0.25)
			(keepout
				(tracks allowed)
				(vias not_allowed)
				(pads allowed)
				(copperpour not_allowed)
				(footprints allowed)
			)
			(placement
				(enabled no)
				(sheetname "")
			)
			(fill
				(thermal_gap 0.5)
				(thermal_bridge_width 0.5)
				(island_removal_mode 0)
			)
			(polygon
				(pts
					(arc
						(start 131.346956 -18.750026)
						(mid 130.153156 -18.750026)
						(end 131.346956 -18.750026)
					)
				)
			)
		)
		(zone
			(layer "F.Cu")
			(hatch none 0.5)
			(connect_pads
				(clearance 0)
			)
			(min_thickness 0.25)
			(keepout
				(tracks allowed)
				(vias not_allowed)
				(pads allowed)
				(copperpour not_allowed)
				(footprints allowed)
			)
			(placement
				(enabled no)
				(sheetname "")
			)
			(fill
				(thermal_gap 0.5)
				(thermal_bridge_width 0.5)
				(island_removal_mode 0)
			)
			(polygon
				(pts
					(arc
						(start 131.346956 -17.349978)
						(mid 130.153156 -17.349978)
						(end 131.346956 -17.349978)
					)
				)
			)
		)
		(zone
			(layer "F.Cu")
			(hatch none 0.5)
			(connect_pads
				(clearance 0)
			)
			(min_thickness 0.25)
			(keepout
				(tracks not_allowed)
				(vias allowed)
				(pads allowed)
				(copperpour not_allowed)
				(footprints allowed)
			)
			(placement
				(enabled no)
				(sheetname "")
			)
			(fill
				(thermal_gap 0.5)
				(thermal_bridge_width 0.5)
				(island_removal_mode 0)
			)
			(polygon
				(pts
					(arc
						(start 131.346956 -17.349978)
						(mid 130.153156 -17.349978)
						(end 131.346956 -17.349978)
					)
				)
			)
		)
		(zone
			(layer "F.Cu")
			(hatch none 0.5)
			(connect_pads
				(clearance 0)
			)
			(min_thickness 0.25)
			(keepout
				(tracks not_allowed)
				(vias allowed)
				(pads allowed)
				(copperpour not_allowed)
				(footprints allowed)
			)
			(placement
				(enabled no)
				(sheetname "")
			)
			(fill
				(thermal_gap 0.5)
				(thermal_bridge_width 0.5)
				(island_removal_mode 0)
			)
			(polygon
				(pts
					(arc
						(start 133.1468 -23.35022)
						(mid 131.953 -23.35022)
						(end 133.1468 -23.35022)
					)
				)
			)
		)
		(zone
			(layer "F.Cu")
			(hatch none 0.5)
			(connect_pads
				(clearance 0)
			)
			(min_thickness 0.25)
			(keepout
				(tracks allowed)
				(vias not_allowed)
				(pads allowed)
				(copperpour not_allowed)
				(footprints allowed)
			)
			(placement
				(enabled no)
				(sheetname "")
			)
			(fill
				(thermal_gap 0.5)
				(thermal_bridge_width 0.5)
				(island_removal_mode 0)
			)
			(polygon
				(pts
					(arc
						(start 133.1468 -23.35022)
						(mid 131.953 -23.35022)
						(end 133.1468 -23.35022)
					)
				)
			)
		)
		(zone
			(layer "F.Cu")
			(hatch none 0.5)
			(connect_pads
				(clearance 0)
			)
			(min_thickness 0.25)
			(keepout
				(tracks allowed)
				(vias not_allowed)
				(pads allowed)
				(copperpour not_allowed)
				(footprints allowed)
			)
			(placement
				(enabled no)
				(sheetname "")
			)
			(fill
				(thermal_gap 0.5)
				(thermal_bridge_width 0.5)
				(island_removal_mode 0)
			)
			(polygon
				(pts
					(arc
						(start 133.1468 -21.950172)
						(mid 131.953 -21.950172)
						(end 133.1468 -21.950172)
					)
				)
			)
		)
		(zone
			(layer "F.Cu")
			(hatch none 0.5)
			(connect_pads
				(clearance 0)
			)
			(min_thickness 0.25)
			(keepout
				(tracks not_allowed)
				(vias allowed)
				(pads allowed)
				(copperpour not_allowed)
				(footprints allowed)
			)
			(placement
				(enabled no)
				(sheetname "")
			)
			(fill
				(thermal_gap 0.5)
				(thermal_bridge_width 0.5)
				(island_removal_mode 0)
			)
			(polygon
				(pts
					(arc
						(start 133.1468 -21.950172)
						(mid 131.953 -21.950172)
						(end 133.1468 -21.950172)
					)
				)
			)
		)
		(zone
			(layer "F.Cu")
			(hatch none 0.5)
			(connect_pads
				(clearance 0)
			)
			(min_thickness 0.25)
			(keepout
				(tracks allowed)
				(vias not_allowed)
				(pads allowed)
				(copperpour not_allowed)
				(footprints allowed)
			)
			(placement
				(enabled no)
				(sheetname "")
			)
			(fill
				(thermal_gap 0.5)
				(thermal_bridge_width 0.5)
				(island_removal_mode 0)
			)
			(polygon
				(pts
					(arc
						(start 133.1468 -19.750024)
						(mid 131.953 -19.750024)
						(end 133.1468 -19.750024)
					)
				)
			)
		)
		(zone
			(layer "F.Cu")
			(hatch none 0.5)
			(connect_pads
				(clearance 0)
			)
			(min_thickness 0.25)
			(keepout
				(tracks not_allowed)
				(vias allowed)
				(pads allowed)
				(copperpour not_allowed)
				(footprints allowed)
			)
			(placement
				(enabled no)
				(sheetname "")
			)
			(fill
				(thermal_gap 0.5)
				(thermal_bridge_width 0.5)
				(island_removal_mode 0)
			)
			(polygon
				(pts
					(arc
						(start 133.1468 -19.750024)
						(mid 131.953 -19.750024)
						(end 133.1468 -19.750024)
					)
				)
			)
		)
		(zone
			(layer "F.Cu")
			(hatch none 0.5)
			(connect_pads
				(clearance 0)
			)
			(min_thickness 0.25)
			(keepout
				(tracks not_allowed)
				(vias allowed)
				(pads allowed)
				(copperpour not_allowed)
				(footprints allowed)
			)
			(placement
				(enabled no)
				(sheetname "")
			)
			(fill
				(thermal_gap 0.5)
				(thermal_bridge_width 0.5)
				(island_removal_mode 0)
			)
			(polygon
				(pts
					(arc
						(start 133.1468 -18.35023)
						(mid 131.953 -18.35023)
						(end 133.1468 -18.35023)
					)
				)
			)
		)
		(zone
			(layer "F.Cu")
			(hatch none 0.5)
			(connect_pads
				(clearance 0)
			)
			(min_thickness 0.25)
			(keepout
				(tracks allowed)
				(vias not_allowed)
				(pads allowed)
				(copperpour not_allowed)
				(footprints allowed)
			)
			(placement
				(enabled no)
				(sheetname "")
			)
			(fill
				(thermal_gap 0.5)
				(thermal_bridge_width 0.5)
				(island_removal_mode 0)
			)
			(polygon
				(pts
					(arc
						(start 133.1468 -18.35023)
						(mid 131.953 -18.35023)
						(end 133.1468 -18.35023)
					)
				)
			)
		)
		(zone
			(layer "F.Cu")
			(hatch none 0.5)
			(connect_pads
				(clearance 0)
			)
			(min_thickness 0.25)
			(keepout
				(tracks allowed)
				(vias not_allowed)
				(pads allowed)
				(copperpour not_allowed)
				(footprints allowed)
			)
			(placement
				(enabled no)
				(sheetname "")
			)
			(fill
				(thermal_gap 0.5)
				(thermal_bridge_width 0.5)
				(island_removal_mode 0)
			)
			(polygon
				(pts
					(arc
						(start 134.946898 -22.350222)
						(mid 133.753098 -22.350222)
						(end 134.946898 -22.350222)
					)
				)
			)
		)
		(zone
			(layer "F.Cu")
			(hatch none 0.5)
			(connect_pads
				(clearance 0)
			)
			(min_thickness 0.25)
			(keepout
				(tracks not_allowed)
				(vias allowed)
				(pads allowed)
				(copperpour not_allowed)
				(footprints allowed)
			)
			(placement
				(enabled no)
				(sheetname "")
			)
			(fill
				(thermal_gap 0.5)
				(thermal_bridge_width 0.5)
				(island_removal_mode 0)
			)
			(polygon
				(pts
					(arc
						(start 134.946898 -22.350222)
						(mid 133.753098 -22.350222)
						(end 134.946898 -22.350222)
					)
				)
			)
		)
		(zone
			(layer "F.Cu")
			(hatch none 0.5)
			(connect_pads
				(clearance 0)
			)
			(min_thickness 0.25)
			(keepout
				(tracks not_allowed)
				(vias allowed)
				(pads allowed)
				(copperpour not_allowed)
				(footprints allowed)
			)
			(placement
				(enabled no)
				(sheetname "")
			)
			(fill
				(thermal_gap 0.5)
				(thermal_bridge_width 0.5)
				(island_removal_mode 0)
			)
			(polygon
				(pts
					(arc
						(start 134.946898 -20.950174)
						(mid 133.753098 -20.950174)
						(end 134.946898 -20.950174)
					)
				)
			)
		)
		(zone
			(layer "F.Cu")
			(hatch none 0.5)
			(connect_pads
				(clearance 0)
			)
			(min_thickness 0.25)
			(keepout
				(tracks allowed)
				(vias not_allowed)
				(pads allowed)
				(copperpour not_allowed)
				(footprints allowed)
			)
			(placement
				(enabled no)
				(sheetname "")
			)
			(fill
				(thermal_gap 0.5)
				(thermal_bridge_width 0.5)
				(island_removal_mode 0)
			)
			(polygon
				(pts
					(arc
						(start 134.946898 -20.950174)
						(mid 133.753098 -20.950174)
						(end 134.946898 -20.950174)
					)
				)
			)
		)
		(zone
			(layer "F.Cu")
			(hatch none 0.5)
			(connect_pads
				(clearance 0)
			)
			(min_thickness 0.25)
			(keepout
				(tracks not_allowed)
				(vias allowed)
				(pads allowed)
				(copperpour not_allowed)
				(footprints allowed)
			)
			(placement
				(enabled no)
				(sheetname "")
			)
			(fill
				(thermal_gap 0.5)
				(thermal_bridge_width 0.5)
				(island_removal_mode 0)
			)
			(polygon
				(pts
					(arc
						(start 134.946898 -18.750026)
						(mid 133.753098 -18.750026)
						(end 134.946898 -18.750026)
					)
				)
			)
		)
		(zone
			(layer "F.Cu")
			(hatch none 0.5)
			(connect_pads
				(clearance 0)
			)
			(min_thickness 0.25)
			(keepout
				(tracks allowed)
				(vias not_allowed)
				(pads allowed)
				(copperpour not_allowed)
				(footprints allowed)
			)
			(placement
				(enabled no)
				(sheetname "")
			)
			(fill
				(thermal_gap 0.5)
				(thermal_bridge_width 0.5)
				(island_removal_mode 0)
			)
			(polygon
				(pts
					(arc
						(start 134.946898 -18.750026)
						(mid 133.753098 -18.750026)
						(end 134.946898 -18.750026)
					)
				)
			)
		)
		(zone
			(layer "F.Cu")
			(hatch none 0.5)
			(connect_pads
				(clearance 0)
			)
			(min_thickness 0.25)
			(keepout
				(tracks allowed)
				(vias not_allowed)
				(pads allowed)
				(copperpour not_allowed)
				(footprints allowed)
			)
			(placement
				(enabled no)
				(sheetname "")
			)
			(fill
				(thermal_gap 0.5)
				(thermal_bridge_width 0.5)
				(island_removal_mode 0)
			)
			(polygon
				(pts
					(arc
						(start 134.946898 -17.349978)
						(mid 133.753098 -17.349978)
						(end 134.946898 -17.349978)
					)
				)
			)
		)
		(zone
			(layer "F.Cu")
			(hatch none 0.5)
			(connect_pads
				(clearance 0)
			)
			(min_thickness 0.25)
			(keepout
				(tracks not_allowed)
				(vias allowed)
				(pads allowed)
				(copperpour not_allowed)
				(footprints allowed)
			)
			(placement
				(enabled no)
				(sheetname "")
			)
			(fill
				(thermal_gap 0.5)
				(thermal_bridge_width 0.5)
				(island_removal_mode 0)
			)
			(polygon
				(pts
					(arc
						(start 134.946898 -17.349978)
						(mid 133.753098 -17.349978)
						(end 134.946898 -17.349978)
					)
				)
			)
		)
		(zone
			(layer "F.Cu")
			(hatch none 0.5)
			(connect_pads
				(clearance 0)
			)
			(min_thickness 0.25)
			(keepout
				(tracks not_allowed)
				(vias allowed)
				(pads allowed)
				(copperpour not_allowed)
				(footprints allowed)
			)
			(placement
				(enabled no)
				(sheetname "")
			)
			(fill
				(thermal_gap 0.5)
				(thermal_bridge_width 0.5)
				(island_removal_mode 0)
			)
			(polygon
				(pts
					(arc
						(start 136.746996 -23.35022)
						(mid 135.553196 -23.35022)
						(end 136.746996 -23.35022)
					)
				)
			)
		)
		(zone
			(layer "F.Cu")
			(hatch none 0.5)
			(connect_pads
				(clearance 0)
			)
			(min_thickness 0.25)
			(keepout
				(tracks allowed)
				(vias not_allowed)
				(pads allowed)
				(copperpour not_allowed)
				(footprints allowed)
			)
			(placement
				(enabled no)
				(sheetname "")
			)
			(fill
				(thermal_gap 0.5)
				(thermal_bridge_width 0.5)
				(island_removal_mode 0)
			)
			(polygon
				(pts
					(arc
						(start 136.746996 -23.35022)
						(mid 135.553196 -23.35022)
						(end 136.746996 -23.35022)
					)
				)
			)
		)
		(zone
			(layer "F.Cu")
			(hatch none 0.5)
			(connect_pads
				(clearance 0)
			)
			(min_thickness 0.25)
			(keepout
				(tracks not_allowed)
				(vias allowed)
				(pads allowed)
				(copperpour not_allowed)
				(footprints allowed)
			)
			(placement
				(enabled no)
				(sheetname "")
			)
			(fill
				(thermal_gap 0.5)
				(thermal_bridge_width 0.5)
				(island_removal_mode 0)
			)
			(polygon
				(pts
					(arc
						(start 136.746996 -21.950172)
						(mid 135.553196 -21.950172)
						(end 136.746996 -21.950172)
					)
				)
			)
		)
		(zone
			(layer "F.Cu")
			(hatch none 0.5)
			(connect_pads
				(clearance 0)
			)
			(min_thickness 0.25)
			(keepout
				(tracks allowed)
				(vias not_allowed)
				(pads allowed)
				(copperpour not_allowed)
				(footprints allowed)
			)
			(placement
				(enabled no)
				(sheetname "")
			)
			(fill
				(thermal_gap 0.5)
				(thermal_bridge_width 0.5)
				(island_removal_mode 0)
			)
			(polygon
				(pts
					(arc
						(start 136.746996 -21.950172)
						(mid 135.553196 -21.950172)
						(end 136.746996 -21.950172)
					)
				)
			)
		)
		(zone
			(layer "F.Cu")
			(hatch none 0.5)
			(connect_pads
				(clearance 0)
			)
			(min_thickness 0.25)
			(keepout
				(tracks allowed)
				(vias not_allowed)
				(pads allowed)
				(copperpour not_allowed)
				(footprints allowed)
			)
			(placement
				(enabled no)
				(sheetname "")
			)
			(fill
				(thermal_gap 0.5)
				(thermal_bridge_width 0.5)
				(island_removal_mode 0)
			)
			(polygon
				(pts
					(arc
						(start 136.746996 -19.750024)
						(mid 135.553196 -19.750024)
						(end 136.746996 -19.750024)
					)
				)
			)
		)
		(zone
			(layer "F.Cu")
			(hatch none 0.5)
			(connect_pads
				(clearance 0)
			)
			(min_thickness 0.25)
			(keepout
				(tracks not_allowed)
				(vias allowed)
				(pads allowed)
				(copperpour not_allowed)
				(footprints allowed)
			)
			(placement
				(enabled no)
				(sheetname "")
			)
			(fill
				(thermal_gap 0.5)
				(thermal_bridge_width 0.5)
				(island_removal_mode 0)
			)
			(polygon
				(pts
					(arc
						(start 136.746996 -19.750024)
						(mid 135.553196 -19.750024)
						(end 136.746996 -19.750024)
					)
				)
			)
		)
		(zone
			(layer "F.Cu")
			(hatch none 0.5)
			(connect_pads
				(clearance 0)
			)
			(min_thickness 0.25)
			(keepout
				(tracks allowed)
				(vias not_allowed)
				(pads allowed)
				(copperpour not_allowed)
				(footprints allowed)
			)
			(placement
				(enabled no)
				(sheetname "")
			)
			(fill
				(thermal_gap 0.5)
				(thermal_bridge_width 0.5)
				(island_removal_mode 0)
			)
			(polygon
				(pts
					(arc
						(start 136.746996 -18.35023)
						(mid 135.553196 -18.35023)
						(end 136.746996 -18.35023)
					)
				)
			)
		)
		(zone
			(layer "F.Cu")
			(hatch none 0.5)
			(connect_pads
				(clearance 0)
			)
			(min_thickness 0.25)
			(keepout
				(tracks not_allowed)
				(vias allowed)
				(pads allowed)
				(copperpour not_allowed)
				(footprints allowed)
			)
			(placement
				(enabled no)
				(sheetname "")
			)
			(fill
				(thermal_gap 0.5)
				(thermal_bridge_width 0.5)
				(island_removal_mode 0)
			)
			(polygon
				(pts
					(arc
						(start 136.746996 -18.35023)
						(mid 135.553196 -18.35023)
						(end 136.746996 -18.35023)
					)
				)
			)
		)
		(zone
			(layer "F.Cu")
			(hatch none 0.5)
			(connect_pads
				(clearance 0)
			)
			(min_thickness 0.25)
			(keepout
				(tracks not_allowed)
				(vias allowed)
				(pads allowed)
				(copperpour not_allowed)
				(footprints allowed)
			)
			(placement
				(enabled no)
				(sheetname "")
			)
			(fill
				(thermal_gap 0.5)
				(thermal_bridge_width 0.5)
				(island_removal_mode 0)
			)
			(polygon
				(pts
					(arc
						(start 138.54684 -22.350222)
						(mid 137.35304 -22.350222)
						(end 138.54684 -22.350222)
					)
				)
			)
		)
		(zone
			(layer "F.Cu")
			(hatch none 0.5)
			(connect_pads
				(clearance 0)
			)
			(min_thickness 0.25)
			(keepout
				(tracks allowed)
				(vias not_allowed)
				(pads allowed)
				(copperpour not_allowed)
				(footprints allowed)
			)
			(placement
				(enabled no)
				(sheetname "")
			)
			(fill
				(thermal_gap 0.5)
				(thermal_bridge_width 0.5)
				(island_removal_mode 0)
			)
			(polygon
				(pts
					(arc
						(start 138.54684 -22.350222)
						(mid 137.35304 -22.350222)
						(end 138.54684 -22.350222)
					)
				)
			)
		)
		(zone
			(layer "F.Cu")
			(hatch none 0.5)
			(connect_pads
				(clearance 0)
			)
			(min_thickness 0.25)
			(keepout
				(tracks allowed)
				(vias not_allowed)
				(pads allowed)
				(copperpour not_allowed)
				(footprints allowed)
			)
			(placement
				(enabled no)
				(sheetname "")
			)
			(fill
				(thermal_gap 0.5)
				(thermal_bridge_width 0.5)
				(island_removal_mode 0)
			)
			(polygon
				(pts
					(arc
						(start 138.54684 -20.950174)
						(mid 137.35304 -20.950174)
						(end 138.54684 -20.950174)
					)
				)
			)
		)
		(zone
			(layer "F.Cu")
			(hatch none 0.5)
			(connect_pads
				(clearance 0)
			)
			(min_thickness 0.25)
			(keepout
				(tracks not_allowed)
				(vias allowed)
				(pads allowed)
				(copperpour not_allowed)
				(footprints allowed)
			)
			(placement
				(enabled no)
				(sheetname "")
			)
			(fill
				(thermal_gap 0.5)
				(thermal_bridge_width 0.5)
				(island_removal_mode 0)
			)
			(polygon
				(pts
					(arc
						(start 138.54684 -20.950174)
						(mid 137.35304 -20.950174)
						(end 138.54684 -20.950174)
					)
				)
			)
		)
		(zone
			(layer "F.Cu")
			(hatch none 0.5)
			(connect_pads
				(clearance 0)
			)
			(min_thickness 0.25)
			(keepout
				(tracks not_allowed)
				(vias allowed)
				(pads allowed)
				(copperpour not_allowed)
				(footprints allowed)
			)
			(placement
				(enabled no)
				(sheetname "")
			)
			(fill
				(thermal_gap 0.5)
				(thermal_bridge_width 0.5)
				(island_removal_mode 0)
			)
			(polygon
				(pts
					(arc
						(start 138.54684 -18.750026)
						(mid 137.35304 -18.750026)
						(end 138.54684 -18.750026)
					)
				)
			)
		)
		(zone
			(layer "F.Cu")
			(hatch none 0.5)
			(connect_pads
				(clearance 0)
			)
			(min_thickness 0.25)
			(keepout
				(tracks allowed)
				(vias not_allowed)
				(pads allowed)
				(copperpour not_allowed)
				(footprints allowed)
			)
			(placement
				(enabled no)
				(sheetname "")
			)
			(fill
				(thermal_gap 0.5)
				(thermal_bridge_width 0.5)
				(island_removal_mode 0)
			)
			(polygon
				(pts
					(arc
						(start 138.54684 -18.750026)
						(mid 137.35304 -18.750026)
						(end 138.54684 -18.750026)
					)
				)
			)
		)
		(zone
			(layer "F.Cu")
			(hatch none 0.5)
			(connect_pads
				(clearance 0)
			)
			(min_thickness 0.25)
			(keepout
				(tracks not_allowed)
				(vias allowed)
				(pads allowed)
				(copperpour not_allowed)
				(footprints allowed)
			)
			(placement
				(enabled no)
				(sheetname "")
			)
			(fill
				(thermal_gap 0.5)
				(thermal_bridge_width 0.5)
				(island_removal_mode 0)
			)
			(polygon
				(pts
					(arc
						(start 138.54684 -17.349978)
						(mid 137.35304 -17.349978)
						(end 138.54684 -17.349978)
					)
				)
			)
		)
		(zone
			(layer "F.Cu")
			(hatch none 0.5)
			(connect_pads
				(clearance 0)
			)
			(min_thickness 0.25)
			(keepout
				(tracks allowed)
				(vias not_allowed)
				(pads allowed)
				(copperpour not_allowed)
				(footprints allowed)
			)
			(placement
				(enabled no)
				(sheetname "")
			)
			(fill
				(thermal_gap 0.5)
				(thermal_bridge_width 0.5)
				(island_removal_mode 0)
			)
			(polygon
				(pts
					(arc
						(start 138.54684 -17.349978)
						(mid 137.35304 -17.349978)
						(end 138.54684 -17.349978)
					)
				)
			)
		)
		(zone
			(layer "F.Cu")
			(hatch none 0.5)
			(connect_pads
				(clearance 0)
			)
			(min_thickness 0.25)
			(keepout
				(tracks allowed)
				(vias not_allowed)
				(pads allowed)
				(copperpour not_allowed)
				(footprints allowed)
			)
			(placement
				(enabled no)
				(sheetname "")
			)
			(fill
				(thermal_gap 0.5)
				(thermal_bridge_width 0.5)
				(island_removal_mode 0)
			)
			(polygon
				(pts
					(arc
						(start 140.346938 -23.35022)
						(mid 139.153138 -23.35022)
						(end 140.346938 -23.35022)
					)
				)
			)
		)
		(zone
			(layer "F.Cu")
			(hatch none 0.5)
			(connect_pads
				(clearance 0)
			)
			(min_thickness 0.25)
			(keepout
				(tracks not_allowed)
				(vias allowed)
				(pads allowed)
				(copperpour not_allowed)
				(footprints allowed)
			)
			(placement
				(enabled no)
				(sheetname "")
			)
			(fill
				(thermal_gap 0.5)
				(thermal_bridge_width 0.5)
				(island_removal_mode 0)
			)
			(polygon
				(pts
					(arc
						(start 140.346938 -23.35022)
						(mid 139.153138 -23.35022)
						(end 140.346938 -23.35022)
					)
				)
			)
		)
		(zone
			(layer "F.Cu")
			(hatch none 0.5)
			(connect_pads
				(clearance 0)
			)
			(min_thickness 0.25)
			(keepout
				(tracks allowed)
				(vias not_allowed)
				(pads allowed)
				(copperpour not_allowed)
				(footprints allowed)
			)
			(placement
				(enabled no)
				(sheetname "")
			)
			(fill
				(thermal_gap 0.5)
				(thermal_bridge_width 0.5)
				(island_removal_mode 0)
			)
			(polygon
				(pts
					(arc
						(start 140.346938 -21.950172)
						(mid 139.153138 -21.950172)
						(end 140.346938 -21.950172)
					)
				)
			)
		)
		(zone
			(layer "F.Cu")
			(hatch none 0.5)
			(connect_pads
				(clearance 0)
			)
			(min_thickness 0.25)
			(keepout
				(tracks not_allowed)
				(vias allowed)
				(pads allowed)
				(copperpour not_allowed)
				(footprints allowed)
			)
			(placement
				(enabled no)
				(sheetname "")
			)
			(fill
				(thermal_gap 0.5)
				(thermal_bridge_width 0.5)
				(island_removal_mode 0)
			)
			(polygon
				(pts
					(arc
						(start 140.346938 -21.950172)
						(mid 139.153138 -21.950172)
						(end 140.346938 -21.950172)
					)
				)
			)
		)
		(zone
			(layer "F.Cu")
			(hatch none 0.5)
			(connect_pads
				(clearance 0)
			)
			(min_thickness 0.25)
			(keepout
				(tracks allowed)
				(vias not_allowed)
				(pads allowed)
				(copperpour not_allowed)
				(footprints allowed)
			)
			(placement
				(enabled no)
				(sheetname "")
			)
			(fill
				(thermal_gap 0.5)
				(thermal_bridge_width 0.5)
				(island_removal_mode 0)
			)
			(polygon
				(pts
					(arc
						(start 140.346938 -19.750024)
						(mid 139.153138 -19.750024)
						(end 140.346938 -19.750024)
					)
				)
			)
		)
		(zone
			(layer "F.Cu")
			(hatch none 0.5)
			(connect_pads
				(clearance 0)
			)
			(min_thickness 0.25)
			(keepout
				(tracks not_allowed)
				(vias allowed)
				(pads allowed)
				(copperpour not_allowed)
				(footprints allowed)
			)
			(placement
				(enabled no)
				(sheetname "")
			)
			(fill
				(thermal_gap 0.5)
				(thermal_bridge_width 0.5)
				(island_removal_mode 0)
			)
			(polygon
				(pts
					(arc
						(start 140.346938 -19.750024)
						(mid 139.153138 -19.750024)
						(end 140.346938 -19.750024)
					)
				)
			)
		)
		(zone
			(layer "F.Cu")
			(hatch none 0.5)
			(connect_pads
				(clearance 0)
			)
			(min_thickness 0.25)
			(keepout
				(tracks not_allowed)
				(vias allowed)
				(pads allowed)
				(copperpour not_allowed)
				(footprints allowed)
			)
			(placement
				(enabled no)
				(sheetname "")
			)
			(fill
				(thermal_gap 0.5)
				(thermal_bridge_width 0.5)
				(island_removal_mode 0)
			)
			(polygon
				(pts
					(arc
						(start 140.346938 -18.35023)
						(mid 139.153138 -18.35023)
						(end 140.346938 -18.35023)
					)
				)
			)
		)
		(zone
			(layer "F.Cu")
			(hatch none 0.5)
			(connect_pads
				(clearance 0)
			)
			(min_thickness 0.25)
			(keepout
				(tracks allowed)
				(vias not_allowed)
				(pads allowed)
				(copperpour not_allowed)
				(footprints allowed)
			)
			(placement
				(enabled no)
				(sheetname "")
			)
			(fill
				(thermal_gap 0.5)
				(thermal_bridge_width 0.5)
				(island_removal_mode 0)
			)
			(polygon
				(pts
					(arc
						(start 140.346938 -18.35023)
						(mid 139.153138 -18.35023)
						(end 140.346938 -18.35023)
					)
				)
			)
		)
		(zone
			(layer "F.Cu")
			(hatch none 0.5)
			(connect_pads
				(clearance 0)
			)
			(min_thickness 0.25)
			(keepout
				(tracks allowed)
				(vias not_allowed)
				(pads allowed)
				(copperpour not_allowed)
				(footprints allowed)
			)
			(placement
				(enabled no)
				(sheetname "")
			)
			(fill
				(thermal_gap 0.5)
				(thermal_bridge_width 0.5)
				(island_removal_mode 0)
			)
			(polygon
				(pts
					(arc
						(start 142.146782 -22.350222)
						(mid 140.952982 -22.350222)
						(end 142.146782 -22.350222)
					)
				)
			)
		)
		(zone
			(layer "F.Cu")
			(hatch none 0.5)
			(connect_pads
				(clearance 0)
			)
			(min_thickness 0.25)
			(keepout
				(tracks not_allowed)
				(vias allowed)
				(pads allowed)
				(copperpour not_allowed)
				(footprints allowed)
			)
			(placement
				(enabled no)
				(sheetname "")
			)
			(fill
				(thermal_gap 0.5)
				(thermal_bridge_width 0.5)
				(island_removal_mode 0)
			)
			(polygon
				(pts
					(arc
						(start 142.146782 -22.350222)
						(mid 140.952982 -22.350222)
						(end 142.146782 -22.350222)
					)
				)
			)
		)
		(zone
			(layer "F.Cu")
			(hatch none 0.5)
			(connect_pads
				(clearance 0)
			)
			(min_thickness 0.25)
			(keepout
				(tracks allowed)
				(vias not_allowed)
				(pads allowed)
				(copperpour not_allowed)
				(footprints allowed)
			)
			(placement
				(enabled no)
				(sheetname "")
			)
			(fill
				(thermal_gap 0.5)
				(thermal_bridge_width 0.5)
				(island_removal_mode 0)
			)
			(polygon
				(pts
					(arc
						(start 142.146782 -20.950174)
						(mid 140.952982 -20.950174)
						(end 142.146782 -20.950174)
					)
				)
			)
		)
		(zone
			(layer "F.Cu")
			(hatch none 0.5)
			(connect_pads
				(clearance 0)
			)
			(min_thickness 0.25)
			(keepout
				(tracks not_allowed)
				(vias allowed)
				(pads allowed)
				(copperpour not_allowed)
				(footprints allowed)
			)
			(placement
				(enabled no)
				(sheetname "")
			)
			(fill
				(thermal_gap 0.5)
				(thermal_bridge_width 0.5)
				(island_removal_mode 0)
			)
			(polygon
				(pts
					(arc
						(start 142.146782 -20.950174)
						(mid 140.952982 -20.950174)
						(end 142.146782 -20.950174)
					)
				)
			)
		)
		(zone
			(layer "F.Cu")
			(hatch none 0.5)
			(connect_pads
				(clearance 0)
			)
			(min_thickness 0.25)
			(keepout
				(tracks allowed)
				(vias not_allowed)
				(pads allowed)
				(copperpour not_allowed)
				(footprints allowed)
			)
			(placement
				(enabled no)
				(sheetname "")
			)
			(fill
				(thermal_gap 0.5)
				(thermal_bridge_width 0.5)
				(island_removal_mode 0)
			)
			(polygon
				(pts
					(arc
						(start 142.146782 -18.750026)
						(mid 140.952982 -18.750026)
						(end 142.146782 -18.750026)
					)
				)
			)
		)
		(zone
			(layer "F.Cu")
			(hatch none 0.5)
			(connect_pads
				(clearance 0)
			)
			(min_thickness 0.25)
			(keepout
				(tracks not_allowed)
				(vias allowed)
				(pads allowed)
				(copperpour not_allowed)
				(footprints allowed)
			)
			(placement
				(enabled no)
				(sheetname "")
			)
			(fill
				(thermal_gap 0.5)
				(thermal_bridge_width 0.5)
				(island_removal_mode 0)
			)
			(polygon
				(pts
					(arc
						(start 142.146782 -18.750026)
						(mid 140.952982 -18.750026)
						(end 142.146782 -18.750026)
					)
				)
			)
		)
		(zone
			(layer "F.Cu")
			(hatch none 0.5)
			(connect_pads
				(clearance 0)
			)
			(min_thickness 0.25)
			(keepout
				(tracks not_allowed)
				(vias allowed)
				(pads allowed)
				(copperpour not_allowed)
				(footprints allowed)
			)
			(placement
				(enabled no)
				(sheetname "")
			)
			(fill
				(thermal_gap 0.5)
				(thermal_bridge_width 0.5)
				(island_removal_mode 0)
			)
			(polygon
				(pts
					(arc
						(start 142.146782 -17.349978)
						(mid 140.952982 -17.349978)
						(end 142.146782 -17.349978)
					)
				)
			)
		)
		(zone
			(layer "F.Cu")
			(hatch none 0.5)
			(connect_pads
				(clearance 0)
			)
			(min_thickness 0.25)
			(keepout
				(tracks allowed)
				(vias not_allowed)
				(pads allowed)
				(copperpour not_allowed)
				(footprints allowed)
			)
			(placement
				(enabled no)
				(sheetname "")
			)
			(fill
				(thermal_gap 0.5)
				(thermal_bridge_width 0.5)
				(island_removal_mode 0)
			)
			(polygon
				(pts
					(arc
						(start 142.146782 -17.349978)
						(mid 140.952982 -17.349978)
						(end 142.146782 -17.349978)
					)
				)
			)
		)
		(zone
			(layer "F.Cu")
			(hatch none 0.5)
			(connect_pads
				(clearance 0)
			)
			(min_thickness 0.25)
			(keepout
				(tracks allowed)
				(vias not_allowed)
				(pads allowed)
				(copperpour not_allowed)
				(footprints allowed)
			)
			(placement
				(enabled no)
				(sheetname "")
			)
			(fill
				(thermal_gap 0.5)
				(thermal_bridge_width 0.5)
				(island_removal_mode 0)
			)
			(polygon
				(pts
					(arc
						(start 143.94688 -23.35022)
						(mid 142.75308 -23.35022)
						(end 143.94688 -23.35022)
					)
				)
			)
		)
		(zone
			(layer "F.Cu")
			(hatch none 0.5)
			(connect_pads
				(clearance 0)
			)
			(min_thickness 0.25)
			(keepout
				(tracks not_allowed)
				(vias allowed)
				(pads allowed)
				(copperpour not_allowed)
				(footprints allowed)
			)
			(placement
				(enabled no)
				(sheetname "")
			)
			(fill
				(thermal_gap 0.5)
				(thermal_bridge_width 0.5)
				(island_removal_mode 0)
			)
			(polygon
				(pts
					(arc
						(start 143.94688 -23.35022)
						(mid 142.75308 -23.35022)
						(end 143.94688 -23.35022)
					)
				)
			)
		)
		(zone
			(layer "F.Cu")
			(hatch none 0.5)
			(connect_pads
				(clearance 0)
			)
			(min_thickness 0.25)
			(keepout
				(tracks allowed)
				(vias not_allowed)
				(pads allowed)
				(copperpour not_allowed)
				(footprints allowed)
			)
			(placement
				(enabled no)
				(sheetname "")
			)
			(fill
				(thermal_gap 0.5)
				(thermal_bridge_width 0.5)
				(island_removal_mode 0)
			)
			(polygon
				(pts
					(arc
						(start 143.94688 -21.950172)
						(mid 142.75308 -21.950172)
						(end 143.94688 -21.950172)
					)
				)
			)
		)
		(zone
			(layer "F.Cu")
			(hatch none 0.5)
			(connect_pads
				(clearance 0)
			)
			(min_thickness 0.25)
			(keepout
				(tracks not_allowed)
				(vias allowed)
				(pads allowed)
				(copperpour not_allowed)
				(footprints allowed)
			)
			(placement
				(enabled no)
				(sheetname "")
			)
			(fill
				(thermal_gap 0.5)
				(thermal_bridge_width 0.5)
				(island_removal_mode 0)
			)
			(polygon
				(pts
					(arc
						(start 143.94688 -21.950172)
						(mid 142.75308 -21.950172)
						(end 143.94688 -21.950172)
					)
				)
			)
		)
		(zone
			(layer "F.Cu")
			(hatch none 0.5)
			(connect_pads
				(clearance 0)
			)
			(min_thickness 0.25)
			(keepout
				(tracks not_allowed)
				(vias allowed)
				(pads allowed)
				(copperpour not_allowed)
				(footprints allowed)
			)
			(placement
				(enabled no)
				(sheetname "")
			)
			(fill
				(thermal_gap 0.5)
				(thermal_bridge_width 0.5)
				(island_removal_mode 0)
			)
			(polygon
				(pts
					(arc
						(start 143.94688 -19.750024)
						(mid 142.75308 -19.750024)
						(end 143.94688 -19.750024)
					)
				)
			)
		)
		(zone
			(layer "F.Cu")
			(hatch none 0.5)
			(connect_pads
				(clearance 0)
			)
			(min_thickness 0.25)
			(keepout
				(tracks allowed)
				(vias not_allowed)
				(pads allowed)
				(copperpour not_allowed)
				(footprints allowed)
			)
			(placement
				(enabled no)
				(sheetname "")
			)
			(fill
				(thermal_gap 0.5)
				(thermal_bridge_width 0.5)
				(island_removal_mode 0)
			)
			(polygon
				(pts
					(arc
						(start 143.94688 -19.750024)
						(mid 142.75308 -19.750024)
						(end 143.94688 -19.750024)
					)
				)
			)
		)
		(zone
			(layer "F.Cu")
			(hatch none 0.5)
			(connect_pads
				(clearance 0)
			)
			(min_thickness 0.25)
			(keepout
				(tracks allowed)
				(vias not_allowed)
				(pads allowed)
				(copperpour not_allowed)
				(footprints allowed)
			)
			(placement
				(enabled no)
				(sheetname "")
			)
			(fill
				(thermal_gap 0.5)
				(thermal_bridge_width 0.5)
				(island_removal_mode 0)
			)
			(polygon
				(pts
					(arc
						(start 143.94688 -18.35023)
						(mid 142.75308 -18.35023)
						(end 143.94688 -18.35023)
					)
				)
			)
		)
		(zone
			(layer "F.Cu")
			(hatch none 0.5)
			(connect_pads
				(clearance 0)
			)
			(min_thickness 0.25)
			(keepout
				(tracks not_allowed)
				(vias allowed)
				(pads allowed)
				(copperpour not_allowed)
				(footprints allowed)
			)
			(placement
				(enabled no)
				(sheetname "")
			)
			(fill
				(thermal_gap 0.5)
				(thermal_bridge_width 0.5)
				(island_removal_mode 0)
			)
			(polygon
				(pts
					(arc
						(start 143.94688 -18.35023)
						(mid 142.75308 -18.35023)
						(end 143.94688 -18.35023)
					)
				)
			)
		)
		(zone
			(layers "F.Cu" "B.Cu" "In1.Cu" "In2.Cu" "In3.Cu" "In4.Cu" "In5.Cu" "In6.Cu"
				"In7.Cu" "In8.Cu" "In9.Cu" "In10.Cu"
			)
			(hatch none 0.5)
			(connect_pads
				(clearance 0)
			)
			(min_thickness 0.25)
			(keepout
				(tracks not_allowed)
				(vias allowed)
				(pads allowed)
				(copperpour not_allowed)
				(footprints allowed)
			)
			(placement
				(enabled no)
				(sheetname "")
			)
			(fill
				(thermal_gap 0.5)
				(thermal_bridge_width 0.5)
				(island_removal_mode 0)
			)
			(polygon
				(pts
					(arc
						(start 127.648462 -20.550124)
						(mid 124.651262 -20.550124)
						(end 127.648462 -20.550124)
					)
				)
			)
		)
		(zone
			(layers "F.Cu" "B.Cu" "In1.Cu" "In2.Cu" "In3.Cu" "In4.Cu" "In5.Cu" "In6.Cu"
				"In7.Cu" "In8.Cu" "In9.Cu" "In10.Cu"
			)
			(hatch none 0.5)
			(connect_pads
				(clearance 0)
			)
			(min_thickness 0.25)
			(keepout
				(tracks not_allowed)
				(vias allowed)
				(pads allowed)
				(copperpour not_allowed)
				(footprints allowed)
			)
			(placement
				(enabled no)
				(sheetname "")
			)
			(fill
				(thermal_gap 0.5)
				(thermal_bridge_width 0.5)
				(island_removal_mode 0)
			)
			(polygon
				(pts
					(arc
						(start 127.686562 -28.080208)
						(mid 124.613162 -28.080208)
						(end 127.686562 -28.080208)
					)
				)
			)
		)
		(zone
			(layer "B.Cu")
			(hatch none 0.5)
			(connect_pads
				(clearance 0)
			)
			(min_thickness 0.25)
			(keepout
				(tracks not_allowed)
				(vias allowed)
				(pads allowed)
				(copperpour not_allowed)
				(footprints allowed)
			)
			(placement
				(enabled no)
				(sheetname "")
			)
			(fill
				(thermal_gap 0.5)
				(thermal_bridge_width 0.5)
				(island_removal_mode 0)
			)
			(polygon
				(pts
					(xy 122.730006 -34.29) (xy 129.480056 -34.29) (xy 129.480056 -15.000224) (xy 122.730006 -15.000224)
				)
			)
		)
		(zone
			(layer "B.Cu")
			(hatch none 0.5)
			(connect_pads
				(clearance 0)
			)
			(min_thickness 0.25)
			(keepout
				(tracks allowed)
				(vias not_allowed)
				(pads allowed)
				(copperpour not_allowed)
				(footprints allowed)
			)
			(placement
				(enabled no)
				(sheetname "")
			)
			(fill
				(thermal_gap 0.5)
				(thermal_bridge_width 0.5)
				(island_removal_mode 0)
			)
			(polygon
				(pts
					(xy 122.730006 -15.000224) (xy 122.730006 -34.29) (xy 129.480056 -34.29) (xy 129.480056 -15.000224)
				)
			)
		)
	)
	(footprint ""
		(layer "B.Cu")
		(at 480.949 -230.505)
		(property "Reference" "C668"
			(at 0 0 0)
			(layer "B.SilkS")
			(hide yes)
			(effects
				(font
					(size 1.27 1.27)
				)
				(justify mirror)
			)
		)
		(property "Value" "SC68P50V2JN-2-GP"
			(at -1.1811 -2.7051 0)
			(unlocked yes)
			(layer "B.Fab")
			(hide yes)
			(effects
				(font
					(size 1.016 1.016)
					(thickness 0.1524)
				)
				(justify mirror)
			)
		)
		(property "Device Type" "C402H22"
			(at -1.1811 -4.2291 0)
			(unlocked yes)
			(layer "B.Fab")
			(hide yes)
			(effects
				(font
					(size 1.016 1.016)
					(thickness 0.1524)
				)
				(justify mirror)
			)
		)
		(duplicate_pad_numbers_are_jumpers no)
		(fp_rect
			(start 0.4318 0.9525)
			(end -0.4318 -0.9525)
			(stroke
				(width 0)
				(type default)
			)
			(fill no)
			(layer "B.CrtYd")
		)
		(fp_rect
			(start 0.4318 0.9525)
			(end -0.4318 -0.9525)
			(stroke
				(width 0)
				(type default)
			)
			(fill no)
			(layer "B.Fab")
		)
		(pad "1" smd custom
			(at 0 -0.4445 180)
			(size 0.1524 0.1524)
			(layers "B.Cu" "B.Mask" "B.Paste")
			(net "P5V_D_VFB")
			(options
				(clearance outline)
				(anchor circle)
			)
			(primitives
				(gr_poly
					(pts
						(arc
							(start 0.3048 0.2032)
							(mid 0.275042 0.275042)
							(end 0.2032 0.3048)
						)
						(arc
							(start -0.2032 0.3048)
							(mid -0.275042 0.275042)
							(end -0.3048 0.2032)
						)
						(arc
							(start -0.3048 -0.2032)
							(mid -0.275042 -0.275042)
							(end -0.2032 -0.3048)
						)
						(arc
							(start 0.2032 -0.3048)
							(mid 0.275042 -0.275042)
							(end 0.3048 -0.2032)
						)
					)
					(width 0)
					(fill yes)
				)
			)
		)
		(pad "2" smd custom
			(at 0 0.4445 180)
			(size 0.1524 0.1524)
			(layers "B.Cu" "B.Mask" "B.Paste")
			(net "P5V_D_VFB_R")
			(options
				(clearance outline)
				(anchor circle)
			)
			(primitives
				(gr_poly
					(pts
						(arc
							(start 0.3048 0.2032)
							(mid 0.275042 0.275042)
							(end 0.2032 0.3048)
						)
						(arc
							(start -0.2032 0.3048)
							(mid -0.275042 0.275042)
							(end -0.3048 0.2032)
						)
						(arc
							(start -0.3048 -0.2032)
							(mid -0.275042 -0.275042)
							(end -0.2032 -0.3048)
						)
						(arc
							(start 0.2032 -0.3048)
							(mid 0.275042 -0.275042)
							(end 0.3048 -0.2032)
						)
					)
					(width 0)
					(fill yes)
				)
			)
		)
	)
	(footprint ""
		(layer "B.Cu")
		(at 476.572834 -238.700564)
		(property "Reference" "C659"
			(at 0 0 0)
			(layer "B.SilkS")
			(hide yes)
			(effects
				(font
					(size 1.27 1.27)
				)
				(justify mirror)
			)
		)
		(property "Value" "SC1U16V3KX-5GP"
			(at 0 -2.8194 0)
			(unlocked yes)
			(layer "B.Fab")
			(hide yes)
			(effects
				(font
					(size 1.016 1.016)
					(thickness 0.1524)
				)
				(justify mirror)
			)
		)
		(property "Device Type" "C603H36"
			(at 0 -4.3434 0)
			(unlocked yes)
			(layer "B.Fab")
			(hide yes)
			(effects
				(font
					(size 1.016 1.016)
					(thickness 0.1524)
				)
				(justify mirror)
			)
		)
		(duplicate_pad_numbers_are_jumpers no)
		(fp_line
			(start -0.508 0)
			(end 0.508 0)
			(stroke
				(width 0.2032)
				(type default)
			)
			(layer "B.SilkS")
		)
		(fp_rect
			(start 0.5842 1.3335)
			(end -0.5842 -1.3335)
			(stroke
				(width 0)
				(type default)
			)
			(fill no)
			(layer "B.CrtYd")
		)
		(fp_rect
			(start 0.5842 1.3335)
			(end -0.5842 -1.3335)
			(stroke
				(width 0)
				(type default)
			)
			(fill no)
			(layer "B.Fab")
		)
		(pad "1" smd custom
			(at 0 -0.762 180)
			(size 0.2159 0.2159)
			(layers "B.Cu" "B.Mask" "B.Paste")
			(net "GND")
			(options
				(clearance outline)
				(anchor circle)
			)
			(primitives
				(gr_poly
					(pts
						(arc
							(start -0.3302 0.4318)
							(mid -0.402042 0.402042)
							(end -0.4318 0.3302)
						)
						(arc
							(start -0.4318 -0.3302)
							(mid -0.402042 -0.402042)
							(end -0.3302 -0.4318)
						)
						(arc
							(start 0.3302 -0.4318)
							(mid 0.402042 -0.402042)
							(end 0.4318 -0.3302)
						)
						(arc
							(start 0.4318 0.3302)
							(mid 0.402042 0.402042)
							(end 0.3302 0.4318)
						)
					)
					(width 0)
					(fill yes)
				)
			)
		)
		(pad "2" smd custom
			(at 0 0.762 180)
			(size 0.2159 0.2159)
			(layers "B.Cu" "B.Mask" "B.Paste")
			(net "P5V_D_VREG")
			(options
				(clearance outline)
				(anchor circle)
			)
			(primitives
				(gr_poly
					(pts
						(arc
							(start -0.3302 0.4318)
							(mid -0.402042 0.402042)
							(end -0.4318 0.3302)
						)
						(arc
							(start -0.4318 -0.3302)
							(mid -0.402042 -0.402042)
							(end -0.3302 -0.4318)
						)
						(arc
							(start 0.3302 -0.4318)
							(mid 0.402042 -0.402042)
							(end 0.4318 -0.3302)
						)
						(arc
							(start 0.4318 0.3302)
							(mid 0.402042 0.402042)
							(end 0.3302 0.4318)
						)
					)
					(width 0)
					(fill yes)
				)
			)
		)
	)
	(footprint ""
		(layer "B.Cu")
		(at 445.9732 -256.3622)
		(property "Reference" "PG15"
			(at 0 0 0)
			(layer "B.SilkS")
			(hide yes)
			(effects
				(font
					(size 1.27 1.27)
				)
				(justify mirror)
			)
		)
		(property "Value" "COPPER-CLOSE-GP-U"
			(at -0.0762 -2.8702 0)
			(unlocked yes)
			(layer "B.Fab")
			(hide yes)
			(effects
				(font
					(size 1.016 1.016)
					(thickness 0.1524)
				)
				(justify mirror)
			)
		)
		(property "Device Type" "CON2C-U"
			(at -0.0762 -4.3942 0)
			(unlocked yes)
			(layer "B.Fab")
			(hide yes)
			(effects
				(font
					(size 1.016 1.016)
					(thickness 0.1524)
				)
				(justify mirror)
			)
		)
		(duplicate_pad_numbers_are_jumpers no)
		(fp_rect
			(start 0.9398 0.9652)
			(end -0.9398 -0.9652)
			(stroke
				(width 0)
				(type default)
			)
			(fill no)
			(layer "B.CrtYd")
		)
		(fp_rect
			(start 0.9398 0.9652)
			(end -0.9398 -0.9652)
			(stroke
				(width 0)
				(type default)
			)
			(fill no)
			(layer "B.Fab")
		)
		(pad "1" smd custom
			(at 0 -0.5334 180)
			(size 0.17145 0.17145)
			(layers "B.Cu" "B.Mask" "B.Paste")
			(net "AGND_P5V_C")
			(options
				(clearance outline)
				(anchor circle)
			)
			(primitives
				(gr_poly
					(pts
						(xy -0.127 -0.3429) (xy -0.127 -0.1651) (xy -0.635 0.3429) (xy 0.635 0.3429) (xy 0.127 -0.1651)
						(xy 0.127 -0.3429)
					)
					(width 0)
					(fill yes)
				)
			)
		)
		(pad "2" smd custom
			(at 0 0.5334 180)
			(size 0.17145 0.17145)
			(layers "B.Cu" "B.Mask" "B.Paste")
			(net "GND")
			(options
				(clearance outline)
				(anchor circle)
			)
			(primitives
				(gr_poly
					(pts
						(xy -0.635 -0.3429) (xy -0.127 0.1651) (xy -0.127 0.3429) (xy 0.127 0.3429) (xy 0.127 0.1651)
						(xy 0.635 -0.3429)
					)
					(width 0)
					(fill yes)
				)
			)
		)
	)
	(footprint ""
		(layer "B.Cu")
		(at 483.449884 -204.199998 180)
		(property "Reference" "NUT2"
			(at 0 0 0)
			(layer "B.SilkS")
			(hide yes)
			(effects
				(font
					(size 1.27 1.27)
				)
				(justify mirror)
			)
		)
		(property "Value" "STF256R168H278-GP"
			(at 4.826 0.0508 180)
			(unlocked yes)
			(layer "B.Fab")
			(hide yes)
			(effects
				(font
					(size 1.016 1.016)
					(thickness 0.1524)
				)
				(justify mirror)
			)
		)
		(property "Device Type" "STF256R168H278"
			(at 4.826 -1.4732 180)
			(unlocked yes)
			(layer "B.Fab")
			(hide yes)
			(effects
				(font
					(size 1.016 1.016)
					(thickness 0.1524)
				)
				(justify mirror)
			)
		)
		(duplicate_pad_numbers_are_jumpers no)
		(fp_circle
			(center 0 0)
			(end -3.6068 0)
			(stroke
				(width 0.3048)
				(type default)
			)
			(fill no)
			(layer "B.SilkS")
		)
		(fp_poly
			(pts
				(arc
					(start -2.5019 0)
					(mid 2.5019 0)
					(end -2.5019 0)
				)
			)
			(stroke
				(width 0)
				(type default)
			)
			(fill no)
			(layer "B.CrtYd")
		)
		(fp_poly
			(pts
				(arc
					(start -3.7592 0.00635)
					(mid 3.759205 0)
					(end -3.7592 -0.00635)
				)
				(arc
					(start -2.5019 -0.00635)
					(mid 2.501908 0)
					(end -2.5019 0.00635)
				)
			)
			(stroke
				(width 0)
				(type default)
			)
			(fill no)
			(layer "B.CrtYd")
		)
		(fp_poly
			(pts
				(arc
					(start -3.7592 0)
					(mid 3.7592 0)
					(end -3.7592 0)
				)
			)
			(stroke
				(width 0)
				(type default)
			)
			(fill no)
			(layer "F.CrtYd")
		)
		(fp_poly
			(pts
				(arc
					(start -3.7592 0)
					(mid 3.7592 0)
					(end -3.7592 0)
				)
			)
			(stroke
				(width 0)
				(type default)
			)
			(fill no)
			(layer "B.Fab")
		)
		(fp_poly
			(pts
				(arc
					(start -3.7592 0)
					(mid 3.7592 0)
					(end -3.7592 0)
				)
			)
			(stroke
				(width 0)
				(type default)
			)
			(fill no)
			(layer "F.Fab")
		)
		(pad "1" thru_hole circle
			(at 0 0)
			(size 6.5024 6.5024)
			(drill 4.2672)
			(layers "*.Cu" "*.Mask")
			(remove_unused_layers no)
			(net "Net_14")
			(clearance -0.6096)
			(padstack
				(mode front_inner_back)
				(layer "Inner"
					(shape circle)
					(size 4.6736 4.6736)
					(clearance 0.3048)
				)
				(layer "B.Cu"
					(shape circle)
					(size 6.5024 6.5024)
					(thermal_gap 0.3048)
					(clearance -0.6096)
				)
			)
		)
	)
	(footprint ""
		(layer "B.Cu")
		(at 189.377828 -236.296708 90)
		(property "Reference" "C683"
			(at 0 0 90)
			(layer "B.SilkS")
			(hide yes)
			(effects
				(font
					(size 1.27 1.27)
				)
				(justify mirror)
			)
		)
		(property "Value" "SC10U6D3V5KX-4GP"
			(at 0.0762 -6.1214 90)
			(unlocked yes)
			(layer "B.Fab")
			(hide yes)
			(effects
				(font
					(size 1.016 1.016)
					(thickness 0.1524)
				)
				(justify mirror)
			)
		)
		(property "Device Type" "C805H58"
			(at 0.0762 -8.1534 90)
			(unlocked yes)
			(layer "B.Fab")
			(hide yes)
			(effects
				(font
					(size 1.016 1.016)
					(thickness 0.1524)
				)
				(justify mirror)
			)
		)
		(duplicate_pad_numbers_are_jumpers no)
		(fp_line
			(start -0.635 0)
			(end 0.635 0)
			(stroke
				(width 0.508)
				(type default)
			)
			(layer "B.SilkS")
		)
		(fp_rect
			(start 0.9652 1.778)
			(end -0.9652 -1.778)
			(stroke
				(width 0)
				(type default)
			)
			(fill no)
			(layer "B.CrtYd")
		)
		(fp_poly
			(pts
				(xy 0.9652 -1.778) (xy -0.9652 -1.778) (xy -0.9652 1.778) (xy 0.9652 1.778)
			)
			(stroke
				(width 0)
				(type default)
			)
			(fill no)
			(layer "B.Fab")
		)
		(pad "1" smd rect
			(at 0 -0.9652 270)
			(size 1.397 1.143)
			(layers "B.Cu" "B.Mask" "B.Paste")
			(net "P3V3_STBY_A")
		)
		(pad "2" smd rect
			(at 0 0.9652 270)
			(size 1.397 1.143)
			(layers "B.Cu" "B.Mask" "B.Paste")
			(net "GND")
		)
	)
	(footprint ""
		(layer "B.Cu")
		(at 347.000068 -164.200078 180)
		(property "Reference" "NUT5"
			(at 0 0 0)
			(layer "B.SilkS")
			(hide yes)
			(effects
				(font
					(size 1.27 1.27)
				)
				(justify mirror)
			)
		)
		(property "Value" "STF256R168H278-GP"
			(at 4.826 0.0508 180)
			(unlocked yes)
			(layer "B.Fab")
			(hide yes)
			(effects
				(font
					(size 1.016 1.016)
					(thickness 0.1524)
				)
				(justify mirror)
			)
		)
		(property "Device Type" "STF256R168H278"
			(at 4.826 -1.4732 180)
			(unlocked yes)
			(layer "B.Fab")
			(hide yes)
			(effects
				(font
					(size 1.016 1.016)
					(thickness 0.1524)
				)
				(justify mirror)
			)
		)
		(duplicate_pad_numbers_are_jumpers no)
		(fp_circle
			(center 0 0)
			(end -3.6068 0)
			(stroke
				(width 0.3048)
				(type default)
			)
			(fill no)
			(layer "B.SilkS")
		)
		(fp_poly
			(pts
				(arc
					(start -2.5019 0)
					(mid 2.5019 0)
					(end -2.5019 0)
				)
			)
			(stroke
				(width 0)
				(type default)
			)
			(fill no)
			(layer "B.CrtYd")
		)
		(fp_poly
			(pts
				(arc
					(start -3.7592 0.00635)
					(mid 3.759205 0)
					(end -3.7592 -0.00635)
				)
				(arc
					(start -2.5019 -0.00635)
					(mid 2.501908 0)
					(end -2.5019 0.00635)
				)
			)
			(stroke
				(width 0)
				(type default)
			)
			(fill no)
			(layer "B.CrtYd")
		)
		(fp_poly
			(pts
				(arc
					(start -3.7592 0)
					(mid 3.7592 0)
					(end -3.7592 0)
				)
			)
			(stroke
				(width 0)
				(type default)
			)
			(fill no)
			(layer "F.CrtYd")
		)
		(fp_poly
			(pts
				(arc
					(start -3.7592 0)
					(mid 3.7592 0)
					(end -3.7592 0)
				)
			)
			(stroke
				(width 0)
				(type default)
			)
			(fill no)
			(layer "B.Fab")
		)
		(fp_poly
			(pts
				(arc
					(start -3.7592 0)
					(mid 3.7592 0)
					(end -3.7592 0)
				)
			)
			(stroke
				(width 0)
				(type default)
			)
			(fill no)
			(layer "F.Fab")
		)
		(pad "1" thru_hole circle
			(at 0 0)
			(size 6.5024 6.5024)
			(drill 4.2672)
			(layers "*.Cu" "*.Mask")
			(remove_unused_layers no)
			(net "Net_11")
			(clearance -0.6096)
			(padstack
				(mode front_inner_back)
				(layer "Inner"
					(shape circle)
					(size 4.6736 4.6736)
					(clearance 0.3048)
				)
				(layer "B.Cu"
					(shape circle)
					(size 6.5024 6.5024)
					(thermal_gap 0.3048)
					(clearance -0.6096)
				)
			)
		)
	)
	(footprint ""
		(layer "B.Cu")
		(at 52.1716 -252.1966 180)
		(property "Reference" "C613"
			(at 0 0 0)
			(layer "B.SilkS")
			(hide yes)
			(effects
				(font
					(size 1.27 1.27)
				)
				(justify mirror)
			)
		)
		(property "Value" "SC10U16V5KX-7-GP-U"
			(at 0.0762 -6.1214 180)
			(unlocked yes)
			(layer "B.Fab")
			(hide yes)
			(effects
				(font
					(size 1.016 1.016)
					(thickness 0.1524)
				)
				(justify mirror)
			)
		)
		(property "Device Type" "C805H58"
			(at 0.0762 -8.1534 180)
			(unlocked yes)
			(layer "B.Fab")
			(hide yes)
			(effects
				(font
					(size 1.016 1.016)
					(thickness 0.1524)
				)
				(justify mirror)
			)
		)
		(duplicate_pad_numbers_are_jumpers no)
		(fp_line
			(start -0.635 0)
			(end 0.635 0)
			(stroke
				(width 0.508)
				(type default)
			)
			(layer "B.SilkS")
		)
		(fp_rect
			(start 0.9652 1.778)
			(end -0.9652 -1.778)
			(stroke
				(width 0)
				(type default)
			)
			(fill no)
			(layer "B.CrtYd")
		)
		(fp_poly
			(pts
				(xy 0.9652 -1.778) (xy -0.9652 -1.778) (xy -0.9652 1.778) (xy 0.9652 1.778)
			)
			(stroke
				(width 0)
				(type default)
			)
			(fill no)
			(layer "B.Fab")
		)
		(pad "1" smd rect
			(at 0 -0.9652)
			(size 1.397 1.143)
			(layers "B.Cu" "B.Mask" "B.Paste")
			(net "P5V_A_1")
		)
		(pad "2" smd rect
			(at 0 0.9652)
			(size 1.397 1.143)
			(layers "B.Cu" "B.Mask" "B.Paste")
			(net "GND")
		)
	)
	(footprint ""
		(layer "B.Cu")
		(at 48.6156 -253.9492 180)
		(property "Reference" "TC9"
			(at 0 0 0)
			(layer "B.SilkS")
			(hide yes)
			(effects
				(font
					(size 1.27 1.27)
				)
				(justify mirror)
			)
		)
		(property "Value" "ST220U10VDM-LGP"
			(at 0 -9.6012 180)
			(unlocked yes)
			(layer "B.Fab")
			(hide yes)
			(effects
				(font
					(size 1.016 1.016)
					(thickness 0.1524)
				)
				(justify mirror)
			)
		)
		(property "Device Type" "CT7343H119"
			(at 0 -11.1252 180)
			(unlocked yes)
			(layer "B.Fab")
			(hide yes)
			(effects
				(font
					(size 1.016 1.016)
					(thickness 0.1524)
				)
				(justify mirror)
			)
		)
		(duplicate_pad_numbers_are_jumpers no)
		(fp_line
			(start 2.286 4.8768)
			(end 2.286 2.032)
			(stroke
				(width 0.1524)
				(type default)
			)
			(layer "B.SilkS")
		)
		(fp_line
			(start 2.286 -4.8768)
			(end 2.286 -2.032)
			(stroke
				(width 0.1524)
				(type default)
			)
			(layer "B.SilkS")
		)
		(fp_line
			(start -2.1082 -4.699)
			(end 2.1082 -4.699)
			(stroke
				(width 0.508)
				(type default)
			)
			(layer "B.SilkS")
		)
		(fp_line
			(start -2.286 4.8768)
			(end 2.286 4.8768)
			(stroke
				(width 0.1524)
				(type default)
			)
			(layer "B.SilkS")
		)
		(fp_line
			(start -2.286 2.032)
			(end -2.286 4.8768)
			(stroke
				(width 0.1524)
				(type default)
			)
			(layer "B.SilkS")
		)
		(fp_line
			(start -2.286 -2.032)
			(end -2.286 -4.8768)
			(stroke
				(width 0.1524)
				(type default)
			)
			(layer "B.SilkS")
		)
		(fp_line
			(start -2.286 -4.8768)
			(end 2.286 -4.8768)
			(stroke
				(width 0.1524)
				(type default)
			)
			(layer "B.SilkS")
		)
		(fp_rect
			(start 2.1463 3.6449)
			(end -2.1463 -3.6449)
			(stroke
				(width 0)
				(type default)
			)
			(fill no)
			(layer "B.CrtYd")
		)
		(fp_poly
			(pts
				(xy 2.54 4.953) (xy 2.54 4.2926) (xy 3.81 4.2926) (xy 3.81 -4.2926) (xy 2.54 -4.2926) (xy 2.54 -4.953)
				(xy -2.54 -4.953) (xy -2.54 -4.2926) (xy -3.81 -4.2926) (xy -3.81 -1.6256) (xy -2.1463 -1.6256)
				(xy -2.1463 -3.6449) (xy 2.1463 -3.6449) (xy 2.1463 3.6449) (xy -2.1463 3.6449) (xy -2.1463 -1.6129)
				(xy -3.81 -1.6129) (xy -3.81 4.2926) (xy -2.54 4.2926) (xy -2.54 4.953)
			)
			(stroke
				(width 0)
				(type default)
			)
			(fill no)
			(layer "B.CrtYd")
		)
		(fp_rect
			(start 3.81 4.2926)
			(end 2.54 -4.2926)
			(stroke
				(width 0)
				(type default)
			)
			(fill no)
			(layer "B.Fab")
		)
		(fp_rect
			(start 2.54 4.953)
			(end -2.54 -4.953)
			(stroke
				(width 0)
				(type default)
			)
			(fill no)
			(layer "B.Fab")
		)
		(fp_rect
			(start -2.54 4.2926)
			(end -3.81 -4.2926)
			(stroke
				(width 0)
				(type default)
			)
			(fill no)
			(layer "B.Fab")
		)
		(pad "1" smd rect
			(at 0 -3.1496)
			(size 2.413 2.286)
			(layers "B.Cu" "B.Mask" "B.Paste")
			(net "P5V_A_1")
		)
		(pad "2" smd rect
			(at 0 3.1496)
			(size 2.413 2.286)
			(layers "B.Cu" "B.Mask" "B.Paste")
			(net "GND")
		)
		(zone
			(layer "B.Cu")
			(hatch none 0.5)
			(connect_pads
				(clearance 0)
			)
			(min_thickness 0.25)
			(keepout
				(tracks allowed)
				(vias not_allowed)
				(pads allowed)
				(copperpour not_allowed)
				(footprints allowed)
			)
			(placement
				(enabled no)
				(sheetname "")
			)
			(fill
				(thermal_gap 0.5)
				(thermal_bridge_width 0.5)
				(island_removal_mode 0)
			)
			(polygon
				(pts
					(xy 47.1043 -258.5466) (xy 50.1269 -258.5466) (xy 50.1269 -255.651) (xy 50.1269 -255.3208) (xy 47.1043 -255.3208)
					(xy 47.1043 -255.651)
				)
			)
		)
		(zone
			(layer "B.Cu")
			(hatch none 0.5)
			(connect_pads
				(clearance 0)
			)
			(min_thickness 0.25)
			(keepout
				(tracks allowed)
				(vias not_allowed)
				(pads allowed)
				(copperpour not_allowed)
				(footprints allowed)
			)
			(placement
				(enabled no)
				(sheetname "")
			)
			(fill
				(thermal_gap 0.5)
				(thermal_bridge_width 0.5)
				(island_removal_mode 0)
			)
			(polygon
				(pts
					(xy 50.1269 -252.2601) (xy 50.1269 -249.3518) (xy 47.1043 -249.3518) (xy 47.1043 -252.2474) (xy 47.1043 -252.5776)
					(xy 50.1269 -252.5776)
				)
			)
		)
	)
	(footprint ""
		(layer "B.Cu")
		(at 480.871022 -213.114128 90)
		(property "Reference" "TC8"
			(at 0 0 90)
			(layer "B.SilkS")
			(hide yes)
			(effects
				(font
					(size 1.27 1.27)
				)
				(justify mirror)
			)
		)
		(property "Value" "ST220U10VDM-LGP"
			(at 0 -9.6012 90)
			(unlocked yes)
			(layer "B.Fab")
			(hide yes)
			(effects
				(font
					(size 1.016 1.016)
					(thickness 0.1524)
				)
				(justify mirror)
			)
		)
		(property "Device Type" "CT7343H119"
			(at 0 -11.1252 90)
			(unlocked yes)
			(layer "B.Fab")
			(hide yes)
			(effects
				(font
					(size 1.016 1.016)
					(thickness 0.1524)
				)
				(justify mirror)
			)
		)
		(duplicate_pad_numbers_are_jumpers no)
		(fp_line
			(start 2.286 -4.8768)
			(end 2.286 -2.032)
			(stroke
				(width 0.1524)
				(type default)
			)
			(layer "B.SilkS")
		)
		(fp_line
			(start -2.286 -4.8768)
			(end 2.286 -4.8768)
			(stroke
				(width 0.1524)
				(type default)
			)
			(layer "B.SilkS")
		)
		(fp_line
			(start -2.1082 -4.699)
			(end 2.1082 -4.699)
			(stroke
				(width 0.508)
				(type default)
			)
			(layer "B.SilkS")
		)
		(fp_line
			(start -2.286 -2.032)
			(end -2.286 -4.8768)
			(stroke
				(width 0.1524)
				(type default)
			)
			(layer "B.SilkS")
		)
		(fp_line
			(start -2.286 2.032)
			(end -2.286 4.8768)
			(stroke
				(width 0.1524)
				(type default)
			)
			(layer "B.SilkS")
		)
		(fp_line
			(start 2.286 4.8768)
			(end 2.286 2.032)
			(stroke
				(width 0.1524)
				(type default)
			)
			(layer "B.SilkS")
		)
		(fp_line
			(start -2.286 4.8768)
			(end 2.286 4.8768)
			(stroke
				(width 0.1524)
				(type default)
			)
			(layer "B.SilkS")
		)
		(fp_rect
			(start 2.1463 3.6449)
			(end -2.1463 -3.6449)
			(stroke
				(width 0)
				(type default)
			)
			(fill no)
			(layer "B.CrtYd")
		)
		(fp_poly
			(pts
				(xy 2.54 4.953) (xy 2.54 4.2926) (xy 3.81 4.2926) (xy 3.81 -4.2926) (xy 2.54 -4.2926) (xy 2.54 -4.953)
				(xy -2.54 -4.953) (xy -2.54 -4.2926) (xy -3.81 -4.2926) (xy -3.81 -1.6256) (xy -2.1463 -1.6256)
				(xy -2.1463 -3.6449) (xy 2.1463 -3.6449) (xy 2.1463 3.6449) (xy -2.1463 3.6449) (xy -2.1463 -1.6129)
				(xy -3.81 -1.6129) (xy -3.81 4.2926) (xy -2.54 4.2926) (xy -2.54 4.953)
			)
			(stroke
				(width 0)
				(type default)
			)
			(fill no)
			(layer "B.CrtYd")
		)
		(fp_rect
			(start 3.81 4.2926)
			(end 2.54 -4.2926)
			(stroke
				(width 0)
				(type default)
			)
			(fill no)
			(layer "B.Fab")
		)
		(fp_rect
			(start -2.54 4.2926)
			(end -3.81 -4.2926)
			(stroke
				(width 0)
				(type default)
			)
			(fill no)
			(layer "B.Fab")
		)
		(fp_rect
			(start 2.54 4.953)
			(end -2.54 -4.953)
			(stroke
				(width 0)
				(type default)
			)
			(fill no)
			(layer "B.Fab")
		)
		(pad "1" smd rect
			(at 0 -3.1496 270)
			(size 2.413 2.286)
			(layers "B.Cu" "B.Mask" "B.Paste")
			(net "P5V_A_4")
		)
		(pad "2" smd rect
			(at 0 3.1496 270)
			(size 2.413 2.286)
			(layers "B.Cu" "B.Mask" "B.Paste")
			(net "GND")
		)
		(zone
			(layer "B.Cu")
			(hatch none 0.5)
			(connect_pads
				(clearance 0)
			)
			(min_thickness 0.25)
			(keepout
				(tracks allowed)
				(vias not_allowed)
				(pads allowed)
				(copperpour not_allowed)
				(footprints allowed)
			)
			(placement
				(enabled no)
				(sheetname "")
			)
			(fill
				(thermal_gap 0.5)
				(thermal_bridge_width 0.5)
				(island_removal_mode 0)
			)
			(polygon
				(pts
					(xy 479.181922 -211.602828) (xy 476.273622 -211.602828) (xy 476.273622 -214.625428) (xy 479.169222 -214.625428)
					(xy 479.499422 -214.625428) (xy 479.499422 -211.602828)
				)
			)
		)
		(zone
			(layer "B.Cu")
			(hatch none 0.5)
			(connect_pads
				(clearance 0)
			)
			(min_thickness 0.25)
			(keepout
				(tracks allowed)
				(vias not_allowed)
				(pads allowed)
				(copperpour not_allowed)
				(footprints allowed)
			)
			(placement
				(enabled no)
				(sheetname "")
			)
			(fill
				(thermal_gap 0.5)
				(thermal_bridge_width 0.5)
				(island_removal_mode 0)
			)
			(polygon
				(pts
					(xy 485.468422 -214.625428) (xy 485.468422 -211.602828) (xy 482.572822 -211.602828) (xy 482.242622 -211.602828)
					(xy 482.242622 -214.625428) (xy 482.572822 -214.625428)
				)
			)
		)
	)
	(footprint ""
		(layer "B.Cu")
		(at 482.092 -225.679 90)
		(property "Reference" "TP259"
			(at 0 0 90)
			(layer "B.SilkS")
			(hide yes)
			(effects
				(font
					(size 1.27 1.27)
				)
				(justify mirror)
			)
		)
		(property "Value" "TPAD32-GP"
			(at 0.0508 -1.6764 90)
			(unlocked yes)
			(layer "B.Fab")
			(hide yes)
			(effects
				(font
					(size 1.016 1.016)
					(thickness 0.1524)
				)
				(justify mirror)
			)
		)
		(property "Device Type" "TPAD32"
			(at 0.0508 -3.2004 90)
			(unlocked yes)
			(layer "B.Fab")
			(hide yes)
			(effects
				(font
					(size 1.016 1.016)
					(thickness 0.1524)
				)
				(justify mirror)
			)
		)
		(duplicate_pad_numbers_are_jumpers no)
		(fp_poly
			(pts
				(arc
					(start 0 0.4064)
					(mid 0 -0.4064)
					(end 0 0.4064)
				)
			)
			(stroke
				(width 0)
				(type default)
			)
			(fill no)
			(layer "B.CrtYd")
		)
		(fp_poly
			(pts
				(arc
					(start 0 0.7112)
					(mid 0 -0.7112)
					(end 0 0.7112)
				)
			)
			(stroke
				(width 0)
				(type default)
			)
			(fill no)
			(layer "B.Fab")
		)
		(pad "1" smd circle
			(at 0 0 270)
			(size 0.8128 0.8128)
			(layers "B.Cu" "B.Mask" "B.Paste")
			(net "P5V_A_4_PGOOD")
		)
	)
	(footprint ""
		(layer "B.Cu")
		(at 244.094 -385.7498 180)
		(property "Reference" "C587"
			(at 0 0 0)
			(layer "B.SilkS")
			(hide yes)
			(effects
				(font
					(size 1.27 1.27)
				)
				(justify mirror)
			)
		)
		(property "Value" "SCD015U25V2KX-GP"
			(at -1.1811 -2.7051 180)
			(unlocked yes)
			(layer "B.Fab")
			(hide yes)
			(effects
				(font
					(size 1.016 1.016)
					(thickness 0.1524)
				)
				(justify mirror)
			)
		)
		(property "Device Type" "C402H22"
			(at -1.1811 -4.2291 180)
			(unlocked yes)
			(layer "B.Fab")
			(hide yes)
			(effects
				(font
					(size 1.016 1.016)
					(thickness 0.1524)
				)
				(justify mirror)
			)
		)
		(duplicate_pad_numbers_are_jumpers no)
		(fp_rect
			(start 0.4318 0.9525)
			(end -0.4318 -0.9525)
			(stroke
				(width 0)
				(type default)
			)
			(fill no)
			(layer "B.CrtYd")
		)
		(fp_rect
			(start 0.4318 0.9525)
			(end -0.4318 -0.9525)
			(stroke
				(width 0)
				(type default)
			)
			(fill no)
			(layer "B.Fab")
		)
		(pad "1" smd custom
			(at 0 -0.4445)
			(size 0.1524 0.1524)
			(layers "B.Cu" "B.Mask" "B.Paste")
			(net "MB3_CM_SENSE_P")
			(options
				(clearance outline)
				(anchor circle)
			)
			(primitives
				(gr_poly
					(pts
						(arc
							(start 0.3048 0.2032)
							(mid 0.275042 0.275042)
							(end 0.2032 0.3048)
						)
						(arc
							(start -0.2032 0.3048)
							(mid -0.275042 0.275042)
							(end -0.3048 0.2032)
						)
						(arc
							(start -0.3048 -0.2032)
							(mid -0.275042 -0.275042)
							(end -0.2032 -0.3048)
						)
						(arc
							(start 0.2032 -0.3048)
							(mid 0.275042 -0.275042)
							(end 0.3048 -0.2032)
						)
					)
					(width 0)
					(fill yes)
				)
			)
		)
		(pad "2" smd custom
			(at 0 0.4445)
			(size 0.1524 0.1524)
			(layers "B.Cu" "B.Mask" "B.Paste")
			(net "MB3_CM_SENSE_N")
			(options
				(clearance outline)
				(anchor circle)
			)
			(primitives
				(gr_poly
					(pts
						(arc
							(start 0.3048 0.2032)
							(mid 0.275042 0.275042)
							(end 0.2032 0.3048)
						)
						(arc
							(start -0.2032 0.3048)
							(mid -0.275042 0.275042)
							(end -0.3048 0.2032)
						)
						(arc
							(start -0.3048 -0.2032)
							(mid -0.275042 -0.275042)
							(end -0.2032 -0.3048)
						)
						(arc
							(start 0.2032 -0.3048)
							(mid 0.275042 -0.275042)
							(end 0.3048 -0.2032)
						)
					)
					(width 0)
					(fill yes)
				)
			)
		)
	)
	(footprint ""
		(layer "B.Cu")
		(at 56.4642 -141.2494 90)
		(property "Reference" "L4"
			(at 0 0 90)
			(layer "B.SilkS")
			(hide yes)
			(effects
				(font
					(size 1.27 1.27)
				)
				(justify mirror)
			)
		)
		(property "Value" "IND-1UH-191-GP"
			(at 6.7818 -2.1082 90)
			(unlocked yes)
			(layer "B.Fab")
			(hide yes)
			(effects
				(font
					(size 1.016 1.016)
					(thickness 0.1524)
				)
				(justify mirror)
			)
		)
		(property "Device Type" "L109100-2430-UH119"
			(at 6.7818 -3.6322 90)
			(unlocked yes)
			(layer "B.Fab")
			(hide yes)
			(effects
				(font
					(size 1.016 1.016)
					(thickness 0.1524)
				)
				(justify mirror)
			)
		)
		(duplicate_pad_numbers_are_jumpers no)
		(fp_line
			(start 5.2578 -6.4262)
			(end -5.2578 -6.4262)
			(stroke
				(width 0.1524)
				(type default)
			)
			(layer "B.SilkS")
		)
		(fp_line
			(start -5.2578 -6.4262)
			(end -5.2578 6.4262)
			(stroke
				(width 0.1524)
				(type default)
			)
			(layer "B.SilkS")
		)
		(fp_line
			(start 5.2578 6.4262)
			(end 5.2578 -6.4262)
			(stroke
				(width 0.1524)
				(type default)
			)
			(layer "B.SilkS")
		)
		(fp_line
			(start -5.2578 6.4262)
			(end 5.2578 6.4262)
			(stroke
				(width 0.1524)
				(type default)
			)
			(layer "B.SilkS")
		)
		(fp_rect
			(start 5.0038 5.4229)
			(end -5.0038 -5.4229)
			(stroke
				(width 0)
				(type default)
			)
			(fill no)
			(layer "B.CrtYd")
		)
		(fp_poly
			(pts
				(xy 5.5118 6.5024) (xy 5.5118 -6.5024) (xy -5.5118 -6.5024) (xy -5.5118 -0.8509) (xy -5.0038 -0.8509)
				(xy -5.0038 -5.4229) (xy 5.0038 -5.4229) (xy 5.0038 5.4229) (xy -5.0038 5.4229) (xy -5.0038 -0.8382)
				(xy -5.5118 -0.8382) (xy -5.5118 6.5024)
			)
			(stroke
				(width 0)
				(type default)
			)
			(fill no)
			(layer "B.CrtYd")
		)
		(fp_rect
			(start 5.5118 6.5024)
			(end -5.5118 -6.5024)
			(stroke
				(width 0)
				(type default)
			)
			(fill no)
			(layer "B.Fab")
		)
		(pad "1" smd rect
			(at 0 -4.396994 270)
			(size 3.5052 3.556)
			(layers "B.Cu" "B.Mask" "B.Paste")
			(net "P5V_B_LL")
		)
		(pad "2" smd rect
			(at 0 4.396994 270)
			(size 3.5052 3.556)
			(layers "B.Cu" "B.Mask" "B.Paste")
			(net "P5V_A_2")
		)
	)
	(footprint ""
		(layer "B.Cu")
		(at 187.955428 -229.641908 -90)
		(property "Reference" "R1287"
			(at 0 0 90)
			(layer "B.SilkS")
			(hide yes)
			(effects
				(font
					(size 1.27 1.27)
				)
				(justify mirror)
			)
		)
		(property "Value" "0R2J-2-GP"
			(at -0.064008 -3.993896 270)
			(unlocked yes)
			(layer "B.Fab")
			(hide yes)
			(effects
				(font
					(size 1.016 1.016)
					(thickness 0.1524)
				)
				(justify mirror)
			)
		)
		(property "Device Type" "R402H16"
			(at -0.064008 -5.517896 270)
			(unlocked yes)
			(layer "B.Fab")
			(hide yes)
			(effects
				(font
					(size 1.016 1.016)
					(thickness 0.1524)
				)
				(justify mirror)
			)
		)
		(duplicate_pad_numbers_are_jumpers no)
		(fp_line
			(start -0.508 -0.9398)
			(end 0.508 -0.9398)
			(stroke
				(width 0.1524)
				(type default)
			)
			(layer "B.SilkS")
		)
		(fp_line
			(start 0.508 -0.9398)
			(end 0.508 0.9398)
			(stroke
				(width 0.1524)
				(type default)
			)
			(layer "B.SilkS")
		)
		(fp_rect
			(start 0.508 0.9398)
			(end -0.508 -0.9398)
			(stroke
				(width 0)
				(type default)
			)
			(fill no)
			(layer "B.CrtYd")
		)
		(fp_rect
			(start 0.508 0.9398)
			(end -0.508 -0.9398)
			(stroke
				(width 0)
				(type default)
			)
			(fill no)
			(layer "B.Fab")
		)
		(pad "1" smd custom
			(at 0 -0.4445 90)
			(size 0.1397 0.1397)
			(layers "B.Cu" "B.Mask" "B.Paste")
			(net "P3V3_STBY_VBST_RR")
			(options
				(clearance outline)
				(anchor circle)
			)
			(primitives
				(gr_poly
					(pts
						(arc
							(start -0.1778 0.2794)
							(mid -0.249642 0.249642)
							(end -0.2794 0.1778)
						)
						(arc
							(start -0.2794 -0.1778)
							(mid -0.249642 -0.249642)
							(end -0.1778 -0.2794)
						)
						(arc
							(start 0.1778 -0.2794)
							(mid 0.249642 -0.249642)
							(end 0.2794 -0.1778)
						)
						(arc
							(start 0.2794 0.1778)
							(mid 0.249642 0.249642)
							(end 0.1778 0.2794)
						)
					)
					(width 0)
					(fill yes)
				)
			)
		)
		(pad "2" smd custom
			(at 0 0.4445 90)
			(size 0.1397 0.1397)
			(layers "B.Cu" "B.Mask" "B.Paste")
			(net "P3V3_STBY_VBST")
			(options
				(clearance outline)
				(anchor circle)
			)
			(primitives
				(gr_poly
					(pts
						(arc
							(start -0.1778 0.2794)
							(mid -0.249642 0.249642)
							(end -0.2794 0.1778)
						)
						(arc
							(start -0.2794 -0.1778)
							(mid -0.249642 -0.249642)
							(end -0.1778 -0.2794)
						)
						(arc
							(start 0.1778 -0.2794)
							(mid 0.249642 -0.249642)
							(end 0.2794 -0.1778)
						)
						(arc
							(start 0.2794 0.1778)
							(mid 0.249642 0.249642)
							(end 0.1778 0.2794)
						)
					)
					(width 0)
					(fill yes)
				)
			)
		)
	)
	(footprint ""
		(layer "B.Cu")
		(at 39.5224 -245.8974 90)
		(property "Reference" "L2"
			(at 0 0 90)
			(layer "B.SilkS")
			(hide yes)
			(effects
				(font
					(size 1.27 1.27)
				)
				(justify mirror)
			)
		)
		(property "Value" "IND-1UH-191-GP"
			(at 6.7818 -2.1082 90)
			(unlocked yes)
			(layer "B.Fab")
			(hide yes)
			(effects
				(font
					(size 1.016 1.016)
					(thickness 0.1524)
				)
				(justify mirror)
			)
		)
		(property "Device Type" "L109100-2430-UH119"
			(at 6.7818 -3.6322 90)
			(unlocked yes)
			(layer "B.Fab")
			(hide yes)
			(effects
				(font
					(size 1.016 1.016)
					(thickness 0.1524)
				)
				(justify mirror)
			)
		)
		(duplicate_pad_numbers_are_jumpers no)
		(fp_line
			(start 5.2578 -6.4262)
			(end -5.2578 -6.4262)
			(stroke
				(width 0.1524)
				(type default)
			)
			(layer "B.SilkS")
		)
		(fp_line
			(start -5.2578 -6.4262)
			(end -5.2578 6.4262)
			(stroke
				(width 0.1524)
				(type default)
			)
			(layer "B.SilkS")
		)
		(fp_line
			(start 5.2578 6.4262)
			(end 5.2578 -6.4262)
			(stroke
				(width 0.1524)
				(type default)
			)
			(layer "B.SilkS")
		)
		(fp_line
			(start -5.2578 6.4262)
			(end 5.2578 6.4262)
			(stroke
				(width 0.1524)
				(type default)
			)
			(layer "B.SilkS")
		)
		(fp_rect
			(start 5.0038 5.4229)
			(end -5.0038 -5.4229)
			(stroke
				(width 0)
				(type default)
			)
			(fill no)
			(layer "B.CrtYd")
		)
		(fp_poly
			(pts
				(xy 5.5118 6.5024) (xy 5.5118 -6.5024) (xy -5.5118 -6.5024) (xy -5.5118 -0.8509) (xy -5.0038 -0.8509)
				(xy -5.0038 -5.4229) (xy 5.0038 -5.4229) (xy 5.0038 5.4229) (xy -5.0038 5.4229) (xy -5.0038 -0.8382)
				(xy -5.5118 -0.8382) (xy -5.5118 6.5024)
			)
			(stroke
				(width 0)
				(type default)
			)
			(fill no)
			(layer "B.CrtYd")
		)
		(fp_rect
			(start 5.5118 6.5024)
			(end -5.5118 -6.5024)
			(stroke
				(width 0)
				(type default)
			)
			(fill no)
			(layer "B.Fab")
		)
		(pad "1" smd rect
			(at 0 -4.396994 270)
			(size 3.5052 3.556)
			(layers "B.Cu" "B.Mask" "B.Paste")
			(net "P5V_A_LL")
		)
		(pad "2" smd rect
			(at 0 4.396994 270)
			(size 3.5052 3.556)
			(layers "B.Cu" "B.Mask" "B.Paste")
			(net "P5V_A_1")
		)
	)
	(footprint ""
		(layer "B.Cu")
		(at 188.438282 -220.240606 180)
		(property "Reference" "C679"
			(at 0 0 0)
			(layer "B.SilkS")
			(hide yes)
			(effects
				(font
					(size 1.27 1.27)
				)
				(justify mirror)
			)
		)
		(property "Value" "SC1KP50V2KX-1GP"
			(at -1.1811 -2.7051 180)
			(unlocked yes)
			(layer "B.Fab")
			(hide yes)
			(effects
				(font
					(size 1.016 1.016)
					(thickness 0.1524)
				)
				(justify mirror)
			)
		)
		(property "Device Type" "C402H22"
			(at -1.1811 -4.2291 180)
			(unlocked yes)
			(layer "B.Fab")
			(hide yes)
			(effects
				(font
					(size 1.016 1.016)
					(thickness 0.1524)
				)
				(justify mirror)
			)
		)
		(duplicate_pad_numbers_are_jumpers no)
		(fp_rect
			(start 0.4318 0.9525)
			(end -0.4318 -0.9525)
			(stroke
				(width 0)
				(type default)
			)
			(fill no)
			(layer "B.CrtYd")
		)
		(fp_rect
			(start 0.4318 0.9525)
			(end -0.4318 -0.9525)
			(stroke
				(width 0)
				(type default)
			)
			(fill no)
			(layer "B.Fab")
		)
		(pad "1" smd custom
			(at 0 -0.4445)
			(size 0.1524 0.1524)
			(layers "B.Cu" "B.Mask" "B.Paste")
			(net "P3V3_STBY_VFB_R")
			(options
				(clearance outline)
				(anchor circle)
			)
			(primitives
				(gr_poly
					(pts
						(arc
							(start 0.3048 0.2032)
							(mid 0.275042 0.275042)
							(end 0.2032 0.3048)
						)
						(arc
							(start -0.2032 0.3048)
							(mid -0.275042 0.275042)
							(end -0.3048 0.2032)
						)
						(arc
							(start -0.3048 -0.2032)
							(mid -0.275042 -0.275042)
							(end -0.2032 -0.3048)
						)
						(arc
							(start 0.2032 -0.3048)
							(mid 0.275042 -0.275042)
							(end 0.3048 -0.2032)
						)
					)
					(width 0)
					(fill yes)
				)
			)
		)
		(pad "2" smd custom
			(at 0 0.4445)
			(size 0.1524 0.1524)
			(layers "B.Cu" "B.Mask" "B.Paste")
			(net "P3V3_STBY_VFB")
			(options
				(clearance outline)
				(anchor circle)
			)
			(primitives
				(gr_poly
					(pts
						(arc
							(start 0.3048 0.2032)
							(mid 0.275042 0.275042)
							(end 0.2032 0.3048)
						)
						(arc
							(start -0.2032 0.3048)
							(mid -0.275042 0.275042)
							(end -0.3048 0.2032)
						)
						(arc
							(start -0.3048 -0.2032)
							(mid -0.275042 -0.275042)
							(end -0.2032 -0.3048)
						)
						(arc
							(start 0.2032 -0.3048)
							(mid 0.275042 -0.275042)
							(end 0.3048 -0.2032)
						)
					)
					(width 0)
					(fill yes)
				)
			)
		)
	)
	(footprint ""
		(layer "B.Cu")
		(at 178.252628 -235.229908 180)
		(property "Reference" "R1290"
			(at 0 0 0)
			(layer "B.SilkS")
			(hide yes)
			(effects
				(font
					(size 1.27 1.27)
				)
				(justify mirror)
			)
		)
		(property "Value" "3D01R5F-GP"
			(at 0 -8.9535 180)
			(unlocked yes)
			(layer "B.Fab")
			(hide yes)
			(effects
				(font
					(size 1.27 1.016)
					(thickness 0.1524)
				)
				(justify mirror)
			)
		)
		(property "Device Type" "R805H24"
			(at 0 -10.6299 180)
			(unlocked yes)
			(layer "B.Fab")
			(hide yes)
			(effects
				(font
					(size 1.27 1.016)
					(thickness 0.1524)
				)
				(justify mirror)
			)
		)
		(duplicate_pad_numbers_are_jumpers no)
		(fp_line
			(start 0.889 1.7018)
			(end -0.889 1.7018)
			(stroke
				(width 0.1524)
				(type default)
			)
			(layer "B.SilkS")
		)
		(fp_line
			(start 0.889 0.0762)
			(end 0.889 1.7018)
			(stroke
				(width 0.1524)
				(type default)
			)
			(layer "B.SilkS")
		)
		(fp_line
			(start 0.889 -1.7018)
			(end 0.889 0.2794)
			(stroke
				(width 0.1524)
				(type default)
			)
			(layer "B.SilkS")
		)
		(fp_line
			(start -0.889 1.7018)
			(end -0.889 -0.508)
			(stroke
				(width 0.1524)
				(type default)
			)
			(layer "B.SilkS")
		)
		(fp_line
			(start -0.889 -1.7018)
			(end 0.889 -1.7018)
			(stroke
				(width 0.1524)
				(type default)
			)
			(layer "B.SilkS")
		)
		(fp_line
			(start -0.889 -1.7018)
			(end -0.889 -0.381)
			(stroke
				(width 0.1524)
				(type default)
			)
			(layer "B.SilkS")
		)
		(fp_poly
			(pts
				(xy -0.9652 -1.778) (xy -0.9652 1.778) (xy 0.9652 1.778) (xy 0.9652 -1.778)
			)
			(stroke
				(width 0)
				(type default)
			)
			(fill no)
			(layer "B.CrtYd")
		)
		(fp_rect
			(start 0.9652 1.778)
			(end -0.9652 -1.778)
			(stroke
				(width 0)
				(type default)
			)
			(fill no)
			(layer "B.Fab")
		)
		(pad "1" smd rect
			(at 0 -0.9652)
			(size 1.397 1.143)
			(layers "B.Cu" "B.Mask" "B.Paste")
			(net "P3V3_STBY_SNB")
		)
		(pad "2" smd rect
			(at 0 0.9652)
			(size 1.397 1.143)
			(layers "B.Cu" "B.Mask" "B.Paste")
			(net "GND")
		)
	)
	(footprint ""
		(layer "B.Cu")
		(at 194.162172 -228.396292 180)
		(property "Reference" "C671"
			(at 0 0 0)
			(layer "B.SilkS")
			(hide yes)
			(effects
				(font
					(size 1.27 1.27)
				)
				(justify mirror)
			)
		)
		(property "Value" "SC10U16V5KX-7-GP-U"
			(at 0.0762 -6.1214 180)
			(unlocked yes)
			(layer "B.Fab")
			(hide yes)
			(effects
				(font
					(size 1.016 1.016)
					(thickness 0.1524)
				)
				(justify mirror)
			)
		)
		(property "Device Type" "C805H58"
			(at 0.0762 -8.1534 180)
			(unlocked yes)
			(layer "B.Fab")
			(hide yes)
			(effects
				(font
					(size 1.016 1.016)
					(thickness 0.1524)
				)
				(justify mirror)
			)
		)
		(duplicate_pad_numbers_are_jumpers no)
		(fp_line
			(start -0.635 0)
			(end 0.635 0)
			(stroke
				(width 0.508)
				(type default)
			)
			(layer "B.SilkS")
		)
		(fp_rect
			(start 0.9652 1.778)
			(end -0.9652 -1.778)
			(stroke
				(width 0)
				(type default)
			)
			(fill no)
			(layer "B.CrtYd")
		)
		(fp_poly
			(pts
				(xy 0.9652 -1.778) (xy -0.9652 -1.778) (xy -0.9652 1.778) (xy 0.9652 1.778)
			)
			(stroke
				(width 0)
				(type default)
			)
			(fill no)
			(layer "B.Fab")
		)
		(pad "1" smd rect
			(at 0 -0.9652)
			(size 1.397 1.143)
			(layers "B.Cu" "B.Mask" "B.Paste")
			(net "P3V3_STBY_VIN")
		)
		(pad "2" smd rect
			(at 0 0.9652)
			(size 1.397 1.143)
			(layers "B.Cu" "B.Mask" "B.Paste")
			(net "GND")
		)
	)
	(footprint ""
		(layer "B.Cu")
		(at 216.8398 -116.459 90)
		(property "Reference" "R622"
			(at 0 0 90)
			(layer "B.SilkS")
			(hide yes)
			(effects
				(font
					(size 1.27 1.27)
				)
				(justify mirror)
			)
		)
		(property "Value" "4K7R2F-GP"
			(at -0.064008 -3.993896 90)
			(unlocked yes)
			(layer "B.Fab")
			(hide yes)
			(effects
				(font
					(size 1.016 1.016)
					(thickness 0.1524)
				)
				(justify mirror)
			)
		)
		(property "Device Type" "R402H16"
			(at -0.064008 -5.517896 90)
			(unlocked yes)
			(layer "B.Fab")
			(hide yes)
			(effects
				(font
					(size 1.016 1.016)
					(thickness 0.1524)
				)
				(justify mirror)
			)
		)
		(duplicate_pad_numbers_are_jumpers no)
		(fp_line
			(start 0.508 -0.9398)
			(end 0.508 0.9398)
			(stroke
				(width 0.1524)
				(type default)
			)
			(layer "B.SilkS")
		)
		(fp_line
			(start -0.508 -0.9398)
			(end 0.508 -0.9398)
			(stroke
				(width 0.1524)
				(type default)
			)
			(layer "B.SilkS")
		)
		(fp_rect
			(start 0.508 0.9398)
			(end -0.508 -0.9398)
			(stroke
				(width 0)
				(type default)
			)
			(fill no)
			(layer "B.CrtYd")
		)
		(fp_rect
			(start 0.508 0.9398)
			(end -0.508 -0.9398)
			(stroke
				(width 0)
				(type default)
			)
			(fill no)
			(layer "B.Fab")
		)
		(pad "1" smd custom
			(at 0 -0.4445 270)
			(size 0.1397 0.1397)
			(layers "B.Cu" "B.Mask" "B.Paste")
			(net "I2C_BMC_A_COMP_A_SDA")
			(options
				(clearance outline)
				(anchor circle)
			)
			(primitives
				(gr_poly
					(pts
						(arc
							(start -0.1778 0.2794)
							(mid -0.249642 0.249642)
							(end -0.2794 0.1778)
						)
						(arc
							(start -0.2794 -0.1778)
							(mid -0.249642 -0.249642)
							(end -0.1778 -0.2794)
						)
						(arc
							(start 0.1778 -0.2794)
							(mid 0.249642 -0.249642)
							(end 0.2794 -0.1778)
						)
						(arc
							(start 0.2794 0.1778)
							(mid 0.249642 0.249642)
							(end 0.1778 0.2794)
						)
					)
					(width 0)
					(fill yes)
				)
			)
		)
		(pad "2" smd custom
			(at 0 0.4445 270)
			(size 0.1397 0.1397)
			(layers "B.Cu" "B.Mask" "B.Paste")
			(net "P3V3_STBY_A")
			(options
				(clearance outline)
				(anchor circle)
			)
			(primitives
				(gr_poly
					(pts
						(arc
							(start -0.1778 0.2794)
							(mid -0.249642 0.249642)
							(end -0.2794 0.1778)
						)
						(arc
							(start -0.2794 -0.1778)
							(mid -0.249642 -0.249642)
							(end -0.1778 -0.2794)
						)
						(arc
							(start 0.1778 -0.2794)
							(mid 0.249642 -0.249642)
							(end 0.2794 -0.1778)
						)
						(arc
							(start 0.2794 0.1778)
							(mid 0.249642 0.249642)
							(end 0.1778 0.2794)
						)
					)
					(width 0)
					(fill yes)
				)
			)
		)
	)
	(footprint ""
		(layer "B.Cu")
		(at 47.356014 -148.695664 180)
		(property "Reference" "R1241"
			(at 0 0 0)
			(layer "B.SilkS")
			(hide yes)
			(effects
				(font
					(size 1.27 1.27)
				)
				(justify mirror)
			)
		)
		(property "Value" "10KR2F-2-GP"
			(at -0.064008 -3.993896 180)
			(unlocked yes)
			(layer "B.Fab")
			(hide yes)
			(effects
				(font
					(size 1.016 1.016)
					(thickness 0.1524)
				)
				(justify mirror)
			)
		)
		(property "Device Type" "R402H16"
			(at -0.064008 -5.517896 180)
			(unlocked yes)
			(layer "B.Fab")
			(hide yes)
			(effects
				(font
					(size 1.016 1.016)
					(thickness 0.1524)
				)
				(justify mirror)
			)
		)
		(duplicate_pad_numbers_are_jumpers no)
		(fp_line
			(start 0.508 -0.9398)
			(end 0.508 0.9398)
			(stroke
				(width 0.1524)
				(type default)
			)
			(layer "B.SilkS")
		)
		(fp_line
			(start -0.508 -0.9398)
			(end 0.508 -0.9398)
			(stroke
				(width 0.1524)
				(type default)
			)
			(layer "B.SilkS")
		)
		(fp_rect
			(start 0.508 0.9398)
			(end -0.508 -0.9398)
			(stroke
				(width 0)
				(type default)
			)
			(fill no)
			(layer "B.CrtYd")
		)
		(fp_rect
			(start 0.508 0.9398)
			(end -0.508 -0.9398)
			(stroke
				(width 0)
				(type default)
			)
			(fill no)
			(layer "B.Fab")
		)
		(pad "1" smd custom
			(at 0 -0.4445)
			(size 0.1397 0.1397)
			(layers "B.Cu" "B.Mask" "B.Paste")
			(net "P5V_B_VFB")
			(options
				(clearance outline)
				(anchor circle)
			)
			(primitives
				(gr_poly
					(pts
						(arc
							(start -0.1778 0.2794)
							(mid -0.249642 0.249642)
							(end -0.2794 0.1778)
						)
						(arc
							(start -0.2794 -0.1778)
							(mid -0.249642 -0.249642)
							(end -0.1778 -0.2794)
						)
						(arc
							(start 0.1778 -0.2794)
							(mid 0.249642 -0.249642)
							(end 0.2794 -0.1778)
						)
						(arc
							(start 0.2794 0.1778)
							(mid 0.249642 0.249642)
							(end 0.1778 0.2794)
						)
					)
					(width 0)
					(fill yes)
				)
			)
		)
		(pad "2" smd custom
			(at 0 0.4445)
			(size 0.1397 0.1397)
			(layers "B.Cu" "B.Mask" "B.Paste")
			(net "AGND_P5V_B")
			(options
				(clearance outline)
				(anchor circle)
			)
			(primitives
				(gr_poly
					(pts
						(arc
							(start -0.1778 0.2794)
							(mid -0.249642 0.249642)
							(end -0.2794 0.1778)
						)
						(arc
							(start -0.2794 -0.1778)
							(mid -0.249642 -0.249642)
							(end -0.1778 -0.2794)
						)
						(arc
							(start 0.1778 -0.2794)
							(mid 0.249642 -0.249642)
							(end 0.2794 -0.1778)
						)
						(arc
							(start 0.2794 0.1778)
							(mid 0.249642 0.249642)
							(end 0.1778 0.2794)
						)
					)
					(width 0)
					(fill yes)
				)
			)
		)
	)
	(footprint ""
		(layer "B.Cu")
		(at 436.732172 -252.076966 180)
		(property "Reference" "C635"
			(at 0 0 0)
			(layer "B.SilkS")
			(hide yes)
			(effects
				(font
					(size 1.27 1.27)
				)
				(justify mirror)
			)
		)
		(property "Value" "SC10U16V5KX-7-GP-U"
			(at 0.0762 -6.1214 180)
			(unlocked yes)
			(layer "B.Fab")
			(hide yes)
			(effects
				(font
					(size 1.016 1.016)
					(thickness 0.1524)
				)
				(justify mirror)
			)
		)
		(property "Device Type" "C805H58"
			(at 0.0762 -8.1534 180)
			(unlocked yes)
			(layer "B.Fab")
			(hide yes)
			(effects
				(font
					(size 1.016 1.016)
					(thickness 0.1524)
				)
				(justify mirror)
			)
		)
		(duplicate_pad_numbers_are_jumpers no)
		(fp_line
			(start -0.635 0)
			(end 0.635 0)
			(stroke
				(width 0.508)
				(type default)
			)
			(layer "B.SilkS")
		)
		(fp_rect
			(start 0.9652 1.778)
			(end -0.9652 -1.778)
			(stroke
				(width 0)
				(type default)
			)
			(fill no)
			(layer "B.CrtYd")
		)
		(fp_poly
			(pts
				(xy 0.9652 -1.778) (xy -0.9652 -1.778) (xy -0.9652 1.778) (xy 0.9652 1.778)
			)
			(stroke
				(width 0)
				(type default)
			)
			(fill no)
			(layer "B.Fab")
		)
		(pad "1" smd rect
			(at 0 -0.9652)
			(size 1.397 1.143)
			(layers "B.Cu" "B.Mask" "B.Paste")
			(net "P12V_A_VIN_U22")
		)
		(pad "2" smd rect
			(at 0 0.9652)
			(size 1.397 1.143)
			(layers "B.Cu" "B.Mask" "B.Paste")
			(net "GND")
		)
	)
	(footprint ""
		(layer "B.Cu")
		(at 432.501294 -255.739138 180)
		(property "Reference" "R1245"
			(at 0 0 0)
			(layer "B.SilkS")
			(hide yes)
			(effects
				(font
					(size 1.27 1.27)
				)
				(justify mirror)
			)
		)
		(property "Value" "2D2R3-1-U-GP"
			(at 0.0254 -2.5146 180)
			(unlocked yes)
			(layer "B.Fab")
			(hide yes)
			(effects
				(font
					(size 1.016 1.016)
					(thickness 0.1524)
				)
				(justify mirror)
			)
		)
		(property "Device Type" "R603H22"
			(at 0.0254 -4.0386 180)
			(unlocked yes)
			(layer "B.Fab")
			(hide yes)
			(effects
				(font
					(size 1.016 1.016)
					(thickness 0.1524)
				)
				(justify mirror)
			)
		)
		(duplicate_pad_numbers_are_jumpers no)
		(fp_line
			(start 0.4826 0)
			(end 0.2032 0)
			(stroke
				(width 0.2032)
				(type default)
			)
			(layer "B.SilkS")
		)
		(fp_line
			(start -0.2032 0)
			(end -0.4826 0)
			(stroke
				(width 0.2032)
				(type default)
			)
			(layer "B.SilkS")
		)
		(fp_rect
			(start 0.5842 1.3335)
			(end -0.5842 -1.3335)
			(stroke
				(width 0)
				(type default)
			)
			(fill no)
			(layer "B.CrtYd")
		)
		(fp_rect
			(start 0.5842 1.3335)
			(end -0.5842 -1.3335)
			(stroke
				(width 0)
				(type default)
			)
			(fill no)
			(layer "B.Fab")
		)
		(pad "1" smd custom
			(at 0 -0.762)
			(size 0.2159 0.2159)
			(layers "B.Cu" "B.Mask" "B.Paste")
			(net "P12V_A")
			(options
				(clearance outline)
				(anchor circle)
			)
			(primitives
				(gr_poly
					(pts
						(arc
							(start -0.3302 0.4318)
							(mid -0.402042 0.402042)
							(end -0.4318 0.3302)
						)
						(arc
							(start -0.4318 -0.3302)
							(mid -0.402042 -0.402042)
							(end -0.3302 -0.4318)
						)
						(arc
							(start 0.3302 -0.4318)
							(mid 0.402042 -0.402042)
							(end 0.4318 -0.3302)
						)
						(arc
							(start 0.4318 0.3302)
							(mid 0.402042 0.402042)
							(end 0.3302 0.4318)
						)
					)
					(width 0)
					(fill yes)
				)
			)
		)
		(pad "2" smd custom
			(at 0 0.762)
			(size 0.2159 0.2159)
			(layers "B.Cu" "B.Mask" "B.Paste")
			(net "P12V_A_VDD_U22")
			(options
				(clearance outline)
				(anchor circle)
			)
			(primitives
				(gr_poly
					(pts
						(arc
							(start -0.3302 0.4318)
							(mid -0.402042 0.402042)
							(end -0.4318 0.3302)
						)
						(arc
							(start -0.4318 -0.3302)
							(mid -0.402042 -0.402042)
							(end -0.3302 -0.4318)
						)
						(arc
							(start 0.3302 -0.4318)
							(mid 0.402042 -0.402042)
							(end 0.4318 -0.3302)
						)
						(arc
							(start 0.4318 0.3302)
							(mid 0.402042 0.402042)
							(end 0.3302 0.4318)
						)
					)
					(width 0)
					(fill yes)
				)
			)
		)
	)
	(footprint ""
		(layer "B.Cu")
		(at 472.186 -243.459 90)
		(property "Reference" "L7"
			(at 0 0 90)
			(layer "B.SilkS")
			(hide yes)
			(effects
				(font
					(size 1.27 1.27)
				)
				(justify mirror)
			)
		)
		(property "Value" "BLM21PG220SN1DGP"
			(at -0.0254 -5.6896 90)
			(unlocked yes)
			(layer "B.Fab")
			(hide yes)
			(effects
				(font
					(size 1.016 1.016)
					(thickness 0.1524)
				)
				(justify mirror)
			)
		)
		(property "Device Type" "L20125H42"
			(at -0.0254 -7.5946 90)
			(unlocked yes)
			(layer "B.Fab")
			(hide yes)
			(effects
				(font
					(size 1.016 1.016)
					(thickness 0.1524)
				)
				(justify mirror)
			)
		)
		(duplicate_pad_numbers_are_jumpers no)
		(fp_line
			(start 0.9144 -1.7018)
			(end 0.9144 1.7018)
			(stroke
				(width 0.1524)
				(type default)
			)
			(layer "B.SilkS")
		)
		(fp_line
			(start -0.9144 -1.7018)
			(end 0.9144 -1.7018)
			(stroke
				(width 0.1524)
				(type default)
			)
			(layer "B.SilkS")
		)
		(fp_line
			(start 0.9144 1.7018)
			(end -0.9144 1.7018)
			(stroke
				(width 0.1524)
				(type default)
			)
			(layer "B.SilkS")
		)
		(fp_line
			(start -0.9144 1.7018)
			(end -0.9144 -1.7018)
			(stroke
				(width 0.1524)
				(type default)
			)
			(layer "B.SilkS")
		)
		(fp_rect
			(start 1.0033 1.778)
			(end -1.0033 -1.778)
			(stroke
				(width 0)
				(type default)
			)
			(fill no)
			(layer "B.CrtYd")
		)
		(fp_poly
			(pts
				(xy 1.0033 -1.778) (xy -1.0033 -1.778) (xy -1.0033 1.778) (xy 1.0033 1.778)
			)
			(stroke
				(width 0)
				(type default)
			)
			(fill no)
			(layer "B.Fab")
		)
		(pad "1" smd rect
			(at 0 -0.9652 270)
			(size 1.397 1.143)
			(layers "B.Cu" "B.Mask" "B.Paste")
			(net "P12V_A")
		)
		(pad "2" smd rect
			(at 0 0.9652 270)
			(size 1.397 1.143)
			(layers "B.Cu" "B.Mask" "B.Paste")
			(net "P12V_A_VIN_U27")
		)
	)
	(footprint ""
		(layer "B.Cu")
		(at 471.17 -252.5522 180)
		(property "Reference" "C646"
			(at 0 0 0)
			(layer "B.SilkS")
			(hide yes)
			(effects
				(font
					(size 1.27 1.27)
				)
				(justify mirror)
			)
		)
		(property "Value" "SC10U16V5KX-7-GP-U"
			(at 0.0762 -6.1214 180)
			(unlocked yes)
			(layer "B.Fab")
			(hide yes)
			(effects
				(font
					(size 1.016 1.016)
					(thickness 0.1524)
				)
				(justify mirror)
			)
		)
		(property "Device Type" "C805H58"
			(at 0.0762 -8.1534 180)
			(unlocked yes)
			(layer "B.Fab")
			(hide yes)
			(effects
				(font
					(size 1.016 1.016)
					(thickness 0.1524)
				)
				(justify mirror)
			)
		)
		(duplicate_pad_numbers_are_jumpers no)
		(fp_line
			(start -0.635 0)
			(end 0.635 0)
			(stroke
				(width 0.508)
				(type default)
			)
			(layer "B.SilkS")
		)
		(fp_rect
			(start 0.9652 1.778)
			(end -0.9652 -1.778)
			(stroke
				(width 0)
				(type default)
			)
			(fill no)
			(layer "B.CrtYd")
		)
		(fp_poly
			(pts
				(xy 0.9652 -1.778) (xy -0.9652 -1.778) (xy -0.9652 1.778) (xy 0.9652 1.778)
			)
			(stroke
				(width 0)
				(type default)
			)
			(fill no)
			(layer "B.Fab")
		)
		(pad "1" smd rect
			(at 0 -0.9652)
			(size 1.397 1.143)
			(layers "B.Cu" "B.Mask" "B.Paste")
			(net "P5V_A_3")
		)
		(pad "2" smd rect
			(at 0 0.9652)
			(size 1.397 1.143)
			(layers "B.Cu" "B.Mask" "B.Paste")
			(net "GND")
		)
	)
	(footprint ""
		(layer "B.Cu")
		(at 480.695 -225.806 180)
		(property "Reference" "R1271"
			(at 0 0 0)
			(layer "B.SilkS")
			(hide yes)
			(effects
				(font
					(size 1.27 1.27)
				)
				(justify mirror)
			)
		)
		(property "Value" "15KR2F-GP"
			(at -0.064008 -3.993896 180)
			(unlocked yes)
			(layer "B.Fab")
			(hide yes)
			(effects
				(font
					(size 1.016 1.016)
					(thickness 0.1524)
				)
				(justify mirror)
			)
		)
		(property "Device Type" "R402H16"
			(at -0.064008 -5.517896 180)
			(unlocked yes)
			(layer "B.Fab")
			(hide yes)
			(effects
				(font
					(size 1.016 1.016)
					(thickness 0.1524)
				)
				(justify mirror)
			)
		)
		(duplicate_pad_numbers_are_jumpers no)
		(fp_line
			(start 0.508 -0.9398)
			(end 0.508 0.9398)
			(stroke
				(width 0.1524)
				(type default)
			)
			(layer "B.SilkS")
		)
		(fp_line
			(start -0.508 -0.9398)
			(end 0.508 -0.9398)
			(stroke
				(width 0.1524)
				(type default)
			)
			(layer "B.SilkS")
		)
		(fp_rect
			(start 0.508 0.9398)
			(end -0.508 -0.9398)
			(stroke
				(width 0)
				(type default)
			)
			(fill no)
			(layer "B.CrtYd")
		)
		(fp_rect
			(start 0.508 0.9398)
			(end -0.508 -0.9398)
			(stroke
				(width 0)
				(type default)
			)
			(fill no)
			(layer "B.Fab")
		)
		(pad "1" smd custom
			(at 0 -0.4445)
			(size 0.1397 0.1397)
			(layers "B.Cu" "B.Mask" "B.Paste")
			(net "P5V_A_4_PGOOD")
			(options
				(clearance outline)
				(anchor circle)
			)
			(primitives
				(gr_poly
					(pts
						(arc
							(start -0.1778 0.2794)
							(mid -0.249642 0.249642)
							(end -0.2794 0.1778)
						)
						(arc
							(start -0.2794 -0.1778)
							(mid -0.249642 -0.249642)
							(end -0.1778 -0.2794)
						)
						(arc
							(start 0.1778 -0.2794)
							(mid 0.249642 -0.249642)
							(end 0.2794 -0.1778)
						)
						(arc
							(start 0.2794 0.1778)
							(mid 0.249642 0.249642)
							(end 0.1778 0.2794)
						)
					)
					(width 0)
					(fill yes)
				)
			)
		)
		(pad "2" smd custom
			(at 0 0.4445)
			(size 0.1397 0.1397)
			(layers "B.Cu" "B.Mask" "B.Paste")
			(net "GND")
			(options
				(clearance outline)
				(anchor circle)
			)
			(primitives
				(gr_poly
					(pts
						(arc
							(start -0.1778 0.2794)
							(mid -0.249642 0.249642)
							(end -0.2794 0.1778)
						)
						(arc
							(start -0.2794 -0.1778)
							(mid -0.249642 -0.249642)
							(end -0.1778 -0.2794)
						)
						(arc
							(start 0.1778 -0.2794)
							(mid 0.249642 -0.249642)
							(end 0.2794 -0.1778)
						)
						(arc
							(start 0.2794 0.1778)
							(mid 0.249642 0.249642)
							(end 0.1778 0.2794)
						)
					)
					(width 0)
					(fill yes)
				)
			)
		)
	)
	(footprint ""
		(layer "B.Cu")
		(at 23.6474 -247.0912 180)
		(property "Reference" "C600"
			(at 0 0 0)
			(layer "B.SilkS")
			(hide yes)
			(effects
				(font
					(size 1.27 1.27)
				)
				(justify mirror)
			)
		)
		(property "Value" "SCD1U16V2KX-3GP"
			(at -1.1811 -2.7051 180)
			(unlocked yes)
			(layer "B.Fab")
			(hide yes)
			(effects
				(font
					(size 1.016 1.016)
					(thickness 0.1524)
				)
				(justify mirror)
			)
		)
		(property "Device Type" "C402H22"
			(at -1.1811 -4.2291 180)
			(unlocked yes)
			(layer "B.Fab")
			(hide yes)
			(effects
				(font
					(size 1.016 1.016)
					(thickness 0.1524)
				)
				(justify mirror)
			)
		)
		(duplicate_pad_numbers_are_jumpers no)
		(fp_rect
			(start 0.4318 0.9525)
			(end -0.4318 -0.9525)
			(stroke
				(width 0)
				(type default)
			)
			(fill no)
			(layer "B.CrtYd")
		)
		(fp_rect
			(start 0.4318 0.9525)
			(end -0.4318 -0.9525)
			(stroke
				(width 0)
				(type default)
			)
			(fill no)
			(layer "B.Fab")
		)
		(pad "1" smd custom
			(at 0 -0.4445)
			(size 0.1524 0.1524)
			(layers "B.Cu" "B.Mask" "B.Paste")
			(net "P12V_A_VIN_U20")
			(options
				(clearance outline)
				(anchor circle)
			)
			(primitives
				(gr_poly
					(pts
						(arc
							(start 0.3048 0.2032)
							(mid 0.275042 0.275042)
							(end 0.2032 0.3048)
						)
						(arc
							(start -0.2032 0.3048)
							(mid -0.275042 0.275042)
							(end -0.3048 0.2032)
						)
						(arc
							(start -0.3048 -0.2032)
							(mid -0.275042 -0.275042)
							(end -0.2032 -0.3048)
						)
						(arc
							(start 0.2032 -0.3048)
							(mid 0.275042 -0.275042)
							(end 0.3048 -0.2032)
						)
					)
					(width 0)
					(fill yes)
				)
			)
		)
		(pad "2" smd custom
			(at 0 0.4445)
			(size 0.1524 0.1524)
			(layers "B.Cu" "B.Mask" "B.Paste")
			(net "GND")
			(options
				(clearance outline)
				(anchor circle)
			)
			(primitives
				(gr_poly
					(pts
						(arc
							(start 0.3048 0.2032)
							(mid 0.275042 0.275042)
							(end 0.2032 0.3048)
						)
						(arc
							(start -0.2032 0.3048)
							(mid -0.275042 0.275042)
							(end -0.3048 0.2032)
						)
						(arc
							(start -0.3048 -0.2032)
							(mid -0.275042 -0.275042)
							(end -0.2032 -0.3048)
						)
						(arc
							(start 0.2032 -0.3048)
							(mid 0.275042 -0.275042)
							(end 0.3048 -0.2032)
						)
					)
					(width 0)
					(fill yes)
				)
			)
		)
	)
	(footprint ""
		(layer "B.Cu")
		(at 440.362594 -254.514096 90)
		(property "Reference" "C641"
			(at 0 0 90)
			(layer "B.SilkS")
			(hide yes)
			(effects
				(font
					(size 1.27 1.27)
				)
				(justify mirror)
			)
		)
		(property "Value" "SC1U16V3KX-5GP"
			(at 0 -2.8194 90)
			(unlocked yes)
			(layer "B.Fab")
			(hide yes)
			(effects
				(font
					(size 1.016 1.016)
					(thickness 0.1524)
				)
				(justify mirror)
			)
		)
		(property "Device Type" "C603H36"
			(at 0 -4.3434 90)
			(unlocked yes)
			(layer "B.Fab")
			(hide yes)
			(effects
				(font
					(size 1.016 1.016)
					(thickness 0.1524)
				)
				(justify mirror)
			)
		)
		(duplicate_pad_numbers_are_jumpers no)
		(fp_line
			(start -0.508 0)
			(end 0.508 0)
			(stroke
				(width 0.2032)
				(type default)
			)
			(layer "B.SilkS")
		)
		(fp_rect
			(start 0.5842 1.3335)
			(end -0.5842 -1.3335)
			(stroke
				(width 0)
				(type default)
			)
			(fill no)
			(layer "B.CrtYd")
		)
		(fp_rect
			(start 0.5842 1.3335)
			(end -0.5842 -1.3335)
			(stroke
				(width 0)
				(type default)
			)
			(fill no)
			(layer "B.Fab")
		)
		(pad "1" smd custom
			(at 0 -0.762 270)
			(size 0.2159 0.2159)
			(layers "B.Cu" "B.Mask" "B.Paste")
			(net "GND")
			(options
				(clearance outline)
				(anchor circle)
			)
			(primitives
				(gr_poly
					(pts
						(arc
							(start -0.3302 0.4318)
							(mid -0.402042 0.402042)
							(end -0.4318 0.3302)
						)
						(arc
							(start -0.4318 -0.3302)
							(mid -0.402042 -0.402042)
							(end -0.3302 -0.4318)
						)
						(arc
							(start 0.3302 -0.4318)
							(mid 0.402042 -0.402042)
							(end 0.4318 -0.3302)
						)
						(arc
							(start 0.4318 0.3302)
							(mid 0.402042 0.402042)
							(end 0.3302 0.4318)
						)
					)
					(width 0)
					(fill yes)
				)
			)
		)
		(pad "2" smd custom
			(at 0 0.762 270)
			(size 0.2159 0.2159)
			(layers "B.Cu" "B.Mask" "B.Paste")
			(net "P5V_C_VREG")
			(options
				(clearance outline)
				(anchor circle)
			)
			(primitives
				(gr_poly
					(pts
						(arc
							(start -0.3302 0.4318)
							(mid -0.402042 0.402042)
							(end -0.4318 0.3302)
						)
						(arc
							(start -0.4318 -0.3302)
							(mid -0.402042 -0.402042)
							(end -0.3302 -0.4318)
						)
						(arc
							(start 0.3302 -0.4318)
							(mid 0.402042 -0.402042)
							(end 0.4318 -0.3302)
						)
						(arc
							(start 0.4318 0.3302)
							(mid 0.402042 0.402042)
							(end 0.3302 0.4318)
						)
					)
					(width 0)
					(fill yes)
				)
			)
		)
	)
	(footprint ""
		(layer "B.Cu")
		(at 29.4132 -248.7168 -90)
		(property "Reference" "U20"
			(at 0 0 90)
			(layer "B.SilkS")
			(hide yes)
			(effects
				(font
					(size 1.27 1.27)
				)
				(justify mirror)
			)
		)
		(property "Value" "TPS53319DQPR-GP"
			(at -4.7498 -5.6896 270)
			(unlocked yes)
			(layer "B.Fab")
			(hide yes)
			(effects
				(font
					(size 1.016 1.016)
					(thickness 0.1524)
				)
				(justify mirror)
			)
		)
		(property "Device Type" "QFN22G6050-G6133H60"
			(at -4.7498 -7.2136 270)
			(unlocked yes)
			(layer "B.Fab")
			(hide yes)
			(effects
				(font
					(size 1.016 1.016)
					(thickness 0.1524)
				)
				(justify mirror)
			)
		)
		(duplicate_pad_numbers_are_jumpers no)
		(fp_line
			(start -3.556 3.5179)
			(end -3.556 2.2479)
			(stroke
				(width 0.1524)
				(type default)
			)
			(layer "B.SilkS")
		)
		(fp_line
			(start -2.286 3.5179)
			(end -3.556 3.5179)
			(stroke
				(width 0.1524)
				(type default)
			)
			(layer "B.SilkS")
		)
		(fp_line
			(start 3.556 3.5179)
			(end 2.286 3.5179)
			(stroke
				(width 0.1524)
				(type default)
			)
			(layer "B.SilkS")
		)
		(fp_line
			(start -1.500124 3.262122)
			(end -1.500124 4.024122)
			(stroke
				(width 0.1524)
				(type default)
			)
			(layer "B.SilkS")
		)
		(fp_line
			(start 0.999998 3.262122)
			(end 0.999998 3.770122)
			(stroke
				(width 0.1524)
				(type default)
			)
			(layer "B.SilkS")
		)
		(fp_line
			(start 3.556 2.2479)
			(end 3.556 3.5179)
			(stroke
				(width 0.1524)
				(type default)
			)
			(layer "B.SilkS")
		)
		(fp_line
			(start -0.500126 -3.262122)
			(end -0.500126 -3.770122)
			(stroke
				(width 0.1524)
				(type default)
			)
			(layer "B.SilkS")
		)
		(fp_line
			(start 1.999996 -3.262122)
			(end 1.999996 -4.024122)
			(stroke
				(width 0.1524)
				(type default)
			)
			(layer "B.SilkS")
		)
		(fp_line
			(start 2.286 -3.5179)
			(end 3.556 -3.5179)
			(stroke
				(width 0.1524)
				(type default)
			)
			(layer "B.SilkS")
		)
		(fp_line
			(start 3.556 -3.5179)
			(end 3.556 -2.2479)
			(stroke
				(width 0.1524)
				(type default)
			)
			(layer "B.SilkS")
		)
		(fp_poly
			(pts
				(xy -3.556 -3.5179) (xy -2.5273 -3.5179) (xy -3.556 -2.4892)
			)
			(stroke
				(width 0)
				(type default)
			)
			(fill yes)
			(layer "B.SilkS")
		)
		(fp_rect
			(start 2.9972 2.5019)
			(end -2.9972 -2.5019)
			(stroke
				(width 0)
				(type default)
			)
			(fill no)
			(layer "B.CrtYd")
		)
		(fp_poly
			(pts
				(xy -3.556 -2.5019) (xy 2.9972 -2.5019) (xy 2.9972 2.5019) (xy -2.9972 2.5019) (xy -2.9972 -2.4892)
				(xy -3.556 -2.4892) (xy -3.556 3.5179) (xy 3.556 3.5179) (xy 3.556 -3.5179) (xy -3.556 -3.5179)
			)
			(stroke
				(width 0)
				(type default)
			)
			(fill no)
			(layer "B.CrtYd")
		)
		(fp_rect
			(start 3.556 3.5179)
			(end -3.556 -3.5179)
			(stroke
				(width 0)
				(type default)
			)
			(fill no)
			(layer "B.Fab")
		)
		(pad "1" smd rect
			(at -2.500122 -2.449322 90)
			(size 0.3048 1.1176)
			(layers "B.Cu" "B.Mask" "B.Paste")
			(net "P5V_A_VFB")
		)
		(pad "2" smd rect
			(at -1.999996 -2.449322 90)
			(size 0.3048 1.1176)
			(layers "B.Cu" "B.Mask" "B.Paste")
			(net "P5V_A_EN_R")
		)
		(pad "3" smd rect
			(at -1.500124 -2.449322 90)
			(size 0.3048 1.1176)
			(layers "B.Cu" "B.Mask" "B.Paste")
			(net "P5V_A_1_PGOOD")
		)
		(pad "4" smd rect
			(at -0.999998 -2.449322 90)
			(size 0.3048 1.1176)
			(layers "B.Cu" "B.Mask" "B.Paste")
			(net "P5V_A_VBST")
		)
		(pad "5" smd rect
			(at -0.500126 -2.449322 90)
			(size 0.3048 1.1176)
			(layers "B.Cu" "B.Mask" "B.Paste")
			(net "P5V_A_ROVP")
		)
		(pad "6" smd rect
			(at 0 -2.449322 90)
			(size 0.3048 1.1176)
			(layers "B.Cu" "B.Mask" "B.Paste")
			(net "P5V_A_LL")
		)
		(pad "7" smd rect
			(at 0.500126 -2.449322 90)
			(size 0.3048 1.1176)
			(layers "B.Cu" "B.Mask" "B.Paste")
			(net "P5V_A_LL")
		)
		(pad "8" smd rect
			(at 0.999998 -2.449322 90)
			(size 0.3048 1.1176)
			(layers "B.Cu" "B.Mask" "B.Paste")
			(net "P5V_A_LL")
		)
		(pad "9" smd rect
			(at 1.500124 -2.449322 90)
			(size 0.3048 1.1176)
			(layers "B.Cu" "B.Mask" "B.Paste")
			(net "P5V_A_LL")
		)
		(pad "10" smd rect
			(at 1.999996 -2.449322 90)
			(size 0.3048 1.1176)
			(layers "B.Cu" "B.Mask" "B.Paste")
			(net "P5V_A_LL")
		)
		(pad "11" smd rect
			(at 2.500122 -2.449322 90)
			(size 0.3048 1.1176)
			(layers "B.Cu" "B.Mask" "B.Paste")
			(net "P5V_A_LL")
		)
		(pad "12" smd rect
			(at 2.500122 2.449322 90)
			(size 0.3048 1.1176)
			(layers "B.Cu" "B.Mask" "B.Paste")
			(net "P12V_A_VIN_U20")
		)
		(pad "13" smd rect
			(at 1.999996 2.449322 90)
			(size 0.3048 1.1176)
			(layers "B.Cu" "B.Mask" "B.Paste")
			(net "P12V_A_VIN_U20")
		)
		(pad "14" smd rect
			(at 1.500124 2.449322 90)
			(size 0.3048 1.1176)
			(layers "B.Cu" "B.Mask" "B.Paste")
			(net "P12V_A_VIN_U20")
		)
		(pad "15" smd rect
			(at 0.999998 2.449322 90)
			(size 0.3048 1.1176)
			(layers "B.Cu" "B.Mask" "B.Paste")
			(net "P12V_A_VIN_U20")
		)
		(pad "16" smd rect
			(at 0.500126 2.449322 90)
			(size 0.3048 1.1176)
			(layers "B.Cu" "B.Mask" "B.Paste")
			(net "P12V_A_VIN_U20")
		)
		(pad "17" smd rect
			(at 0 2.449322 90)
			(size 0.3048 1.1176)
			(layers "B.Cu" "B.Mask" "B.Paste")
			(net "P12V_A_VIN_U20")
		)
		(pad "18" smd rect
			(at -0.500126 2.449322 90)
			(size 0.3048 1.1176)
			(layers "B.Cu" "B.Mask" "B.Paste")
			(net "P5V_A_VREG")
		)
		(pad "19" smd rect
			(at -0.999998 2.449322 90)
			(size 0.3048 1.1176)
			(layers "B.Cu" "B.Mask" "B.Paste")
			(net "P12V_A_VDD_U20")
		)
		(pad "20" smd rect
			(at -1.500124 2.449322 90)
			(size 0.3048 1.1176)
			(layers "B.Cu" "B.Mask" "B.Paste")
			(net "P5V_A_MODE")
		)
		(pad "21" smd rect
			(at -1.999996 2.449322 90)
			(size 0.3048 1.1176)
			(layers "B.Cu" "B.Mask" "B.Paste")
			(net "P5V_A_TRIP")
		)
		(pad "22" smd rect
			(at -2.500122 2.449322 90)
			(size 0.3048 1.1176)
			(layers "B.Cu" "B.Mask" "B.Paste")
			(net "P5V_A_RF")
		)
		(pad "23" smd custom
			(at 0 0 90)
			(size 0.83185 0.83185)
			(layers "B.Cu" "B.Mask" "B.Paste")
			(net "GND")
			(options
				(clearance outline)
				(anchor circle)
			)
			(primitives
				(gr_poly
					(pts
						(xy -2.7813 -1.6637) (xy -2.7813 -1.2954) (xy -3.048 -1.2954) (xy -3.048 -0.9525) (xy -2.7813 -0.9525)
						(xy -2.7813 0.9525) (xy -3.048 0.9525) (xy -3.048 1.2954) (xy -2.7813 1.2954) (xy -2.7813 1.6637)
						(xy 2.7813 1.6637) (xy 2.7813 1.2954) (xy 3.048 1.2954) (xy 3.048 0.9525) (xy 2.7813 0.9525) (xy 2.7813 -0.9525)
						(xy 3.048 -0.9525) (xy 3.048 -1.2954) (xy 2.7813 -1.2954) (xy 2.7813 -1.6637)
					)
					(width 0)
					(fill yes)
				)
			)
		)
	)
	(footprint ""
		(layer "B.Cu")
		(at 180.774594 -224.3328)
		(property "Reference" "R1292"
			(at 0 0 0)
			(layer "B.SilkS")
			(hide yes)
			(effects
				(font
					(size 1.27 1.27)
				)
				(justify mirror)
			)
		)
		(property "Value" "0R2J-2-GP"
			(at -0.064008 -3.993896 0)
			(unlocked yes)
			(layer "B.Fab")
			(hide yes)
			(effects
				(font
					(size 1.016 1.016)
					(thickness 0.1524)
				)
				(justify mirror)
			)
		)
		(property "Device Type" "R402H16"
			(at -0.064008 -5.517896 0)
			(unlocked yes)
			(layer "B.Fab")
			(hide yes)
			(effects
				(font
					(size 1.016 1.016)
					(thickness 0.1524)
				)
				(justify mirror)
			)
		)
		(duplicate_pad_numbers_are_jumpers no)
		(fp_line
			(start -0.508 -0.9398)
			(end 0.508 -0.9398)
			(stroke
				(width 0.1524)
				(type default)
			)
			(layer "B.SilkS")
		)
		(fp_line
			(start 0.508 -0.9398)
			(end 0.508 0.9398)
			(stroke
				(width 0.1524)
				(type default)
			)
			(layer "B.SilkS")
		)
		(fp_rect
			(start 0.508 0.9398)
			(end -0.508 -0.9398)
			(stroke
				(width 0)
				(type default)
			)
			(fill no)
			(layer "B.CrtYd")
		)
		(fp_rect
			(start 0.508 0.9398)
			(end -0.508 -0.9398)
			(stroke
				(width 0)
				(type default)
			)
			(fill no)
			(layer "B.Fab")
		)
		(pad "1" smd custom
			(at 0 -0.4445 180)
			(size 0.1397 0.1397)
			(layers "B.Cu" "B.Mask" "B.Paste")
			(net "P3V3_STBY_EN_R")
			(options
				(clearance outline)
				(anchor circle)
			)
			(primitives
				(gr_poly
					(pts
						(arc
							(start -0.1778 0.2794)
							(mid -0.249642 0.249642)
							(end -0.2794 0.1778)
						)
						(arc
							(start -0.2794 -0.1778)
							(mid -0.249642 -0.249642)
							(end -0.1778 -0.2794)
						)
						(arc
							(start 0.1778 -0.2794)
							(mid 0.249642 -0.249642)
							(end 0.2794 -0.1778)
						)
						(arc
							(start 0.2794 0.1778)
							(mid 0.249642 0.249642)
							(end 0.1778 0.2794)
						)
					)
					(width 0)
					(fill yes)
				)
			)
		)
		(pad "2" smd custom
			(at 0 0.4445 180)
			(size 0.1397 0.1397)
			(layers "B.Cu" "B.Mask" "B.Paste")
			(net "P12V_A_PGOOD")
			(options
				(clearance outline)
				(anchor circle)
			)
			(primitives
				(gr_poly
					(pts
						(arc
							(start -0.1778 0.2794)
							(mid -0.249642 0.249642)
							(end -0.2794 0.1778)
						)
						(arc
							(start -0.2794 -0.1778)
							(mid -0.249642 -0.249642)
							(end -0.1778 -0.2794)
						)
						(arc
							(start 0.1778 -0.2794)
							(mid 0.249642 -0.249642)
							(end 0.2794 -0.1778)
						)
						(arc
							(start 0.2794 0.1778)
							(mid 0.249642 0.249642)
							(end 0.1778 0.2794)
						)
					)
					(width 0)
					(fill yes)
				)
			)
		)
	)
	(footprint ""
		(layer "B.Cu")
		(at 49.2252 -148.7678 90)
		(property "Reference" "R1236"
			(at 0 0 90)
			(layer "B.SilkS")
			(hide yes)
			(effects
				(font
					(size 1.27 1.27)
				)
				(justify mirror)
			)
		)
		(property "Value" "71K5R2F-GP"
			(at -0.064008 -3.993896 90)
			(unlocked yes)
			(layer "B.Fab")
			(hide yes)
			(effects
				(font
					(size 1.016 1.016)
					(thickness 0.1524)
				)
				(justify mirror)
			)
		)
		(property "Device Type" "R402H16"
			(at -0.064008 -5.517896 90)
			(unlocked yes)
			(layer "B.Fab")
			(hide yes)
			(effects
				(font
					(size 1.016 1.016)
					(thickness 0.1524)
				)
				(justify mirror)
			)
		)
		(duplicate_pad_numbers_are_jumpers no)
		(fp_line
			(start 0.508 -0.9398)
			(end 0.508 0.9398)
			(stroke
				(width 0.1524)
				(type default)
			)
			(layer "B.SilkS")
		)
		(fp_line
			(start -0.508 -0.9398)
			(end 0.508 -0.9398)
			(stroke
				(width 0.1524)
				(type default)
			)
			(layer "B.SilkS")
		)
		(fp_rect
			(start 0.508 0.9398)
			(end -0.508 -0.9398)
			(stroke
				(width 0)
				(type default)
			)
			(fill no)
			(layer "B.CrtYd")
		)
		(fp_rect
			(start 0.508 0.9398)
			(end -0.508 -0.9398)
			(stroke
				(width 0)
				(type default)
			)
			(fill no)
			(layer "B.Fab")
		)
		(pad "1" smd custom
			(at 0 -0.4445 270)
			(size 0.1397 0.1397)
			(layers "B.Cu" "B.Mask" "B.Paste")
			(net "P5V_B_VFB")
			(options
				(clearance outline)
				(anchor circle)
			)
			(primitives
				(gr_poly
					(pts
						(arc
							(start -0.1778 0.2794)
							(mid -0.249642 0.249642)
							(end -0.2794 0.1778)
						)
						(arc
							(start -0.2794 -0.1778)
							(mid -0.249642 -0.249642)
							(end -0.1778 -0.2794)
						)
						(arc
							(start 0.1778 -0.2794)
							(mid 0.249642 -0.249642)
							(end 0.2794 -0.1778)
						)
						(arc
							(start 0.2794 0.1778)
							(mid 0.249642 0.249642)
							(end 0.1778 0.2794)
						)
					)
					(width 0)
					(fill yes)
				)
			)
		)
		(pad "2" smd custom
			(at 0 0.4445 270)
			(size 0.1397 0.1397)
			(layers "B.Cu" "B.Mask" "B.Paste")
			(net "P5V_B_VFB_R")
			(options
				(clearance outline)
				(anchor circle)
			)
			(primitives
				(gr_poly
					(pts
						(arc
							(start -0.1778 0.2794)
							(mid -0.249642 0.249642)
							(end -0.2794 0.1778)
						)
						(arc
							(start -0.2794 -0.1778)
							(mid -0.249642 -0.249642)
							(end -0.1778 -0.2794)
						)
						(arc
							(start 0.1778 -0.2794)
							(mid 0.249642 -0.249642)
							(end 0.2794 -0.1778)
						)
						(arc
							(start 0.2794 0.1778)
							(mid 0.249642 0.249642)
							(end 0.1778 0.2794)
						)
					)
					(width 0)
					(fill yes)
				)
			)
		)
	)
	(footprint ""
		(layer "B.Cu")
		(at 185.212228 -219.507308)
		(property "Reference" "R1288"
			(at 0 0 0)
			(layer "B.SilkS")
			(hide yes)
			(effects
				(font
					(size 1.27 1.27)
				)
				(justify mirror)
			)
		)
		(property "Value" "10KR2F-2-GP"
			(at -0.064008 -3.993896 0)
			(unlocked yes)
			(layer "B.Fab")
			(hide yes)
			(effects
				(font
					(size 1.016 1.016)
					(thickness 0.1524)
				)
				(justify mirror)
			)
		)
		(property "Device Type" "R402H16"
			(at -0.064008 -5.517896 0)
			(unlocked yes)
			(layer "B.Fab")
			(hide yes)
			(effects
				(font
					(size 1.016 1.016)
					(thickness 0.1524)
				)
				(justify mirror)
			)
		)
		(duplicate_pad_numbers_are_jumpers no)
		(fp_line
			(start -0.508 -0.9398)
			(end 0.508 -0.9398)
			(stroke
				(width 0.1524)
				(type default)
			)
			(layer "B.SilkS")
		)
		(fp_line
			(start 0.508 -0.9398)
			(end 0.508 0.9398)
			(stroke
				(width 0.1524)
				(type default)
			)
			(layer "B.SilkS")
		)
		(fp_rect
			(start 0.508 0.9398)
			(end -0.508 -0.9398)
			(stroke
				(width 0)
				(type default)
			)
			(fill no)
			(layer "B.CrtYd")
		)
		(fp_rect
			(start 0.508 0.9398)
			(end -0.508 -0.9398)
			(stroke
				(width 0)
				(type default)
			)
			(fill no)
			(layer "B.Fab")
		)
		(pad "1" smd custom
			(at 0 -0.4445 180)
			(size 0.1397 0.1397)
			(layers "B.Cu" "B.Mask" "B.Paste")
			(net "P3V3_STBY_VRG5")
			(options
				(clearance outline)
				(anchor circle)
			)
			(primitives
				(gr_poly
					(pts
						(arc
							(start -0.1778 0.2794)
							(mid -0.249642 0.249642)
							(end -0.2794 0.1778)
						)
						(arc
							(start -0.2794 -0.1778)
							(mid -0.249642 -0.249642)
							(end -0.1778 -0.2794)
						)
						(arc
							(start 0.1778 -0.2794)
							(mid 0.249642 -0.249642)
							(end 0.2794 -0.1778)
						)
						(arc
							(start 0.2794 0.1778)
							(mid 0.249642 0.249642)
							(end 0.1778 0.2794)
						)
					)
					(width 0)
					(fill yes)
				)
			)
		)
		(pad "2" smd custom
			(at 0 0.4445 180)
			(size 0.1397 0.1397)
			(layers "B.Cu" "B.Mask" "B.Paste")
			(net "PWRGD_P3V3_STBY")
			(options
				(clearance outline)
				(anchor circle)
			)
			(primitives
				(gr_poly
					(pts
						(arc
							(start -0.1778 0.2794)
							(mid -0.249642 0.249642)
							(end -0.2794 0.1778)
						)
						(arc
							(start -0.2794 -0.1778)
							(mid -0.249642 -0.249642)
							(end -0.1778 -0.2794)
						)
						(arc
							(start 0.1778 -0.2794)
							(mid 0.249642 -0.249642)
							(end 0.2794 -0.1778)
						)
						(arc
							(start 0.2794 0.1778)
							(mid 0.249642 0.249642)
							(end 0.1778 0.2794)
						)
					)
					(width 0)
					(fill yes)
				)
			)
		)
	)
	(footprint ""
		(layer "B.Cu")
		(at 456.880214 -255.941576 180)
		(property "Reference" "C642"
			(at 0 0 0)
			(layer "B.SilkS")
			(hide yes)
			(effects
				(font
					(size 1.27 1.27)
				)
				(justify mirror)
			)
		)
		(property "Value" "SCD1U50V3KX-GP"
			(at 0 -2.8194 180)
			(unlocked yes)
			(layer "B.Fab")
			(hide yes)
			(effects
				(font
					(size 1.016 1.016)
					(thickness 0.1524)
				)
				(justify mirror)
			)
		)
		(property "Device Type" "C603H36"
			(at 0 -4.3434 180)
			(unlocked yes)
			(layer "B.Fab")
			(hide yes)
			(effects
				(font
					(size 1.016 1.016)
					(thickness 0.1524)
				)
				(justify mirror)
			)
		)
		(duplicate_pad_numbers_are_jumpers no)
		(fp_line
			(start -0.508 0)
			(end 0.508 0)
			(stroke
				(width 0.2032)
				(type default)
			)
			(layer "B.SilkS")
		)
		(fp_rect
			(start 0.5842 1.3335)
			(end -0.5842 -1.3335)
			(stroke
				(width 0)
				(type default)
			)
			(fill no)
			(layer "B.CrtYd")
		)
		(fp_rect
			(start 0.5842 1.3335)
			(end -0.5842 -1.3335)
			(stroke
				(width 0)
				(type default)
			)
			(fill no)
			(layer "B.Fab")
		)
		(pad "1" smd custom
			(at 0 -0.762)
			(size 0.2159 0.2159)
			(layers "B.Cu" "B.Mask" "B.Paste")
			(net "P5V_A_3")
			(options
				(clearance outline)
				(anchor circle)
			)
			(primitives
				(gr_poly
					(pts
						(arc
							(start -0.3302 0.4318)
							(mid -0.402042 0.402042)
							(end -0.4318 0.3302)
						)
						(arc
							(start -0.4318 -0.3302)
							(mid -0.402042 -0.402042)
							(end -0.3302 -0.4318)
						)
						(arc
							(start 0.3302 -0.4318)
							(mid 0.402042 -0.402042)
							(end 0.4318 -0.3302)
						)
						(arc
							(start 0.4318 0.3302)
							(mid 0.402042 0.402042)
							(end 0.3302 0.4318)
						)
					)
					(width 0)
					(fill yes)
				)
			)
		)
		(pad "2" smd custom
			(at 0 0.762)
			(size 0.2159 0.2159)
			(layers "B.Cu" "B.Mask" "B.Paste")
			(net "P5V_C_LL_R")
			(options
				(clearance outline)
				(anchor circle)
			)
			(primitives
				(gr_poly
					(pts
						(arc
							(start -0.3302 0.4318)
							(mid -0.402042 0.402042)
							(end -0.4318 0.3302)
						)
						(arc
							(start -0.4318 -0.3302)
							(mid -0.402042 -0.402042)
							(end -0.3302 -0.4318)
						)
						(arc
							(start 0.3302 -0.4318)
							(mid 0.402042 -0.402042)
							(end 0.4318 -0.3302)
						)
						(arc
							(start 0.4318 0.3302)
							(mid 0.402042 0.402042)
							(end 0.3302 0.4318)
						)
					)
					(width 0)
					(fill yes)
				)
			)
		)
	)
	(footprint ""
		(layer "B.Cu")
		(at 221.488 -123.444)
		(property "Reference" "R369"
			(at 0 0 0)
			(layer "B.SilkS")
			(hide yes)
			(effects
				(font
					(size 1.27 1.27)
				)
				(justify mirror)
			)
		)
		(property "Value" "0R2J-2-GP"
			(at -0.064008 -3.993896 0)
			(unlocked yes)
			(layer "B.Fab")
			(hide yes)
			(effects
				(font
					(size 1.016 1.016)
					(thickness 0.1524)
				)
				(justify mirror)
			)
		)
		(property "Device Type" "R402H16"
			(at -0.064008 -5.517896 0)
			(unlocked yes)
			(layer "B.Fab")
			(hide yes)
			(effects
				(font
					(size 1.016 1.016)
					(thickness 0.1524)
				)
				(justify mirror)
			)
		)
		(duplicate_pad_numbers_are_jumpers no)
		(fp_line
			(start -0.508 -0.9398)
			(end 0.508 -0.9398)
			(stroke
				(width 0.1524)
				(type default)
			)
			(layer "B.SilkS")
		)
		(fp_line
			(start 0.508 -0.9398)
			(end 0.508 0.9398)
			(stroke
				(width 0.1524)
				(type default)
			)
			(layer "B.SilkS")
		)
		(fp_rect
			(start 0.508 0.9398)
			(end -0.508 -0.9398)
			(stroke
				(width 0)
				(type default)
			)
			(fill no)
			(layer "B.CrtYd")
		)
		(fp_rect
			(start 0.508 0.9398)
			(end -0.508 -0.9398)
			(stroke
				(width 0)
				(type default)
			)
			(fill no)
			(layer "B.Fab")
		)
		(pad "1" smd custom
			(at 0 -0.4445 180)
			(size 0.1397 0.1397)
			(layers "B.Cu" "B.Mask" "B.Paste")
			(net "COMP_A_PGOOD")
			(options
				(clearance outline)
				(anchor circle)
			)
			(primitives
				(gr_poly
					(pts
						(arc
							(start -0.1778 0.2794)
							(mid -0.249642 0.249642)
							(end -0.2794 0.1778)
						)
						(arc
							(start -0.2794 -0.1778)
							(mid -0.249642 -0.249642)
							(end -0.1778 -0.2794)
						)
						(arc
							(start 0.1778 -0.2794)
							(mid 0.249642 -0.249642)
							(end 0.2794 -0.1778)
						)
						(arc
							(start 0.2794 0.1778)
							(mid 0.249642 0.249642)
							(end 0.1778 0.2794)
						)
					)
					(width 0)
					(fill yes)
				)
			)
		)
		(pad "2" smd custom
			(at 0 0.4445 180)
			(size 0.1397 0.1397)
			(layers "B.Cu" "B.Mask" "B.Paste")
			(net "TXS0102_A_OE")
			(options
				(clearance outline)
				(anchor circle)
			)
			(primitives
				(gr_poly
					(pts
						(arc
							(start -0.1778 0.2794)
							(mid -0.249642 0.249642)
							(end -0.2794 0.1778)
						)
						(arc
							(start -0.2794 -0.1778)
							(mid -0.249642 -0.249642)
							(end -0.1778 -0.2794)
						)
						(arc
							(start 0.1778 -0.2794)
							(mid 0.249642 -0.249642)
							(end 0.2794 -0.1778)
						)
						(arc
							(start 0.2794 0.1778)
							(mid 0.249642 0.249642)
							(end 0.1778 0.2794)
						)
					)
					(width 0)
					(fill yes)
				)
			)
		)
	)
	(footprint ""
		(layer "B.Cu")
		(at 432.608482 -252.098302)
		(property "Reference" "L5"
			(at 0 0 0)
			(layer "B.SilkS")
			(hide yes)
			(effects
				(font
					(size 1.27 1.27)
				)
				(justify mirror)
			)
		)
		(property "Value" "BLM21PG220SN1DGP"
			(at -0.0254 -5.6896 0)
			(unlocked yes)
			(layer "B.Fab")
			(hide yes)
			(effects
				(font
					(size 1.016 1.016)
					(thickness 0.1524)
				)
				(justify mirror)
			)
		)
		(property "Device Type" "L20125H42"
			(at -0.0254 -7.5946 0)
			(unlocked yes)
			(layer "B.Fab")
			(hide yes)
			(effects
				(font
					(size 1.016 1.016)
					(thickness 0.1524)
				)
				(justify mirror)
			)
		)
		(duplicate_pad_numbers_are_jumpers no)
		(fp_line
			(start -0.9144 -1.7018)
			(end 0.9144 -1.7018)
			(stroke
				(width 0.1524)
				(type default)
			)
			(layer "B.SilkS")
		)
		(fp_line
			(start -0.9144 1.7018)
			(end -0.9144 -1.7018)
			(stroke
				(width 0.1524)
				(type default)
			)
			(layer "B.SilkS")
		)
		(fp_line
			(start 0.9144 -1.7018)
			(end 0.9144 1.7018)
			(stroke
				(width 0.1524)
				(type default)
			)
			(layer "B.SilkS")
		)
		(fp_line
			(start 0.9144 1.7018)
			(end -0.9144 1.7018)
			(stroke
				(width 0.1524)
				(type default)
			)
			(layer "B.SilkS")
		)
		(fp_rect
			(start 1.0033 1.778)
			(end -1.0033 -1.778)
			(stroke
				(width 0)
				(type default)
			)
			(fill no)
			(layer "B.CrtYd")
		)
		(fp_poly
			(pts
				(xy 1.0033 -1.778) (xy -1.0033 -1.778) (xy -1.0033 1.778) (xy 1.0033 1.778)
			)
			(stroke
				(width 0)
				(type default)
			)
			(fill no)
			(layer "B.Fab")
		)
		(pad "1" smd rect
			(at 0 -0.9652 180)
			(size 1.397 1.143)
			(layers "B.Cu" "B.Mask" "B.Paste")
			(net "P12V_A")
		)
		(pad "2" smd rect
			(at 0 0.9652 180)
			(size 1.397 1.143)
			(layers "B.Cu" "B.Mask" "B.Paste")
			(net "P12V_A_VIN_U22")
		)
	)
	(footprint ""
		(layer "B.Cu")
		(at 478.71888 -222.229172 90)
		(property "Reference" "C658"
			(at 0 0 90)
			(layer "B.SilkS")
			(hide yes)
			(effects
				(font
					(size 1.27 1.27)
				)
				(justify mirror)
			)
		)
		(property "Value" "SCD1U50V3KX-GP"
			(at 0 -2.8194 90)
			(unlocked yes)
			(layer "B.Fab")
			(hide yes)
			(effects
				(font
					(size 1.016 1.016)
					(thickness 0.1524)
				)
				(justify mirror)
			)
		)
		(property "Device Type" "C603H36"
			(at 0 -4.3434 90)
			(unlocked yes)
			(layer "B.Fab")
			(hide yes)
			(effects
				(font
					(size 1.016 1.016)
					(thickness 0.1524)
				)
				(justify mirror)
			)
		)
		(duplicate_pad_numbers_are_jumpers no)
		(fp_line
			(start -0.508 0)
			(end 0.508 0)
			(stroke
				(width 0.2032)
				(type default)
			)
			(layer "B.SilkS")
		)
		(fp_rect
			(start 0.5842 1.3335)
			(end -0.5842 -1.3335)
			(stroke
				(width 0)
				(type default)
			)
			(fill no)
			(layer "B.CrtYd")
		)
		(fp_rect
			(start 0.5842 1.3335)
			(end -0.5842 -1.3335)
			(stroke
				(width 0)
				(type default)
			)
			(fill no)
			(layer "B.Fab")
		)
		(pad "1" smd custom
			(at 0 -0.762 270)
			(size 0.2159 0.2159)
			(layers "B.Cu" "B.Mask" "B.Paste")
			(net "P5V_A_4")
			(options
				(clearance outline)
				(anchor circle)
			)
			(primitives
				(gr_poly
					(pts
						(arc
							(start -0.3302 0.4318)
							(mid -0.402042 0.402042)
							(end -0.4318 0.3302)
						)
						(arc
							(start -0.4318 -0.3302)
							(mid -0.402042 -0.402042)
							(end -0.3302 -0.4318)
						)
						(arc
							(start 0.3302 -0.4318)
							(mid 0.402042 -0.402042)
							(end 0.4318 -0.3302)
						)
						(arc
							(start 0.4318 0.3302)
							(mid 0.402042 0.402042)
							(end 0.3302 0.4318)
						)
					)
					(width 0)
					(fill yes)
				)
			)
		)
		(pad "2" smd custom
			(at 0 0.762 270)
			(size 0.2159 0.2159)
			(layers "B.Cu" "B.Mask" "B.Paste")
			(net "P5V_D_LL_R")
			(options
				(clearance outline)
				(anchor circle)
			)
			(primitives
				(gr_poly
					(pts
						(arc
							(start -0.3302 0.4318)
							(mid -0.402042 0.402042)
							(end -0.4318 0.3302)
						)
						(arc
							(start -0.4318 -0.3302)
							(mid -0.402042 -0.402042)
							(end -0.3302 -0.4318)
						)
						(arc
							(start 0.3302 -0.4318)
							(mid 0.402042 -0.402042)
							(end 0.4318 -0.3302)
						)
						(arc
							(start 0.4318 0.3302)
							(mid 0.402042 0.402042)
							(end 0.3302 0.4318)
						)
					)
					(width 0)
					(fill yes)
				)
			)
		)
	)
	(footprint ""
		(layer "B.Cu")
		(at 35.007804 -253.426214 -90)
		(property "Reference" "R1216"
			(at 0 0 90)
			(layer "B.SilkS")
			(hide yes)
			(effects
				(font
					(size 1.27 1.27)
				)
				(justify mirror)
			)
		)
		(property "Value" "10R3F-GP"
			(at 0.0254 -2.5146 270)
			(unlocked yes)
			(layer "B.Fab")
			(hide yes)
			(effects
				(font
					(size 1.016 1.016)
					(thickness 0.1524)
				)
				(justify mirror)
			)
		)
		(property "Device Type" "R603H22"
			(at 0.0254 -4.0386 270)
			(unlocked yes)
			(layer "B.Fab")
			(hide yes)
			(effects
				(font
					(size 1.016 1.016)
					(thickness 0.1524)
				)
				(justify mirror)
			)
		)
		(duplicate_pad_numbers_are_jumpers no)
		(fp_line
			(start -0.2032 0)
			(end -0.4826 0)
			(stroke
				(width 0.2032)
				(type default)
			)
			(layer "B.SilkS")
		)
		(fp_line
			(start 0.4826 0)
			(end 0.2032 0)
			(stroke
				(width 0.2032)
				(type default)
			)
			(layer "B.SilkS")
		)
		(fp_rect
			(start 0.5842 1.3335)
			(end -0.5842 -1.3335)
			(stroke
				(width 0)
				(type default)
			)
			(fill no)
			(layer "B.CrtYd")
		)
		(fp_rect
			(start 0.5842 1.3335)
			(end -0.5842 -1.3335)
			(stroke
				(width 0)
				(type default)
			)
			(fill no)
			(layer "B.Fab")
		)
		(pad "1" smd custom
			(at 0 -0.762 90)
			(size 0.2159 0.2159)
			(layers "B.Cu" "B.Mask" "B.Paste")
			(net "P5V_A_CC")
			(options
				(clearance outline)
				(anchor circle)
			)
			(primitives
				(gr_poly
					(pts
						(arc
							(start -0.3302 0.4318)
							(mid -0.402042 0.402042)
							(end -0.4318 0.3302)
						)
						(arc
							(start -0.4318 -0.3302)
							(mid -0.402042 -0.402042)
							(end -0.3302 -0.4318)
						)
						(arc
							(start 0.3302 -0.4318)
							(mid 0.402042 -0.402042)
							(end 0.4318 -0.3302)
						)
						(arc
							(start 0.4318 0.3302)
							(mid 0.402042 0.402042)
							(end 0.3302 0.4318)
						)
					)
					(width 0)
					(fill yes)
				)
			)
		)
		(pad "2" smd custom
			(at 0 0.762 90)
			(size 0.2159 0.2159)
			(layers "B.Cu" "B.Mask" "B.Paste")
			(net "P5V_A_VFB_R")
			(options
				(clearance outline)
				(anchor circle)
			)
			(primitives
				(gr_poly
					(pts
						(arc
							(start -0.3302 0.4318)
							(mid -0.402042 0.402042)
							(end -0.4318 0.3302)
						)
						(arc
							(start -0.4318 -0.3302)
							(mid -0.402042 -0.402042)
							(end -0.3302 -0.4318)
						)
						(arc
							(start 0.3302 -0.4318)
							(mid 0.402042 -0.402042)
							(end 0.4318 -0.3302)
						)
						(arc
							(start 0.4318 0.3302)
							(mid 0.402042 0.402042)
							(end 0.3302 0.4318)
						)
					)
					(width 0)
					(fill yes)
				)
			)
		)
	)
	(footprint ""
		(layer "B.Cu")
		(at 465.6328 -244.094)
		(property "Reference" "TC11"
			(at 0 0 0)
			(layer "B.SilkS")
			(hide yes)
			(effects
				(font
					(size 1.27 1.27)
				)
				(justify mirror)
			)
		)
		(property "Value" "ST220U10VDM-LGP"
			(at 0 -9.6012 0)
			(unlocked yes)
			(layer "B.Fab")
			(hide yes)
			(effects
				(font
					(size 1.016 1.016)
					(thickness 0.1524)
				)
				(justify mirror)
			)
		)
		(property "Device Type" "CT7343H119"
			(at 0 -11.1252 0)
			(unlocked yes)
			(layer "B.Fab")
			(hide yes)
			(effects
				(font
					(size 1.016 1.016)
					(thickness 0.1524)
				)
				(justify mirror)
			)
		)
		(duplicate_pad_numbers_are_jumpers no)
		(fp_line
			(start -2.286 -4.8768)
			(end 2.286 -4.8768)
			(stroke
				(width 0.1524)
				(type default)
			)
			(layer "B.SilkS")
		)
		(fp_line
			(start -2.286 -2.032)
			(end -2.286 -4.8768)
			(stroke
				(width 0.1524)
				(type default)
			)
			(layer "B.SilkS")
		)
		(fp_line
			(start -2.286 2.032)
			(end -2.286 4.8768)
			(stroke
				(width 0.1524)
				(type default)
			)
			(layer "B.SilkS")
		)
		(fp_line
			(start -2.286 4.8768)
			(end 2.286 4.8768)
			(stroke
				(width 0.1524)
				(type default)
			)
			(layer "B.SilkS")
		)
		(fp_line
			(start -2.1082 -4.699)
			(end 2.1082 -4.699)
			(stroke
				(width 0.508)
				(type default)
			)
			(layer "B.SilkS")
		)
		(fp_line
			(start 2.286 -4.8768)
			(end 2.286 -2.032)
			(stroke
				(width 0.1524)
				(type default)
			)
			(layer "B.SilkS")
		)
		(fp_line
			(start 2.286 4.8768)
			(end 2.286 2.032)
			(stroke
				(width 0.1524)
				(type default)
			)
			(layer "B.SilkS")
		)
		(fp_rect
			(start 2.1463 3.6449)
			(end -2.1463 -3.6449)
			(stroke
				(width 0)
				(type default)
			)
			(fill no)
			(layer "B.CrtYd")
		)
		(fp_poly
			(pts
				(xy 2.54 4.953) (xy 2.54 4.2926) (xy 3.81 4.2926) (xy 3.81 -4.2926) (xy 2.54 -4.2926) (xy 2.54 -4.953)
				(xy -2.54 -4.953) (xy -2.54 -4.2926) (xy -3.81 -4.2926) (xy -3.81 -1.6256) (xy -2.1463 -1.6256)
				(xy -2.1463 -3.6449) (xy 2.1463 -3.6449) (xy 2.1463 3.6449) (xy -2.1463 3.6449) (xy -2.1463 -1.6129)
				(xy -3.81 -1.6129) (xy -3.81 4.2926) (xy -2.54 4.2926) (xy -2.54 4.953)
			)
			(stroke
				(width 0)
				(type default)
			)
			(fill no)
			(layer "B.CrtYd")
		)
		(fp_rect
			(start -2.54 4.2926)
			(end -3.81 -4.2926)
			(stroke
				(width 0)
				(type default)
			)
			(fill no)
			(layer "B.Fab")
		)
		(fp_rect
			(start 2.54 4.953)
			(end -2.54 -4.953)
			(stroke
				(width 0)
				(type default)
			)
			(fill no)
			(layer "B.Fab")
		)
		(fp_rect
			(start 3.81 4.2926)
			(end 2.54 -4.2926)
			(stroke
				(width 0)
				(type default)
			)
			(fill no)
			(layer "B.Fab")
		)
		(pad "1" smd rect
			(at 0 -3.1496 180)
			(size 2.413 2.286)
			(layers "B.Cu" "B.Mask" "B.Paste")
			(net "P5V_A_3")
		)
		(pad "2" smd rect
			(at 0 3.1496 180)
			(size 2.413 2.286)
			(layers "B.Cu" "B.Mask" "B.Paste")
			(net "GND")
		)
		(zone
			(layer "B.Cu")
			(hatch none 0.5)
			(connect_pads
				(clearance 0)
			)
			(min_thickness 0.25)
			(keepout
				(tracks allowed)
				(vias not_allowed)
				(pads allowed)
				(copperpour not_allowed)
				(footprints allowed)
			)
			(placement
				(enabled no)
				(sheetname "")
			)
			(fill
				(thermal_gap 0.5)
				(thermal_bridge_width 0.5)
				(island_removal_mode 0)
			)
			(polygon
				(pts
					(xy 464.1215 -245.7831) (xy 464.1215 -248.6914) (xy 467.1441 -248.6914) (xy 467.1441 -245.7958)
					(xy 467.1441 -245.4656) (xy 464.1215 -245.4656)
				)
			)
		)
		(zone
			(layer "B.Cu")
			(hatch none 0.5)
			(connect_pads
				(clearance 0)
			)
			(min_thickness 0.25)
			(keepout
				(tracks allowed)
				(vias not_allowed)
				(pads allowed)
				(copperpour not_allowed)
				(footprints allowed)
			)
			(placement
				(enabled no)
				(sheetname "")
			)
			(fill
				(thermal_gap 0.5)
				(thermal_bridge_width 0.5)
				(island_removal_mode 0)
			)
			(polygon
				(pts
					(xy 467.1441 -239.4966) (xy 464.1215 -239.4966) (xy 464.1215 -242.3922) (xy 464.1215 -242.7224)
					(xy 467.1441 -242.7224) (xy 467.1441 -242.3922)
				)
			)
		)
	)
	(footprint ""
		(layer "B.Cu")
		(at 481.823522 -228.4095 180)
		(property "Reference" "R1262"
			(at 0 0 0)
			(layer "B.SilkS")
			(hide yes)
			(effects
				(font
					(size 1.27 1.27)
				)
				(justify mirror)
			)
		)
		(property "Value" "49K9R2F-L-GP"
			(at -0.064008 -3.993896 180)
			(unlocked yes)
			(layer "B.Fab")
			(hide yes)
			(effects
				(font
					(size 1.016 1.016)
					(thickness 0.1524)
				)
				(justify mirror)
			)
		)
		(property "Device Type" "R402H16"
			(at -0.064008 -5.517896 180)
			(unlocked yes)
			(layer "B.Fab")
			(hide yes)
			(effects
				(font
					(size 1.016 1.016)
					(thickness 0.1524)
				)
				(justify mirror)
			)
		)
		(duplicate_pad_numbers_are_jumpers no)
		(fp_line
			(start 0.508 -0.9398)
			(end 0.508 0.9398)
			(stroke
				(width 0.1524)
				(type default)
			)
			(layer "B.SilkS")
		)
		(fp_line
			(start -0.508 -0.9398)
			(end 0.508 -0.9398)
			(stroke
				(width 0.1524)
				(type default)
			)
			(layer "B.SilkS")
		)
		(fp_rect
			(start 0.508 0.9398)
			(end -0.508 -0.9398)
			(stroke
				(width 0)
				(type default)
			)
			(fill no)
			(layer "B.CrtYd")
		)
		(fp_rect
			(start 0.508 0.9398)
			(end -0.508 -0.9398)
			(stroke
				(width 0)
				(type default)
			)
			(fill no)
			(layer "B.Fab")
		)
		(pad "1" smd custom
			(at 0 -0.4445)
			(size 0.1397 0.1397)
			(layers "B.Cu" "B.Mask" "B.Paste")
			(net "P12V_A")
			(options
				(clearance outline)
				(anchor circle)
			)
			(primitives
				(gr_poly
					(pts
						(arc
							(start -0.1778 0.2794)
							(mid -0.249642 0.249642)
							(end -0.2794 0.1778)
						)
						(arc
							(start -0.2794 -0.1778)
							(mid -0.249642 -0.249642)
							(end -0.1778 -0.2794)
						)
						(arc
							(start 0.1778 -0.2794)
							(mid 0.249642 -0.249642)
							(end 0.2794 -0.1778)
						)
						(arc
							(start 0.2794 0.1778)
							(mid 0.249642 0.249642)
							(end 0.1778 0.2794)
						)
					)
					(width 0)
					(fill yes)
				)
			)
		)
		(pad "2" smd custom
			(at 0 0.4445)
			(size 0.1397 0.1397)
			(layers "B.Cu" "B.Mask" "B.Paste")
			(net "P5V_D_EN_R")
			(options
				(clearance outline)
				(anchor circle)
			)
			(primitives
				(gr_poly
					(pts
						(arc
							(start -0.1778 0.2794)
							(mid -0.249642 0.249642)
							(end -0.2794 0.1778)
						)
						(arc
							(start -0.2794 -0.1778)
							(mid -0.249642 -0.249642)
							(end -0.1778 -0.2794)
						)
						(arc
							(start 0.1778 -0.2794)
							(mid 0.249642 -0.249642)
							(end 0.2794 -0.1778)
						)
						(arc
							(start 0.2794 0.1778)
							(mid 0.249642 0.249642)
							(end 0.1778 0.2794)
						)
					)
					(width 0)
					(fill yes)
				)
			)
		)
	)
	(footprint ""
		(layer "B.Cu")
		(at 189.073282 -234.871006 180)
		(property "Reference" "G2"
			(at 0 0 0)
			(layer "B.SilkS")
			(hide yes)
			(effects
				(font
					(size 1.27 1.27)
				)
				(justify mirror)
			)
		)
		(property "Value" "GAP-CLOSE-PWR-4-GP"
			(at 2.4638 -0.5461 180)
			(unlocked yes)
			(layer "B.Fab")
			(hide yes)
			(effects
				(font
					(size 1.016 1.016)
					(thickness 0.1524)
				)
				(justify mirror)
			)
		)
		(property "Device Type" "GAP-CLOSE-PWR-4"
			(at 2.4638 -2.0701 180)
			(unlocked yes)
			(layer "B.Fab")
			(hide yes)
			(effects
				(font
					(size 1.016 1.016)
					(thickness 0.1524)
				)
				(justify mirror)
			)
		)
		(duplicate_pad_numbers_are_jumpers no)
		(fp_rect
			(start 0.2794 0.254)
			(end -0.2794 -0.254)
			(stroke
				(width 0)
				(type default)
			)
			(fill no)
			(layer "B.CrtYd")
		)
		(fp_rect
			(start 0.2794 0.254)
			(end -0.2794 -0.254)
			(stroke
				(width 0)
				(type default)
			)
			(fill no)
			(layer "B.Fab")
		)
		(pad "1" smd rect
			(at 0.0635 0)
			(size 0.1778 0.254)
			(layers "B.Cu" "B.Mask" "B.Paste")
			(net "P3V3_STBY_A")
		)
		(pad "2" smd rect
			(at -0.0635 0)
			(size 0.1778 0.254)
			(layers "B.Cu" "B.Mask" "B.Paste")
			(net "P3V3_STBY_CC")
		)
	)
	(footprint ""
		(layer "B.Cu")
		(at 465.598764 -230.606346 90)
		(property "Reference" "R1266"
			(at 0 0 90)
			(layer "B.SilkS")
			(hide yes)
			(effects
				(font
					(size 1.27 1.27)
				)
				(justify mirror)
			)
		)
		(property "Value" "0R3J-0-U-GP"
			(at 0.0254 -2.5146 90)
			(unlocked yes)
			(layer "B.Fab")
			(hide yes)
			(effects
				(font
					(size 1.016 1.016)
					(thickness 0.1524)
				)
				(justify mirror)
			)
		)
		(property "Device Type" "R603H22"
			(at 0.0254 -4.0386 90)
			(unlocked yes)
			(layer "B.Fab")
			(hide yes)
			(effects
				(font
					(size 1.016 1.016)
					(thickness 0.1524)
				)
				(justify mirror)
			)
		)
		(duplicate_pad_numbers_are_jumpers no)
		(fp_line
			(start 0.4826 0)
			(end 0.2032 0)
			(stroke
				(width 0.2032)
				(type default)
			)
			(layer "B.SilkS")
		)
		(fp_line
			(start -0.2032 0)
			(end -0.4826 0)
			(stroke
				(width 0.2032)
				(type default)
			)
			(layer "B.SilkS")
		)
		(fp_rect
			(start 0.5842 1.3335)
			(end -0.5842 -1.3335)
			(stroke
				(width 0)
				(type default)
			)
			(fill no)
			(layer "B.CrtYd")
		)
		(fp_rect
			(start 0.5842 1.3335)
			(end -0.5842 -1.3335)
			(stroke
				(width 0)
				(type default)
			)
			(fill no)
			(layer "B.Fab")
		)
		(pad "1" smd custom
			(at 0 -0.762 270)
			(size 0.2159 0.2159)
			(layers "B.Cu" "B.Mask" "B.Paste")
			(net "P5V_D_VBST")
			(options
				(clearance outline)
				(anchor circle)
			)
			(primitives
				(gr_poly
					(pts
						(arc
							(start -0.3302 0.4318)
							(mid -0.402042 0.402042)
							(end -0.4318 0.3302)
						)
						(arc
							(start -0.4318 -0.3302)
							(mid -0.402042 -0.402042)
							(end -0.3302 -0.4318)
						)
						(arc
							(start 0.3302 -0.4318)
							(mid 0.402042 -0.402042)
							(end 0.4318 -0.3302)
						)
						(arc
							(start 0.4318 0.3302)
							(mid 0.402042 0.402042)
							(end 0.3302 0.4318)
						)
					)
					(width 0)
					(fill yes)
				)
			)
		)
		(pad "2" smd custom
			(at 0 0.762 270)
			(size 0.2159 0.2159)
			(layers "B.Cu" "B.Mask" "B.Paste")
			(net "P5V_D_VBST_RC")
			(options
				(clearance outline)
				(anchor circle)
			)
			(primitives
				(gr_poly
					(pts
						(arc
							(start -0.3302 0.4318)
							(mid -0.402042 0.402042)
							(end -0.4318 0.3302)
						)
						(arc
							(start -0.4318 -0.3302)
							(mid -0.402042 -0.402042)
							(end -0.3302 -0.4318)
						)
						(arc
							(start 0.3302 -0.4318)
							(mid 0.402042 -0.402042)
							(end 0.4318 -0.3302)
						)
						(arc
							(start 0.4318 0.3302)
							(mid 0.402042 0.402042)
							(end 0.3302 0.4318)
						)
					)
					(width 0)
					(fill yes)
				)
			)
		)
	)
	(footprint ""
		(layer "B.Cu")
		(at 181.801516 -222.747332 -90)
		(property "Reference" "R1291"
			(at 0 0 90)
			(layer "B.SilkS")
			(hide yes)
			(effects
				(font
					(size 1.27 1.27)
				)
				(justify mirror)
			)
		)
		(property "Value" "15KR2F-GP"
			(at -0.064008 -3.993896 270)
			(unlocked yes)
			(layer "B.Fab")
			(hide yes)
			(effects
				(font
					(size 1.016 1.016)
					(thickness 0.1524)
				)
				(justify mirror)
			)
		)
		(property "Device Type" "R402H16"
			(at -0.064008 -5.517896 270)
			(unlocked yes)
			(layer "B.Fab")
			(hide yes)
			(effects
				(font
					(size 1.016 1.016)
					(thickness 0.1524)
				)
				(justify mirror)
			)
		)
		(duplicate_pad_numbers_are_jumpers no)
		(fp_line
			(start -0.508 -0.9398)
			(end 0.508 -0.9398)
			(stroke
				(width 0.1524)
				(type default)
			)
			(layer "B.SilkS")
		)
		(fp_line
			(start 0.508 -0.9398)
			(end 0.508 0.9398)
			(stroke
				(width 0.1524)
				(type default)
			)
			(layer "B.SilkS")
		)
		(fp_rect
			(start 0.508 0.9398)
			(end -0.508 -0.9398)
			(stroke
				(width 0)
				(type default)
			)
			(fill no)
			(layer "B.CrtYd")
		)
		(fp_rect
			(start 0.508 0.9398)
			(end -0.508 -0.9398)
			(stroke
				(width 0)
				(type default)
			)
			(fill no)
			(layer "B.Fab")
		)
		(pad "1" smd custom
			(at 0 -0.4445 90)
			(size 0.1397 0.1397)
			(layers "B.Cu" "B.Mask" "B.Paste")
			(net "PWRGD_P3V3_STBY")
			(options
				(clearance outline)
				(anchor circle)
			)
			(primitives
				(gr_poly
					(pts
						(arc
							(start -0.1778 0.2794)
							(mid -0.249642 0.249642)
							(end -0.2794 0.1778)
						)
						(arc
							(start -0.2794 -0.1778)
							(mid -0.249642 -0.249642)
							(end -0.1778 -0.2794)
						)
						(arc
							(start 0.1778 -0.2794)
							(mid 0.249642 -0.249642)
							(end 0.2794 -0.1778)
						)
						(arc
							(start 0.2794 0.1778)
							(mid 0.249642 0.249642)
							(end 0.1778 0.2794)
						)
					)
					(width 0)
					(fill yes)
				)
			)
		)
		(pad "2" smd custom
			(at 0 0.4445 90)
			(size 0.1397 0.1397)
			(layers "B.Cu" "B.Mask" "B.Paste")
			(net "GND")
			(options
				(clearance outline)
				(anchor circle)
			)
			(primitives
				(gr_poly
					(pts
						(arc
							(start -0.1778 0.2794)
							(mid -0.249642 0.249642)
							(end -0.2794 0.1778)
						)
						(arc
							(start -0.2794 -0.1778)
							(mid -0.249642 -0.249642)
							(end -0.1778 -0.2794)
						)
						(arc
							(start 0.1778 -0.2794)
							(mid 0.249642 -0.249642)
							(end 0.2794 -0.1778)
						)
						(arc
							(start 0.2794 0.1778)
							(mid 0.249642 0.249642)
							(end 0.1778 0.2794)
						)
					)
					(width 0)
					(fill yes)
				)
			)
		)
	)
	(footprint ""
		(layer "B.Cu")
		(at 190.934594 -223.448118)
		(property "Reference" "C669"
			(at 0 0 0)
			(layer "B.SilkS")
			(hide yes)
			(effects
				(font
					(size 1.27 1.27)
				)
				(justify mirror)
			)
		)
		(property "Value" "SC1U16V3KX-5GP"
			(at 0 -2.8194 0)
			(unlocked yes)
			(layer "B.Fab")
			(hide yes)
			(effects
				(font
					(size 1.016 1.016)
					(thickness 0.1524)
				)
				(justify mirror)
			)
		)
		(property "Device Type" "C603H36"
			(at 0 -4.3434 0)
			(unlocked yes)
			(layer "B.Fab")
			(hide yes)
			(effects
				(font
					(size 1.016 1.016)
					(thickness 0.1524)
				)
				(justify mirror)
			)
		)
		(duplicate_pad_numbers_are_jumpers no)
		(fp_line
			(start -0.508 0)
			(end 0.508 0)
			(stroke
				(width 0.2032)
				(type default)
			)
			(layer "B.SilkS")
		)
		(fp_rect
			(start 0.5842 1.3335)
			(end -0.5842 -1.3335)
			(stroke
				(width 0)
				(type default)
			)
			(fill no)
			(layer "B.CrtYd")
		)
		(fp_rect
			(start 0.5842 1.3335)
			(end -0.5842 -1.3335)
			(stroke
				(width 0)
				(type default)
			)
			(fill no)
			(layer "B.Fab")
		)
		(pad "1" smd custom
			(at 0 -0.762 180)
			(size 0.2159 0.2159)
			(layers "B.Cu" "B.Mask" "B.Paste")
			(net "P3V3_STBY_VCC")
			(options
				(clearance outline)
				(anchor circle)
			)
			(primitives
				(gr_poly
					(pts
						(arc
							(start -0.3302 0.4318)
							(mid -0.402042 0.402042)
							(end -0.4318 0.3302)
						)
						(arc
							(start -0.4318 -0.3302)
							(mid -0.402042 -0.402042)
							(end -0.3302 -0.4318)
						)
						(arc
							(start 0.3302 -0.4318)
							(mid 0.402042 -0.402042)
							(end 0.4318 -0.3302)
						)
						(arc
							(start 0.4318 0.3302)
							(mid 0.402042 0.402042)
							(end 0.3302 0.4318)
						)
					)
					(width 0)
					(fill yes)
				)
			)
		)
		(pad "2" smd custom
			(at 0 0.762 180)
			(size 0.2159 0.2159)
			(layers "B.Cu" "B.Mask" "B.Paste")
			(net "GND")
			(options
				(clearance outline)
				(anchor circle)
			)
			(primitives
				(gr_poly
					(pts
						(arc
							(start -0.3302 0.4318)
							(mid -0.402042 0.402042)
							(end -0.4318 0.3302)
						)
						(arc
							(start -0.4318 -0.3302)
							(mid -0.402042 -0.402042)
							(end -0.3302 -0.4318)
						)
						(arc
							(start 0.3302 -0.4318)
							(mid 0.402042 -0.402042)
							(end 0.4318 -0.3302)
						)
						(arc
							(start 0.4318 0.3302)
							(mid 0.402042 0.402042)
							(end 0.3302 0.4318)
						)
					)
					(width 0)
					(fill yes)
				)
			)
		)
	)
	(footprint ""
		(layer "B.Cu")
		(at 49.215802 -149.79015 90)
		(property "Reference" "C666"
			(at 0 0 90)
			(layer "B.SilkS")
			(hide yes)
			(effects
				(font
					(size 1.27 1.27)
				)
				(justify mirror)
			)
		)
		(property "Value" "SC68P50V2JN-2-GP"
			(at -1.1811 -2.7051 90)
			(unlocked yes)
			(layer "B.Fab")
			(hide yes)
			(effects
				(font
					(size 1.016 1.016)
					(thickness 0.1524)
				)
				(justify mirror)
			)
		)
		(property "Device Type" "C402H22"
			(at -1.1811 -4.2291 90)
			(unlocked yes)
			(layer "B.Fab")
			(hide yes)
			(effects
				(font
					(size 1.016 1.016)
					(thickness 0.1524)
				)
				(justify mirror)
			)
		)
		(duplicate_pad_numbers_are_jumpers no)
		(fp_rect
			(start 0.4318 0.9525)
			(end -0.4318 -0.9525)
			(stroke
				(width 0)
				(type default)
			)
			(fill no)
			(layer "B.CrtYd")
		)
		(fp_rect
			(start 0.4318 0.9525)
			(end -0.4318 -0.9525)
			(stroke
				(width 0)
				(type default)
			)
			(fill no)
			(layer "B.Fab")
		)
		(pad "1" smd custom
			(at 0 -0.4445 270)
			(size 0.1524 0.1524)
			(layers "B.Cu" "B.Mask" "B.Paste")
			(net "P5V_B_VFB")
			(options
				(clearance outline)
				(anchor circle)
			)
			(primitives
				(gr_poly
					(pts
						(arc
							(start 0.3048 0.2032)
							(mid 0.275042 0.275042)
							(end 0.2032 0.3048)
						)
						(arc
							(start -0.2032 0.3048)
							(mid -0.275042 0.275042)
							(end -0.3048 0.2032)
						)
						(arc
							(start -0.3048 -0.2032)
							(mid -0.275042 -0.275042)
							(end -0.2032 -0.3048)
						)
						(arc
							(start 0.2032 -0.3048)
							(mid 0.275042 -0.275042)
							(end 0.3048 -0.2032)
						)
					)
					(width 0)
					(fill yes)
				)
			)
		)
		(pad "2" smd custom
			(at 0 0.4445 270)
			(size 0.1524 0.1524)
			(layers "B.Cu" "B.Mask" "B.Paste")
			(net "P5V_B_VFB_R")
			(options
				(clearance outline)
				(anchor circle)
			)
			(primitives
				(gr_poly
					(pts
						(arc
							(start 0.3048 0.2032)
							(mid 0.275042 0.275042)
							(end 0.2032 0.3048)
						)
						(arc
							(start -0.2032 0.3048)
							(mid -0.275042 0.275042)
							(end -0.3048 0.2032)
						)
						(arc
							(start -0.3048 -0.2032)
							(mid -0.275042 -0.275042)
							(end -0.2032 -0.3048)
						)
						(arc
							(start 0.2032 -0.3048)
							(mid 0.275042 -0.275042)
							(end 0.3048 -0.2032)
						)
					)
					(width 0)
					(fill yes)
				)
			)
		)
	)
	(footprint ""
		(layer "B.Cu")
		(at 33.909 -139.2936 90)
		(property "Reference" "L3"
			(at 0 0 90)
			(layer "B.SilkS")
			(hide yes)
			(effects
				(font
					(size 1.27 1.27)
				)
				(justify mirror)
			)
		)
		(property "Value" "BLM21PG220SN1DGP"
			(at -0.0254 -5.6896 90)
			(unlocked yes)
			(layer "B.Fab")
			(hide yes)
			(effects
				(font
					(size 1.016 1.016)
					(thickness 0.1524)
				)
				(justify mirror)
			)
		)
		(property "Device Type" "L20125H42"
			(at -0.0254 -7.5946 90)
			(unlocked yes)
			(layer "B.Fab")
			(hide yes)
			(effects
				(font
					(size 1.016 1.016)
					(thickness 0.1524)
				)
				(justify mirror)
			)
		)
		(duplicate_pad_numbers_are_jumpers no)
		(fp_line
			(start 0.9144 -1.7018)
			(end 0.9144 1.7018)
			(stroke
				(width 0.1524)
				(type default)
			)
			(layer "B.SilkS")
		)
		(fp_line
			(start -0.9144 -1.7018)
			(end 0.9144 -1.7018)
			(stroke
				(width 0.1524)
				(type default)
			)
			(layer "B.SilkS")
		)
		(fp_line
			(start 0.9144 1.7018)
			(end -0.9144 1.7018)
			(stroke
				(width 0.1524)
				(type default)
			)
			(layer "B.SilkS")
		)
		(fp_line
			(start -0.9144 1.7018)
			(end -0.9144 -1.7018)
			(stroke
				(width 0.1524)
				(type default)
			)
			(layer "B.SilkS")
		)
		(fp_rect
			(start 1.0033 1.778)
			(end -1.0033 -1.778)
			(stroke
				(width 0)
				(type default)
			)
			(fill no)
			(layer "B.CrtYd")
		)
		(fp_poly
			(pts
				(xy 1.0033 -1.778) (xy -1.0033 -1.778) (xy -1.0033 1.778) (xy 1.0033 1.778)
			)
			(stroke
				(width 0)
				(type default)
			)
			(fill no)
			(layer "B.Fab")
		)
		(pad "1" smd rect
			(at 0 -0.9652 270)
			(size 1.397 1.143)
			(layers "B.Cu" "B.Mask" "B.Paste")
			(net "P12V_A")
		)
		(pad "2" smd rect
			(at 0 0.9652 270)
			(size 1.397 1.143)
			(layers "B.Cu" "B.Mask" "B.Paste")
			(net "P12V_A_VIN_U21")
		)
	)
	(footprint ""
		(layer "B.Cu")
		(at 480.536758 -223.215962 180)
		(property "Reference" "C660"
			(at 0 0 0)
			(layer "B.SilkS")
			(hide yes)
			(effects
				(font
					(size 1.27 1.27)
				)
				(justify mirror)
			)
		)
		(property "Value" "SC470P50V2KX-3GP"
			(at -1.1811 -2.7051 180)
			(unlocked yes)
			(layer "B.Fab")
			(hide yes)
			(effects
				(font
					(size 1.016 1.016)
					(thickness 0.1524)
				)
				(justify mirror)
			)
		)
		(property "Device Type" "C402H22"
			(at -1.1811 -4.2291 180)
			(unlocked yes)
			(layer "B.Fab")
			(hide yes)
			(effects
				(font
					(size 1.016 1.016)
					(thickness 0.1524)
				)
				(justify mirror)
			)
		)
		(duplicate_pad_numbers_are_jumpers no)
		(fp_rect
			(start 0.4318 0.9525)
			(end -0.4318 -0.9525)
			(stroke
				(width 0)
				(type default)
			)
			(fill no)
			(layer "B.CrtYd")
		)
		(fp_rect
			(start 0.4318 0.9525)
			(end -0.4318 -0.9525)
			(stroke
				(width 0)
				(type default)
			)
			(fill no)
			(layer "B.Fab")
		)
		(pad "1" smd custom
			(at 0 -0.4445)
			(size 0.1524 0.1524)
			(layers "B.Cu" "B.Mask" "B.Paste")
			(net "P5V_D_LL_R")
			(options
				(clearance outline)
				(anchor circle)
			)
			(primitives
				(gr_poly
					(pts
						(arc
							(start 0.3048 0.2032)
							(mid 0.275042 0.275042)
							(end 0.2032 0.3048)
						)
						(arc
							(start -0.2032 0.3048)
							(mid -0.275042 0.275042)
							(end -0.3048 0.2032)
						)
						(arc
							(start -0.3048 -0.2032)
							(mid -0.275042 -0.275042)
							(end -0.2032 -0.3048)
						)
						(arc
							(start 0.2032 -0.3048)
							(mid 0.275042 -0.275042)
							(end 0.3048 -0.2032)
						)
					)
					(width 0)
					(fill yes)
				)
			)
		)
		(pad "2" smd custom
			(at 0 0.4445)
			(size 0.1524 0.1524)
			(layers "B.Cu" "B.Mask" "B.Paste")
			(net "P5V_D_VFB")
			(options
				(clearance outline)
				(anchor circle)
			)
			(primitives
				(gr_poly
					(pts
						(arc
							(start 0.3048 0.2032)
							(mid 0.275042 0.275042)
							(end 0.2032 0.3048)
						)
						(arc
							(start -0.2032 0.3048)
							(mid -0.275042 0.275042)
							(end -0.3048 0.2032)
						)
						(arc
							(start -0.3048 -0.2032)
							(mid -0.275042 -0.275042)
							(end -0.2032 -0.3048)
						)
						(arc
							(start 0.2032 -0.3048)
							(mid 0.275042 -0.275042)
							(end 0.3048 -0.2032)
						)
					)
					(width 0)
					(fill yes)
				)
			)
		)
	)
	(footprint ""
		(layer "B.Cu")
		(at 69.1134 -147.5486 180)
		(property "Reference" "C630"
			(at 0 0 0)
			(layer "B.SilkS")
			(hide yes)
			(effects
				(font
					(size 1.27 1.27)
				)
				(justify mirror)
			)
		)
		(property "Value" "SC10U16V5KX-7-GP-U"
			(at 0.0762 -6.1214 180)
			(unlocked yes)
			(layer "B.Fab")
			(hide yes)
			(effects
				(font
					(size 1.016 1.016)
					(thickness 0.1524)
				)
				(justify mirror)
			)
		)
		(property "Device Type" "C805H58"
			(at 0.0762 -8.1534 180)
			(unlocked yes)
			(layer "B.Fab")
			(hide yes)
			(effects
				(font
					(size 1.016 1.016)
					(thickness 0.1524)
				)
				(justify mirror)
			)
		)
		(duplicate_pad_numbers_are_jumpers no)
		(fp_line
			(start -0.635 0)
			(end 0.635 0)
			(stroke
				(width 0.508)
				(type default)
			)
			(layer "B.SilkS")
		)
		(fp_rect
			(start 0.9652 1.778)
			(end -0.9652 -1.778)
			(stroke
				(width 0)
				(type default)
			)
			(fill no)
			(layer "B.CrtYd")
		)
		(fp_poly
			(pts
				(xy 0.9652 -1.778) (xy -0.9652 -1.778) (xy -0.9652 1.778) (xy 0.9652 1.778)
			)
			(stroke
				(width 0)
				(type default)
			)
			(fill no)
			(layer "B.Fab")
		)
		(pad "1" smd rect
			(at 0 -0.9652)
			(size 1.397 1.143)
			(layers "B.Cu" "B.Mask" "B.Paste")
			(net "P5V_A_2")
		)
		(pad "2" smd rect
			(at 0 0.9652)
			(size 1.397 1.143)
			(layers "B.Cu" "B.Mask" "B.Paste")
			(net "GND")
		)
	)
	(footprint ""
		(layer "B.Cu")
		(at 471.885518 -205.36789 -90)
		(property "Reference" "C664"
			(at 0 0 90)
			(layer "B.SilkS")
			(hide yes)
			(effects
				(font
					(size 1.27 1.27)
				)
				(justify mirror)
			)
		)
		(property "Value" "SC10U16V5KX-7-GP-U"
			(at 0.0762 -6.1214 270)
			(unlocked yes)
			(layer "B.Fab")
			(hide yes)
			(effects
				(font
					(size 1.016 1.016)
					(thickness 0.1524)
				)
				(justify mirror)
			)
		)
		(property "Device Type" "C805H58"
			(at 0.0762 -8.1534 270)
			(unlocked yes)
			(layer "B.Fab")
			(hide yes)
			(effects
				(font
					(size 1.016 1.016)
					(thickness 0.1524)
				)
				(justify mirror)
			)
		)
		(duplicate_pad_numbers_are_jumpers no)
		(fp_line
			(start -0.635 0)
			(end 0.635 0)
			(stroke
				(width 0.508)
				(type default)
			)
			(layer "B.SilkS")
		)
		(fp_rect
			(start 0.9652 1.778)
			(end -0.9652 -1.778)
			(stroke
				(width 0)
				(type default)
			)
			(fill no)
			(layer "B.CrtYd")
		)
		(fp_poly
			(pts
				(xy 0.9652 -1.778) (xy -0.9652 -1.778) (xy -0.9652 1.778) (xy 0.9652 1.778)
			)
			(stroke
				(width 0)
				(type default)
			)
			(fill no)
			(layer "B.Fab")
		)
		(pad "1" smd rect
			(at 0 -0.9652 90)
			(size 1.397 1.143)
			(layers "B.Cu" "B.Mask" "B.Paste")
			(net "P5V_A_4")
		)
		(pad "2" smd rect
			(at 0 0.9652 90)
			(size 1.397 1.143)
			(layers "B.Cu" "B.Mask" "B.Paste")
			(net "GND")
		)
	)
	(footprint ""
		(layer "B.Cu")
		(at 20.1422 -246.7864 180)
		(property "Reference" "C601"
			(at 0 0 0)
			(layer "B.SilkS")
			(hide yes)
			(effects
				(font
					(size 1.27 1.27)
				)
				(justify mirror)
			)
		)
		(property "Value" "SC10U16V5KX-7-GP-U"
			(at 0.0762 -6.1214 180)
			(unlocked yes)
			(layer "B.Fab")
			(hide yes)
			(effects
				(font
					(size 1.016 1.016)
					(thickness 0.1524)
				)
				(justify mirror)
			)
		)
		(property "Device Type" "C805H58"
			(at 0.0762 -8.1534 180)
			(unlocked yes)
			(layer "B.Fab")
			(hide yes)
			(effects
				(font
					(size 1.016 1.016)
					(thickness 0.1524)
				)
				(justify mirror)
			)
		)
		(duplicate_pad_numbers_are_jumpers no)
		(fp_line
			(start -0.635 0)
			(end 0.635 0)
			(stroke
				(width 0.508)
				(type default)
			)
			(layer "B.SilkS")
		)
		(fp_rect
			(start 0.9652 1.778)
			(end -0.9652 -1.778)
			(stroke
				(width 0)
				(type default)
			)
			(fill no)
			(layer "B.CrtYd")
		)
		(fp_poly
			(pts
				(xy 0.9652 -1.778) (xy -0.9652 -1.778) (xy -0.9652 1.778) (xy 0.9652 1.778)
			)
			(stroke
				(width 0)
				(type default)
			)
			(fill no)
			(layer "B.Fab")
		)
		(pad "1" smd rect
			(at 0 -0.9652)
			(size 1.397 1.143)
			(layers "B.Cu" "B.Mask" "B.Paste")
			(net "P12V_A_VIN_U20")
		)
		(pad "2" smd rect
			(at 0 0.9652)
			(size 1.397 1.143)
			(layers "B.Cu" "B.Mask" "B.Paste")
			(net "GND")
		)
	)
	(footprint ""
		(layer "B.Cu")
		(at 479.552 -225.806)
		(property "Reference" "R1267"
			(at 0 0 0)
			(layer "B.SilkS")
			(hide yes)
			(effects
				(font
					(size 1.27 1.27)
				)
				(justify mirror)
			)
		)
		(property "Value" "10KR2F-2-GP"
			(at -0.064008 -3.993896 0)
			(unlocked yes)
			(layer "B.Fab")
			(hide yes)
			(effects
				(font
					(size 1.016 1.016)
					(thickness 0.1524)
				)
				(justify mirror)
			)
		)
		(property "Device Type" "R402H16"
			(at -0.064008 -5.517896 0)
			(unlocked yes)
			(layer "B.Fab")
			(hide yes)
			(effects
				(font
					(size 1.016 1.016)
					(thickness 0.1524)
				)
				(justify mirror)
			)
		)
		(duplicate_pad_numbers_are_jumpers no)
		(fp_line
			(start -0.508 -0.9398)
			(end 0.508 -0.9398)
			(stroke
				(width 0.1524)
				(type default)
			)
			(layer "B.SilkS")
		)
		(fp_line
			(start 0.508 -0.9398)
			(end 0.508 0.9398)
			(stroke
				(width 0.1524)
				(type default)
			)
			(layer "B.SilkS")
		)
		(fp_rect
			(start 0.508 0.9398)
			(end -0.508 -0.9398)
			(stroke
				(width 0)
				(type default)
			)
			(fill no)
			(layer "B.CrtYd")
		)
		(fp_rect
			(start 0.508 0.9398)
			(end -0.508 -0.9398)
			(stroke
				(width 0)
				(type default)
			)
			(fill no)
			(layer "B.Fab")
		)
		(pad "1" smd custom
			(at 0 -0.4445 180)
			(size 0.1397 0.1397)
			(layers "B.Cu" "B.Mask" "B.Paste")
			(net "P5V_A_4")
			(options
				(clearance outline)
				(anchor circle)
			)
			(primitives
				(gr_poly
					(pts
						(arc
							(start -0.1778 0.2794)
							(mid -0.249642 0.249642)
							(end -0.2794 0.1778)
						)
						(arc
							(start -0.2794 -0.1778)
							(mid -0.249642 -0.249642)
							(end -0.1778 -0.2794)
						)
						(arc
							(start 0.1778 -0.2794)
							(mid 0.249642 -0.249642)
							(end 0.2794 -0.1778)
						)
						(arc
							(start 0.2794 0.1778)
							(mid 0.249642 0.249642)
							(end 0.1778 0.2794)
						)
					)
					(width 0)
					(fill yes)
				)
			)
		)
		(pad "2" smd custom
			(at 0 0.4445 180)
			(size 0.1397 0.1397)
			(layers "B.Cu" "B.Mask" "B.Paste")
			(net "P5V_A_4_PGOOD")
			(options
				(clearance outline)
				(anchor circle)
			)
			(primitives
				(gr_poly
					(pts
						(arc
							(start -0.1778 0.2794)
							(mid -0.249642 0.249642)
							(end -0.2794 0.1778)
						)
						(arc
							(start -0.2794 -0.1778)
							(mid -0.249642 -0.249642)
							(end -0.1778 -0.2794)
						)
						(arc
							(start 0.1778 -0.2794)
							(mid 0.249642 -0.249642)
							(end 0.2794 -0.1778)
						)
						(arc
							(start 0.2794 0.1778)
							(mid 0.249642 0.249642)
							(end 0.1778 0.2794)
						)
					)
					(width 0)
					(fill yes)
				)
			)
		)
	)
	(footprint ""
		(layer "B.Cu")
		(at 474.091 -241.427 90)
		(property "Reference" "C649"
			(at 0 0 90)
			(layer "B.SilkS")
			(hide yes)
			(effects
				(font
					(size 1.27 1.27)
				)
				(justify mirror)
			)
		)
		(property "Value" "SC10U16V5KX-7-GP-U"
			(at 0.0762 -6.1214 90)
			(unlocked yes)
			(layer "B.Fab")
			(hide yes)
			(effects
				(font
					(size 1.016 1.016)
					(thickness 0.1524)
				)
				(justify mirror)
			)
		)
		(property "Device Type" "C805H58"
			(at 0.0762 -8.1534 90)
			(unlocked yes)
			(layer "B.Fab")
			(hide yes)
			(effects
				(font
					(size 1.016 1.016)
					(thickness 0.1524)
				)
				(justify mirror)
			)
		)
		(duplicate_pad_numbers_are_jumpers no)
		(fp_line
			(start -0.635 0)
			(end 0.635 0)
			(stroke
				(width 0.508)
				(type default)
			)
			(layer "B.SilkS")
		)
		(fp_rect
			(start 0.9652 1.778)
			(end -0.9652 -1.778)
			(stroke
				(width 0)
				(type default)
			)
			(fill no)
			(layer "B.CrtYd")
		)
		(fp_poly
			(pts
				(xy 0.9652 -1.778) (xy -0.9652 -1.778) (xy -0.9652 1.778) (xy 0.9652 1.778)
			)
			(stroke
				(width 0)
				(type default)
			)
			(fill no)
			(layer "B.Fab")
		)
		(pad "1" smd rect
			(at 0 -0.9652 270)
			(size 1.397 1.143)
			(layers "B.Cu" "B.Mask" "B.Paste")
			(net "P12V_A_VIN_U27")
		)
		(pad "2" smd rect
			(at 0 0.9652 270)
			(size 1.397 1.143)
			(layers "B.Cu" "B.Mask" "B.Paste")
			(net "GND")
		)
	)
	(footprint ""
		(layer "B.Cu")
		(at 192.206118 -223.441006)
		(property "Reference" "R1281"
			(at 0 0 0)
			(layer "B.SilkS")
			(hide yes)
			(effects
				(font
					(size 1.27 1.27)
				)
				(justify mirror)
			)
		)
		(property "Value" "2D2R3-1-U-GP"
			(at 0.0254 -2.5146 0)
			(unlocked yes)
			(layer "B.Fab")
			(hide yes)
			(effects
				(font
					(size 1.016 1.016)
					(thickness 0.1524)
				)
				(justify mirror)
			)
		)
		(property "Device Type" "R603H22"
			(at 0.0254 -4.0386 0)
			(unlocked yes)
			(layer "B.Fab")
			(hide yes)
			(effects
				(font
					(size 1.016 1.016)
					(thickness 0.1524)
				)
				(justify mirror)
			)
		)
		(duplicate_pad_numbers_are_jumpers no)
		(fp_line
			(start -0.2032 0)
			(end -0.4826 0)
			(stroke
				(width 0.2032)
				(type default)
			)
			(layer "B.SilkS")
		)
		(fp_line
			(start 0.4826 0)
			(end 0.2032 0)
			(stroke
				(width 0.2032)
				(type default)
			)
			(layer "B.SilkS")
		)
		(fp_rect
			(start 0.5842 1.3335)
			(end -0.5842 -1.3335)
			(stroke
				(width 0)
				(type default)
			)
			(fill no)
			(layer "B.CrtYd")
		)
		(fp_rect
			(start 0.5842 1.3335)
			(end -0.5842 -1.3335)
			(stroke
				(width 0)
				(type default)
			)
			(fill no)
			(layer "B.Fab")
		)
		(pad "1" smd custom
			(at 0 -0.762 180)
			(size 0.2159 0.2159)
			(layers "B.Cu" "B.Mask" "B.Paste")
			(net "P3V3_STBY_VCC")
			(options
				(clearance outline)
				(anchor circle)
			)
			(primitives
				(gr_poly
					(pts
						(arc
							(start -0.3302 0.4318)
							(mid -0.402042 0.402042)
							(end -0.4318 0.3302)
						)
						(arc
							(start -0.4318 -0.3302)
							(mid -0.402042 -0.402042)
							(end -0.3302 -0.4318)
						)
						(arc
							(start 0.3302 -0.4318)
							(mid 0.402042 -0.402042)
							(end 0.4318 -0.3302)
						)
						(arc
							(start 0.4318 0.3302)
							(mid 0.402042 0.402042)
							(end 0.3302 0.4318)
						)
					)
					(width 0)
					(fill yes)
				)
			)
		)
		(pad "2" smd custom
			(at 0 0.762 180)
			(size 0.2159 0.2159)
			(layers "B.Cu" "B.Mask" "B.Paste")
			(net "P12V_A")
			(options
				(clearance outline)
				(anchor circle)
			)
			(primitives
				(gr_poly
					(pts
						(arc
							(start -0.3302 0.4318)
							(mid -0.402042 0.402042)
							(end -0.4318 0.3302)
						)
						(arc
							(start -0.4318 -0.3302)
							(mid -0.402042 -0.402042)
							(end -0.3302 -0.4318)
						)
						(arc
							(start 0.3302 -0.4318)
							(mid 0.402042 -0.402042)
							(end 0.4318 -0.3302)
						)
						(arc
							(start 0.4318 0.3302)
							(mid 0.402042 0.402042)
							(end 0.3302 0.4318)
						)
					)
					(width 0)
					(fill yes)
				)
			)
		)
	)
	(footprint ""
		(layer "B.Cu")
		(at 16.129 -246.8118)
		(property "Reference" "L1"
			(at 0 0 0)
			(layer "B.SilkS")
			(hide yes)
			(effects
				(font
					(size 1.27 1.27)
				)
				(justify mirror)
			)
		)
		(property "Value" "BLM21PG220SN1DGP"
			(at -0.0254 -5.6896 0)
			(unlocked yes)
			(layer "B.Fab")
			(hide yes)
			(effects
				(font
					(size 1.016 1.016)
					(thickness 0.1524)
				)
				(justify mirror)
			)
		)
		(property "Device Type" "L20125H42"
			(at -0.0254 -7.5946 0)
			(unlocked yes)
			(layer "B.Fab")
			(hide yes)
			(effects
				(font
					(size 1.016 1.016)
					(thickness 0.1524)
				)
				(justify mirror)
			)
		)
		(duplicate_pad_numbers_are_jumpers no)
		(fp_line
			(start -0.9144 -1.7018)
			(end 0.9144 -1.7018)
			(stroke
				(width 0.1524)
				(type default)
			)
			(layer "B.SilkS")
		)
		(fp_line
			(start -0.9144 1.7018)
			(end -0.9144 -1.7018)
			(stroke
				(width 0.1524)
				(type default)
			)
			(layer "B.SilkS")
		)
		(fp_line
			(start 0.9144 -1.7018)
			(end 0.9144 1.7018)
			(stroke
				(width 0.1524)
				(type default)
			)
			(layer "B.SilkS")
		)
		(fp_line
			(start 0.9144 1.7018)
			(end -0.9144 1.7018)
			(stroke
				(width 0.1524)
				(type default)
			)
			(layer "B.SilkS")
		)
		(fp_rect
			(start 1.0033 1.778)
			(end -1.0033 -1.778)
			(stroke
				(width 0)
				(type default)
			)
			(fill no)
			(layer "B.CrtYd")
		)
		(fp_poly
			(pts
				(xy 1.0033 -1.778) (xy -1.0033 -1.778) (xy -1.0033 1.778) (xy 1.0033 1.778)
			)
			(stroke
				(width 0)
				(type default)
			)
			(fill no)
			(layer "B.Fab")
		)
		(pad "1" smd rect
			(at 0 -0.9652 180)
			(size 1.397 1.143)
			(layers "B.Cu" "B.Mask" "B.Paste")
			(net "P12V_A")
		)
		(pad "2" smd rect
			(at 0 0.9652 180)
			(size 1.397 1.143)
			(layers "B.Cu" "B.Mask" "B.Paste")
			(net "P12V_A_VIN_U20")
		)
	)
	(footprint ""
		(layer "B.Cu")
		(at 38.876224 -254.711454 -90)
		(property "Reference" "C609"
			(at 0 0 90)
			(layer "B.SilkS")
			(hide yes)
			(effects
				(font
					(size 1.27 1.27)
				)
				(justify mirror)
			)
		)
		(property "Value" "SC470P50V2KX-3GP"
			(at -1.1811 -2.7051 270)
			(unlocked yes)
			(layer "B.Fab")
			(hide yes)
			(effects
				(font
					(size 1.016 1.016)
					(thickness 0.1524)
				)
				(justify mirror)
			)
		)
		(property "Device Type" "C402H22"
			(at -1.1811 -4.2291 270)
			(unlocked yes)
			(layer "B.Fab")
			(hide yes)
			(effects
				(font
					(size 1.016 1.016)
					(thickness 0.1524)
				)
				(justify mirror)
			)
		)
		(duplicate_pad_numbers_are_jumpers no)
		(fp_rect
			(start 0.4318 0.9525)
			(end -0.4318 -0.9525)
			(stroke
				(width 0)
				(type default)
			)
			(fill no)
			(layer "B.CrtYd")
		)
		(fp_rect
			(start 0.4318 0.9525)
			(end -0.4318 -0.9525)
			(stroke
				(width 0)
				(type default)
			)
			(fill no)
			(layer "B.Fab")
		)
		(pad "1" smd custom
			(at 0 -0.4445 90)
			(size 0.1524 0.1524)
			(layers "B.Cu" "B.Mask" "B.Paste")
			(net "P5V_A_LL_R")
			(options
				(clearance outline)
				(anchor circle)
			)
			(primitives
				(gr_poly
					(pts
						(arc
							(start 0.3048 0.2032)
							(mid 0.275042 0.275042)
							(end 0.2032 0.3048)
						)
						(arc
							(start -0.2032 0.3048)
							(mid -0.275042 0.275042)
							(end -0.3048 0.2032)
						)
						(arc
							(start -0.3048 -0.2032)
							(mid -0.275042 -0.275042)
							(end -0.2032 -0.3048)
						)
						(arc
							(start 0.2032 -0.3048)
							(mid 0.275042 -0.275042)
							(end 0.3048 -0.2032)
						)
					)
					(width 0)
					(fill yes)
				)
			)
		)
		(pad "2" smd custom
			(at 0 0.4445 90)
			(size 0.1524 0.1524)
			(layers "B.Cu" "B.Mask" "B.Paste")
			(net "P5V_A_VFB")
			(options
				(clearance outline)
				(anchor circle)
			)
			(primitives
				(gr_poly
					(pts
						(arc
							(start 0.3048 0.2032)
							(mid 0.275042 0.275042)
							(end 0.2032 0.3048)
						)
						(arc
							(start -0.2032 0.3048)
							(mid -0.275042 0.275042)
							(end -0.3048 0.2032)
						)
						(arc
							(start -0.3048 -0.2032)
							(mid -0.275042 -0.275042)
							(end -0.2032 -0.3048)
						)
						(arc
							(start 0.2032 -0.3048)
							(mid 0.275042 -0.275042)
							(end 0.3048 -0.2032)
						)
					)
					(width 0)
					(fill yes)
				)
			)
		)
	)
	(footprint ""
		(layer "B.Cu")
		(at 187.447936 -220.242384 180)
		(property "Reference" "R1283"
			(at 0 0 0)
			(layer "B.SilkS")
			(hide yes)
			(effects
				(font
					(size 1.27 1.27)
				)
				(justify mirror)
			)
		)
		(property "Value" "10KR2F-2-GP"
			(at -0.064008 -3.993896 180)
			(unlocked yes)
			(layer "B.Fab")
			(hide yes)
			(effects
				(font
					(size 1.016 1.016)
					(thickness 0.1524)
				)
				(justify mirror)
			)
		)
		(property "Device Type" "R402H16"
			(at -0.064008 -5.517896 180)
			(unlocked yes)
			(layer "B.Fab")
			(hide yes)
			(effects
				(font
					(size 1.016 1.016)
					(thickness 0.1524)
				)
				(justify mirror)
			)
		)
		(duplicate_pad_numbers_are_jumpers no)
		(fp_line
			(start 0.508 -0.9398)
			(end 0.508 0.9398)
			(stroke
				(width 0.1524)
				(type default)
			)
			(layer "B.SilkS")
		)
		(fp_line
			(start -0.508 -0.9398)
			(end 0.508 -0.9398)
			(stroke
				(width 0.1524)
				(type default)
			)
			(layer "B.SilkS")
		)
		(fp_rect
			(start 0.508 0.9398)
			(end -0.508 -0.9398)
			(stroke
				(width 0)
				(type default)
			)
			(fill no)
			(layer "B.CrtYd")
		)
		(fp_rect
			(start 0.508 0.9398)
			(end -0.508 -0.9398)
			(stroke
				(width 0)
				(type default)
			)
			(fill no)
			(layer "B.Fab")
		)
		(pad "1" smd custom
			(at 0 -0.4445)
			(size 0.1397 0.1397)
			(layers "B.Cu" "B.Mask" "B.Paste")
			(net "AGND_P3V3_STBY")
			(options
				(clearance outline)
				(anchor circle)
			)
			(primitives
				(gr_poly
					(pts
						(arc
							(start -0.1778 0.2794)
							(mid -0.249642 0.249642)
							(end -0.2794 0.1778)
						)
						(arc
							(start -0.2794 -0.1778)
							(mid -0.249642 -0.249642)
							(end -0.1778 -0.2794)
						)
						(arc
							(start 0.1778 -0.2794)
							(mid 0.249642 -0.249642)
							(end 0.2794 -0.1778)
						)
						(arc
							(start 0.2794 0.1778)
							(mid 0.249642 0.249642)
							(end 0.1778 0.2794)
						)
					)
					(width 0)
					(fill yes)
				)
			)
		)
		(pad "2" smd custom
			(at 0 0.4445)
			(size 0.1397 0.1397)
			(layers "B.Cu" "B.Mask" "B.Paste")
			(net "P3V3_STBY_VFB")
			(options
				(clearance outline)
				(anchor circle)
			)
			(primitives
				(gr_poly
					(pts
						(arc
							(start -0.1778 0.2794)
							(mid -0.249642 0.249642)
							(end -0.2794 0.1778)
						)
						(arc
							(start -0.2794 -0.1778)
							(mid -0.249642 -0.249642)
							(end -0.1778 -0.2794)
						)
						(arc
							(start 0.1778 -0.2794)
							(mid 0.249642 -0.249642)
							(end 0.2794 -0.1778)
						)
						(arc
							(start 0.2794 0.1778)
							(mid 0.249642 0.249642)
							(end 0.1778 0.2794)
						)
					)
					(width 0)
					(fill yes)
				)
			)
		)
	)
	(footprint ""
		(layer "B.Cu")
		(at 471.885518 -207.34909 -90)
		(property "Reference" "C663"
			(at 0 0 90)
			(layer "B.SilkS")
			(hide yes)
			(effects
				(font
					(size 1.27 1.27)
				)
				(justify mirror)
			)
		)
		(property "Value" "SC10U16V5KX-7-GP-U"
			(at 0.0762 -6.1214 270)
			(unlocked yes)
			(layer "B.Fab")
			(hide yes)
			(effects
				(font
					(size 1.016 1.016)
					(thickness 0.1524)
				)
				(justify mirror)
			)
		)
		(property "Device Type" "C805H58"
			(at 0.0762 -8.1534 270)
			(unlocked yes)
			(layer "B.Fab")
			(hide yes)
			(effects
				(font
					(size 1.016 1.016)
					(thickness 0.1524)
				)
				(justify mirror)
			)
		)
		(duplicate_pad_numbers_are_jumpers no)
		(fp_line
			(start -0.635 0)
			(end 0.635 0)
			(stroke
				(width 0.508)
				(type default)
			)
			(layer "B.SilkS")
		)
		(fp_rect
			(start 0.9652 1.778)
			(end -0.9652 -1.778)
			(stroke
				(width 0)
				(type default)
			)
			(fill no)
			(layer "B.CrtYd")
		)
		(fp_poly
			(pts
				(xy 0.9652 -1.778) (xy -0.9652 -1.778) (xy -0.9652 1.778) (xy 0.9652 1.778)
			)
			(stroke
				(width 0)
				(type default)
			)
			(fill no)
			(layer "B.Fab")
		)
		(pad "1" smd rect
			(at 0 -0.9652 90)
			(size 1.397 1.143)
			(layers "B.Cu" "B.Mask" "B.Paste")
			(net "P5V_A_4")
		)
		(pad "2" smd rect
			(at 0 0.9652 90)
			(size 1.397 1.143)
			(layers "B.Cu" "B.Mask" "B.Paste")
			(net "GND")
		)
	)
	(footprint ""
		(layer "B.Cu")
		(at 470.939622 -213.114128 -90)
		(property "Reference" "TC12"
			(at 0 0 90)
			(layer "B.SilkS")
			(hide yes)
			(effects
				(font
					(size 1.27 1.27)
				)
				(justify mirror)
			)
		)
		(property "Value" "ST220U10VDM-LGP"
			(at 0 -9.6012 270)
			(unlocked yes)
			(layer "B.Fab")
			(hide yes)
			(effects
				(font
					(size 1.016 1.016)
					(thickness 0.1524)
				)
				(justify mirror)
			)
		)
		(property "Device Type" "CT7343H119"
			(at 0 -11.1252 270)
			(unlocked yes)
			(layer "B.Fab")
			(hide yes)
			(effects
				(font
					(size 1.016 1.016)
					(thickness 0.1524)
				)
				(justify mirror)
			)
		)
		(duplicate_pad_numbers_are_jumpers no)
		(fp_line
			(start -2.286 4.8768)
			(end 2.286 4.8768)
			(stroke
				(width 0.1524)
				(type default)
			)
			(layer "B.SilkS")
		)
		(fp_line
			(start 2.286 4.8768)
			(end 2.286 2.032)
			(stroke
				(width 0.1524)
				(type default)
			)
			(layer "B.SilkS")
		)
		(fp_line
			(start -2.286 2.032)
			(end -2.286 4.8768)
			(stroke
				(width 0.1524)
				(type default)
			)
			(layer "B.SilkS")
		)
		(fp_line
			(start -2.286 -2.032)
			(end -2.286 -4.8768)
			(stroke
				(width 0.1524)
				(type default)
			)
			(layer "B.SilkS")
		)
		(fp_line
			(start -2.1082 -4.699)
			(end 2.1082 -4.699)
			(stroke
				(width 0.508)
				(type default)
			)
			(layer "B.SilkS")
		)
		(fp_line
			(start -2.286 -4.8768)
			(end 2.286 -4.8768)
			(stroke
				(width 0.1524)
				(type default)
			)
			(layer "B.SilkS")
		)
		(fp_line
			(start 2.286 -4.8768)
			(end 2.286 -2.032)
			(stroke
				(width 0.1524)
				(type default)
			)
			(layer "B.SilkS")
		)
		(fp_rect
			(start 2.1463 3.6449)
			(end -2.1463 -3.6449)
			(stroke
				(width 0)
				(type default)
			)
			(fill no)
			(layer "B.CrtYd")
		)
		(fp_poly
			(pts
				(xy 2.54 4.953) (xy 2.54 4.2926) (xy 3.81 4.2926) (xy 3.81 -4.2926) (xy 2.54 -4.2926) (xy 2.54 -4.953)
				(xy -2.54 -4.953) (xy -2.54 -4.2926) (xy -3.81 -4.2926) (xy -3.81 -1.6256) (xy -2.1463 -1.6256)
				(xy -2.1463 -3.6449) (xy 2.1463 -3.6449) (xy 2.1463 3.6449) (xy -2.1463 3.6449) (xy -2.1463 -1.6129)
				(xy -3.81 -1.6129) (xy -3.81 4.2926) (xy -2.54 4.2926) (xy -2.54 4.953)
			)
			(stroke
				(width 0)
				(type default)
			)
			(fill no)
			(layer "B.CrtYd")
		)
		(fp_rect
			(start 2.54 4.953)
			(end -2.54 -4.953)
			(stroke
				(width 0)
				(type default)
			)
			(fill no)
			(layer "B.Fab")
		)
		(fp_rect
			(start -2.54 4.2926)
			(end -3.81 -4.2926)
			(stroke
				(width 0)
				(type default)
			)
			(fill no)
			(layer "B.Fab")
		)
		(fp_rect
			(start 3.81 4.2926)
			(end 2.54 -4.2926)
			(stroke
				(width 0)
				(type default)
			)
			(fill no)
			(layer "B.Fab")
		)
		(pad "1" smd rect
			(at 0 -3.1496 90)
			(size 2.413 2.286)
			(layers "B.Cu" "B.Mask" "B.Paste")
			(net "P5V_A_4")
		)
		(pad "2" smd rect
			(at 0 3.1496 90)
			(size 2.413 2.286)
			(layers "B.Cu" "B.Mask" "B.Paste")
			(net "GND")
		)
		(zone
			(layer "B.Cu")
			(hatch none 0.5)
			(connect_pads
				(clearance 0)
			)
			(min_thickness 0.25)
			(keepout
				(tracks allowed)
				(vias not_allowed)
				(pads allowed)
				(copperpour not_allowed)
				(footprints allowed)
			)
			(placement
				(enabled no)
				(sheetname "")
			)
			(fill
				(thermal_gap 0.5)
				(thermal_bridge_width 0.5)
				(island_removal_mode 0)
			)
			(polygon
				(pts
					(xy 466.342222 -211.602828) (xy 466.342222 -214.625428) (xy 469.237822 -214.625428) (xy 469.568022 -214.625428)
					(xy 469.568022 -211.602828) (xy 469.237822 -211.602828)
				)
			)
		)
		(zone
			(layer "B.Cu")
			(hatch none 0.5)
			(connect_pads
				(clearance 0)
			)
			(min_thickness 0.25)
			(keepout
				(tracks allowed)
				(vias not_allowed)
				(pads allowed)
				(copperpour not_allowed)
				(footprints allowed)
			)
			(placement
				(enabled no)
				(sheetname "")
			)
			(fill
				(thermal_gap 0.5)
				(thermal_bridge_width 0.5)
				(island_removal_mode 0)
			)
			(polygon
				(pts
					(xy 472.628722 -214.625428) (xy 475.537022 -214.625428) (xy 475.537022 -211.602828) (xy 472.641422 -211.602828)
					(xy 472.311222 -211.602828) (xy 472.311222 -214.625428)
				)
			)
		)
	)
	(footprint ""
		(layer "B.Cu")
		(at 452.025004 -256.474214 -90)
		(property "Reference" "R1254"
			(at 0 0 90)
			(layer "B.SilkS")
			(hide yes)
			(effects
				(font
					(size 1.27 1.27)
				)
				(justify mirror)
			)
		)
		(property "Value" "10R3F-GP"
			(at 0.0254 -2.5146 270)
			(unlocked yes)
			(layer "B.Fab")
			(hide yes)
			(effects
				(font
					(size 1.016 1.016)
					(thickness 0.1524)
				)
				(justify mirror)
			)
		)
		(property "Device Type" "R603H22"
			(at 0.0254 -4.0386 270)
			(unlocked yes)
			(layer "B.Fab")
			(hide yes)
			(effects
				(font
					(size 1.016 1.016)
					(thickness 0.1524)
				)
				(justify mirror)
			)
		)
		(duplicate_pad_numbers_are_jumpers no)
		(fp_line
			(start -0.2032 0)
			(end -0.4826 0)
			(stroke
				(width 0.2032)
				(type default)
			)
			(layer "B.SilkS")
		)
		(fp_line
			(start 0.4826 0)
			(end 0.2032 0)
			(stroke
				(width 0.2032)
				(type default)
			)
			(layer "B.SilkS")
		)
		(fp_rect
			(start 0.5842 1.3335)
			(end -0.5842 -1.3335)
			(stroke
				(width 0)
				(type default)
			)
			(fill no)
			(layer "B.CrtYd")
		)
		(fp_rect
			(start 0.5842 1.3335)
			(end -0.5842 -1.3335)
			(stroke
				(width 0)
				(type default)
			)
			(fill no)
			(layer "B.Fab")
		)
		(pad "1" smd custom
			(at 0 -0.762 90)
			(size 0.2159 0.2159)
			(layers "B.Cu" "B.Mask" "B.Paste")
			(net "P5V_C_CC")
			(options
				(clearance outline)
				(anchor circle)
			)
			(primitives
				(gr_poly
					(pts
						(arc
							(start -0.3302 0.4318)
							(mid -0.402042 0.402042)
							(end -0.4318 0.3302)
						)
						(arc
							(start -0.4318 -0.3302)
							(mid -0.402042 -0.402042)
							(end -0.3302 -0.4318)
						)
						(arc
							(start 0.3302 -0.4318)
							(mid 0.402042 -0.402042)
							(end 0.4318 -0.3302)
						)
						(arc
							(start 0.4318 0.3302)
							(mid 0.402042 0.402042)
							(end 0.3302 0.4318)
						)
					)
					(width 0)
					(fill yes)
				)
			)
		)
		(pad "2" smd custom
			(at 0 0.762 90)
			(size 0.2159 0.2159)
			(layers "B.Cu" "B.Mask" "B.Paste")
			(net "P5V_C_VFB_R")
			(options
				(clearance outline)
				(anchor circle)
			)
			(primitives
				(gr_poly
					(pts
						(arc
							(start -0.3302 0.4318)
							(mid -0.402042 0.402042)
							(end -0.4318 0.3302)
						)
						(arc
							(start -0.4318 -0.3302)
							(mid -0.402042 -0.402042)
							(end -0.3302 -0.4318)
						)
						(arc
							(start 0.3302 -0.4318)
							(mid 0.402042 -0.402042)
							(end 0.4318 -0.3302)
						)
						(arc
							(start 0.4318 0.3302)
							(mid 0.402042 0.402042)
							(end 0.3302 0.4318)
						)
					)
					(width 0)
					(fill yes)
				)
			)
		)
	)
	(footprint ""
		(layer "B.Cu")
		(at 470.408 -239.395 -90)
		(property "Reference" "C652"
			(at 0 0 90)
			(layer "B.SilkS")
			(hide yes)
			(effects
				(font
					(size 1.27 1.27)
				)
				(justify mirror)
			)
		)
		(property "Value" "SC10U16V5KX-7-GP-U"
			(at 0.0762 -6.1214 270)
			(unlocked yes)
			(layer "B.Fab")
			(hide yes)
			(effects
				(font
					(size 1.016 1.016)
					(thickness 0.1524)
				)
				(justify mirror)
			)
		)
		(property "Device Type" "C805H58"
			(at 0.0762 -8.1534 270)
			(unlocked yes)
			(layer "B.Fab")
			(hide yes)
			(effects
				(font
					(size 1.016 1.016)
					(thickness 0.1524)
				)
				(justify mirror)
			)
		)
		(duplicate_pad_numbers_are_jumpers no)
		(fp_line
			(start -0.635 0)
			(end 0.635 0)
			(stroke
				(width 0.508)
				(type default)
			)
			(layer "B.SilkS")
		)
		(fp_rect
			(start 0.9652 1.778)
			(end -0.9652 -1.778)
			(stroke
				(width 0)
				(type default)
			)
			(fill no)
			(layer "B.CrtYd")
		)
		(fp_poly
			(pts
				(xy 0.9652 -1.778) (xy -0.9652 -1.778) (xy -0.9652 1.778) (xy 0.9652 1.778)
			)
			(stroke
				(width 0)
				(type default)
			)
			(fill no)
			(layer "B.Fab")
		)
		(pad "1" smd rect
			(at 0 -0.9652 90)
			(size 1.397 1.143)
			(layers "B.Cu" "B.Mask" "B.Paste")
			(net "P12V_A_VIN_U27")
		)
		(pad "2" smd rect
			(at 0 0.9652 90)
			(size 1.397 1.143)
			(layers "B.Cu" "B.Mask" "B.Paste")
			(net "GND")
		)
	)
	(footprint ""
		(layer "B.Cu")
		(at 39.863014 -252.893576 180)
		(property "Reference" "C608"
			(at 0 0 0)
			(layer "B.SilkS")
			(hide yes)
			(effects
				(font
					(size 1.27 1.27)
				)
				(justify mirror)
			)
		)
		(property "Value" "SCD1U50V3KX-GP"
			(at 0 -2.8194 180)
			(unlocked yes)
			(layer "B.Fab")
			(hide yes)
			(effects
				(font
					(size 1.016 1.016)
					(thickness 0.1524)
				)
				(justify mirror)
			)
		)
		(property "Device Type" "C603H36"
			(at 0 -4.3434 180)
			(unlocked yes)
			(layer "B.Fab")
			(hide yes)
			(effects
				(font
					(size 1.016 1.016)
					(thickness 0.1524)
				)
				(justify mirror)
			)
		)
		(duplicate_pad_numbers_are_jumpers no)
		(fp_line
			(start -0.508 0)
			(end 0.508 0)
			(stroke
				(width 0.2032)
				(type default)
			)
			(layer "B.SilkS")
		)
		(fp_rect
			(start 0.5842 1.3335)
			(end -0.5842 -1.3335)
			(stroke
				(width 0)
				(type default)
			)
			(fill no)
			(layer "B.CrtYd")
		)
		(fp_rect
			(start 0.5842 1.3335)
			(end -0.5842 -1.3335)
			(stroke
				(width 0)
				(type default)
			)
			(fill no)
			(layer "B.Fab")
		)
		(pad "1" smd custom
			(at 0 -0.762)
			(size 0.2159 0.2159)
			(layers "B.Cu" "B.Mask" "B.Paste")
			(net "P5V_A_1")
			(options
				(clearance outline)
				(anchor circle)
			)
			(primitives
				(gr_poly
					(pts
						(arc
							(start -0.3302 0.4318)
							(mid -0.402042 0.402042)
							(end -0.4318 0.3302)
						)
						(arc
							(start -0.4318 -0.3302)
							(mid -0.402042 -0.402042)
							(end -0.3302 -0.4318)
						)
						(arc
							(start 0.3302 -0.4318)
							(mid 0.402042 -0.402042)
							(end 0.4318 -0.3302)
						)
						(arc
							(start 0.4318 0.3302)
							(mid 0.402042 0.402042)
							(end 0.3302 0.4318)
						)
					)
					(width 0)
					(fill yes)
				)
			)
		)
		(pad "2" smd custom
			(at 0 0.762)
			(size 0.2159 0.2159)
			(layers "B.Cu" "B.Mask" "B.Paste")
			(net "P5V_A_LL_R")
			(options
				(clearance outline)
				(anchor circle)
			)
			(primitives
				(gr_poly
					(pts
						(arc
							(start -0.3302 0.4318)
							(mid -0.402042 0.402042)
							(end -0.4318 0.3302)
						)
						(arc
							(start -0.4318 -0.3302)
							(mid -0.402042 -0.402042)
							(end -0.3302 -0.4318)
						)
						(arc
							(start 0.3302 -0.4318)
							(mid 0.402042 -0.402042)
							(end 0.4318 -0.3302)
						)
						(arc
							(start 0.4318 0.3302)
							(mid 0.402042 0.402042)
							(end 0.3302 0.4318)
						)
					)
					(width 0)
					(fill yes)
				)
			)
		)
	)
	(footprint ""
		(layer "B.Cu")
		(at 35.1028 -142.1384 180)
		(property "Reference" "C619"
			(at 0 0 0)
			(layer "B.SilkS")
			(hide yes)
			(effects
				(font
					(size 1.27 1.27)
				)
				(justify mirror)
			)
		)
		(property "Value" "SC10U16V5KX-7-GP-U"
			(at 0.0762 -6.1214 180)
			(unlocked yes)
			(layer "B.Fab")
			(hide yes)
			(effects
				(font
					(size 1.016 1.016)
					(thickness 0.1524)
				)
				(justify mirror)
			)
		)
		(property "Device Type" "C805H58"
			(at 0.0762 -8.1534 180)
			(unlocked yes)
			(layer "B.Fab")
			(hide yes)
			(effects
				(font
					(size 1.016 1.016)
					(thickness 0.1524)
				)
				(justify mirror)
			)
		)
		(duplicate_pad_numbers_are_jumpers no)
		(fp_line
			(start -0.635 0)
			(end 0.635 0)
			(stroke
				(width 0.508)
				(type default)
			)
			(layer "B.SilkS")
		)
		(fp_rect
			(start 0.9652 1.778)
			(end -0.9652 -1.778)
			(stroke
				(width 0)
				(type default)
			)
			(fill no)
			(layer "B.CrtYd")
		)
		(fp_poly
			(pts
				(xy 0.9652 -1.778) (xy -0.9652 -1.778) (xy -0.9652 1.778) (xy 0.9652 1.778)
			)
			(stroke
				(width 0)
				(type default)
			)
			(fill no)
			(layer "B.Fab")
		)
		(pad "1" smd rect
			(at 0 -0.9652)
			(size 1.397 1.143)
			(layers "B.Cu" "B.Mask" "B.Paste")
			(net "P12V_A_VIN_U21")
		)
		(pad "2" smd rect
			(at 0 0.9652)
			(size 1.397 1.143)
			(layers "B.Cu" "B.Mask" "B.Paste")
			(net "GND")
		)
	)
	(footprint ""
		(layer "B.Cu")
		(at 219.9894 -123.4694)
		(property "Reference" "R450"
			(at 0 0 0)
			(layer "B.SilkS")
			(hide yes)
			(effects
				(font
					(size 1.27 1.27)
				)
				(justify mirror)
			)
		)
		(property "Value" "0R2J-2-GP"
			(at -0.064008 -3.993896 0)
			(unlocked yes)
			(layer "B.Fab")
			(hide yes)
			(effects
				(font
					(size 1.016 1.016)
					(thickness 0.1524)
				)
				(justify mirror)
			)
		)
		(property "Device Type" "R402H16"
			(at -0.064008 -5.517896 0)
			(unlocked yes)
			(layer "B.Fab")
			(hide yes)
			(effects
				(font
					(size 1.016 1.016)
					(thickness 0.1524)
				)
				(justify mirror)
			)
		)
		(duplicate_pad_numbers_are_jumpers no)
		(fp_line
			(start -0.508 -0.9398)
			(end 0.508 -0.9398)
			(stroke
				(width 0.1524)
				(type default)
			)
			(layer "B.SilkS")
		)
		(fp_line
			(start 0.508 -0.9398)
			(end 0.508 0.9398)
			(stroke
				(width 0.1524)
				(type default)
			)
			(layer "B.SilkS")
		)
		(fp_rect
			(start 0.508 0.9398)
			(end -0.508 -0.9398)
			(stroke
				(width 0)
				(type default)
			)
			(fill no)
			(layer "B.CrtYd")
		)
		(fp_rect
			(start 0.508 0.9398)
			(end -0.508 -0.9398)
			(stroke
				(width 0)
				(type default)
			)
			(fill no)
			(layer "B.Fab")
		)
		(pad "1" smd custom
			(at 0 -0.4445 180)
			(size 0.1397 0.1397)
			(layers "B.Cu" "B.Mask" "B.Paste")
			(net "I2C_BMC_A_COMP_A_SCL_R")
			(options
				(clearance outline)
				(anchor circle)
			)
			(primitives
				(gr_poly
					(pts
						(arc
							(start -0.1778 0.2794)
							(mid -0.249642 0.249642)
							(end -0.2794 0.1778)
						)
						(arc
							(start -0.2794 -0.1778)
							(mid -0.249642 -0.249642)
							(end -0.1778 -0.2794)
						)
						(arc
							(start 0.1778 -0.2794)
							(mid 0.249642 -0.249642)
							(end 0.2794 -0.1778)
						)
						(arc
							(start 0.2794 0.1778)
							(mid 0.249642 0.249642)
							(end 0.1778 0.2794)
						)
					)
					(width 0)
					(fill yes)
				)
			)
		)
		(pad "2" smd custom
			(at 0 0.4445 180)
			(size 0.1397 0.1397)
			(layers "B.Cu" "B.Mask" "B.Paste")
			(net "I2C_BMC_A_COMP_A_SCL_BUF")
			(options
				(clearance outline)
				(anchor circle)
			)
			(primitives
				(gr_poly
					(pts
						(arc
							(start -0.1778 0.2794)
							(mid -0.249642 0.249642)
							(end -0.2794 0.1778)
						)
						(arc
							(start -0.2794 -0.1778)
							(mid -0.249642 -0.249642)
							(end -0.1778 -0.2794)
						)
						(arc
							(start 0.1778 -0.2794)
							(mid 0.249642 -0.249642)
							(end 0.2794 -0.1778)
						)
						(arc
							(start 0.2794 0.1778)
							(mid 0.249642 0.249642)
							(end 0.1778 0.2794)
						)
					)
					(width 0)
					(fill yes)
				)
			)
		)
	)
	(footprint ""
		(layer "B.Cu")
		(at 73.0758 -147.5486 180)
		(property "Reference" "C628"
			(at 0 0 0)
			(layer "B.SilkS")
			(hide yes)
			(effects
				(font
					(size 1.27 1.27)
				)
				(justify mirror)
			)
		)
		(property "Value" "SC10U16V5KX-7-GP-U"
			(at 0.0762 -6.1214 180)
			(unlocked yes)
			(layer "B.Fab")
			(hide yes)
			(effects
				(font
					(size 1.016 1.016)
					(thickness 0.1524)
				)
				(justify mirror)
			)
		)
		(property "Device Type" "C805H58"
			(at 0.0762 -8.1534 180)
			(unlocked yes)
			(layer "B.Fab")
			(hide yes)
			(effects
				(font
					(size 1.016 1.016)
					(thickness 0.1524)
				)
				(justify mirror)
			)
		)
		(duplicate_pad_numbers_are_jumpers no)
		(fp_line
			(start -0.635 0)
			(end 0.635 0)
			(stroke
				(width 0.508)
				(type default)
			)
			(layer "B.SilkS")
		)
		(fp_rect
			(start 0.9652 1.778)
			(end -0.9652 -1.778)
			(stroke
				(width 0)
				(type default)
			)
			(fill no)
			(layer "B.CrtYd")
		)
		(fp_poly
			(pts
				(xy 0.9652 -1.778) (xy -0.9652 -1.778) (xy -0.9652 1.778) (xy 0.9652 1.778)
			)
			(stroke
				(width 0)
				(type default)
			)
			(fill no)
			(layer "B.Fab")
		)
		(pad "1" smd rect
			(at 0 -0.9652)
			(size 1.397 1.143)
			(layers "B.Cu" "B.Mask" "B.Paste")
			(net "P5V_A_2")
		)
		(pad "2" smd rect
			(at 0 0.9652)
			(size 1.397 1.143)
			(layers "B.Cu" "B.Mask" "B.Paste")
			(net "GND")
		)
	)
	(footprint ""
		(layer "B.Cu")
		(at 32.274002 -254.43815 90)
		(property "Reference" "C665"
			(at 0 0 90)
			(layer "B.SilkS")
			(hide yes)
			(effects
				(font
					(size 1.27 1.27)
				)
				(justify mirror)
			)
		)
		(property "Value" "SC68P50V2JN-2-GP"
			(at -1.1811 -2.7051 90)
			(unlocked yes)
			(layer "B.Fab")
			(hide yes)
			(effects
				(font
					(size 1.016 1.016)
					(thickness 0.1524)
				)
				(justify mirror)
			)
		)
		(property "Device Type" "C402H22"
			(at -1.1811 -4.2291 90)
			(unlocked yes)
			(layer "B.Fab")
			(hide yes)
			(effects
				(font
					(size 1.016 1.016)
					(thickness 0.1524)
				)
				(justify mirror)
			)
		)
		(duplicate_pad_numbers_are_jumpers no)
		(fp_rect
			(start 0.4318 0.9525)
			(end -0.4318 -0.9525)
			(stroke
				(width 0)
				(type default)
			)
			(fill no)
			(layer "B.CrtYd")
		)
		(fp_rect
			(start 0.4318 0.9525)
			(end -0.4318 -0.9525)
			(stroke
				(width 0)
				(type default)
			)
			(fill no)
			(layer "B.Fab")
		)
		(pad "1" smd custom
			(at 0 -0.4445 270)
			(size 0.1524 0.1524)
			(layers "B.Cu" "B.Mask" "B.Paste")
			(net "P5V_A_VFB")
			(options
				(clearance outline)
				(anchor circle)
			)
			(primitives
				(gr_poly
					(pts
						(arc
							(start 0.3048 0.2032)
							(mid 0.275042 0.275042)
							(end 0.2032 0.3048)
						)
						(arc
							(start -0.2032 0.3048)
							(mid -0.275042 0.275042)
							(end -0.3048 0.2032)
						)
						(arc
							(start -0.3048 -0.2032)
							(mid -0.275042 -0.275042)
							(end -0.2032 -0.3048)
						)
						(arc
							(start 0.2032 -0.3048)
							(mid 0.275042 -0.275042)
							(end 0.3048 -0.2032)
						)
					)
					(width 0)
					(fill yes)
				)
			)
		)
		(pad "2" smd custom
			(at 0 0.4445 270)
			(size 0.1524 0.1524)
			(layers "B.Cu" "B.Mask" "B.Paste")
			(net "P5V_A_VFB_R")
			(options
				(clearance outline)
				(anchor circle)
			)
			(primitives
				(gr_poly
					(pts
						(arc
							(start 0.3048 0.2032)
							(mid 0.275042 0.275042)
							(end 0.2032 0.3048)
						)
						(arc
							(start -0.2032 0.3048)
							(mid -0.275042 0.275042)
							(end -0.3048 0.2032)
						)
						(arc
							(start -0.3048 -0.2032)
							(mid -0.275042 -0.275042)
							(end -0.2032 -0.3048)
						)
						(arc
							(start 0.2032 -0.3048)
							(mid 0.275042 -0.275042)
							(end 0.3048 -0.2032)
						)
					)
					(width 0)
					(fill yes)
				)
			)
		)
	)
	(footprint ""
		(layer "B.Cu")
		(at 218.821 -119.761 -90)
		(property "Reference" "U49"
			(at 0 0 90)
			(layer "B.SilkS")
			(hide yes)
			(effects
				(font
					(size 1.27 1.27)
				)
				(justify mirror)
			)
		)
		(property "Value" "TXS0102QDCURQ1-GP"
			(at 0 -11.1252 270)
			(unlocked yes)
			(layer "B.Fab")
			(hide yes)
			(effects
				(font
					(size 1.016 1.016)
					(thickness 0.1524)
				)
				(justify mirror)
			)
		)
		(property "Device Type" "SSOIC8-4H36"
			(at 0 -12.6492 270)
			(unlocked yes)
			(layer "B.Fab")
			(hide yes)
			(effects
				(font
					(size 1.016 1.016)
					(thickness 0.1524)
				)
				(justify mirror)
			)
		)
		(duplicate_pad_numbers_are_jumpers no)
		(fp_line
			(start -1.2573 2.1844)
			(end 1.2573 2.1844)
			(stroke
				(width 0.1524)
				(type default)
			)
			(layer "B.SilkS")
		)
		(fp_line
			(start 1.2573 2.1844)
			(end 1.2573 -2.1844)
			(stroke
				(width 0.1524)
				(type default)
			)
			(layer "B.SilkS")
		)
		(fp_line
			(start 1.2954 0.4572)
			(end 1.2954 2.159)
			(stroke
				(width 0.4064)
				(type default)
			)
			(layer "B.SilkS")
		)
		(fp_line
			(start 1.2065 0.2667)
			(end 1.27 0.2667)
			(stroke
				(width 0.1524)
				(type default)
			)
			(layer "B.SilkS")
		)
		(fp_line
			(start 0.9017 -0.0381)
			(end 1.2065 0.2667)
			(stroke
				(width 0.1524)
				(type default)
			)
			(layer "B.SilkS")
		)
		(fp_line
			(start 1.2192 -0.3556)
			(end 0.9017 -0.0381)
			(stroke
				(width 0.1524)
				(type default)
			)
			(layer "B.SilkS")
		)
		(fp_line
			(start 1.2573 -0.3556)
			(end 1.2192 -0.3556)
			(stroke
				(width 0.1524)
				(type default)
			)
			(layer "B.SilkS")
		)
		(fp_line
			(start -1.2573 -2.1844)
			(end -1.2573 2.1844)
			(stroke
				(width 0.1524)
				(type default)
			)
			(layer "B.SilkS")
		)
		(fp_line
			(start 1.2573 -2.1844)
			(end -1.2573 -2.1844)
			(stroke
				(width 0.1524)
				(type default)
			)
			(layer "B.SilkS")
		)
		(fp_poly
			(pts
				(xy 1.5113 2.4384) (xy -1.5113 2.4384) (xy -1.5113 -2.4384) (xy 1.5113 -2.4384)
			)
			(stroke
				(width 0)
				(type default)
			)
			(fill no)
			(layer "B.CrtYd")
		)
		(fp_poly
			(pts
				(xy 1.5113 -2.4384) (xy -1.5113 -2.4384) (xy -1.5113 2.4384) (xy 1.5113 2.4384)
			)
			(stroke
				(width 0)
				(type default)
			)
			(fill no)
			(layer "B.Fab")
		)
		(pad "1" smd rect
			(at 0.75057 1.1684 90)
			(size 0.3048 1.524)
			(layers "B.Cu" "B.Mask" "B.Paste")
			(net "I2C_BMC_A_COMP_A_SDA")
		)
		(pad "2" smd rect
			(at 0.25019 1.1684 90)
			(size 0.3048 1.524)
			(layers "B.Cu" "B.Mask" "B.Paste")
			(net "GND")
		)
		(pad "3" smd rect
			(at -0.25019 1.1684 90)
			(size 0.3048 1.524)
			(layers "B.Cu" "B.Mask" "B.Paste")
			(net "P3V3_STBY_A")
		)
		(pad "4" smd rect
			(at -0.75057 1.1684 90)
			(size 0.3048 1.524)
			(layers "B.Cu" "B.Mask" "B.Paste")
			(net "I2C_BMC_A_COMP_A_SDA_BUF")
		)
		(pad "5" smd rect
			(at -0.75057 -1.1684 90)
			(size 0.3048 1.524)
			(layers "B.Cu" "B.Mask" "B.Paste")
			(net "I2C_BMC_A_COMP_A_SCL_BUF")
		)
		(pad "6" smd rect
			(at -0.25019 -1.1684 90)
			(size 0.3048 1.524)
			(layers "B.Cu" "B.Mask" "B.Paste")
			(net "TXS0102_A_OE")
		)
		(pad "7" smd rect
			(at 0.25019 -1.1684 90)
			(size 0.3048 1.524)
			(layers "B.Cu" "B.Mask" "B.Paste")
			(net "P3V3_STBY_A")
		)
		(pad "8" smd rect
			(at 0.75057 -1.1684 90)
			(size 0.3048 1.524)
			(layers "B.Cu" "B.Mask" "B.Paste")
			(net "I2C_BMC_A_COMP_A_SCL")
		)
	)
	(footprint ""
		(layer "B.Cu")
		(at 182.39994 -208.499964 180)
		(property "Reference" "NUT7"
			(at 0 0 0)
			(layer "B.SilkS")
			(hide yes)
			(effects
				(font
					(size 1.27 1.27)
				)
				(justify mirror)
			)
		)
		(property "Value" "STF256R168H278-GP"
			(at 4.826 0.0508 180)
			(unlocked yes)
			(layer "B.Fab")
			(hide yes)
			(effects
				(font
					(size 1.016 1.016)
					(thickness 0.1524)
				)
				(justify mirror)
			)
		)
		(property "Device Type" "STF256R168H278"
			(at 4.826 -1.4732 180)
			(unlocked yes)
			(layer "B.Fab")
			(hide yes)
			(effects
				(font
					(size 1.016 1.016)
					(thickness 0.1524)
				)
				(justify mirror)
			)
		)
		(duplicate_pad_numbers_are_jumpers no)
		(fp_circle
			(center 0 0)
			(end -3.6068 0)
			(stroke
				(width 0.3048)
				(type default)
			)
			(fill no)
			(layer "B.SilkS")
		)
		(fp_poly
			(pts
				(arc
					(start -2.5019 0)
					(mid 2.5019 0)
					(end -2.5019 0)
				)
			)
			(stroke
				(width 0)
				(type default)
			)
			(fill no)
			(layer "B.CrtYd")
		)
		(fp_poly
			(pts
				(arc
					(start -3.7592 0.00635)
					(mid 3.759205 0)
					(end -3.7592 -0.00635)
				)
				(arc
					(start -2.5019 -0.00635)
					(mid 2.501908 0)
					(end -2.5019 0.00635)
				)
			)
			(stroke
				(width 0)
				(type default)
			)
			(fill no)
			(layer "B.CrtYd")
		)
		(fp_poly
			(pts
				(arc
					(start -3.7592 0)
					(mid 3.7592 0)
					(end -3.7592 0)
				)
			)
			(stroke
				(width 0)
				(type default)
			)
			(fill no)
			(layer "F.CrtYd")
		)
		(fp_poly
			(pts
				(arc
					(start -3.7592 0)
					(mid 3.7592 0)
					(end -3.7592 0)
				)
			)
			(stroke
				(width 0)
				(type default)
			)
			(fill no)
			(layer "B.Fab")
		)
		(fp_poly
			(pts
				(arc
					(start -3.7592 0)
					(mid 3.7592 0)
					(end -3.7592 0)
				)
			)
			(stroke
				(width 0)
				(type default)
			)
			(fill no)
			(layer "F.Fab")
		)
		(pad "1" thru_hole circle
			(at 0 0)
			(size 6.5024 6.5024)
			(drill 4.2672)
			(layers "*.Cu" "*.Mask")
			(remove_unused_layers no)
			(net "Net_5")
			(clearance -0.6096)
			(padstack
				(mode front_inner_back)
				(layer "Inner"
					(shape circle)
					(size 4.6736 4.6736)
					(clearance 0.3048)
				)
				(layer "B.Cu"
					(shape circle)
					(size 6.5024 6.5024)
					(thermal_gap 0.3048)
					(clearance -0.6096)
				)
			)
		)
	)
	(footprint ""
		(layer "B.Cu")
		(at 16.119602 -250.01855 180)
		(property "Reference" "R1206"
			(at 0 0 0)
			(layer "B.SilkS")
			(hide yes)
			(effects
				(font
					(size 1.27 1.27)
				)
				(justify mirror)
			)
		)
		(property "Value" "2D2R3-1-U-GP"
			(at 0.0254 -2.5146 180)
			(unlocked yes)
			(layer "B.Fab")
			(hide yes)
			(effects
				(font
					(size 1.016 1.016)
					(thickness 0.1524)
				)
				(justify mirror)
			)
		)
		(property "Device Type" "R603H22"
			(at 0.0254 -4.0386 180)
			(unlocked yes)
			(layer "B.Fab")
			(hide yes)
			(effects
				(font
					(size 1.016 1.016)
					(thickness 0.1524)
				)
				(justify mirror)
			)
		)
		(duplicate_pad_numbers_are_jumpers no)
		(fp_line
			(start 0.4826 0)
			(end 0.2032 0)
			(stroke
				(width 0.2032)
				(type default)
			)
			(layer "B.SilkS")
		)
		(fp_line
			(start -0.2032 0)
			(end -0.4826 0)
			(stroke
				(width 0.2032)
				(type default)
			)
			(layer "B.SilkS")
		)
		(fp_rect
			(start 0.5842 1.3335)
			(end -0.5842 -1.3335)
			(stroke
				(width 0)
				(type default)
			)
			(fill no)
			(layer "B.CrtYd")
		)
		(fp_rect
			(start 0.5842 1.3335)
			(end -0.5842 -1.3335)
			(stroke
				(width 0)
				(type default)
			)
			(fill no)
			(layer "B.Fab")
		)
		(pad "1" smd custom
			(at 0 -0.762)
			(size 0.2159 0.2159)
			(layers "B.Cu" "B.Mask" "B.Paste")
			(net "P12V_A")
			(options
				(clearance outline)
				(anchor circle)
			)
			(primitives
				(gr_poly
					(pts
						(arc
							(start -0.3302 0.4318)
							(mid -0.402042 0.402042)
							(end -0.4318 0.3302)
						)
						(arc
							(start -0.4318 -0.3302)
							(mid -0.402042 -0.402042)
							(end -0.3302 -0.4318)
						)
						(arc
							(start 0.3302 -0.4318)
							(mid 0.402042 -0.402042)
							(end 0.4318 -0.3302)
						)
						(arc
							(start 0.4318 0.3302)
							(mid 0.402042 0.402042)
							(end 0.3302 0.4318)
						)
					)
					(width 0)
					(fill yes)
				)
			)
		)
		(pad "2" smd custom
			(at 0 0.762)
			(size 0.2159 0.2159)
			(layers "B.Cu" "B.Mask" "B.Paste")
			(net "P12V_A_VDD_U20")
			(options
				(clearance outline)
				(anchor circle)
			)
			(primitives
				(gr_poly
					(pts
						(arc
							(start -0.3302 0.4318)
							(mid -0.402042 0.402042)
							(end -0.4318 0.3302)
						)
						(arc
							(start -0.4318 -0.3302)
							(mid -0.402042 -0.402042)
							(end -0.3302 -0.4318)
						)
						(arc
							(start 0.3302 -0.4318)
							(mid 0.402042 -0.402042)
							(end 0.4318 -0.3302)
						)
						(arc
							(start 0.4318 0.3302)
							(mid 0.402042 0.402042)
							(end 0.3302 0.4318)
						)
					)
					(width 0)
					(fill yes)
				)
			)
		)
	)
	(footprint ""
		(layer "B.Cu")
		(at 472.027504 -203.399898)
		(property "Reference" "PG16"
			(at 0 0 0)
			(layer "B.SilkS")
			(hide yes)
			(effects
				(font
					(size 1.27 1.27)
				)
				(justify mirror)
			)
		)
		(property "Value" "GAP-CLOSE-PWR-4-GP"
			(at 2.4638 -0.5461 0)
			(unlocked yes)
			(layer "B.Fab")
			(hide yes)
			(effects
				(font
					(size 1.016 1.016)
					(thickness 0.1524)
				)
				(justify mirror)
			)
		)
		(property "Device Type" "GAP-CLOSE-PWR-4"
			(at 2.4638 -2.0701 0)
			(unlocked yes)
			(layer "B.Fab")
			(hide yes)
			(effects
				(font
					(size 1.016 1.016)
					(thickness 0.1524)
				)
				(justify mirror)
			)
		)
		(duplicate_pad_numbers_are_jumpers no)
		(fp_rect
			(start 0.2794 0.254)
			(end -0.2794 -0.254)
			(stroke
				(width 0)
				(type default)
			)
			(fill no)
			(layer "B.CrtYd")
		)
		(fp_rect
			(start 0.2794 0.254)
			(end -0.2794 -0.254)
			(stroke
				(width 0)
				(type default)
			)
			(fill no)
			(layer "B.Fab")
		)
		(pad "1" smd rect
			(at 0.0635 0 180)
			(size 0.1778 0.254)
			(layers "B.Cu" "B.Mask" "B.Paste")
			(net "P5V_A_4")
		)
		(pad "2" smd rect
			(at -0.0635 0 180)
			(size 0.1778 0.254)
			(layers "B.Cu" "B.Mask" "B.Paste")
			(net "P5V_D_CC")
		)
	)
	(footprint ""
		(layer "B.Cu")
		(at 183.151526 -219.93987 -90)
		(property "Reference" "G1"
			(at 0 0 90)
			(layer "B.SilkS")
			(hide yes)
			(effects
				(font
					(size 1.27 1.27)
				)
				(justify mirror)
			)
		)
		(property "Value" "COPPER-CLOSE-GP-U"
			(at -0.0762 -2.8702 270)
			(unlocked yes)
			(layer "B.Fab")
			(hide yes)
			(effects
				(font
					(size 1.016 1.016)
					(thickness 0.1524)
				)
				(justify mirror)
			)
		)
		(property "Device Type" "CON2C-U"
			(at -0.0762 -4.3942 270)
			(unlocked yes)
			(layer "B.Fab")
			(hide yes)
			(effects
				(font
					(size 1.016 1.016)
					(thickness 0.1524)
				)
				(justify mirror)
			)
		)
		(duplicate_pad_numbers_are_jumpers no)
		(fp_rect
			(start 0.9398 0.9652)
			(end -0.9398 -0.9652)
			(stroke
				(width 0)
				(type default)
			)
			(fill no)
			(layer "B.CrtYd")
		)
		(fp_rect
			(start 0.9398 0.9652)
			(end -0.9398 -0.9652)
			(stroke
				(width 0)
				(type default)
			)
			(fill no)
			(layer "B.Fab")
		)
		(pad "1" smd custom
			(at 0 -0.5334 90)
			(size 0.17145 0.17145)
			(layers "B.Cu" "B.Mask" "B.Paste")
			(net "AGND_P3V3_STBY")
			(options
				(clearance outline)
				(anchor circle)
			)
			(primitives
				(gr_poly
					(pts
						(xy -0.127 -0.3429) (xy -0.127 -0.1651) (xy -0.635 0.3429) (xy 0.635 0.3429) (xy 0.127 -0.1651)
						(xy 0.127 -0.3429)
					)
					(width 0)
					(fill yes)
				)
			)
		)
		(pad "2" smd custom
			(at 0 0.5334 90)
			(size 0.17145 0.17145)
			(layers "B.Cu" "B.Mask" "B.Paste")
			(net "GND")
			(options
				(clearance outline)
				(anchor circle)
			)
			(primitives
				(gr_poly
					(pts
						(xy -0.635 -0.3429) (xy -0.127 0.1651) (xy -0.127 0.3429) (xy 0.127 0.3429) (xy 0.127 0.1651)
						(xy 0.635 -0.3429)
					)
					(width 0)
					(fill yes)
				)
			)
		)
	)
	(footprint ""
		(layer "B.Cu")
		(at 127.824992 -210.799934 180)
		(property "Reference" "SCW1"
			(at 0 0 0)
			(layer "B.SilkS")
			(hide yes)
			(effects
				(font
					(size 1.27 1.27)
				)
				(justify mirror)
			)
		)
		(property "Value" ""
			(at 0 0 0)
			(layer "B.Fab")
			(effects
				(font
					(size 1.27 1.27)
				)
				(justify mirror)
			)
		)
		(duplicate_pad_numbers_are_jumpers no)
		(fp_poly
			(pts
				(arc
					(start -5.4356 0)
					(mid 5.4356 0)
					(end -5.4356 0)
				)
			)
			(stroke
				(width 0)
				(type default)
			)
			(fill no)
			(layer "B.CrtYd")
		)
		(fp_poly
			(pts
				(arc
					(start -5.4356 0)
					(mid 5.4356 0)
					(end -5.4356 0)
				)
			)
			(stroke
				(width 0)
				(type default)
			)
			(fill no)
			(layer "F.CrtYd")
		)
		(fp_poly
			(pts
				(arc
					(start -5.4356 0)
					(mid 5.4356 0)
					(end -5.4356 0)
				)
			)
			(stroke
				(width 0)
				(type default)
			)
			(fill no)
			(layer "B.Fab")
		)
		(fp_poly
			(pts
				(arc
					(start -5.4356 0)
					(mid 5.4356 0)
					(end -5.4356 0)
				)
			)
			(stroke
				(width 0)
				(type default)
			)
			(fill no)
			(layer "F.Fab")
		)
		(pad "" np_thru_hole circle
			(at 0 0)
			(size 0.254 0.254)
			(drill 10.2616)
			(layers "*.Cu" "*.Mask")
			(clearance 5.3594)
			(thermal_gap 5.3594)
		)
		(zone
			(layers "F.Cu" "B.Cu" "In1.Cu" "In2.Cu" "In3.Cu" "In4.Cu" "In5.Cu" "In6.Cu"
				"In7.Cu" "In8.Cu" "In9.Cu" "In10.Cu"
			)
			(hatch none 0.5)
			(connect_pads
				(clearance 0)
			)
			(min_thickness 0.25)
			(keepout
				(tracks not_allowed)
				(vias allowed)
				(pads allowed)
				(copperpour not_allowed)
				(footprints allowed)
			)
			(placement
				(enabled no)
				(sheetname "")
			)
			(fill
				(thermal_gap 0.5)
				(thermal_bridge_width 0.5)
				(island_removal_mode 0)
			)
			(polygon
				(pts
					(arc
						(start 133.260592 -210.799934)
						(mid 122.389392 -210.799934)
						(end 133.260592 -210.799934)
					)
				)
			)
		)
	)
	(footprint ""
		(layer "B.Cu")
		(at 40.714422 -144.57553 90)
		(property "Reference" "C625"
			(at 0 0 90)
			(layer "B.SilkS")
			(hide yes)
			(effects
				(font
					(size 1.27 1.27)
				)
				(justify mirror)
			)
		)
		(property "Value" "SC1U16V3KX-5GP"
			(at 0 -2.8194 90)
			(unlocked yes)
			(layer "B.Fab")
			(hide yes)
			(effects
				(font
					(size 1.016 1.016)
					(thickness 0.1524)
				)
				(justify mirror)
			)
		)
		(property "Device Type" "C603H36"
			(at 0 -4.3434 90)
			(unlocked yes)
			(layer "B.Fab")
			(hide yes)
			(effects
				(font
					(size 1.016 1.016)
					(thickness 0.1524)
				)
				(justify mirror)
			)
		)
		(duplicate_pad_numbers_are_jumpers no)
		(fp_line
			(start -0.508 0)
			(end 0.508 0)
			(stroke
				(width 0.2032)
				(type default)
			)
			(layer "B.SilkS")
		)
		(fp_rect
			(start 0.5842 1.3335)
			(end -0.5842 -1.3335)
			(stroke
				(width 0)
				(type default)
			)
			(fill no)
			(layer "B.CrtYd")
		)
		(fp_rect
			(start 0.5842 1.3335)
			(end -0.5842 -1.3335)
			(stroke
				(width 0)
				(type default)
			)
			(fill no)
			(layer "B.Fab")
		)
		(pad "1" smd custom
			(at 0 -0.762 270)
			(size 0.2159 0.2159)
			(layers "B.Cu" "B.Mask" "B.Paste")
			(net "GND")
			(options
				(clearance outline)
				(anchor circle)
			)
			(primitives
				(gr_poly
					(pts
						(arc
							(start -0.3302 0.4318)
							(mid -0.402042 0.402042)
							(end -0.4318 0.3302)
						)
						(arc
							(start -0.4318 -0.3302)
							(mid -0.402042 -0.402042)
							(end -0.3302 -0.4318)
						)
						(arc
							(start 0.3302 -0.4318)
							(mid 0.402042 -0.402042)
							(end 0.4318 -0.3302)
						)
						(arc
							(start 0.4318 0.3302)
							(mid 0.402042 0.402042)
							(end 0.3302 0.4318)
						)
					)
					(width 0)
					(fill yes)
				)
			)
		)
		(pad "2" smd custom
			(at 0 0.762 270)
			(size 0.2159 0.2159)
			(layers "B.Cu" "B.Mask" "B.Paste")
			(net "P5V_B_VREG")
			(options
				(clearance outline)
				(anchor circle)
			)
			(primitives
				(gr_poly
					(pts
						(arc
							(start -0.3302 0.4318)
							(mid -0.402042 0.402042)
							(end -0.4318 0.3302)
						)
						(arc
							(start -0.4318 -0.3302)
							(mid -0.402042 -0.402042)
							(end -0.3302 -0.4318)
						)
						(arc
							(start 0.3302 -0.4318)
							(mid 0.402042 -0.402042)
							(end 0.4318 -0.3302)
						)
						(arc
							(start 0.4318 0.3302)
							(mid 0.402042 0.402042)
							(end 0.3302 0.4318)
						)
					)
					(width 0)
					(fill yes)
				)
			)
		)
	)
	(footprint ""
		(layer "B.Cu")
		(at 190.292482 -233.753406 90)
		(property "Reference" "C678"
			(at 0 0 90)
			(layer "B.SilkS")
			(hide yes)
			(effects
				(font
					(size 1.27 1.27)
				)
				(justify mirror)
			)
		)
		(property "Value" "SCD1U25V3KX-GP"
			(at 0 -2.8194 90)
			(unlocked yes)
			(layer "B.Fab")
			(hide yes)
			(effects
				(font
					(size 1.016 1.016)
					(thickness 0.1524)
				)
				(justify mirror)
			)
		)
		(property "Device Type" "C603H36"
			(at 0 -4.3434 90)
			(unlocked yes)
			(layer "B.Fab")
			(hide yes)
			(effects
				(font
					(size 1.016 1.016)
					(thickness 0.1524)
				)
				(justify mirror)
			)
		)
		(duplicate_pad_numbers_are_jumpers no)
		(fp_line
			(start -0.508 0)
			(end 0.508 0)
			(stroke
				(width 0.2032)
				(type default)
			)
			(layer "B.SilkS")
		)
		(fp_rect
			(start 0.5842 1.3335)
			(end -0.5842 -1.3335)
			(stroke
				(width 0)
				(type default)
			)
			(fill no)
			(layer "B.CrtYd")
		)
		(fp_rect
			(start 0.5842 1.3335)
			(end -0.5842 -1.3335)
			(stroke
				(width 0)
				(type default)
			)
			(fill no)
			(layer "B.Fab")
		)
		(pad "1" smd custom
			(at 0 -0.762 270)
			(size 0.2159 0.2159)
			(layers "B.Cu" "B.Mask" "B.Paste")
			(net "P3V3_STBY_A")
			(options
				(clearance outline)
				(anchor circle)
			)
			(primitives
				(gr_poly
					(pts
						(arc
							(start -0.3302 0.4318)
							(mid -0.402042 0.402042)
							(end -0.4318 0.3302)
						)
						(arc
							(start -0.4318 -0.3302)
							(mid -0.402042 -0.402042)
							(end -0.3302 -0.4318)
						)
						(arc
							(start 0.3302 -0.4318)
							(mid 0.402042 -0.402042)
							(end 0.4318 -0.3302)
						)
						(arc
							(start 0.4318 0.3302)
							(mid 0.402042 0.402042)
							(end 0.3302 0.4318)
						)
					)
					(width 0)
					(fill yes)
				)
			)
		)
		(pad "2" smd custom
			(at 0 0.762 270)
			(size 0.2159 0.2159)
			(layers "B.Cu" "B.Mask" "B.Paste")
			(net "P3V3_STBY_VFB_R")
			(options
				(clearance outline)
				(anchor circle)
			)
			(primitives
				(gr_poly
					(pts
						(arc
							(start -0.3302 0.4318)
							(mid -0.402042 0.402042)
							(end -0.4318 0.3302)
						)
						(arc
							(start -0.4318 -0.3302)
							(mid -0.402042 -0.402042)
							(end -0.3302 -0.4318)
						)
						(arc
							(start 0.3302 -0.4318)
							(mid 0.402042 -0.402042)
							(end 0.4318 -0.3302)
						)
						(arc
							(start 0.4318 0.3302)
							(mid 0.402042 0.402042)
							(end 0.3302 0.4318)
						)
					)
					(width 0)
					(fill yes)
				)
			)
		)
	)
	(footprint ""
		(layer "B.Cu")
		(at 482.219 -237.109 -90)
		(property "Reference" "R1272"
			(at 0 0 90)
			(layer "B.SilkS")
			(hide yes)
			(effects
				(font
					(size 1.27 1.27)
				)
				(justify mirror)
			)
		)
		(property "Value" "100KR2F-L1-GP"
			(at -0.064008 -3.993896 270)
			(unlocked yes)
			(layer "B.Fab")
			(hide yes)
			(effects
				(font
					(size 1.016 1.016)
					(thickness 0.1524)
				)
				(justify mirror)
			)
		)
		(property "Device Type" "R402H16"
			(at -0.064008 -5.517896 270)
			(unlocked yes)
			(layer "B.Fab")
			(hide yes)
			(effects
				(font
					(size 1.016 1.016)
					(thickness 0.1524)
				)
				(justify mirror)
			)
		)
		(duplicate_pad_numbers_are_jumpers no)
		(fp_line
			(start -0.508 -0.9398)
			(end 0.508 -0.9398)
			(stroke
				(width 0.1524)
				(type default)
			)
			(layer "B.SilkS")
		)
		(fp_line
			(start 0.508 -0.9398)
			(end 0.508 0.9398)
			(stroke
				(width 0.1524)
				(type default)
			)
			(layer "B.SilkS")
		)
		(fp_rect
			(start 0.508 0.9398)
			(end -0.508 -0.9398)
			(stroke
				(width 0)
				(type default)
			)
			(fill no)
			(layer "B.CrtYd")
		)
		(fp_rect
			(start 0.508 0.9398)
			(end -0.508 -0.9398)
			(stroke
				(width 0)
				(type default)
			)
			(fill no)
			(layer "B.Fab")
		)
		(pad "1" smd custom
			(at 0 -0.4445 90)
			(size 0.1397 0.1397)
			(layers "B.Cu" "B.Mask" "B.Paste")
			(net "AGND_P5V_D")
			(options
				(clearance outline)
				(anchor circle)
			)
			(primitives
				(gr_poly
					(pts
						(arc
							(start -0.1778 0.2794)
							(mid -0.249642 0.249642)
							(end -0.2794 0.1778)
						)
						(arc
							(start -0.2794 -0.1778)
							(mid -0.249642 -0.249642)
							(end -0.1778 -0.2794)
						)
						(arc
							(start 0.1778 -0.2794)
							(mid 0.249642 -0.249642)
							(end 0.2794 -0.1778)
						)
						(arc
							(start 0.2794 0.1778)
							(mid 0.249642 0.249642)
							(end 0.1778 0.2794)
						)
					)
					(width 0)
					(fill yes)
				)
			)
		)
		(pad "2" smd custom
			(at 0 0.4445 90)
			(size 0.1397 0.1397)
			(layers "B.Cu" "B.Mask" "B.Paste")
			(net "P5V_D_MODE")
			(options
				(clearance outline)
				(anchor circle)
			)
			(primitives
				(gr_poly
					(pts
						(arc
							(start -0.1778 0.2794)
							(mid -0.249642 0.249642)
							(end -0.2794 0.1778)
						)
						(arc
							(start -0.2794 -0.1778)
							(mid -0.249642 -0.249642)
							(end -0.1778 -0.2794)
						)
						(arc
							(start 0.1778 -0.2794)
							(mid 0.249642 -0.249642)
							(end 0.2794 -0.1778)
						)
						(arc
							(start 0.2794 0.1778)
							(mid 0.249642 0.249642)
							(end 0.1778 0.2794)
						)
					)
					(width 0)
					(fill yes)
				)
			)
		)
	)
	(footprint ""
		(layer "B.Cu")
		(at 30.414214 -253.343664 180)
		(property "Reference" "R1221"
			(at 0 0 0)
			(layer "B.SilkS")
			(hide yes)
			(effects
				(font
					(size 1.27 1.27)
				)
				(justify mirror)
			)
		)
		(property "Value" "10KR2F-2-GP"
			(at -0.064008 -3.993896 180)
			(unlocked yes)
			(layer "B.Fab")
			(hide yes)
			(effects
				(font
					(size 1.016 1.016)
					(thickness 0.1524)
				)
				(justify mirror)
			)
		)
		(property "Device Type" "R402H16"
			(at -0.064008 -5.517896 180)
			(unlocked yes)
			(layer "B.Fab")
			(hide yes)
			(effects
				(font
					(size 1.016 1.016)
					(thickness 0.1524)
				)
				(justify mirror)
			)
		)
		(duplicate_pad_numbers_are_jumpers no)
		(fp_line
			(start 0.508 -0.9398)
			(end 0.508 0.9398)
			(stroke
				(width 0.1524)
				(type default)
			)
			(layer "B.SilkS")
		)
		(fp_line
			(start -0.508 -0.9398)
			(end 0.508 -0.9398)
			(stroke
				(width 0.1524)
				(type default)
			)
			(layer "B.SilkS")
		)
		(fp_rect
			(start 0.508 0.9398)
			(end -0.508 -0.9398)
			(stroke
				(width 0)
				(type default)
			)
			(fill no)
			(layer "B.CrtYd")
		)
		(fp_rect
			(start 0.508 0.9398)
			(end -0.508 -0.9398)
			(stroke
				(width 0)
				(type default)
			)
			(fill no)
			(layer "B.Fab")
		)
		(pad "1" smd custom
			(at 0 -0.4445)
			(size 0.1397 0.1397)
			(layers "B.Cu" "B.Mask" "B.Paste")
			(net "P5V_A_VFB")
			(options
				(clearance outline)
				(anchor circle)
			)
			(primitives
				(gr_poly
					(pts
						(arc
							(start -0.1778 0.2794)
							(mid -0.249642 0.249642)
							(end -0.2794 0.1778)
						)
						(arc
							(start -0.2794 -0.1778)
							(mid -0.249642 -0.249642)
							(end -0.1778 -0.2794)
						)
						(arc
							(start 0.1778 -0.2794)
							(mid 0.249642 -0.249642)
							(end 0.2794 -0.1778)
						)
						(arc
							(start 0.2794 0.1778)
							(mid 0.249642 0.249642)
							(end 0.1778 0.2794)
						)
					)
					(width 0)
					(fill yes)
				)
			)
		)
		(pad "2" smd custom
			(at 0 0.4445)
			(size 0.1397 0.1397)
			(layers "B.Cu" "B.Mask" "B.Paste")
			(net "AGND_P5V_A")
			(options
				(clearance outline)
				(anchor circle)
			)
			(primitives
				(gr_poly
					(pts
						(arc
							(start -0.1778 0.2794)
							(mid -0.249642 0.249642)
							(end -0.2794 0.1778)
						)
						(arc
							(start -0.2794 -0.1778)
							(mid -0.249642 -0.249642)
							(end -0.1778 -0.2794)
						)
						(arc
							(start 0.1778 -0.2794)
							(mid 0.249642 -0.249642)
							(end 0.2794 -0.1778)
						)
						(arc
							(start 0.2794 0.1778)
							(mid 0.249642 0.249642)
							(end 0.1778 0.2794)
						)
					)
					(width 0)
					(fill yes)
				)
			)
		)
	)
	(footprint ""
		(layer "B.Cu")
		(at 56.804814 -148.245576 180)
		(property "Reference" "C624"
			(at 0 0 0)
			(layer "B.SilkS")
			(hide yes)
			(effects
				(font
					(size 1.27 1.27)
				)
				(justify mirror)
			)
		)
		(property "Value" "SCD1U50V3KX-GP"
			(at 0 -2.8194 180)
			(unlocked yes)
			(layer "B.Fab")
			(hide yes)
			(effects
				(font
					(size 1.016 1.016)
					(thickness 0.1524)
				)
				(justify mirror)
			)
		)
		(property "Device Type" "C603H36"
			(at 0 -4.3434 180)
			(unlocked yes)
			(layer "B.Fab")
			(hide yes)
			(effects
				(font
					(size 1.016 1.016)
					(thickness 0.1524)
				)
				(justify mirror)
			)
		)
		(duplicate_pad_numbers_are_jumpers no)
		(fp_line
			(start -0.508 0)
			(end 0.508 0)
			(stroke
				(width 0.2032)
				(type default)
			)
			(layer "B.SilkS")
		)
		(fp_rect
			(start 0.5842 1.3335)
			(end -0.5842 -1.3335)
			(stroke
				(width 0)
				(type default)
			)
			(fill no)
			(layer "B.CrtYd")
		)
		(fp_rect
			(start 0.5842 1.3335)
			(end -0.5842 -1.3335)
			(stroke
				(width 0)
				(type default)
			)
			(fill no)
			(layer "B.Fab")
		)
		(pad "1" smd custom
			(at 0 -0.762)
			(size 0.2159 0.2159)
			(layers "B.Cu" "B.Mask" "B.Paste")
			(net "P5V_A_2")
			(options
				(clearance outline)
				(anchor circle)
			)
			(primitives
				(gr_poly
					(pts
						(arc
							(start -0.3302 0.4318)
							(mid -0.402042 0.402042)
							(end -0.4318 0.3302)
						)
						(arc
							(start -0.4318 -0.3302)
							(mid -0.402042 -0.402042)
							(end -0.3302 -0.4318)
						)
						(arc
							(start 0.3302 -0.4318)
							(mid 0.402042 -0.402042)
							(end 0.4318 -0.3302)
						)
						(arc
							(start 0.4318 0.3302)
							(mid 0.402042 0.402042)
							(end 0.3302 0.4318)
						)
					)
					(width 0)
					(fill yes)
				)
			)
		)
		(pad "2" smd custom
			(at 0 0.762)
			(size 0.2159 0.2159)
			(layers "B.Cu" "B.Mask" "B.Paste")
			(net "P5V_B_LL_R")
			(options
				(clearance outline)
				(anchor circle)
			)
			(primitives
				(gr_poly
					(pts
						(arc
							(start -0.3302 0.4318)
							(mid -0.402042 0.402042)
							(end -0.4318 0.3302)
						)
						(arc
							(start -0.4318 -0.3302)
							(mid -0.402042 -0.402042)
							(end -0.3302 -0.4318)
						)
						(arc
							(start 0.3302 -0.4318)
							(mid 0.402042 -0.402042)
							(end 0.4318 -0.3302)
						)
						(arc
							(start 0.4318 0.3302)
							(mid 0.402042 0.402042)
							(end 0.3302 0.4318)
						)
					)
					(width 0)
					(fill yes)
				)
			)
		)
	)
	(footprint ""
		(layer "B.Cu")
		(at 482.219 -235.966 -90)
		(property "Reference" "R1275"
			(at 0 0 90)
			(layer "B.SilkS")
			(hide yes)
			(effects
				(font
					(size 1.27 1.27)
				)
				(justify mirror)
			)
		)
		(property "Value" "143KR2F-L-1-GP"
			(at -0.064008 -3.993896 270)
			(unlocked yes)
			(layer "B.Fab")
			(hide yes)
			(effects
				(font
					(size 1.016 1.016)
					(thickness 0.1524)
				)
				(justify mirror)
			)
		)
		(property "Device Type" "R402H16"
			(at -0.064008 -5.517896 270)
			(unlocked yes)
			(layer "B.Fab")
			(hide yes)
			(effects
				(font
					(size 1.016 1.016)
					(thickness 0.1524)
				)
				(justify mirror)
			)
		)
		(duplicate_pad_numbers_are_jumpers no)
		(fp_line
			(start -0.508 -0.9398)
			(end 0.508 -0.9398)
			(stroke
				(width 0.1524)
				(type default)
			)
			(layer "B.SilkS")
		)
		(fp_line
			(start 0.508 -0.9398)
			(end 0.508 0.9398)
			(stroke
				(width 0.1524)
				(type default)
			)
			(layer "B.SilkS")
		)
		(fp_rect
			(start 0.508 0.9398)
			(end -0.508 -0.9398)
			(stroke
				(width 0)
				(type default)
			)
			(fill no)
			(layer "B.CrtYd")
		)
		(fp_rect
			(start 0.508 0.9398)
			(end -0.508 -0.9398)
			(stroke
				(width 0)
				(type default)
			)
			(fill no)
			(layer "B.Fab")
		)
		(pad "1" smd custom
			(at 0 -0.4445 90)
			(size 0.1397 0.1397)
			(layers "B.Cu" "B.Mask" "B.Paste")
			(net "AGND_P5V_D")
			(options
				(clearance outline)
				(anchor circle)
			)
			(primitives
				(gr_poly
					(pts
						(arc
							(start -0.1778 0.2794)
							(mid -0.249642 0.249642)
							(end -0.2794 0.1778)
						)
						(arc
							(start -0.2794 -0.1778)
							(mid -0.249642 -0.249642)
							(end -0.1778 -0.2794)
						)
						(arc
							(start 0.1778 -0.2794)
							(mid 0.249642 -0.249642)
							(end 0.2794 -0.1778)
						)
						(arc
							(start 0.2794 0.1778)
							(mid 0.249642 0.249642)
							(end 0.1778 0.2794)
						)
					)
					(width 0)
					(fill yes)
				)
			)
		)
		(pad "2" smd custom
			(at 0 0.4445 90)
			(size 0.1397 0.1397)
			(layers "B.Cu" "B.Mask" "B.Paste")
			(net "P5V_D_TRIP")
			(options
				(clearance outline)
				(anchor circle)
			)
			(primitives
				(gr_poly
					(pts
						(arc
							(start -0.1778 0.2794)
							(mid -0.249642 0.249642)
							(end -0.2794 0.1778)
						)
						(arc
							(start -0.2794 -0.1778)
							(mid -0.249642 -0.249642)
							(end -0.1778 -0.2794)
						)
						(arc
							(start 0.1778 -0.2794)
							(mid 0.249642 -0.249642)
							(end 0.2794 -0.1778)
						)
						(arc
							(start 0.2794 0.1778)
							(mid 0.249642 0.249642)
							(end 0.1778 0.2794)
						)
					)
					(width 0)
					(fill yes)
				)
			)
		)
	)
	(footprint ""
		(layer "B.Cu")
		(at 178.786282 -232.077006 180)
		(property "Reference" "C677"
			(at 0 0 0)
			(layer "B.SilkS")
			(hide yes)
			(effects
				(font
					(size 1.27 1.27)
				)
				(justify mirror)
			)
		)
		(property "Value" "SC2200P50V2KX-2GP"
			(at -1.1811 -2.7051 180)
			(unlocked yes)
			(layer "B.Fab")
			(hide yes)
			(effects
				(font
					(size 1.016 1.016)
					(thickness 0.1524)
				)
				(justify mirror)
			)
		)
		(property "Device Type" "C402H22"
			(at -1.1811 -4.2291 180)
			(unlocked yes)
			(layer "B.Fab")
			(hide yes)
			(effects
				(font
					(size 1.016 1.016)
					(thickness 0.1524)
				)
				(justify mirror)
			)
		)
		(duplicate_pad_numbers_are_jumpers no)
		(fp_rect
			(start 0.4318 0.9525)
			(end -0.4318 -0.9525)
			(stroke
				(width 0)
				(type default)
			)
			(fill no)
			(layer "B.CrtYd")
		)
		(fp_rect
			(start 0.4318 0.9525)
			(end -0.4318 -0.9525)
			(stroke
				(width 0)
				(type default)
			)
			(fill no)
			(layer "B.Fab")
		)
		(pad "1" smd custom
			(at 0 -0.4445)
			(size 0.1524 0.1524)
			(layers "B.Cu" "B.Mask" "B.Paste")
			(net "P3V3_STBY_SW")
			(options
				(clearance outline)
				(anchor circle)
			)
			(primitives
				(gr_poly
					(pts
						(arc
							(start 0.3048 0.2032)
							(mid 0.275042 0.275042)
							(end 0.2032 0.3048)
						)
						(arc
							(start -0.2032 0.3048)
							(mid -0.275042 0.275042)
							(end -0.3048 0.2032)
						)
						(arc
							(start -0.3048 -0.2032)
							(mid -0.275042 -0.275042)
							(end -0.2032 -0.3048)
						)
						(arc
							(start 0.2032 -0.3048)
							(mid 0.275042 -0.275042)
							(end 0.3048 -0.2032)
						)
					)
					(width 0)
					(fill yes)
				)
			)
		)
		(pad "2" smd custom
			(at 0 0.4445)
			(size 0.1524 0.1524)
			(layers "B.Cu" "B.Mask" "B.Paste")
			(net "P3V3_STBY_SNB")
			(options
				(clearance outline)
				(anchor circle)
			)
			(primitives
				(gr_poly
					(pts
						(arc
							(start 0.3048 0.2032)
							(mid 0.275042 0.275042)
							(end 0.2032 0.3048)
						)
						(arc
							(start -0.2032 0.3048)
							(mid -0.275042 0.275042)
							(end -0.3048 0.2032)
						)
						(arc
							(start -0.3048 -0.2032)
							(mid -0.275042 -0.275042)
							(end -0.2032 -0.3048)
						)
						(arc
							(start 0.2032 -0.3048)
							(mid 0.275042 -0.275042)
							(end 0.3048 -0.2032)
						)
					)
					(width 0)
					(fill yes)
				)
			)
		)
	)
	(footprint ""
		(layer "B.Cu")
		(at 183.082692 -239.238028 180)
		(property "Reference" "C685"
			(at 0 0 0)
			(layer "B.SilkS")
			(hide yes)
			(effects
				(font
					(size 1.27 1.27)
				)
				(justify mirror)
			)
		)
		(property "Value" "SC10U6D3V5KX-4GP"
			(at 0.0762 -6.1214 180)
			(unlocked yes)
			(layer "B.Fab")
			(hide yes)
			(effects
				(font
					(size 1.016 1.016)
					(thickness 0.1524)
				)
				(justify mirror)
			)
		)
		(property "Device Type" "C805H58"
			(at 0.0762 -8.1534 180)
			(unlocked yes)
			(layer "B.Fab")
			(hide yes)
			(effects
				(font
					(size 1.016 1.016)
					(thickness 0.1524)
				)
				(justify mirror)
			)
		)
		(duplicate_pad_numbers_are_jumpers no)
		(fp_line
			(start -0.635 0)
			(end 0.635 0)
			(stroke
				(width 0.508)
				(type default)
			)
			(layer "B.SilkS")
		)
		(fp_rect
			(start 0.9652 1.778)
			(end -0.9652 -1.778)
			(stroke
				(width 0)
				(type default)
			)
			(fill no)
			(layer "B.CrtYd")
		)
		(fp_poly
			(pts
				(xy 0.9652 -1.778) (xy -0.9652 -1.778) (xy -0.9652 1.778) (xy 0.9652 1.778)
			)
			(stroke
				(width 0)
				(type default)
			)
			(fill no)
			(layer "B.Fab")
		)
		(pad "1" smd rect
			(at 0 -0.9652)
			(size 1.397 1.143)
			(layers "B.Cu" "B.Mask" "B.Paste")
			(net "P3V3_STBY_A")
		)
		(pad "2" smd rect
			(at 0 0.9652)
			(size 1.397 1.143)
			(layers "B.Cu" "B.Mask" "B.Paste")
			(net "GND")
		)
	)
	(footprint ""
		(layer "B.Cu")
		(at 220.175328 -100.6856 -90)
		(property "Reference" "C31"
			(at 0 0 90)
			(layer "B.SilkS")
			(hide yes)
			(effects
				(font
					(size 1.27 1.27)
				)
				(justify mirror)
			)
		)
		(property "Value" "SC2D2U25V5KX-2-GP"
			(at 0.0762 -6.1214 270)
			(unlocked yes)
			(layer "B.Fab")
			(hide yes)
			(effects
				(font
					(size 1.016 1.016)
					(thickness 0.1524)
				)
				(justify mirror)
			)
		)
		(property "Device Type" "C805H54"
			(at 0.0762 -8.1534 270)
			(unlocked yes)
			(layer "B.Fab")
			(hide yes)
			(effects
				(font
					(size 1.016 1.016)
					(thickness 0.1524)
				)
				(justify mirror)
			)
		)
		(duplicate_pad_numbers_are_jumpers no)
		(fp_line
			(start -0.635 0)
			(end 0.635 0)
			(stroke
				(width 0.508)
				(type default)
			)
			(layer "B.SilkS")
		)
		(fp_rect
			(start 0.9652 1.778)
			(end -0.9652 -1.778)
			(stroke
				(width 0)
				(type default)
			)
			(fill no)
			(layer "B.CrtYd")
		)
		(fp_poly
			(pts
				(xy 0.9652 -1.778) (xy -0.9652 -1.778) (xy -0.9652 1.778) (xy 0.9652 1.778)
			)
			(stroke
				(width 0)
				(type default)
			)
			(fill no)
			(layer "B.Fab")
		)
		(pad "1" smd rect
			(at 0 -0.9652 90)
			(size 1.397 1.143)
			(layers "B.Cu" "B.Mask" "B.Paste")
			(net "P12V_A_COMP")
		)
		(pad "2" smd rect
			(at 0 0.9652 90)
			(size 1.397 1.143)
			(layers "B.Cu" "B.Mask" "B.Paste")
			(net "GND")
		)
	)
	(footprint ""
		(layer "B.Cu")
		(at 465.6328 -254.0254 180)
		(property "Reference" "TC7"
			(at 0 0 0)
			(layer "B.SilkS")
			(hide yes)
			(effects
				(font
					(size 1.27 1.27)
				)
				(justify mirror)
			)
		)
		(property "Value" "ST220U10VDM-LGP"
			(at 0 -9.6012 180)
			(unlocked yes)
			(layer "B.Fab")
			(hide yes)
			(effects
				(font
					(size 1.016 1.016)
					(thickness 0.1524)
				)
				(justify mirror)
			)
		)
		(property "Device Type" "CT7343H119"
			(at 0 -11.1252 180)
			(unlocked yes)
			(layer "B.Fab")
			(hide yes)
			(effects
				(font
					(size 1.016 1.016)
					(thickness 0.1524)
				)
				(justify mirror)
			)
		)
		(duplicate_pad_numbers_are_jumpers no)
		(fp_line
			(start 2.286 4.8768)
			(end 2.286 2.032)
			(stroke
				(width 0.1524)
				(type default)
			)
			(layer "B.SilkS")
		)
		(fp_line
			(start 2.286 -4.8768)
			(end 2.286 -2.032)
			(stroke
				(width 0.1524)
				(type default)
			)
			(layer "B.SilkS")
		)
		(fp_line
			(start -2.1082 -4.699)
			(end 2.1082 -4.699)
			(stroke
				(width 0.508)
				(type default)
			)
			(layer "B.SilkS")
		)
		(fp_line
			(start -2.286 4.8768)
			(end 2.286 4.8768)
			(stroke
				(width 0.1524)
				(type default)
			)
			(layer "B.SilkS")
		)
		(fp_line
			(start -2.286 2.032)
			(end -2.286 4.8768)
			(stroke
				(width 0.1524)
				(type default)
			)
			(layer "B.SilkS")
		)
		(fp_line
			(start -2.286 -2.032)
			(end -2.286 -4.8768)
			(stroke
				(width 0.1524)
				(type default)
			)
			(layer "B.SilkS")
		)
		(fp_line
			(start -2.286 -4.8768)
			(end 2.286 -4.8768)
			(stroke
				(width 0.1524)
				(type default)
			)
			(layer "B.SilkS")
		)
		(fp_rect
			(start 2.1463 3.6449)
			(end -2.1463 -3.6449)
			(stroke
				(width 0)
				(type default)
			)
			(fill no)
			(layer "B.CrtYd")
		)
		(fp_poly
			(pts
				(xy 2.54 4.953) (xy 2.54 4.2926) (xy 3.81 4.2926) (xy 3.81 -4.2926) (xy 2.54 -4.2926) (xy 2.54 -4.953)
				(xy -2.54 -4.953) (xy -2.54 -4.2926) (xy -3.81 -4.2926) (xy -3.81 -1.6256) (xy -2.1463 -1.6256)
				(xy -2.1463 -3.6449) (xy 2.1463 -3.6449) (xy 2.1463 3.6449) (xy -2.1463 3.6449) (xy -2.1463 -1.6129)
				(xy -3.81 -1.6129) (xy -3.81 4.2926) (xy -2.54 4.2926) (xy -2.54 4.953)
			)
			(stroke
				(width 0)
				(type default)
			)
			(fill no)
			(layer "B.CrtYd")
		)
		(fp_rect
			(start 3.81 4.2926)
			(end 2.54 -4.2926)
			(stroke
				(width 0)
				(type default)
			)
			(fill no)
			(layer "B.Fab")
		)
		(fp_rect
			(start 2.54 4.953)
			(end -2.54 -4.953)
			(stroke
				(width 0)
				(type default)
			)
			(fill no)
			(layer "B.Fab")
		)
		(fp_rect
			(start -2.54 4.2926)
			(end -3.81 -4.2926)
			(stroke
				(width 0)
				(type default)
			)
			(fill no)
			(layer "B.Fab")
		)
		(pad "1" smd rect
			(at 0 -3.1496)
			(size 2.413 2.286)
			(layers "B.Cu" "B.Mask" "B.Paste")
			(net "P5V_A_3")
		)
		(pad "2" smd rect
			(at 0 3.1496)
			(size 2.413 2.286)
			(layers "B.Cu" "B.Mask" "B.Paste")
			(net "GND")
		)
		(zone
			(layer "B.Cu")
			(hatch none 0.5)
			(connect_pads
				(clearance 0)
			)
			(min_thickness 0.25)
			(keepout
				(tracks allowed)
				(vias not_allowed)
				(pads allowed)
				(copperpour not_allowed)
				(footprints allowed)
			)
			(placement
				(enabled no)
				(sheetname "")
			)
			(fill
				(thermal_gap 0.5)
				(thermal_bridge_width 0.5)
				(island_removal_mode 0)
			)
			(polygon
				(pts
					(xy 464.1215 -258.6228) (xy 467.1441 -258.6228) (xy 467.1441 -255.7272) (xy 467.1441 -255.397)
					(xy 464.1215 -255.397) (xy 464.1215 -255.7272)
				)
			)
		)
		(zone
			(layer "B.Cu")
			(hatch none 0.5)
			(connect_pads
				(clearance 0)
			)
			(min_thickness 0.25)
			(keepout
				(tracks allowed)
				(vias not_allowed)
				(pads allowed)
				(copperpour not_allowed)
				(footprints allowed)
			)
			(placement
				(enabled no)
				(sheetname "")
			)
			(fill
				(thermal_gap 0.5)
				(thermal_bridge_width 0.5)
				(island_removal_mode 0)
			)
			(polygon
				(pts
					(xy 467.1441 -252.3363) (xy 467.1441 -249.428) (xy 464.1215 -249.428) (xy 464.1215 -252.3236) (xy 464.1215 -252.6538)
					(xy 467.1441 -252.6538)
				)
			)
		)
	)
	(footprint ""
		(layer "B.Cu")
		(at 269.5702 -102.7938 -90)
		(property "Reference" "C520"
			(at 0 0 90)
			(layer "B.SilkS")
			(hide yes)
			(effects
				(font
					(size 1.27 1.27)
				)
				(justify mirror)
			)
		)
		(property "Value" "SC22U25V6KX-2-GP-U"
			(at 2.860802 -5.279644 270)
			(unlocked yes)
			(layer "B.Fab")
			(hide yes)
			(effects
				(font
					(size 1.016 1.016)
					(thickness 0.1524)
				)
				(justify mirror)
			)
		)
		(property "Device Type" "C1206-TO0D3H75"
			(at 2.860802 -6.803644 270)
			(unlocked yes)
			(layer "B.Fab")
			(hide yes)
			(effects
				(font
					(size 1.016 1.016)
					(thickness 0.1524)
				)
				(justify mirror)
			)
		)
		(duplicate_pad_numbers_are_jumpers no)
		(fp_line
			(start -1.3081 2.3749)
			(end 1.3081 2.3749)
			(stroke
				(width 0.1524)
				(type default)
			)
			(layer "B.SilkS")
		)
		(fp_line
			(start 1.3081 2.3749)
			(end 1.3081 -2.3749)
			(stroke
				(width 0.1524)
				(type default)
			)
			(layer "B.SilkS")
		)
		(fp_line
			(start -1.3081 -2.3749)
			(end -1.3081 2.3749)
			(stroke
				(width 0.1524)
				(type default)
			)
			(layer "B.SilkS")
		)
		(fp_line
			(start 1.3081 -2.3749)
			(end -1.3081 -2.3749)
			(stroke
				(width 0.1524)
				(type default)
			)
			(layer "B.SilkS")
		)
		(fp_rect
			(start 0.8001 1.6002)
			(end -0.8001 -1.6002)
			(stroke
				(width 0)
				(type default)
			)
			(fill no)
			(layer "B.CrtYd")
		)
		(fp_poly
			(pts
				(xy 1.5621 2.4511) (xy 1.5621 1.6002) (xy -0.8001 1.6002) (xy -0.8001 -1.6002) (xy 0.8001 -1.6002)
				(xy 0.8001 1.5875) (xy 1.5621 1.5875) (xy 1.5621 -2.4511) (xy -1.5621 -2.4511) (xy -1.5621 2.4511)
			)
			(stroke
				(width 0)
				(type default)
			)
			(fill no)
			(layer "B.CrtYd")
		)
		(fp_rect
			(start 1.5621 2.4511)
			(end -1.5621 -2.4511)
			(stroke
				(width 0)
				(type default)
			)
			(fill no)
			(layer "B.Fab")
		)
		(pad "1" smd rect
			(at 0 -1.392936 90)
			(size 2.1082 1.4478)
			(layers "B.Cu" "B.Mask" "B.Paste")
			(net "P12V_B_COMP")
		)
		(pad "2" smd rect
			(at 0 1.392936 90)
			(size 2.1082 1.4478)
			(layers "B.Cu" "B.Mask" "B.Paste")
			(net "GND")
		)
	)
	(footprint ""
		(layer "B.Cu")
		(at 54.1528 -252.1966 180)
		(property "Reference" "C612"
			(at 0 0 0)
			(layer "B.SilkS")
			(hide yes)
			(effects
				(font
					(size 1.27 1.27)
				)
				(justify mirror)
			)
		)
		(property "Value" "SC10U16V5KX-7-GP-U"
			(at 0.0762 -6.1214 180)
			(unlocked yes)
			(layer "B.Fab")
			(hide yes)
			(effects
				(font
					(size 1.016 1.016)
					(thickness 0.1524)
				)
				(justify mirror)
			)
		)
		(property "Device Type" "C805H58"
			(at 0.0762 -8.1534 180)
			(unlocked yes)
			(layer "B.Fab")
			(hide yes)
			(effects
				(font
					(size 1.016 1.016)
					(thickness 0.1524)
				)
				(justify mirror)
			)
		)
		(duplicate_pad_numbers_are_jumpers no)
		(fp_line
			(start -0.635 0)
			(end 0.635 0)
			(stroke
				(width 0.508)
				(type default)
			)
			(layer "B.SilkS")
		)
		(fp_rect
			(start 0.9652 1.778)
			(end -0.9652 -1.778)
			(stroke
				(width 0)
				(type default)
			)
			(fill no)
			(layer "B.CrtYd")
		)
		(fp_poly
			(pts
				(xy 0.9652 -1.778) (xy -0.9652 -1.778) (xy -0.9652 1.778) (xy 0.9652 1.778)
			)
			(stroke
				(width 0)
				(type default)
			)
			(fill no)
			(layer "B.Fab")
		)
		(pad "1" smd rect
			(at 0 -0.9652)
			(size 1.397 1.143)
			(layers "B.Cu" "B.Mask" "B.Paste")
			(net "P5V_A_1")
		)
		(pad "2" smd rect
			(at 0 0.9652)
			(size 1.397 1.143)
			(layers "B.Cu" "B.Mask" "B.Paste")
			(net "GND")
		)
	)
	(footprint ""
		(layer "B.Cu")
		(at 469.138 -233.299 90)
		(property "Reference" "R1269"
			(at 0 0 90)
			(layer "B.SilkS")
			(hide yes)
			(effects
				(font
					(size 1.27 1.27)
				)
				(justify mirror)
			)
		)
		(property "Value" "3D01R5F-GP"
			(at 0 -8.9535 90)
			(unlocked yes)
			(layer "B.Fab")
			(hide yes)
			(effects
				(font
					(size 1.27 1.016)
					(thickness 0.1524)
				)
				(justify mirror)
			)
		)
		(property "Device Type" "R805H24"
			(at 0 -10.6299 90)
			(unlocked yes)
			(layer "B.Fab")
			(hide yes)
			(effects
				(font
					(size 1.27 1.016)
					(thickness 0.1524)
				)
				(justify mirror)
			)
		)
		(duplicate_pad_numbers_are_jumpers no)
		(fp_line
			(start 0.889 -1.7018)
			(end 0.889 0.2794)
			(stroke
				(width 0.1524)
				(type default)
			)
			(layer "B.SilkS")
		)
		(fp_line
			(start -0.889 -1.7018)
			(end 0.889 -1.7018)
			(stroke
				(width 0.1524)
				(type default)
			)
			(layer "B.SilkS")
		)
		(fp_line
			(start -0.889 -1.7018)
			(end -0.889 -0.381)
			(stroke
				(width 0.1524)
				(type default)
			)
			(layer "B.SilkS")
		)
		(fp_line
			(start 0.889 0.0762)
			(end 0.889 1.7018)
			(stroke
				(width 0.1524)
				(type default)
			)
			(layer "B.SilkS")
		)
		(fp_line
			(start 0.889 1.7018)
			(end -0.889 1.7018)
			(stroke
				(width 0.1524)
				(type default)
			)
			(layer "B.SilkS")
		)
		(fp_line
			(start -0.889 1.7018)
			(end -0.889 -0.508)
			(stroke
				(width 0.1524)
				(type default)
			)
			(layer "B.SilkS")
		)
		(fp_poly
			(pts
				(xy -0.9652 -1.778) (xy -0.9652 1.778) (xy 0.9652 1.778) (xy 0.9652 -1.778)
			)
			(stroke
				(width 0)
				(type default)
			)
			(fill no)
			(layer "B.CrtYd")
		)
		(fp_rect
			(start 0.9652 1.778)
			(end -0.9652 -1.778)
			(stroke
				(width 0)
				(type default)
			)
			(fill no)
			(layer "B.Fab")
		)
		(pad "1" smd rect
			(at 0 -0.9652 270)
			(size 1.397 1.143)
			(layers "B.Cu" "B.Mask" "B.Paste")
			(net "P5V_D_SNB")
		)
		(pad "2" smd rect
			(at 0 0.9652 270)
			(size 1.397 1.143)
			(layers "B.Cu" "B.Mask" "B.Paste")
			(net "GND")
		)
	)
	(footprint ""
		(layer "B.Cu")
		(at 48.6156 -244.0178)
		(property "Reference" "TC5"
			(at 0 0 0)
			(layer "B.SilkS")
			(hide yes)
			(effects
				(font
					(size 1.27 1.27)
				)
				(justify mirror)
			)
		)
		(property "Value" "ST220U10VDM-LGP"
			(at 0 -9.6012 0)
			(unlocked yes)
			(layer "B.Fab")
			(hide yes)
			(effects
				(font
					(size 1.016 1.016)
					(thickness 0.1524)
				)
				(justify mirror)
			)
		)
		(property "Device Type" "CT7343H119"
			(at 0 -11.1252 0)
			(unlocked yes)
			(layer "B.Fab")
			(hide yes)
			(effects
				(font
					(size 1.016 1.016)
					(thickness 0.1524)
				)
				(justify mirror)
			)
		)
		(duplicate_pad_numbers_are_jumpers no)
		(fp_line
			(start -2.286 -4.8768)
			(end 2.286 -4.8768)
			(stroke
				(width 0.1524)
				(type default)
			)
			(layer "B.SilkS")
		)
		(fp_line
			(start -2.286 -2.032)
			(end -2.286 -4.8768)
			(stroke
				(width 0.1524)
				(type default)
			)
			(layer "B.SilkS")
		)
		(fp_line
			(start -2.286 2.032)
			(end -2.286 4.8768)
			(stroke
				(width 0.1524)
				(type default)
			)
			(layer "B.SilkS")
		)
		(fp_line
			(start -2.286 4.8768)
			(end 2.286 4.8768)
			(stroke
				(width 0.1524)
				(type default)
			)
			(layer "B.SilkS")
		)
		(fp_line
			(start -2.1082 -4.699)
			(end 2.1082 -4.699)
			(stroke
				(width 0.508)
				(type default)
			)
			(layer "B.SilkS")
		)
		(fp_line
			(start 2.286 -4.8768)
			(end 2.286 -2.032)
			(stroke
				(width 0.1524)
				(type default)
			)
			(layer "B.SilkS")
		)
		(fp_line
			(start 2.286 4.8768)
			(end 2.286 2.032)
			(stroke
				(width 0.1524)
				(type default)
			)
			(layer "B.SilkS")
		)
		(fp_rect
			(start 2.1463 3.6449)
			(end -2.1463 -3.6449)
			(stroke
				(width 0)
				(type default)
			)
			(fill no)
			(layer "B.CrtYd")
		)
		(fp_poly
			(pts
				(xy 2.54 4.953) (xy 2.54 4.2926) (xy 3.81 4.2926) (xy 3.81 -4.2926) (xy 2.54 -4.2926) (xy 2.54 -4.953)
				(xy -2.54 -4.953) (xy -2.54 -4.2926) (xy -3.81 -4.2926) (xy -3.81 -1.6256) (xy -2.1463 -1.6256)
				(xy -2.1463 -3.6449) (xy 2.1463 -3.6449) (xy 2.1463 3.6449) (xy -2.1463 3.6449) (xy -2.1463 -1.6129)
				(xy -3.81 -1.6129) (xy -3.81 4.2926) (xy -2.54 4.2926) (xy -2.54 4.953)
			)
			(stroke
				(width 0)
				(type default)
			)
			(fill no)
			(layer "B.CrtYd")
		)
		(fp_rect
			(start -2.54 4.2926)
			(end -3.81 -4.2926)
			(stroke
				(width 0)
				(type default)
			)
			(fill no)
			(layer "B.Fab")
		)
		(fp_rect
			(start 2.54 4.953)
			(end -2.54 -4.953)
			(stroke
				(width 0)
				(type default)
			)
			(fill no)
			(layer "B.Fab")
		)
		(fp_rect
			(start 3.81 4.2926)
			(end 2.54 -4.2926)
			(stroke
				(width 0)
				(type default)
			)
			(fill no)
			(layer "B.Fab")
		)
		(pad "1" smd rect
			(at 0 -3.1496 180)
			(size 2.413 2.286)
			(layers "B.Cu" "B.Mask" "B.Paste")
			(net "P5V_A_1")
		)
		(pad "2" smd rect
			(at 0 3.1496 180)
			(size 2.413 2.286)
			(layers "B.Cu" "B.Mask" "B.Paste")
			(net "GND")
		)
		(zone
			(layer "B.Cu")
			(hatch none 0.5)
			(connect_pads
				(clearance 0)
			)
			(min_thickness 0.25)
			(keepout
				(tracks allowed)
				(vias not_allowed)
				(pads allowed)
				(copperpour not_allowed)
				(footprints allowed)
			)
			(placement
				(enabled no)
				(sheetname "")
			)
			(fill
				(thermal_gap 0.5)
				(thermal_bridge_width 0.5)
				(island_removal_mode 0)
			)
			(polygon
				(pts
					(xy 47.1043 -245.7069) (xy 47.1043 -248.6152) (xy 50.1269 -248.6152) (xy 50.1269 -245.7196) (xy 50.1269 -245.3894)
					(xy 47.1043 -245.3894)
				)
			)
		)
		(zone
			(layer "B.Cu")
			(hatch none 0.5)
			(connect_pads
				(clearance 0)
			)
			(min_thickness 0.25)
			(keepout
				(tracks allowed)
				(vias not_allowed)
				(pads allowed)
				(copperpour not_allowed)
				(footprints allowed)
			)
			(placement
				(enabled no)
				(sheetname "")
			)
			(fill
				(thermal_gap 0.5)
				(thermal_bridge_width 0.5)
				(island_removal_mode 0)
			)
			(polygon
				(pts
					(xy 50.1269 -239.4204) (xy 47.1043 -239.4204) (xy 47.1043 -242.316) (xy 47.1043 -242.6462) (xy 50.1269 -242.6462)
					(xy 50.1269 -242.316)
				)
			)
		)
	)
	(footprint ""
		(layer "B.Cu")
		(at 474.462602 -252.40615 -90)
		(property "Reference" "PG14"
			(at 0 0 90)
			(layer "B.SilkS")
			(hide yes)
			(effects
				(font
					(size 1.27 1.27)
				)
				(justify mirror)
			)
		)
		(property "Value" "GAP-CLOSE-PWR-4-GP"
			(at 2.4638 -0.5461 270)
			(unlocked yes)
			(layer "B.Fab")
			(hide yes)
			(effects
				(font
					(size 1.016 1.016)
					(thickness 0.1524)
				)
				(justify mirror)
			)
		)
		(property "Device Type" "GAP-CLOSE-PWR-4"
			(at 2.4638 -2.0701 270)
			(unlocked yes)
			(layer "B.Fab")
			(hide yes)
			(effects
				(font
					(size 1.016 1.016)
					(thickness 0.1524)
				)
				(justify mirror)
			)
		)
		(duplicate_pad_numbers_are_jumpers no)
		(fp_rect
			(start 0.2794 0.254)
			(end -0.2794 -0.254)
			(stroke
				(width 0)
				(type default)
			)
			(fill no)
			(layer "B.CrtYd")
		)
		(fp_rect
			(start 0.2794 0.254)
			(end -0.2794 -0.254)
			(stroke
				(width 0)
				(type default)
			)
			(fill no)
			(layer "B.Fab")
		)
		(pad "1" smd rect
			(at 0.0635 0 90)
			(size 0.1778 0.254)
			(layers "B.Cu" "B.Mask" "B.Paste")
			(net "P5V_A_3")
		)
		(pad "2" smd rect
			(at -0.0635 0 90)
			(size 0.1778 0.254)
			(layers "B.Cu" "B.Mask" "B.Paste")
			(net "P5V_C_CC")
		)
	)
	(footprint ""
		(layer "B.Cu")
		(at 55.431944 -148.253196 180)
		(property "Reference" "R1230"
			(at 0 0 0)
			(layer "B.SilkS")
			(hide yes)
			(effects
				(font
					(size 1.27 1.27)
				)
				(justify mirror)
			)
		)
		(property "Value" "2K7R2F-GP"
			(at -0.064008 -3.993896 180)
			(unlocked yes)
			(layer "B.Fab")
			(hide yes)
			(effects
				(font
					(size 1.016 1.016)
					(thickness 0.1524)
				)
				(justify mirror)
			)
		)
		(property "Device Type" "R402H16"
			(at -0.064008 -5.517896 180)
			(unlocked yes)
			(layer "B.Fab")
			(hide yes)
			(effects
				(font
					(size 1.016 1.016)
					(thickness 0.1524)
				)
				(justify mirror)
			)
		)
		(duplicate_pad_numbers_are_jumpers no)
		(fp_line
			(start 0.508 -0.9398)
			(end 0.508 0.9398)
			(stroke
				(width 0.1524)
				(type default)
			)
			(layer "B.SilkS")
		)
		(fp_line
			(start -0.508 -0.9398)
			(end 0.508 -0.9398)
			(stroke
				(width 0.1524)
				(type default)
			)
			(layer "B.SilkS")
		)
		(fp_rect
			(start 0.508 0.9398)
			(end -0.508 -0.9398)
			(stroke
				(width 0)
				(type default)
			)
			(fill no)
			(layer "B.CrtYd")
		)
		(fp_rect
			(start 0.508 0.9398)
			(end -0.508 -0.9398)
			(stroke
				(width 0)
				(type default)
			)
			(fill no)
			(layer "B.Fab")
		)
		(pad "1" smd custom
			(at 0 -0.4445)
			(size 0.1397 0.1397)
			(layers "B.Cu" "B.Mask" "B.Paste")
			(net "P5V_B_LL")
			(options
				(clearance outline)
				(anchor circle)
			)
			(primitives
				(gr_poly
					(pts
						(arc
							(start -0.1778 0.2794)
							(mid -0.249642 0.249642)
							(end -0.2794 0.1778)
						)
						(arc
							(start -0.2794 -0.1778)
							(mid -0.249642 -0.249642)
							(end -0.1778 -0.2794)
						)
						(arc
							(start 0.1778 -0.2794)
							(mid 0.249642 -0.249642)
							(end 0.2794 -0.1778)
						)
						(arc
							(start 0.2794 0.1778)
							(mid 0.249642 0.249642)
							(end 0.1778 0.2794)
						)
					)
					(width 0)
					(fill yes)
				)
			)
		)
		(pad "2" smd custom
			(at 0 0.4445)
			(size 0.1397 0.1397)
			(layers "B.Cu" "B.Mask" "B.Paste")
			(net "P5V_B_LL_R")
			(options
				(clearance outline)
				(anchor circle)
			)
			(primitives
				(gr_poly
					(pts
						(arc
							(start -0.1778 0.2794)
							(mid -0.249642 0.249642)
							(end -0.2794 0.1778)
						)
						(arc
							(start -0.2794 -0.1778)
							(mid -0.249642 -0.249642)
							(end -0.1778 -0.2794)
						)
						(arc
							(start 0.1778 -0.2794)
							(mid 0.249642 -0.249642)
							(end 0.2794 -0.1778)
						)
						(arc
							(start 0.2794 0.1778)
							(mid 0.249642 0.249642)
							(end 0.1778 0.2794)
						)
					)
					(width 0)
					(fill yes)
				)
			)
		)
	)
	(footprint ""
		(layer "B.Cu")
		(at 362.6358 -141.7574 90)
		(property "Reference" "R1087"
			(at 0 0 90)
			(layer "B.SilkS")
			(hide yes)
			(effects
				(font
					(size 1.27 1.27)
				)
				(justify mirror)
			)
		)
		(property "Value" "10R2F-L-GP"
			(at -0.064008 -3.993896 90)
			(unlocked yes)
			(layer "B.Fab")
			(hide yes)
			(effects
				(font
					(size 1.016 1.016)
					(thickness 0.1524)
				)
				(justify mirror)
			)
		)
		(property "Device Type" "R402H14"
			(at -0.064008 -5.517896 90)
			(unlocked yes)
			(layer "B.Fab")
			(hide yes)
			(effects
				(font
					(size 1.016 1.016)
					(thickness 0.1524)
				)
				(justify mirror)
			)
		)
		(duplicate_pad_numbers_are_jumpers no)
		(fp_line
			(start 0.508 -0.9398)
			(end 0.508 0.9398)
			(stroke
				(width 0.1524)
				(type default)
			)
			(layer "B.SilkS")
		)
		(fp_line
			(start -0.508 -0.9398)
			(end 0.508 -0.9398)
			(stroke
				(width 0.1524)
				(type default)
			)
			(layer "B.SilkS")
		)
		(fp_rect
			(start 0.508 0.9398)
			(end -0.508 -0.9398)
			(stroke
				(width 0)
				(type default)
			)
			(fill no)
			(layer "B.CrtYd")
		)
		(fp_rect
			(start 0.508 0.9398)
			(end -0.508 -0.9398)
			(stroke
				(width 0)
				(type default)
			)
			(fill no)
			(layer "B.Fab")
		)
		(pad "1" smd custom
			(at 0 -0.4445 270)
			(size 0.1397 0.1397)
			(layers "B.Cu" "B.Mask" "B.Paste")
			(net "MB1_CM_SENSE_R1_N")
			(options
				(clearance outline)
				(anchor circle)
			)
			(primitives
				(gr_poly
					(pts
						(arc
							(start -0.1778 0.2794)
							(mid -0.249642 0.249642)
							(end -0.2794 0.1778)
						)
						(arc
							(start -0.2794 -0.1778)
							(mid -0.249642 -0.249642)
							(end -0.1778 -0.2794)
						)
						(arc
							(start 0.1778 -0.2794)
							(mid 0.249642 -0.249642)
							(end 0.2794 -0.1778)
						)
						(arc
							(start 0.2794 0.1778)
							(mid 0.249642 0.249642)
							(end 0.1778 0.2794)
						)
					)
					(width 0)
					(fill yes)
				)
			)
		)
		(pad "2" smd custom
			(at 0 0.4445 270)
			(size 0.1397 0.1397)
			(layers "B.Cu" "B.Mask" "B.Paste")
			(net "MB1_CM_SENSE_N")
			(options
				(clearance outline)
				(anchor circle)
			)
			(primitives
				(gr_poly
					(pts
						(arc
							(start -0.1778 0.2794)
							(mid -0.249642 0.249642)
							(end -0.2794 0.1778)
						)
						(arc
							(start -0.2794 -0.1778)
							(mid -0.249642 -0.249642)
							(end -0.1778 -0.2794)
						)
						(arc
							(start 0.1778 -0.2794)
							(mid 0.249642 -0.249642)
							(end 0.2794 -0.1778)
						)
						(arc
							(start 0.2794 0.1778)
							(mid 0.249642 0.249642)
							(end 0.1778 0.2794)
						)
					)
					(width 0)
					(fill yes)
				)
			)
		)
	)
	(footprint ""
		(layer "B.Cu")
		(at 40.5892 -142.4432 180)
		(property "Reference" "C617"
			(at 0 0 0)
			(layer "B.SilkS")
			(hide yes)
			(effects
				(font
					(size 1.27 1.27)
				)
				(justify mirror)
			)
		)
		(property "Value" "SCD1U16V2KX-3GP"
			(at -1.1811 -2.7051 180)
			(unlocked yes)
			(layer "B.Fab")
			(hide yes)
			(effects
				(font
					(size 1.016 1.016)
					(thickness 0.1524)
				)
				(justify mirror)
			)
		)
		(property "Device Type" "C402H22"
			(at -1.1811 -4.2291 180)
			(unlocked yes)
			(layer "B.Fab")
			(hide yes)
			(effects
				(font
					(size 1.016 1.016)
					(thickness 0.1524)
				)
				(justify mirror)
			)
		)
		(duplicate_pad_numbers_are_jumpers no)
		(fp_rect
			(start 0.4318 0.9525)
			(end -0.4318 -0.9525)
			(stroke
				(width 0)
				(type default)
			)
			(fill no)
			(layer "B.CrtYd")
		)
		(fp_rect
			(start 0.4318 0.9525)
			(end -0.4318 -0.9525)
			(stroke
				(width 0)
				(type default)
			)
			(fill no)
			(layer "B.Fab")
		)
		(pad "1" smd custom
			(at 0 -0.4445)
			(size 0.1524 0.1524)
			(layers "B.Cu" "B.Mask" "B.Paste")
			(net "P12V_A_VIN_U21")
			(options
				(clearance outline)
				(anchor circle)
			)
			(primitives
				(gr_poly
					(pts
						(arc
							(start 0.3048 0.2032)
							(mid 0.275042 0.275042)
							(end 0.2032 0.3048)
						)
						(arc
							(start -0.2032 0.3048)
							(mid -0.275042 0.275042)
							(end -0.3048 0.2032)
						)
						(arc
							(start -0.3048 -0.2032)
							(mid -0.275042 -0.275042)
							(end -0.2032 -0.3048)
						)
						(arc
							(start 0.2032 -0.3048)
							(mid 0.275042 -0.275042)
							(end 0.3048 -0.2032)
						)
					)
					(width 0)
					(fill yes)
				)
			)
		)
		(pad "2" smd custom
			(at 0 0.4445)
			(size 0.1524 0.1524)
			(layers "B.Cu" "B.Mask" "B.Paste")
			(net "GND")
			(options
				(clearance outline)
				(anchor circle)
			)
			(primitives
				(gr_poly
					(pts
						(arc
							(start 0.3048 0.2032)
							(mid 0.275042 0.275042)
							(end 0.2032 0.3048)
						)
						(arc
							(start -0.2032 0.3048)
							(mid -0.275042 0.275042)
							(end -0.3048 0.2032)
						)
						(arc
							(start -0.3048 -0.2032)
							(mid -0.275042 -0.275042)
							(end -0.2032 -0.3048)
						)
						(arc
							(start 0.2032 -0.3048)
							(mid 0.275042 -0.275042)
							(end 0.3048 -0.2032)
						)
					)
					(width 0)
					(fill yes)
				)
			)
		)
	)
	(footprint ""
		(layer "B.Cu")
		(at 40.198802 -146.23415 -90)
		(property "Reference" "C621"
			(at 0 0 90)
			(layer "B.SilkS")
			(hide yes)
			(effects
				(font
					(size 1.27 1.27)
				)
				(justify mirror)
			)
		)
		(property "Value" "SC4D7U25V5KX-GP"
			(at 0.0762 -6.1214 270)
			(unlocked yes)
			(layer "B.Fab")
			(hide yes)
			(effects
				(font
					(size 1.016 1.016)
					(thickness 0.1524)
				)
				(justify mirror)
			)
		)
		(property "Device Type" "C805H54"
			(at 0.0762 -8.1534 270)
			(unlocked yes)
			(layer "B.Fab")
			(hide yes)
			(effects
				(font
					(size 1.016 1.016)
					(thickness 0.1524)
				)
				(justify mirror)
			)
		)
		(duplicate_pad_numbers_are_jumpers no)
		(fp_line
			(start -0.635 0)
			(end 0.635 0)
			(stroke
				(width 0.508)
				(type default)
			)
			(layer "B.SilkS")
		)
		(fp_rect
			(start 0.9652 1.778)
			(end -0.9652 -1.778)
			(stroke
				(width 0)
				(type default)
			)
			(fill no)
			(layer "B.CrtYd")
		)
		(fp_poly
			(pts
				(xy 0.9652 -1.778) (xy -0.9652 -1.778) (xy -0.9652 1.778) (xy 0.9652 1.778)
			)
			(stroke
				(width 0)
				(type default)
			)
			(fill no)
			(layer "B.Fab")
		)
		(pad "1" smd rect
			(at 0 -0.9652 90)
			(size 1.397 1.143)
			(layers "B.Cu" "B.Mask" "B.Paste")
			(net "P12V_A_VDD_U21")
		)
		(pad "2" smd rect
			(at 0 0.9652 90)
			(size 1.397 1.143)
			(layers "B.Cu" "B.Mask" "B.Paste")
			(net "GND")
		)
	)
	(footprint ""
		(layer "B.Cu")
		(at 167.699944 -164.200078 180)
		(property "Reference" "NUT4"
			(at 0 0 0)
			(layer "B.SilkS")
			(hide yes)
			(effects
				(font
					(size 1.27 1.27)
				)
				(justify mirror)
			)
		)
		(property "Value" "STF256R168H278-GP"
			(at 4.826 0.0508 180)
			(unlocked yes)
			(layer "B.Fab")
			(hide yes)
			(effects
				(font
					(size 1.016 1.016)
					(thickness 0.1524)
				)
				(justify mirror)
			)
		)
		(property "Device Type" "STF256R168H278"
			(at 4.826 -1.4732 180)
			(unlocked yes)
			(layer "B.Fab")
			(hide yes)
			(effects
				(font
					(size 1.016 1.016)
					(thickness 0.1524)
				)
				(justify mirror)
			)
		)
		(duplicate_pad_numbers_are_jumpers no)
		(fp_circle
			(center 0 0)
			(end -3.6068 0)
			(stroke
				(width 0.3048)
				(type default)
			)
			(fill no)
			(layer "B.SilkS")
		)
		(fp_poly
			(pts
				(arc
					(start -2.5019 0)
					(mid 2.5019 0)
					(end -2.5019 0)
				)
			)
			(stroke
				(width 0)
				(type default)
			)
			(fill no)
			(layer "B.CrtYd")
		)
		(fp_poly
			(pts
				(arc
					(start -3.7592 0.00635)
					(mid 3.759205 0)
					(end -3.7592 -0.00635)
				)
				(arc
					(start -2.5019 -0.00635)
					(mid 2.501908 0)
					(end -2.5019 0.00635)
				)
			)
			(stroke
				(width 0)
				(type default)
			)
			(fill no)
			(layer "B.CrtYd")
		)
		(fp_poly
			(pts
				(arc
					(start -3.7592 0)
					(mid 3.7592 0)
					(end -3.7592 0)
				)
			)
			(stroke
				(width 0)
				(type default)
			)
			(fill no)
			(layer "F.CrtYd")
		)
		(fp_poly
			(pts
				(arc
					(start -3.7592 0)
					(mid 3.7592 0)
					(end -3.7592 0)
				)
			)
			(stroke
				(width 0)
				(type default)
			)
			(fill no)
			(layer "B.Fab")
		)
		(fp_poly
			(pts
				(arc
					(start -3.7592 0)
					(mid 3.7592 0)
					(end -3.7592 0)
				)
			)
			(stroke
				(width 0)
				(type default)
			)
			(fill no)
			(layer "F.Fab")
		)
		(pad "1" thru_hole circle
			(at 0 0)
			(size 6.5024 6.5024)
			(drill 4.2672)
			(layers "*.Cu" "*.Mask")
			(remove_unused_layers no)
			(net "Net_12")
			(clearance -0.6096)
			(padstack
				(mode front_inner_back)
				(layer "Inner"
					(shape circle)
					(size 4.6736 4.6736)
					(clearance 0.3048)
				)
				(layer "B.Cu"
					(shape circle)
					(size 6.5024 6.5024)
					(thermal_gap 0.3048)
					(clearance -0.6096)
				)
			)
		)
	)
	(footprint ""
		(layer "B.Cu")
		(at 179.662328 -239.192308 180)
		(property "Reference" "C680"
			(at 0 0 0)
			(layer "B.SilkS")
			(hide yes)
			(effects
				(font
					(size 1.27 1.27)
				)
				(justify mirror)
			)
		)
		(property "Value" "SCD1U16V2KX-3GP"
			(at -1.1811 -2.7051 180)
			(unlocked yes)
			(layer "B.Fab")
			(hide yes)
			(effects
				(font
					(size 1.016 1.016)
					(thickness 0.1524)
				)
				(justify mirror)
			)
		)
		(property "Device Type" "C402H22"
			(at -1.1811 -4.2291 180)
			(unlocked yes)
			(layer "B.Fab")
			(hide yes)
			(effects
				(font
					(size 1.016 1.016)
					(thickness 0.1524)
				)
				(justify mirror)
			)
		)
		(duplicate_pad_numbers_are_jumpers no)
		(fp_rect
			(start 0.4318 0.9525)
			(end -0.4318 -0.9525)
			(stroke
				(width 0)
				(type default)
			)
			(fill no)
			(layer "B.CrtYd")
		)
		(fp_rect
			(start 0.4318 0.9525)
			(end -0.4318 -0.9525)
			(stroke
				(width 0)
				(type default)
			)
			(fill no)
			(layer "B.Fab")
		)
		(pad "1" smd custom
			(at 0 -0.4445)
			(size 0.1524 0.1524)
			(layers "B.Cu" "B.Mask" "B.Paste")
			(net "P3V3_STBY_A")
			(options
				(clearance outline)
				(anchor circle)
			)
			(primitives
				(gr_poly
					(pts
						(arc
							(start 0.3048 0.2032)
							(mid 0.275042 0.275042)
							(end 0.2032 0.3048)
						)
						(arc
							(start -0.2032 0.3048)
							(mid -0.275042 0.275042)
							(end -0.3048 0.2032)
						)
						(arc
							(start -0.3048 -0.2032)
							(mid -0.275042 -0.275042)
							(end -0.2032 -0.3048)
						)
						(arc
							(start 0.2032 -0.3048)
							(mid 0.275042 -0.275042)
							(end 0.3048 -0.2032)
						)
					)
					(width 0)
					(fill yes)
				)
			)
		)
		(pad "2" smd custom
			(at 0 0.4445)
			(size 0.1524 0.1524)
			(layers "B.Cu" "B.Mask" "B.Paste")
			(net "GND")
			(options
				(clearance outline)
				(anchor circle)
			)
			(primitives
				(gr_poly
					(pts
						(arc
							(start 0.3048 0.2032)
							(mid 0.275042 0.275042)
							(end 0.2032 0.3048)
						)
						(arc
							(start -0.2032 0.3048)
							(mid -0.275042 0.275042)
							(end -0.3048 0.2032)
						)
						(arc
							(start -0.3048 -0.2032)
							(mid -0.275042 -0.275042)
							(end -0.2032 -0.3048)
						)
						(arc
							(start 0.2032 -0.3048)
							(mid 0.275042 -0.275042)
							(end 0.3048 -0.2032)
						)
					)
					(width 0)
					(fill yes)
				)
			)
		)
	)
	(footprint ""
		(layer "B.Cu")
		(at 186.329828 -219.869004)
		(property "Reference" "C676"
			(at 0 0 0)
			(layer "B.SilkS")
			(hide yes)
			(effects
				(font
					(size 1.27 1.27)
				)
				(justify mirror)
			)
		)
		(property "Value" "SC1U16V3KX-5GP"
			(at 0 -2.8194 0)
			(unlocked yes)
			(layer "B.Fab")
			(hide yes)
			(effects
				(font
					(size 1.016 1.016)
					(thickness 0.1524)
				)
				(justify mirror)
			)
		)
		(property "Device Type" "C603H36"
			(at 0 -4.3434 0)
			(unlocked yes)
			(layer "B.Fab")
			(hide yes)
			(effects
				(font
					(size 1.016 1.016)
					(thickness 0.1524)
				)
				(justify mirror)
			)
		)
		(duplicate_pad_numbers_are_jumpers no)
		(fp_line
			(start -0.508 0)
			(end 0.508 0)
			(stroke
				(width 0.2032)
				(type default)
			)
			(layer "B.SilkS")
		)
		(fp_rect
			(start 0.5842 1.3335)
			(end -0.5842 -1.3335)
			(stroke
				(width 0)
				(type default)
			)
			(fill no)
			(layer "B.CrtYd")
		)
		(fp_rect
			(start 0.5842 1.3335)
			(end -0.5842 -1.3335)
			(stroke
				(width 0)
				(type default)
			)
			(fill no)
			(layer "B.Fab")
		)
		(pad "1" smd custom
			(at 0 -0.762 180)
			(size 0.2159 0.2159)
			(layers "B.Cu" "B.Mask" "B.Paste")
			(net "P3V3_STBY_VRG5")
			(options
				(clearance outline)
				(anchor circle)
			)
			(primitives
				(gr_poly
					(pts
						(arc
							(start -0.3302 0.4318)
							(mid -0.402042 0.402042)
							(end -0.4318 0.3302)
						)
						(arc
							(start -0.4318 -0.3302)
							(mid -0.402042 -0.402042)
							(end -0.3302 -0.4318)
						)
						(arc
							(start 0.3302 -0.4318)
							(mid 0.402042 -0.402042)
							(end 0.4318 -0.3302)
						)
						(arc
							(start 0.4318 0.3302)
							(mid 0.402042 0.402042)
							(end 0.3302 0.4318)
						)
					)
					(width 0)
					(fill yes)
				)
			)
		)
		(pad "2" smd custom
			(at 0 0.762 180)
			(size 0.2159 0.2159)
			(layers "B.Cu" "B.Mask" "B.Paste")
			(net "GND")
			(options
				(clearance outline)
				(anchor circle)
			)
			(primitives
				(gr_poly
					(pts
						(arc
							(start -0.3302 0.4318)
							(mid -0.402042 0.402042)
							(end -0.4318 0.3302)
						)
						(arc
							(start -0.4318 -0.3302)
							(mid -0.402042 -0.402042)
							(end -0.3302 -0.4318)
						)
						(arc
							(start 0.3302 -0.4318)
							(mid 0.402042 -0.402042)
							(end 0.4318 -0.3302)
						)
						(arc
							(start 0.4318 0.3302)
							(mid 0.402042 0.402042)
							(end 0.3302 0.4318)
						)
					)
					(width 0)
					(fill yes)
				)
			)
		)
	)
	(footprint ""
		(layer "B.Cu")
		(at 194.009772 -224.256092)
		(property "Reference" "R1282"
			(at 0 0 0)
			(layer "B.SilkS")
			(hide yes)
			(effects
				(font
					(size 1.27 1.27)
				)
				(justify mirror)
			)
		)
		(property "Value" "0R6J-3-GP"
			(at 0.0508 -4.8514 0)
			(unlocked yes)
			(layer "B.Fab")
			(hide yes)
			(effects
				(font
					(size 1.016 1.016)
					(thickness 0.1524)
				)
				(justify mirror)
			)
		)
		(property "Device Type" "R1206H28"
			(at 0 -6.3754 0)
			(unlocked yes)
			(layer "B.Fab")
			(hide yes)
			(effects
				(font
					(size 1.016 1.016)
					(thickness 0.1524)
				)
				(justify mirror)
			)
		)
		(duplicate_pad_numbers_are_jumpers no)
		(fp_line
			(start -1.016 -2.2352)
			(end -1.016 2.2352)
			(stroke
				(width 0.1524)
				(type default)
			)
			(layer "B.SilkS")
		)
		(fp_line
			(start -1.016 2.2352)
			(end 1.016 2.2352)
			(stroke
				(width 0.1524)
				(type default)
			)
			(layer "B.SilkS")
		)
		(fp_line
			(start 1.016 -2.2352)
			(end -1.016 -2.2352)
			(stroke
				(width 0.1524)
				(type default)
			)
			(layer "B.SilkS")
		)
		(fp_line
			(start 1.016 2.2352)
			(end 1.016 -2.2352)
			(stroke
				(width 0.1524)
				(type default)
			)
			(layer "B.SilkS")
		)
		(fp_rect
			(start 1.0922 2.3114)
			(end -1.0922 -2.3114)
			(stroke
				(width 0)
				(type default)
			)
			(fill no)
			(layer "B.CrtYd")
		)
		(fp_poly
			(pts
				(xy 1.0922 -2.3114) (xy -1.0922 -2.3114) (xy -1.0922 2.3114) (xy 1.0922 2.3114)
			)
			(stroke
				(width 0)
				(type default)
			)
			(fill no)
			(layer "B.Fab")
		)
		(pad "1" smd rect
			(at 0 -1.397 180)
			(size 1.651 1.27)
			(layers "B.Cu" "B.Mask" "B.Paste")
			(net "P3V3_STBY_VIN")
		)
		(pad "2" smd rect
			(at 0 1.397 180)
			(size 1.651 1.27)
			(layers "B.Cu" "B.Mask" "B.Paste")
			(net "P12V_A")
		)
	)
	(footprint ""
		(layer "B.Cu")
		(at 189.911482 -232.661206 90)
		(property "Reference" "R1289"
			(at 0 0 90)
			(layer "B.SilkS")
			(hide yes)
			(effects
				(font
					(size 1.27 1.27)
				)
				(justify mirror)
			)
		)
		(property "Value" "2KR2F-3-GP"
			(at -0.064008 -3.993896 90)
			(unlocked yes)
			(layer "B.Fab")
			(hide yes)
			(effects
				(font
					(size 1.016 1.016)
					(thickness 0.1524)
				)
				(justify mirror)
			)
		)
		(property "Device Type" "R402H16"
			(at -0.064008 -5.517896 90)
			(unlocked yes)
			(layer "B.Fab")
			(hide yes)
			(effects
				(font
					(size 1.016 1.016)
					(thickness 0.1524)
				)
				(justify mirror)
			)
		)
		(duplicate_pad_numbers_are_jumpers no)
		(fp_line
			(start 0.508 -0.9398)
			(end 0.508 0.9398)
			(stroke
				(width 0.1524)
				(type default)
			)
			(layer "B.SilkS")
		)
		(fp_line
			(start -0.508 -0.9398)
			(end 0.508 -0.9398)
			(stroke
				(width 0.1524)
				(type default)
			)
			(layer "B.SilkS")
		)
		(fp_rect
			(start 0.508 0.9398)
			(end -0.508 -0.9398)
			(stroke
				(width 0)
				(type default)
			)
			(fill no)
			(layer "B.CrtYd")
		)
		(fp_rect
			(start 0.508 0.9398)
			(end -0.508 -0.9398)
			(stroke
				(width 0)
				(type default)
			)
			(fill no)
			(layer "B.Fab")
		)
		(pad "1" smd custom
			(at 0 -0.4445 270)
			(size 0.1397 0.1397)
			(layers "B.Cu" "B.Mask" "B.Paste")
			(net "P3V3_STBY_SW")
			(options
				(clearance outline)
				(anchor circle)
			)
			(primitives
				(gr_poly
					(pts
						(arc
							(start -0.1778 0.2794)
							(mid -0.249642 0.249642)
							(end -0.2794 0.1778)
						)
						(arc
							(start -0.2794 -0.1778)
							(mid -0.249642 -0.249642)
							(end -0.1778 -0.2794)
						)
						(arc
							(start 0.1778 -0.2794)
							(mid 0.249642 -0.249642)
							(end 0.2794 -0.1778)
						)
						(arc
							(start 0.2794 0.1778)
							(mid 0.249642 0.249642)
							(end 0.1778 0.2794)
						)
					)
					(width 0)
					(fill yes)
				)
			)
		)
		(pad "2" smd custom
			(at 0 0.4445 270)
			(size 0.1397 0.1397)
			(layers "B.Cu" "B.Mask" "B.Paste")
			(net "P3V3_STBY_VFB_R")
			(options
				(clearance outline)
				(anchor circle)
			)
			(primitives
				(gr_poly
					(pts
						(arc
							(start -0.1778 0.2794)
							(mid -0.249642 0.249642)
							(end -0.2794 0.1778)
						)
						(arc
							(start -0.2794 -0.1778)
							(mid -0.249642 -0.249642)
							(end -0.1778 -0.2794)
						)
						(arc
							(start 0.1778 -0.2794)
							(mid 0.249642 -0.249642)
							(end 0.2794 -0.1778)
						)
						(arc
							(start 0.2794 0.1778)
							(mid 0.249642 0.249642)
							(end 0.1778 0.2794)
						)
					)
					(width 0)
					(fill yes)
				)
			)
		)
	)
	(footprint ""
		(layer "B.Cu")
		(at 446.4304 -251.7648 -90)
		(property "Reference" "U22"
			(at 0 0 90)
			(layer "B.SilkS")
			(hide yes)
			(effects
				(font
					(size 1.27 1.27)
				)
				(justify mirror)
			)
		)
		(property "Value" "TPS53319DQPR-GP"
			(at -4.7498 -5.6896 270)
			(unlocked yes)
			(layer "B.Fab")
			(hide yes)
			(effects
				(font
					(size 1.016 1.016)
					(thickness 0.1524)
				)
				(justify mirror)
			)
		)
		(property "Device Type" "QFN22G6050-G6133H60"
			(at -4.7498 -7.2136 270)
			(unlocked yes)
			(layer "B.Fab")
			(hide yes)
			(effects
				(font
					(size 1.016 1.016)
					(thickness 0.1524)
				)
				(justify mirror)
			)
		)
		(duplicate_pad_numbers_are_jumpers no)
		(fp_line
			(start -3.556 3.5179)
			(end -3.556 2.2479)
			(stroke
				(width 0.1524)
				(type default)
			)
			(layer "B.SilkS")
		)
		(fp_line
			(start -2.286 3.5179)
			(end -3.556 3.5179)
			(stroke
				(width 0.1524)
				(type default)
			)
			(layer "B.SilkS")
		)
		(fp_line
			(start 3.556 3.5179)
			(end 2.286 3.5179)
			(stroke
				(width 0.1524)
				(type default)
			)
			(layer "B.SilkS")
		)
		(fp_line
			(start -1.500124 3.262122)
			(end -1.500124 4.024122)
			(stroke
				(width 0.1524)
				(type default)
			)
			(layer "B.SilkS")
		)
		(fp_line
			(start 0.999998 3.262122)
			(end 0.999998 3.770122)
			(stroke
				(width 0.1524)
				(type default)
			)
			(layer "B.SilkS")
		)
		(fp_line
			(start 3.556 2.2479)
			(end 3.556 3.5179)
			(stroke
				(width 0.1524)
				(type default)
			)
			(layer "B.SilkS")
		)
		(fp_line
			(start -0.500126 -3.262122)
			(end -0.500126 -3.770122)
			(stroke
				(width 0.1524)
				(type default)
			)
			(layer "B.SilkS")
		)
		(fp_line
			(start 1.999996 -3.262122)
			(end 1.999996 -4.024122)
			(stroke
				(width 0.1524)
				(type default)
			)
			(layer "B.SilkS")
		)
		(fp_line
			(start 2.286 -3.5179)
			(end 3.556 -3.5179)
			(stroke
				(width 0.1524)
				(type default)
			)
			(layer "B.SilkS")
		)
		(fp_line
			(start 3.556 -3.5179)
			(end 3.556 -2.2479)
			(stroke
				(width 0.1524)
				(type default)
			)
			(layer "B.SilkS")
		)
		(fp_poly
			(pts
				(xy -3.556 -3.5179) (xy -2.5273 -3.5179) (xy -3.556 -2.4892)
			)
			(stroke
				(width 0)
				(type default)
			)
			(fill yes)
			(layer "B.SilkS")
		)
		(fp_rect
			(start 2.9972 2.5019)
			(end -2.9972 -2.5019)
			(stroke
				(width 0)
				(type default)
			)
			(fill no)
			(layer "B.CrtYd")
		)
		(fp_poly
			(pts
				(xy -3.556 -2.5019) (xy 2.9972 -2.5019) (xy 2.9972 2.5019) (xy -2.9972 2.5019) (xy -2.9972 -2.4892)
				(xy -3.556 -2.4892) (xy -3.556 3.5179) (xy 3.556 3.5179) (xy 3.556 -3.5179) (xy -3.556 -3.5179)
			)
			(stroke
				(width 0)
				(type default)
			)
			(fill no)
			(layer "B.CrtYd")
		)
		(fp_rect
			(start 3.556 3.5179)
			(end -3.556 -3.5179)
			(stroke
				(width 0)
				(type default)
			)
			(fill no)
			(layer "B.Fab")
		)
		(pad "1" smd rect
			(at -2.500122 -2.449322 90)
			(size 0.3048 1.1176)
			(layers "B.Cu" "B.Mask" "B.Paste")
			(net "P5V_C_VFB")
		)
		(pad "2" smd rect
			(at -1.999996 -2.449322 90)
			(size 0.3048 1.1176)
			(layers "B.Cu" "B.Mask" "B.Paste")
			(net "P5V_C_EN_R")
		)
		(pad "3" smd rect
			(at -1.500124 -2.449322 90)
			(size 0.3048 1.1176)
			(layers "B.Cu" "B.Mask" "B.Paste")
			(net "P5V_A_3_PGOOD")
		)
		(pad "4" smd rect
			(at -0.999998 -2.449322 90)
			(size 0.3048 1.1176)
			(layers "B.Cu" "B.Mask" "B.Paste")
			(net "P5V_C_VBST")
		)
		(pad "5" smd rect
			(at -0.500126 -2.449322 90)
			(size 0.3048 1.1176)
			(layers "B.Cu" "B.Mask" "B.Paste")
			(net "P5V_C_ROVP")
		)
		(pad "6" smd rect
			(at 0 -2.449322 90)
			(size 0.3048 1.1176)
			(layers "B.Cu" "B.Mask" "B.Paste")
			(net "P5V_C_LL")
		)
		(pad "7" smd rect
			(at 0.500126 -2.449322 90)
			(size 0.3048 1.1176)
			(layers "B.Cu" "B.Mask" "B.Paste")
			(net "P5V_C_LL")
		)
		(pad "8" smd rect
			(at 0.999998 -2.449322 90)
			(size 0.3048 1.1176)
			(layers "B.Cu" "B.Mask" "B.Paste")
			(net "P5V_C_LL")
		)
		(pad "9" smd rect
			(at 1.500124 -2.449322 90)
			(size 0.3048 1.1176)
			(layers "B.Cu" "B.Mask" "B.Paste")
			(net "P5V_C_LL")
		)
		(pad "10" smd rect
			(at 1.999996 -2.449322 90)
			(size 0.3048 1.1176)
			(layers "B.Cu" "B.Mask" "B.Paste")
			(net "P5V_C_LL")
		)
		(pad "11" smd rect
			(at 2.500122 -2.449322 90)
			(size 0.3048 1.1176)
			(layers "B.Cu" "B.Mask" "B.Paste")
			(net "P5V_C_LL")
		)
		(pad "12" smd rect
			(at 2.500122 2.449322 90)
			(size 0.3048 1.1176)
			(layers "B.Cu" "B.Mask" "B.Paste")
			(net "P12V_A_VIN_U22")
		)
		(pad "13" smd rect
			(at 1.999996 2.449322 90)
			(size 0.3048 1.1176)
			(layers "B.Cu" "B.Mask" "B.Paste")
			(net "P12V_A_VIN_U22")
		)
		(pad "14" smd rect
			(at 1.500124 2.449322 90)
			(size 0.3048 1.1176)
			(layers "B.Cu" "B.Mask" "B.Paste")
			(net "P12V_A_VIN_U22")
		)
		(pad "15" smd rect
			(at 0.999998 2.449322 90)
			(size 0.3048 1.1176)
			(layers "B.Cu" "B.Mask" "B.Paste")
			(net "P12V_A_VIN_U22")
		)
		(pad "16" smd rect
			(at 0.500126 2.449322 90)
			(size 0.3048 1.1176)
			(layers "B.Cu" "B.Mask" "B.Paste")
			(net "P12V_A_VIN_U22")
		)
		(pad "17" smd rect
			(at 0 2.449322 90)
			(size 0.3048 1.1176)
			(layers "B.Cu" "B.Mask" "B.Paste")
			(net "P12V_A_VIN_U22")
		)
		(pad "18" smd rect
			(at -0.500126 2.449322 90)
			(size 0.3048 1.1176)
			(layers "B.Cu" "B.Mask" "B.Paste")
			(net "P5V_C_VREG")
		)
		(pad "19" smd rect
			(at -0.999998 2.449322 90)
			(size 0.3048 1.1176)
			(layers "B.Cu" "B.Mask" "B.Paste")
			(net "P12V_A_VDD_U22")
		)
		(pad "20" smd rect
			(at -1.500124 2.449322 90)
			(size 0.3048 1.1176)
			(layers "B.Cu" "B.Mask" "B.Paste")
			(net "P5V_C_MODE")
		)
		(pad "21" smd rect
			(at -1.999996 2.449322 90)
			(size 0.3048 1.1176)
			(layers "B.Cu" "B.Mask" "B.Paste")
			(net "P5V_C_TRIP")
		)
		(pad "22" smd rect
			(at -2.500122 2.449322 90)
			(size 0.3048 1.1176)
			(layers "B.Cu" "B.Mask" "B.Paste")
			(net "P5V_C_RF")
		)
		(pad "23" smd custom
			(at 0 0 90)
			(size 0.83185 0.83185)
			(layers "B.Cu" "B.Mask" "B.Paste")
			(net "GND")
			(options
				(clearance outline)
				(anchor circle)
			)
			(primitives
				(gr_poly
					(pts
						(xy -2.7813 -1.6637) (xy -2.7813 -1.2954) (xy -3.048 -1.2954) (xy -3.048 -0.9525) (xy -2.7813 -0.9525)
						(xy -2.7813 0.9525) (xy -3.048 0.9525) (xy -3.048 1.2954) (xy -2.7813 1.2954) (xy -2.7813 1.6637)
						(xy 2.7813 1.6637) (xy 2.7813 1.2954) (xy 3.048 1.2954) (xy 3.048 0.9525) (xy 2.7813 0.9525) (xy 2.7813 -0.9525)
						(xy 3.048 -0.9525) (xy 3.048 -1.2954) (xy 2.7813 -1.2954) (xy 2.7813 -1.6637)
					)
					(width 0)
					(fill yes)
				)
			)
		)
	)
	(footprint ""
		(layer "B.Cu")
		(at 74.615802 -147.37715 -90)
		(property "Reference" "PG12"
			(at 0 0 90)
			(layer "B.SilkS")
			(hide yes)
			(effects
				(font
					(size 1.27 1.27)
				)
				(justify mirror)
			)
		)
		(property "Value" "GAP-CLOSE-PWR-4-GP"
			(at 2.4638 -0.5461 270)
			(unlocked yes)
			(layer "B.Fab")
			(hide yes)
			(effects
				(font
					(size 1.016 1.016)
					(thickness 0.1524)
				)
				(justify mirror)
			)
		)
		(property "Device Type" "GAP-CLOSE-PWR-4"
			(at 2.4638 -2.0701 270)
			(unlocked yes)
			(layer "B.Fab")
			(hide yes)
			(effects
				(font
					(size 1.016 1.016)
					(thickness 0.1524)
				)
				(justify mirror)
			)
		)
		(duplicate_pad_numbers_are_jumpers no)
		(fp_rect
			(start 0.2794 0.254)
			(end -0.2794 -0.254)
			(stroke
				(width 0)
				(type default)
			)
			(fill no)
			(layer "B.CrtYd")
		)
		(fp_rect
			(start 0.2794 0.254)
			(end -0.2794 -0.254)
			(stroke
				(width 0)
				(type default)
			)
			(fill no)
			(layer "B.Fab")
		)
		(pad "1" smd rect
			(at 0.0635 0 90)
			(size 0.1778 0.254)
			(layers "B.Cu" "B.Mask" "B.Paste")
			(net "P5V_A_2")
		)
		(pad "2" smd rect
			(at -0.0635 0 90)
			(size 0.1778 0.254)
			(layers "B.Cu" "B.Mask" "B.Paste")
			(net "P5V_B_CC")
		)
	)
	(footprint ""
		(layer "B.Cu")
		(at 471.722704 -222.569786)
		(property "Reference" "L8"
			(at 0 0 0)
			(layer "B.SilkS")
			(hide yes)
			(effects
				(font
					(size 1.27 1.27)
				)
				(justify mirror)
			)
		)
		(property "Value" "IND-1UH-191-GP"
			(at 6.7818 -2.1082 0)
			(unlocked yes)
			(layer "B.Fab")
			(hide yes)
			(effects
				(font
					(size 1.016 1.016)
					(thickness 0.1524)
				)
				(justify mirror)
			)
		)
		(property "Device Type" "L109100-2430-UH119"
			(at 6.7818 -3.6322 0)
			(unlocked yes)
			(layer "B.Fab")
			(hide yes)
			(effects
				(font
					(size 1.016 1.016)
					(thickness 0.1524)
				)
				(justify mirror)
			)
		)
		(duplicate_pad_numbers_are_jumpers no)
		(fp_line
			(start -5.2578 -6.4262)
			(end -5.2578 6.4262)
			(stroke
				(width 0.1524)
				(type default)
			)
			(layer "B.SilkS")
		)
		(fp_line
			(start -5.2578 6.4262)
			(end 5.2578 6.4262)
			(stroke
				(width 0.1524)
				(type default)
			)
			(layer "B.SilkS")
		)
		(fp_line
			(start 5.2578 -6.4262)
			(end -5.2578 -6.4262)
			(stroke
				(width 0.1524)
				(type default)
			)
			(layer "B.SilkS")
		)
		(fp_line
			(start 5.2578 6.4262)
			(end 5.2578 -6.4262)
			(stroke
				(width 0.1524)
				(type default)
			)
			(layer "B.SilkS")
		)
		(fp_rect
			(start 5.0038 5.4229)
			(end -5.0038 -5.4229)
			(stroke
				(width 0)
				(type default)
			)
			(fill no)
			(layer "B.CrtYd")
		)
		(fp_poly
			(pts
				(xy 5.5118 6.5024) (xy 5.5118 -6.5024) (xy -5.5118 -6.5024) (xy -5.5118 -0.8509) (xy -5.0038 -0.8509)
				(xy -5.0038 -5.4229) (xy 5.0038 -5.4229) (xy 5.0038 5.4229) (xy -5.0038 5.4229) (xy -5.0038 -0.8382)
				(xy -5.5118 -0.8382) (xy -5.5118 6.5024)
			)
			(stroke
				(width 0)
				(type default)
			)
			(fill no)
			(layer "B.CrtYd")
		)
		(fp_rect
			(start 5.5118 6.5024)
			(end -5.5118 -6.5024)
			(stroke
				(width 0)
				(type default)
			)
			(fill no)
			(layer "B.Fab")
		)
		(pad "1" smd rect
			(at 0 -4.396994 180)
			(size 3.5052 3.556)
			(layers "B.Cu" "B.Mask" "B.Paste")
			(net "P5V_D_LL")
		)
		(pad "2" smd rect
			(at 0 4.396994 180)
			(size 3.5052 3.556)
			(layers "B.Cu" "B.Mask" "B.Paste")
			(net "P5V_A_4")
		)
	)
	(footprint ""
		(layer "B.Cu")
		(at 65.5574 -139.3698)
		(property "Reference" "TC10"
			(at 0 0 0)
			(layer "B.SilkS")
			(hide yes)
			(effects
				(font
					(size 1.27 1.27)
				)
				(justify mirror)
			)
		)
		(property "Value" "ST220U10VDM-LGP"
			(at 0 -9.6012 0)
			(unlocked yes)
			(layer "B.Fab")
			(hide yes)
			(effects
				(font
					(size 1.016 1.016)
					(thickness 0.1524)
				)
				(justify mirror)
			)
		)
		(property "Device Type" "CT7343H119"
			(at 0 -11.1252 0)
			(unlocked yes)
			(layer "B.Fab")
			(hide yes)
			(effects
				(font
					(size 1.016 1.016)
					(thickness 0.1524)
				)
				(justify mirror)
			)
		)
		(duplicate_pad_numbers_are_jumpers no)
		(fp_line
			(start -2.286 -4.8768)
			(end 2.286 -4.8768)
			(stroke
				(width 0.1524)
				(type default)
			)
			(layer "B.SilkS")
		)
		(fp_line
			(start -2.286 -2.032)
			(end -2.286 -4.8768)
			(stroke
				(width 0.1524)
				(type default)
			)
			(layer "B.SilkS")
		)
		(fp_line
			(start -2.286 2.032)
			(end -2.286 4.8768)
			(stroke
				(width 0.1524)
				(type default)
			)
			(layer "B.SilkS")
		)
		(fp_line
			(start -2.286 4.8768)
			(end 2.286 4.8768)
			(stroke
				(width 0.1524)
				(type default)
			)
			(layer "B.SilkS")
		)
		(fp_line
			(start -2.1082 -4.699)
			(end 2.1082 -4.699)
			(stroke
				(width 0.508)
				(type default)
			)
			(layer "B.SilkS")
		)
		(fp_line
			(start 2.286 -4.8768)
			(end 2.286 -2.032)
			(stroke
				(width 0.1524)
				(type default)
			)
			(layer "B.SilkS")
		)
		(fp_line
			(start 2.286 4.8768)
			(end 2.286 2.032)
			(stroke
				(width 0.1524)
				(type default)
			)
			(layer "B.SilkS")
		)
		(fp_rect
			(start 2.1463 3.6449)
			(end -2.1463 -3.6449)
			(stroke
				(width 0)
				(type default)
			)
			(fill no)
			(layer "B.CrtYd")
		)
		(fp_poly
			(pts
				(xy 2.54 4.953) (xy 2.54 4.2926) (xy 3.81 4.2926) (xy 3.81 -4.2926) (xy 2.54 -4.2926) (xy 2.54 -4.953)
				(xy -2.54 -4.953) (xy -2.54 -4.2926) (xy -3.81 -4.2926) (xy -3.81 -1.6256) (xy -2.1463 -1.6256)
				(xy -2.1463 -3.6449) (xy 2.1463 -3.6449) (xy 2.1463 3.6449) (xy -2.1463 3.6449) (xy -2.1463 -1.6129)
				(xy -3.81 -1.6129) (xy -3.81 4.2926) (xy -2.54 4.2926) (xy -2.54 4.953)
			)
			(stroke
				(width 0)
				(type default)
			)
			(fill no)
			(layer "B.CrtYd")
		)
		(fp_rect
			(start -2.54 4.2926)
			(end -3.81 -4.2926)
			(stroke
				(width 0)
				(type default)
			)
			(fill no)
			(layer "B.Fab")
		)
		(fp_rect
			(start 2.54 4.953)
			(end -2.54 -4.953)
			(stroke
				(width 0)
				(type default)
			)
			(fill no)
			(layer "B.Fab")
		)
		(fp_rect
			(start 3.81 4.2926)
			(end 2.54 -4.2926)
			(stroke
				(width 0)
				(type default)
			)
			(fill no)
			(layer "B.Fab")
		)
		(pad "1" smd rect
			(at 0 -3.1496 180)
			(size 2.413 2.286)
			(layers "B.Cu" "B.Mask" "B.Paste")
			(net "P5V_A_2")
		)
		(pad "2" smd rect
			(at 0 3.1496 180)
			(size 2.413 2.286)
			(layers "B.Cu" "B.Mask" "B.Paste")
			(net "GND")
		)
		(zone
			(layer "B.Cu")
			(hatch none 0.5)
			(connect_pads
				(clearance 0)
			)
			(min_thickness 0.25)
			(keepout
				(tracks allowed)
				(vias not_allowed)
				(pads allowed)
				(copperpour not_allowed)
				(footprints allowed)
			)
			(placement
				(enabled no)
				(sheetname "")
			)
			(fill
				(thermal_gap 0.5)
				(thermal_bridge_width 0.5)
				(island_removal_mode 0)
			)
			(polygon
				(pts
					(xy 64.0461 -141.0589) (xy 64.0461 -143.9672) (xy 67.0687 -143.9672) (xy 67.0687 -141.0716) (xy 67.0687 -140.7414)
					(xy 64.0461 -140.7414)
				)
			)
		)
		(zone
			(layer "B.Cu")
			(hatch none 0.5)
			(connect_pads
				(clearance 0)
			)
			(min_thickness 0.25)
			(keepout
				(tracks allowed)
				(vias not_allowed)
				(pads allowed)
				(copperpour not_allowed)
				(footprints allowed)
			)
			(placement
				(enabled no)
				(sheetname "")
			)
			(fill
				(thermal_gap 0.5)
				(thermal_bridge_width 0.5)
				(island_removal_mode 0)
			)
			(polygon
				(pts
					(xy 67.0687 -134.7724) (xy 64.0461 -134.7724) (xy 64.0461 -137.668) (xy 64.0461 -137.9982) (xy 67.0687 -137.9982)
					(xy 67.0687 -137.668)
				)
			)
		)
	)
	(footprint ""
		(layer "B.Cu")
		(at 220.281246 -107.461304 -90)
		(property "Reference" "TC3"
			(at 0 0 90)
			(layer "B.SilkS")
			(hide yes)
			(effects
				(font
					(size 1.27 1.27)
				)
				(justify mirror)
			)
		)
		(property "Value" "ST100U16VDM-3-GP"
			(at 0 -9.6012 270)
			(unlocked yes)
			(layer "B.Fab")
			(hide yes)
			(effects
				(font
					(size 1.016 1.016)
					(thickness 0.1524)
				)
				(justify mirror)
			)
		)
		(property "Device Type" "CT7343H79"
			(at 0 -11.1252 270)
			(unlocked yes)
			(layer "B.Fab")
			(hide yes)
			(effects
				(font
					(size 1.016 1.016)
					(thickness 0.1524)
				)
				(justify mirror)
			)
		)
		(duplicate_pad_numbers_are_jumpers no)
		(fp_line
			(start -2.286 4.8768)
			(end 2.286 4.8768)
			(stroke
				(width 0.1524)
				(type default)
			)
			(layer "B.SilkS")
		)
		(fp_line
			(start 2.286 4.8768)
			(end 2.286 2.032)
			(stroke
				(width 0.1524)
				(type default)
			)
			(layer "B.SilkS")
		)
		(fp_line
			(start -2.286 2.032)
			(end -2.286 4.8768)
			(stroke
				(width 0.1524)
				(type default)
			)
			(layer "B.SilkS")
		)
		(fp_line
			(start -2.286 -2.032)
			(end -2.286 -4.8768)
			(stroke
				(width 0.1524)
				(type default)
			)
			(layer "B.SilkS")
		)
		(fp_line
			(start -2.1082 -4.699)
			(end 2.1082 -4.699)
			(stroke
				(width 0.508)
				(type default)
			)
			(layer "B.SilkS")
		)
		(fp_line
			(start -2.286 -4.8768)
			(end 2.286 -4.8768)
			(stroke
				(width 0.1524)
				(type default)
			)
			(layer "B.SilkS")
		)
		(fp_line
			(start 2.286 -4.8768)
			(end 2.286 -2.032)
			(stroke
				(width 0.1524)
				(type default)
			)
			(layer "B.SilkS")
		)
		(fp_rect
			(start 2.1463 3.6449)
			(end -2.1463 -3.6449)
			(stroke
				(width 0)
				(type default)
			)
			(fill no)
			(layer "B.CrtYd")
		)
		(fp_poly
			(pts
				(xy 2.54 4.953) (xy 2.54 4.2926) (xy 3.81 4.2926) (xy 3.81 -4.2926) (xy 2.54 -4.2926) (xy 2.54 -4.953)
				(xy -2.54 -4.953) (xy -2.54 -4.2926) (xy -3.81 -4.2926) (xy -3.81 -1.6256) (xy -2.1463 -1.6256)
				(xy -2.1463 -3.6449) (xy 2.1463 -3.6449) (xy 2.1463 3.6449) (xy -2.1463 3.6449) (xy -2.1463 -1.6129)
				(xy -3.81 -1.6129) (xy -3.81 4.2926) (xy -2.54 4.2926) (xy -2.54 4.953)
			)
			(stroke
				(width 0)
				(type default)
			)
			(fill no)
			(layer "B.CrtYd")
		)
		(fp_rect
			(start 2.54 4.953)
			(end -2.54 -4.953)
			(stroke
				(width 0)
				(type default)
			)
			(fill no)
			(layer "B.Fab")
		)
		(fp_rect
			(start -2.54 4.2926)
			(end -3.81 -4.2926)
			(stroke
				(width 0)
				(type default)
			)
			(fill no)
			(layer "B.Fab")
		)
		(fp_rect
			(start 3.81 4.2926)
			(end 2.54 -4.2926)
			(stroke
				(width 0)
				(type default)
			)
			(fill no)
			(layer "B.Fab")
		)
		(pad "1" smd rect
			(at 0 -3.1496 90)
			(size 2.413 2.286)
			(layers "B.Cu" "B.Mask" "B.Paste")
			(net "P12V_A_COMP")
		)
		(pad "2" smd rect
			(at 0 3.1496 90)
			(size 2.413 2.286)
			(layers "B.Cu" "B.Mask" "B.Paste")
			(net "GND")
		)
		(zone
			(layer "B.Cu")
			(hatch none 0.5)
			(connect_pads
				(clearance 0)
			)
			(min_thickness 0.25)
			(keepout
				(tracks allowed)
				(vias not_allowed)
				(pads allowed)
				(copperpour not_allowed)
				(footprints allowed)
			)
			(placement
				(enabled no)
				(sheetname "")
			)
			(fill
				(thermal_gap 0.5)
				(thermal_bridge_width 0.5)
				(island_removal_mode 0)
			)
			(polygon
				(pts
					(xy 215.683846 -105.950004) (xy 215.683846 -108.972604) (xy 218.579446 -108.972604) (xy 218.909646 -108.972604)
					(xy 218.909646 -105.950004) (xy 218.579446 -105.950004)
				)
			)
		)
		(zone
			(layer "B.Cu")
			(hatch none 0.5)
			(connect_pads
				(clearance 0)
			)
			(min_thickness 0.25)
			(keepout
				(tracks allowed)
				(vias not_allowed)
				(pads allowed)
				(copperpour not_allowed)
				(footprints allowed)
			)
			(placement
				(enabled no)
				(sheetname "")
			)
			(fill
				(thermal_gap 0.5)
				(thermal_bridge_width 0.5)
				(island_removal_mode 0)
			)
			(polygon
				(pts
					(xy 221.970346 -108.972604) (xy 224.878646 -108.972604) (xy 224.878646 -105.950004) (xy 221.983046 -105.950004)
					(xy 221.652846 -105.950004) (xy 221.652846 -108.972604)
				)
			)
		)
	)
	(footprint ""
		(layer "B.Cu")
		(at 192.180972 -228.396292 180)
		(property "Reference" "C672"
			(at 0 0 0)
			(layer "B.SilkS")
			(hide yes)
			(effects
				(font
					(size 1.27 1.27)
				)
				(justify mirror)
			)
		)
		(property "Value" "SC10U16V5KX-7-GP-U"
			(at 0.0762 -6.1214 180)
			(unlocked yes)
			(layer "B.Fab")
			(hide yes)
			(effects
				(font
					(size 1.016 1.016)
					(thickness 0.1524)
				)
				(justify mirror)
			)
		)
		(property "Device Type" "C805H58"
			(at 0.0762 -8.1534 180)
			(unlocked yes)
			(layer "B.Fab")
			(hide yes)
			(effects
				(font
					(size 1.016 1.016)
					(thickness 0.1524)
				)
				(justify mirror)
			)
		)
		(duplicate_pad_numbers_are_jumpers no)
		(fp_line
			(start -0.635 0)
			(end 0.635 0)
			(stroke
				(width 0.508)
				(type default)
			)
			(layer "B.SilkS")
		)
		(fp_rect
			(start 0.9652 1.778)
			(end -0.9652 -1.778)
			(stroke
				(width 0)
				(type default)
			)
			(fill no)
			(layer "B.CrtYd")
		)
		(fp_poly
			(pts
				(xy 0.9652 -1.778) (xy -0.9652 -1.778) (xy -0.9652 1.778) (xy 0.9652 1.778)
			)
			(stroke
				(width 0)
				(type default)
			)
			(fill no)
			(layer "B.Fab")
		)
		(pad "1" smd rect
			(at 0 -0.9652)
			(size 1.397 1.143)
			(layers "B.Cu" "B.Mask" "B.Paste")
			(net "P3V3_STBY_VIN")
		)
		(pad "2" smd rect
			(at 0 0.9652)
			(size 1.397 1.143)
			(layers "B.Cu" "B.Mask" "B.Paste")
			(net "GND")
		)
	)
	(footprint ""
		(layer "B.Cu")
		(at 470.408 -237.363 -90)
		(property "Reference" "C653"
			(at 0 0 90)
			(layer "B.SilkS")
			(hide yes)
			(effects
				(font
					(size 1.27 1.27)
				)
				(justify mirror)
			)
		)
		(property "Value" "SC10U16V5KX-7-GP-U"
			(at 0.0762 -6.1214 270)
			(unlocked yes)
			(layer "B.Fab")
			(hide yes)
			(effects
				(font
					(size 1.016 1.016)
					(thickness 0.1524)
				)
				(justify mirror)
			)
		)
		(property "Device Type" "C805H58"
			(at 0.0762 -8.1534 270)
			(unlocked yes)
			(layer "B.Fab")
			(hide yes)
			(effects
				(font
					(size 1.016 1.016)
					(thickness 0.1524)
				)
				(justify mirror)
			)
		)
		(duplicate_pad_numbers_are_jumpers no)
		(fp_line
			(start -0.635 0)
			(end 0.635 0)
			(stroke
				(width 0.508)
				(type default)
			)
			(layer "B.SilkS")
		)
		(fp_rect
			(start 0.9652 1.778)
			(end -0.9652 -1.778)
			(stroke
				(width 0)
				(type default)
			)
			(fill no)
			(layer "B.CrtYd")
		)
		(fp_poly
			(pts
				(xy 0.9652 -1.778) (xy -0.9652 -1.778) (xy -0.9652 1.778) (xy 0.9652 1.778)
			)
			(stroke
				(width 0)
				(type default)
			)
			(fill no)
			(layer "B.Fab")
		)
		(pad "1" smd rect
			(at 0 -0.9652 90)
			(size 1.397 1.143)
			(layers "B.Cu" "B.Mask" "B.Paste")
			(net "P12V_A_VIN_U27")
		)
		(pad "2" smd rect
			(at 0 0.9652 90)
			(size 1.397 1.143)
			(layers "B.Cu" "B.Mask" "B.Paste")
			(net "GND")
		)
	)
	(footprint ""
		(layer "B.Cu")
		(at 55.818024 -150.063454 -90)
		(property "Reference" "C626"
			(at 0 0 90)
			(layer "B.SilkS")
			(hide yes)
			(effects
				(font
					(size 1.27 1.27)
				)
				(justify mirror)
			)
		)
		(property "Value" "SC470P50V2KX-3GP"
			(at -1.1811 -2.7051 270)
			(unlocked yes)
			(layer "B.Fab")
			(hide yes)
			(effects
				(font
					(size 1.016 1.016)
					(thickness 0.1524)
				)
				(justify mirror)
			)
		)
		(property "Device Type" "C402H22"
			(at -1.1811 -4.2291 270)
			(unlocked yes)
			(layer "B.Fab")
			(hide yes)
			(effects
				(font
					(size 1.016 1.016)
					(thickness 0.1524)
				)
				(justify mirror)
			)
		)
		(duplicate_pad_numbers_are_jumpers no)
		(fp_rect
			(start 0.4318 0.9525)
			(end -0.4318 -0.9525)
			(stroke
				(width 0)
				(type default)
			)
			(fill no)
			(layer "B.CrtYd")
		)
		(fp_rect
			(start 0.4318 0.9525)
			(end -0.4318 -0.9525)
			(stroke
				(width 0)
				(type default)
			)
			(fill no)
			(layer "B.Fab")
		)
		(pad "1" smd custom
			(at 0 -0.4445 90)
			(size 0.1524 0.1524)
			(layers "B.Cu" "B.Mask" "B.Paste")
			(net "P5V_B_LL_R")
			(options
				(clearance outline)
				(anchor circle)
			)
			(primitives
				(gr_poly
					(pts
						(arc
							(start 0.3048 0.2032)
							(mid 0.275042 0.275042)
							(end 0.2032 0.3048)
						)
						(arc
							(start -0.2032 0.3048)
							(mid -0.275042 0.275042)
							(end -0.3048 0.2032)
						)
						(arc
							(start -0.3048 -0.2032)
							(mid -0.275042 -0.275042)
							(end -0.2032 -0.3048)
						)
						(arc
							(start 0.2032 -0.3048)
							(mid 0.275042 -0.275042)
							(end 0.3048 -0.2032)
						)
					)
					(width 0)
					(fill yes)
				)
			)
		)
		(pad "2" smd custom
			(at 0 0.4445 90)
			(size 0.1524 0.1524)
			(layers "B.Cu" "B.Mask" "B.Paste")
			(net "P5V_B_VFB")
			(options
				(clearance outline)
				(anchor circle)
			)
			(primitives
				(gr_poly
					(pts
						(arc
							(start 0.3048 0.2032)
							(mid 0.275042 0.275042)
							(end 0.2032 0.3048)
						)
						(arc
							(start -0.2032 0.3048)
							(mid -0.275042 0.275042)
							(end -0.3048 0.2032)
						)
						(arc
							(start -0.3048 -0.2032)
							(mid -0.275042 -0.275042)
							(end -0.2032 -0.3048)
						)
						(arc
							(start 0.2032 -0.3048)
							(mid 0.275042 -0.275042)
							(end 0.3048 -0.2032)
						)
					)
					(width 0)
					(fill yes)
				)
			)
		)
	)
	(footprint ""
		(layer "B.Cu")
		(at 482.219 -238.252 90)
		(property "Reference" "R1270"
			(at 0 0 90)
			(layer "B.SilkS")
			(hide yes)
			(effects
				(font
					(size 1.27 1.27)
				)
				(justify mirror)
			)
		)
		(property "Value" "200KR2F-L-GP"
			(at -0.064008 -3.993896 90)
			(unlocked yes)
			(layer "B.Fab")
			(hide yes)
			(effects
				(font
					(size 1.016 1.016)
					(thickness 0.1524)
				)
				(justify mirror)
			)
		)
		(property "Device Type" "R402H16"
			(at -0.064008 -5.517896 90)
			(unlocked yes)
			(layer "B.Fab")
			(hide yes)
			(effects
				(font
					(size 1.016 1.016)
					(thickness 0.1524)
				)
				(justify mirror)
			)
		)
		(duplicate_pad_numbers_are_jumpers no)
		(fp_line
			(start 0.508 -0.9398)
			(end 0.508 0.9398)
			(stroke
				(width 0.1524)
				(type default)
			)
			(layer "B.SilkS")
		)
		(fp_line
			(start -0.508 -0.9398)
			(end 0.508 -0.9398)
			(stroke
				(width 0.1524)
				(type default)
			)
			(layer "B.SilkS")
		)
		(fp_rect
			(start 0.508 0.9398)
			(end -0.508 -0.9398)
			(stroke
				(width 0)
				(type default)
			)
			(fill no)
			(layer "B.CrtYd")
		)
		(fp_rect
			(start 0.508 0.9398)
			(end -0.508 -0.9398)
			(stroke
				(width 0)
				(type default)
			)
			(fill no)
			(layer "B.Fab")
		)
		(pad "1" smd custom
			(at 0 -0.4445 270)
			(size 0.1397 0.1397)
			(layers "B.Cu" "B.Mask" "B.Paste")
			(net "P5V_D_MODE")
			(options
				(clearance outline)
				(anchor circle)
			)
			(primitives
				(gr_poly
					(pts
						(arc
							(start -0.1778 0.2794)
							(mid -0.249642 0.249642)
							(end -0.2794 0.1778)
						)
						(arc
							(start -0.2794 -0.1778)
							(mid -0.249642 -0.249642)
							(end -0.1778 -0.2794)
						)
						(arc
							(start 0.1778 -0.2794)
							(mid 0.249642 -0.249642)
							(end 0.2794 -0.1778)
						)
						(arc
							(start 0.2794 0.1778)
							(mid 0.249642 0.249642)
							(end 0.1778 0.2794)
						)
					)
					(width 0)
					(fill yes)
				)
			)
		)
		(pad "2" smd custom
			(at 0 0.4445 270)
			(size 0.1397 0.1397)
			(layers "B.Cu" "B.Mask" "B.Paste")
			(net "P5V_A_4_PGOOD")
			(options
				(clearance outline)
				(anchor circle)
			)
			(primitives
				(gr_poly
					(pts
						(arc
							(start -0.1778 0.2794)
							(mid -0.249642 0.249642)
							(end -0.2794 0.1778)
						)
						(arc
							(start -0.2794 -0.1778)
							(mid -0.249642 -0.249642)
							(end -0.1778 -0.2794)
						)
						(arc
							(start 0.1778 -0.2794)
							(mid 0.249642 -0.249642)
							(end 0.2794 -0.1778)
						)
						(arc
							(start 0.2794 0.1778)
							(mid 0.249642 0.249642)
							(end 0.1778 0.2794)
						)
					)
					(width 0)
					(fill yes)
				)
			)
		)
	)
	(footprint ""
		(layer "B.Cu")
		(at 455.893424 -257.759454 -90)
		(property "Reference" "C643"
			(at 0 0 90)
			(layer "B.SilkS")
			(hide yes)
			(effects
				(font
					(size 1.27 1.27)
				)
				(justify mirror)
			)
		)
		(property "Value" "SC470P50V2KX-3GP"
			(at -1.1811 -2.7051 270)
			(unlocked yes)
			(layer "B.Fab")
			(hide yes)
			(effects
				(font
					(size 1.016 1.016)
					(thickness 0.1524)
				)
				(justify mirror)
			)
		)
		(property "Device Type" "C402H22"
			(at -1.1811 -4.2291 270)
			(unlocked yes)
			(layer "B.Fab")
			(hide yes)
			(effects
				(font
					(size 1.016 1.016)
					(thickness 0.1524)
				)
				(justify mirror)
			)
		)
		(duplicate_pad_numbers_are_jumpers no)
		(fp_rect
			(start 0.4318 0.9525)
			(end -0.4318 -0.9525)
			(stroke
				(width 0)
				(type default)
			)
			(fill no)
			(layer "B.CrtYd")
		)
		(fp_rect
			(start 0.4318 0.9525)
			(end -0.4318 -0.9525)
			(stroke
				(width 0)
				(type default)
			)
			(fill no)
			(layer "B.Fab")
		)
		(pad "1" smd custom
			(at 0 -0.4445 90)
			(size 0.1524 0.1524)
			(layers "B.Cu" "B.Mask" "B.Paste")
			(net "P5V_C_LL_R")
			(options
				(clearance outline)
				(anchor circle)
			)
			(primitives
				(gr_poly
					(pts
						(arc
							(start 0.3048 0.2032)
							(mid 0.275042 0.275042)
							(end 0.2032 0.3048)
						)
						(arc
							(start -0.2032 0.3048)
							(mid -0.275042 0.275042)
							(end -0.3048 0.2032)
						)
						(arc
							(start -0.3048 -0.2032)
							(mid -0.275042 -0.275042)
							(end -0.2032 -0.3048)
						)
						(arc
							(start 0.2032 -0.3048)
							(mid 0.275042 -0.275042)
							(end 0.3048 -0.2032)
						)
					)
					(width 0)
					(fill yes)
				)
			)
		)
		(pad "2" smd custom
			(at 0 0.4445 90)
			(size 0.1524 0.1524)
			(layers "B.Cu" "B.Mask" "B.Paste")
			(net "P5V_C_VFB")
			(options
				(clearance outline)
				(anchor circle)
			)
			(primitives
				(gr_poly
					(pts
						(arc
							(start 0.3048 0.2032)
							(mid 0.275042 0.275042)
							(end 0.2032 0.3048)
						)
						(arc
							(start -0.2032 0.3048)
							(mid -0.275042 0.275042)
							(end -0.3048 0.2032)
						)
						(arc
							(start -0.3048 -0.2032)
							(mid -0.275042 -0.275042)
							(end -0.2032 -0.3048)
						)
						(arc
							(start 0.2032 -0.3048)
							(mid 0.275042 -0.275042)
							(end 0.3048 -0.2032)
						)
					)
					(width 0)
					(fill yes)
				)
			)
		)
	)
	(footprint ""
		(layer "B.Cu")
		(at 56.134 -252.1966 180)
		(property "Reference" "C611"
			(at 0 0 0)
			(layer "B.SilkS")
			(hide yes)
			(effects
				(font
					(size 1.27 1.27)
				)
				(justify mirror)
			)
		)
		(property "Value" "SC10U16V5KX-7-GP-U"
			(at 0.0762 -6.1214 180)
			(unlocked yes)
			(layer "B.Fab")
			(hide yes)
			(effects
				(font
					(size 1.016 1.016)
					(thickness 0.1524)
				)
				(justify mirror)
			)
		)
		(property "Device Type" "C805H58"
			(at 0.0762 -8.1534 180)
			(unlocked yes)
			(layer "B.Fab")
			(hide yes)
			(effects
				(font
					(size 1.016 1.016)
					(thickness 0.1524)
				)
				(justify mirror)
			)
		)
		(duplicate_pad_numbers_are_jumpers no)
		(fp_line
			(start -0.635 0)
			(end 0.635 0)
			(stroke
				(width 0.508)
				(type default)
			)
			(layer "B.SilkS")
		)
		(fp_rect
			(start 0.9652 1.778)
			(end -0.9652 -1.778)
			(stroke
				(width 0)
				(type default)
			)
			(fill no)
			(layer "B.CrtYd")
		)
		(fp_poly
			(pts
				(xy 0.9652 -1.778) (xy -0.9652 -1.778) (xy -0.9652 1.778) (xy 0.9652 1.778)
			)
			(stroke
				(width 0)
				(type default)
			)
			(fill no)
			(layer "B.Fab")
		)
		(pad "1" smd rect
			(at 0 -0.9652)
			(size 1.397 1.143)
			(layers "B.Cu" "B.Mask" "B.Paste")
			(net "P5V_A_1")
		)
		(pad "2" smd rect
			(at 0 0.9652)
			(size 1.397 1.143)
			(layers "B.Cu" "B.Mask" "B.Paste")
			(net "GND")
		)
	)
	(footprint ""
		(layer "B.Cu")
		(at 389.349996 -30.550104 180)
		(property "Reference" "IO2"
			(at 0 0 0)
			(layer "B.SilkS")
			(hide yes)
			(effects
				(font
					(size 1.27 1.27)
				)
				(justify mirror)
			)
		)
		(property "Value" "DM-AMP-CONN200-13R-6-GP-01"
			(at 47.5488 -16.5862 180)
			(unlocked yes)
			(layer "B.Fab")
			(hide yes)
			(effects
				(font
					(size 1.016 1.016)
					(thickness 0.1524)
				)
				(justify mirror)
			)
		)
		(property "Device Type" "DMFIT-200P-384346H577-01"
			(at 47.5488 -18.1102 180)
			(unlocked yes)
			(layer "B.Fab")
			(hide yes)
			(effects
				(font
					(size 1.016 1.016)
					(thickness 0.1524)
				)
				(justify mirror)
			)
		)
		(duplicate_pad_numbers_are_jumpers no)
		(fp_line
			(start 36.703 3.9878)
			(end 36.703 -15.54988)
			(stroke
				(width 0.1524)
				(type default)
			)
			(layer "B.SilkS")
		)
		(fp_line
			(start 36.703 -15.54988)
			(end -2.2098 -15.54988)
			(stroke
				(width 0.1524)
				(type default)
			)
			(layer "B.SilkS")
		)
		(fp_line
			(start -2.2098 3.9878)
			(end 36.703 3.9878)
			(stroke
				(width 0.1524)
				(type default)
			)
			(layer "B.SilkS")
		)
		(fp_line
			(start -2.2098 -15.54988)
			(end -2.2098 3.9878)
			(stroke
				(width 0.1524)
				(type default)
			)
			(layer "B.SilkS")
		)
		(fp_poly
			(pts
				(xy 36.703 3.9878) (xy 36.703 -15.54988) (xy -2.2098 -15.54988) (xy -2.2098 3.9878) (xy 11.9634 3.9878)
				(xy 11.9634 2.2098) (xy -0.5842 2.2098) (xy -0.5842 -14.884146) (xy 34.784284 -14.884146) (xy 34.784284 2.2098)
				(xy 22.3774 2.2098) (xy 22.3774 3.9878)
			)
			(stroke
				(width 0)
				(type default)
			)
			(fill yes)
			(layer "B.SilkS")
		)
		(fp_poly
			(pts
				(arc
					(start 33.947862 1.778)
					(mid 34.201862 2.032)
					(end 34.455862 1.778)
				)
				(arc
					(start 34.455862 1.016)
					(mid 34.201862 0.762)
					(end 33.947862 1.016)
				)
			)
			(stroke
				(width 0)
				(type default)
			)
			(fill yes)
			(layer "B.SilkS")
		)
		(fp_poly
			(pts
				(arc
					(start 32.147764 1.778)
					(mid 32.401764 2.032)
					(end 32.655764 1.778)
				)
				(arc
					(start 32.655764 1.016)
					(mid 32.401764 0.762)
					(end 32.147764 1.016)
				)
			)
			(stroke
				(width 0)
				(type default)
			)
			(fill yes)
			(layer "B.SilkS")
		)
		(fp_poly
			(pts
				(arc
					(start 30.347666 1.778)
					(mid 30.601666 2.032)
					(end 30.855666 1.778)
				)
				(arc
					(start 30.855666 1.016)
					(mid 30.601666 0.762)
					(end 30.347666 1.016)
				)
			)
			(stroke
				(width 0)
				(type default)
			)
			(fill yes)
			(layer "B.SilkS")
		)
		(fp_poly
			(pts
				(arc
					(start 28.547568 1.778)
					(mid 28.801568 2.032)
					(end 29.055568 1.778)
				)
				(arc
					(start 29.055568 1.016)
					(mid 28.801568 0.762)
					(end 28.547568 1.016)
				)
			)
			(stroke
				(width 0)
				(type default)
			)
			(fill yes)
			(layer "B.SilkS")
		)
		(fp_poly
			(pts
				(arc
					(start 26.74747 1.778)
					(mid 27.00147 2.032)
					(end 27.25547 1.778)
				)
				(arc
					(start 27.25547 1.016)
					(mid 27.00147 0.762)
					(end 26.74747 1.016)
				)
			)
			(stroke
				(width 0)
				(type default)
			)
			(fill yes)
			(layer "B.SilkS")
		)
		(fp_poly
			(pts
				(arc
					(start 24.947372 1.778)
					(mid 25.201372 2.032)
					(end 25.455372 1.778)
				)
				(arc
					(start 25.455372 1.016)
					(mid 25.201372 0.762)
					(end 24.947372 1.016)
				)
			)
			(stroke
				(width 0)
				(type default)
			)
			(fill yes)
			(layer "B.SilkS")
		)
		(fp_poly
			(pts
				(arc
					(start 23.147274 1.778)
					(mid 23.401274 2.032)
					(end 23.655274 1.778)
				)
				(arc
					(start 23.655274 1.016)
					(mid 23.401274 0.762)
					(end 23.147274 1.016)
				)
			)
			(stroke
				(width 0)
				(type default)
			)
			(fill yes)
			(layer "B.SilkS")
		)
		(fp_poly
			(pts
				(arc
					(start 21.347176 1.778)
					(mid 21.601176 2.032)
					(end 21.855176 1.778)
				)
				(arc
					(start 21.855176 1.016)
					(mid 21.601176 0.762)
					(end 21.347176 1.016)
				)
			)
			(stroke
				(width 0)
				(type default)
			)
			(fill yes)
			(layer "B.SilkS")
		)
		(fp_poly
			(pts
				(arc
					(start 12.346686 1.778)
					(mid 12.600686 2.032)
					(end 12.854686 1.778)
				)
				(arc
					(start 12.854686 1.016)
					(mid 12.600686 0.762)
					(end 12.346686 1.016)
				)
			)
			(stroke
				(width 0)
				(type default)
			)
			(fill yes)
			(layer "B.SilkS")
		)
		(fp_poly
			(pts
				(arc
					(start 10.546588 1.778)
					(mid 10.800588 2.032)
					(end 11.054588 1.778)
				)
				(arc
					(start 11.054588 1.016)
					(mid 10.800588 0.762)
					(end 10.546588 1.016)
				)
			)
			(stroke
				(width 0)
				(type default)
			)
			(fill yes)
			(layer "B.SilkS")
		)
		(fp_poly
			(pts
				(arc
					(start 8.74649 1.778)
					(mid 9.00049 2.032)
					(end 9.25449 1.778)
				)
				(arc
					(start 9.25449 1.016)
					(mid 9.00049 0.762)
					(end 8.74649 1.016)
				)
			)
			(stroke
				(width 0)
				(type default)
			)
			(fill yes)
			(layer "B.SilkS")
		)
		(fp_poly
			(pts
				(arc
					(start 6.946392 1.778)
					(mid 7.200392 2.032)
					(end 7.454392 1.778)
				)
				(arc
					(start 7.454392 1.016)
					(mid 7.200392 0.762)
					(end 6.946392 1.016)
				)
			)
			(stroke
				(width 0)
				(type default)
			)
			(fill yes)
			(layer "B.SilkS")
		)
		(fp_poly
			(pts
				(arc
					(start 5.146294 1.778)
					(mid 5.400294 2.032)
					(end 5.654294 1.778)
				)
				(arc
					(start 5.654294 1.016)
					(mid 5.400294 0.762)
					(end 5.146294 1.016)
				)
			)
			(stroke
				(width 0)
				(type default)
			)
			(fill yes)
			(layer "B.SilkS")
		)
		(fp_poly
			(pts
				(arc
					(start 3.346196 1.778)
					(mid 3.600196 2.032)
					(end 3.854196 1.778)
				)
				(arc
					(start 3.854196 1.016)
					(mid 3.600196 0.762)
					(end 3.346196 1.016)
				)
			)
			(stroke
				(width 0)
				(type default)
			)
			(fill yes)
			(layer "B.SilkS")
		)
		(fp_poly
			(pts
				(arc
					(start 1.546098 1.778)
					(mid 1.800098 2.032)
					(end 2.054098 1.778)
				)
				(arc
					(start 2.054098 1.016)
					(mid 1.800098 0.762)
					(end 1.546098 1.016)
				)
			)
			(stroke
				(width 0)
				(type default)
			)
			(fill yes)
			(layer "B.SilkS")
		)
		(fp_poly
			(pts
				(arc
					(start -0.254 1.778)
					(mid 0 2.032)
					(end 0.254 1.778)
				)
				(arc
					(start 0.254 1.016)
					(mid 0 0.762)
					(end -0.254 1.016)
				)
			)
			(stroke
				(width 0)
				(type default)
			)
			(fill yes)
			(layer "B.SilkS")
		)
		(fp_rect
			(start 36.449 3.7338)
			(end -1.9558 -30.861)
			(stroke
				(width 0)
				(type default)
			)
			(fill no)
			(layer "B.CrtYd")
		)
		(fp_poly
			(pts
				(xy 41.4528 8.7376) (xy 41.4528 -35.8648) (xy -6.9596 -35.8648) (xy -6.9596 -0.00635) (xy -2.4638 -0.00635)
				(xy -2.4638 -31.369) (xy 36.957 -31.369) (xy 36.957 4.2418) (xy -2.4638 4.2418) (xy -2.4638 0.00635)
				(xy -6.9596 0.00635) (xy -6.9596 8.7376)
			)
			(stroke
				(width 0)
				(type default)
			)
			(fill no)
			(layer "B.CrtYd")
		)
		(fp_poly
			(pts
				(xy 36.957 4.2418) (xy 36.957 -31.369) (xy -2.4638 -31.369) (xy -2.4638 -0.00635) (xy -1.9558 -0.00635)
				(xy -1.9558 -30.861) (xy 36.449 -30.861) (xy 36.449 3.7338) (xy -1.9558 3.7338) (xy -1.9558 0.00635)
				(xy -2.4638 0.00635) (xy -2.4638 4.2418)
			)
			(stroke
				(width 0)
				(type default)
			)
			(fill no)
			(layer "B.CrtYd")
		)
		(fp_rect
			(start 39.5986 5.4864)
			(end -5.3848 -19.685)
			(stroke
				(width 0)
				(type default)
			)
			(fill no)
			(layer "F.CrtYd")
		)
		(fp_rect
			(start 46.4566 13.7414)
			(end -11.9634 -40.8686)
			(stroke
				(width 0)
				(type default)
			)
			(fill no)
			(layer "B.Fab")
		)
		(fp_rect
			(start 41.4528 8.7376)
			(end -6.9596 -35.8648)
			(stroke
				(width 0)
				(type default)
			)
			(fill no)
			(layer "B.Fab")
		)
		(fp_rect
			(start 36.957 4.2418)
			(end -2.4638 -31.369)
			(stroke
				(width 0)
				(type default)
			)
			(fill no)
			(layer "B.Fab")
		)
		(fp_rect
			(start 44.6024 10.4902)
			(end -10.3886 -24.6888)
			(stroke
				(width 0)
				(type default)
			)
			(fill no)
			(layer "F.Fab")
		)
		(fp_rect
			(start 39.5986 5.4864)
			(end -5.3848 -19.685)
			(stroke
				(width 0)
				(type default)
			)
			(fill no)
			(layer "F.Fab")
		)
		(fp_text user "Press Fit"
			(at 22.2504 3.1242 180)
			(unlocked yes)
			(layer "B.SilkS")
			(effects
				(font
					(size 1.016 1.016)
					(thickness 0.1524)
				)
				(justify left mirror)
			)
		)
		(fp_text user "Slit"
			(at 19.27987 -18.071846 180)
			(unlocked yes)
			(layer "B.SilkS")
			(effects
				(font
					(size 1.016 1.016)
					(thickness 0.1524)
				)
				(justify left mirror)
			)
		)
		(fp_text user "Can not place BGA,CSP,Wave Solder Component"
			(at 42.5704 -39.1922 180)
			(unlocked yes)
			(layer "B.Fab")
			(effects
				(font
					(size 1.016 1.016)
					(thickness 0.1524)
				)
				(justify left mirror)
			)
		)
		(fp_text user "High Limit 2mm"
			(at 24.6126 -34.5694 180)
			(unlocked yes)
			(layer "B.Fab")
			(effects
				(font
					(size 1.016 1.016)
					(thickness 0.1524)
				)
				(justify left mirror)
			)
		)
		(fp_text user "Can not place BGA,CSP,Wave Solder Component"
			(at 42.3418 -23.4442 180)
			(unlocked yes)
			(layer "F.Fab")
			(effects
				(font
					(size 1.016 1.016)
					(thickness 0.1524)
				)
				(justify left mirror)
			)
		)
		(pad "" np_thru_hole circle
			(at 17.200118 -9.99998)
			(size 0.254 0.254)
			(drill 2.3876)
			(layers "*.Cu" "*.Mask")
			(clearance 1.4224)
			(thermal_gap 1.4224)
		)
		(pad "" np_thru_hole circle
			(at 17.200118 -2.469896)
			(size 0.254 0.254)
			(drill 2.4638)
			(layers "*.Cu" "*.Mask")
			(clearance 1.4605)
			(thermal_gap 1.4605)
		)
		(pad "A1" thru_hole circle
			(at 0 0)
			(size 0.762 0.762)
			(drill 0.359918)
			(layers "*.Cu" "*.Mask")
			(remove_unused_layers no)
			(net "PCIE_COMP_B_TO_IOM_B_CLK_2_DN")
			(clearance 0.1651)
			(thermal_gap 0.1651)
		)
		(pad "A2" thru_hole circle
			(at 1.800098 -0.999998)
			(size 0.762 0.762)
			(drill 0.359918)
			(layers "*.Cu" "*.Mask")
			(remove_unused_layers no)
			(net "I2C_BMC_B_MISC_SDA")
			(clearance 0.1651)
			(thermal_gap 0.1651)
		)
		(pad "A3" thru_hole circle
			(at 3.599942 0)
			(size 0.762 0.762)
			(drill 0.359918)
			(layers "*.Cu" "*.Mask")
			(remove_unused_layers no)
			(net "BMC_B_HEARTBEAT")
			(clearance 0.1651)
			(thermal_gap 0.1651)
		)
		(pad "A4" thru_hole circle
			(at 5.40004 -0.999998)
			(size 0.762 0.762)
			(drill 0.359918)
			(layers "*.Cu" "*.Mask")
			(remove_unused_layers no)
			(net "SCC_A_FULL_PWR_EN")
			(clearance 0.1651)
			(thermal_gap 0.1651)
		)
		(pad "A5" thru_hole circle
			(at 7.199884 0)
			(size 0.762 0.762)
			(drill 0.359918)
			(layers "*.Cu" "*.Mask")
			(remove_unused_layers no)
			(net "PCIE_COMP_B_TO_IOM_B_CLK_3_DN")
			(clearance 0.1651)
			(thermal_gap 0.1651)
		)
		(pad "A6" thru_hole circle
			(at 8.999982 -0.999998)
			(size 0.762 0.762)
			(drill 0.359918)
			(layers "*.Cu" "*.Mask")
			(remove_unused_layers no)
			(net "I2C_BMC_B_EXP_B_SDA")
			(clearance 0.1651)
			(thermal_gap 0.1651)
		)
		(pad "A7" thru_hole circle
			(at 10.80008 0)
			(size 0.762 0.762)
			(drill 0.359918)
			(layers "*.Cu" "*.Mask")
			(remove_unused_layers no)
			(net "P12V_B")
			(clearance 0.1651)
			(thermal_gap 0.1651)
		)
		(pad "A8" thru_hole circle
			(at 12.599924 -0.999998)
			(size 0.762 0.762)
			(drill 0.359918)
			(layers "*.Cu" "*.Mask")
			(remove_unused_layers no)
			(net "P12V_B")
			(clearance 0.1651)
			(thermal_gap 0.1651)
		)
		(pad "A9" thru_hole circle
			(at 21.599906 0)
			(size 0.762 0.762)
			(drill 0.359918)
			(layers "*.Cu" "*.Mask")
			(remove_unused_layers no)
			(net "PCIE_COMP_B_TO_IOM_B_CLK_4_DN")
			(clearance 0.1651)
			(thermal_gap 0.1651)
		)
		(pad "A10" thru_hole circle
			(at 23.400004 -0.999998)
			(size 0.762 0.762)
			(drill 0.359918)
			(layers "*.Cu" "*.Mask")
			(remove_unused_layers no)
			(net "IOM_B_SLOT_ID_1")
			(clearance 0.1651)
			(thermal_gap 0.1651)
		)
		(pad "A11" thru_hole circle
			(at 25.200102 0)
			(size 0.762 0.762)
			(drill 0.359918)
			(layers "*.Cu" "*.Mask")
			(remove_unused_layers no)
			(net "BMC_B_TO_EXP_B_RESET_N")
			(clearance 0.1651)
			(thermal_gap 0.1651)
		)
		(pad "A12" thru_hole circle
			(at 26.999946 -0.999998)
			(size 0.762 0.762)
			(drill 0.359918)
			(layers "*.Cu" "*.Mask")
			(remove_unused_layers no)
			(net "USB_COMP_B_DN")
			(clearance 0.1651)
			(thermal_gap 0.1651)
		)
		(pad "A13" thru_hole circle
			(at 28.800044 0)
			(size 0.762 0.762)
			(drill 0.359918)
			(layers "*.Cu" "*.Mask")
			(remove_unused_layers no)
			(net "COMP_B_TO_BMC_B_RESET_N")
			(clearance 0.1651)
			(thermal_gap 0.1651)
		)
		(pad "A14" thru_hole circle
			(at 30.599888 -0.999998)
			(size 0.762 0.762)
			(drill 0.359918)
			(layers "*.Cu" "*.Mask")
			(remove_unused_layers no)
			(net "I2C_DPB_B_SDA")
			(clearance 0.1651)
			(thermal_gap 0.1651)
		)
		(pad "A15" thru_hole circle
			(at 32.399986 0)
			(size 0.762 0.762)
			(drill 0.359918)
			(layers "*.Cu" "*.Mask")
			(remove_unused_layers no)
			(net "BMC_B_EXP_B_SPARE_1")
			(clearance 0.1651)
			(thermal_gap 0.1651)
		)
		(pad "A16" thru_hole circle
			(at 34.200084 -0.999998)
			(size 0.762 0.762)
			(drill 0.359918)
			(layers "*.Cu" "*.Mask")
			(remove_unused_layers no)
			(net "COMP_B_BMC_B_SPARE_1")
			(clearance 0.1651)
			(thermal_gap 0.1651)
		)
		(pad "B1" thru_hole circle
			(at 0 -1.400048)
			(size 0.762 0.762)
			(drill 0.359918)
			(layers "*.Cu" "*.Mask")
			(remove_unused_layers no)
			(net "PCIE_COMP_B_TO_IOM_B_CLK_2_DP")
			(clearance 0.1651)
			(thermal_gap 0.1651)
		)
		(pad "B2" thru_hole circle
			(at 1.800098 -2.400046)
			(size 0.762 0.762)
			(drill 0.359918)
			(layers "*.Cu" "*.Mask")
			(remove_unused_layers no)
			(net "I2C_BMC_B_MISC_SCL")
			(clearance 0.1651)
			(thermal_gap 0.1651)
		)
		(pad "B3" thru_hole circle
			(at 3.599942 -1.400048)
			(size 0.762 0.762)
			(drill 0.359918)
			(layers "*.Cu" "*.Mask")
			(remove_unused_layers no)
			(net "BMC_A_HEARTBEAT")
			(clearance 0.1651)
			(thermal_gap 0.1651)
		)
		(pad "B4" thru_hole circle
			(at 5.40004 -2.400046)
			(size 0.762 0.762)
			(drill 0.359918)
			(layers "*.Cu" "*.Mask")
			(remove_unused_layers no)
			(net "SCC_B_FULL_PWR_EN")
			(clearance 0.1651)
			(thermal_gap 0.1651)
		)
		(pad "B5" thru_hole circle
			(at 7.199884 -1.400048)
			(size 0.762 0.762)
			(drill 0.359918)
			(layers "*.Cu" "*.Mask")
			(remove_unused_layers no)
			(net "PCIE_COMP_B_TO_IOM_B_CLK_3_DP")
			(clearance 0.1651)
			(thermal_gap 0.1651)
		)
		(pad "B6" thru_hole circle
			(at 8.999982 -2.400046)
			(size 0.762 0.762)
			(drill 0.359918)
			(layers "*.Cu" "*.Mask")
			(remove_unused_layers no)
			(net "I2C_BMC_B_EXP_B_SCL")
			(clearance 0.1651)
			(thermal_gap 0.1651)
		)
		(pad "B7" thru_hole circle
			(at 10.80008 -1.400048)
			(size 0.762 0.762)
			(drill 0.359918)
			(layers "*.Cu" "*.Mask")
			(remove_unused_layers no)
			(net "P12V_B_PGOOD")
			(clearance 0.1651)
			(thermal_gap 0.1651)
		)
		(pad "B8" thru_hole circle
			(at 12.599924 -2.400046)
			(size 0.762 0.762)
			(drill 0.359918)
			(layers "*.Cu" "*.Mask")
			(remove_unused_layers no)
			(net "P12V_B")
			(clearance 0.1651)
			(thermal_gap 0.1651)
		)
		(pad "B9" thru_hole circle
			(at 21.599906 -1.400048)
			(size 0.762 0.762)
			(drill 0.359918)
			(layers "*.Cu" "*.Mask")
			(remove_unused_layers no)
			(net "PCIE_COMP_B_TO_IOM_B_CLK_4_DP")
			(clearance 0.1651)
			(thermal_gap 0.1651)
		)
		(pad "B10" thru_hole circle
			(at 23.400004 -2.400046)
			(size 0.762 0.762)
			(drill 0.359918)
			(layers "*.Cu" "*.Mask")
			(remove_unused_layers no)
			(net "IOM_B_SLOT_ID_0")
			(clearance 0.1651)
			(thermal_gap 0.1651)
		)
		(pad "B11" thru_hole circle
			(at 25.200102 -1.400048)
			(size 0.762 0.762)
			(drill 0.359918)
			(layers "*.Cu" "*.Mask")
			(remove_unused_layers no)
			(net "BMC_B_MISC_ALERT_N")
			(clearance 0.1651)
			(thermal_gap 0.1651)
		)
		(pad "B12" thru_hole circle
			(at 26.999946 -2.400046)
			(size 0.762 0.762)
			(drill 0.359918)
			(layers "*.Cu" "*.Mask")
			(remove_unused_layers no)
			(net "USB_COMP_B_DP")
			(clearance 0.1651)
			(thermal_gap 0.1651)
		)
		(pad "B13" thru_hole circle
			(at 28.800044 -1.400048)
			(size 0.762 0.762)
			(drill 0.359918)
			(layers "*.Cu" "*.Mask")
			(remove_unused_layers no)
			(net "SYS_B_RESET_N")
			(clearance 0.1651)
			(thermal_gap 0.1651)
		)
		(pad "B14" thru_hole circle
			(at 30.599888 -2.400046)
			(size 0.762 0.762)
			(drill 0.359918)
			(layers "*.Cu" "*.Mask")
			(remove_unused_layers no)
			(net "I2C_DPB_B_SCL")
			(clearance 0.1651)
			(thermal_gap 0.1651)
		)
		(pad "B15" thru_hole circle
			(at 32.399986 -1.400048)
			(size 0.762 0.762)
			(drill 0.359918)
			(layers "*.Cu" "*.Mask")
			(remove_unused_layers no)
			(net "BMC_B_EXP_B_SPARE_0")
			(clearance 0.1651)
			(thermal_gap 0.1651)
		)
		(pad "B16" thru_hole circle
			(at 34.200084 -2.400046)
			(size 0.762 0.762)
			(drill 0.359918)
			(layers "*.Cu" "*.Mask")
			(remove_unused_layers no)
			(net "COMP_B_BMC_B_SPARE_0")
			(clearance 0.1651)
			(thermal_gap 0.1651)
		)
		(pad "C1" thru_hole circle
			(at 0 -3.599942)
			(size 0.762 0.762)
			(drill 0.359918)
			(layers "*.Cu" "*.Mask")
			(remove_unused_layers no)
			(net "IOM_B_MATED_N")
			(clearance 0.1651)
			(thermal_gap 0.1651)
		)
		(pad "C2" thru_hole circle
			(at 1.800098 -4.59994)
			(size 0.762 0.762)
			(drill 0.359918)
			(layers "*.Cu" "*.Mask")
			(remove_unused_layers no)
			(net "I2C_SCC_B_SDA")
			(clearance 0.1651)
			(thermal_gap 0.1651)
		)
		(pad "C3" thru_hole circle
			(at 3.599942 -3.599942)
			(size 0.762 0.762)
			(drill 0.359918)
			(layers "*.Cu" "*.Mask")
			(remove_unused_layers no)
			(net "SCC_A_HEARTBEAT")
			(clearance 0.1651)
			(thermal_gap 0.1651)
		)
		(pad "C4" thru_hole circle
			(at 5.40004 -4.59994)
			(size 0.762 0.762)
			(drill 0.359918)
			(layers "*.Cu" "*.Mask")
			(remove_unused_layers no)
			(net "IOM_B_PWR_LED")
			(clearance 0.1651)
			(thermal_gap 0.1651)
		)
		(pad "C5" thru_hole circle
			(at 7.199884 -3.599942)
			(size 0.762 0.762)
			(drill 0.359918)
			(layers "*.Cu" "*.Mask")
			(remove_unused_layers no)
			(net "IOM_B_INS_N")
			(clearance 0.1651)
			(thermal_gap 0.1651)
		)
		(pad "C6" thru_hole circle
			(at 8.999982 -4.59994)
			(size 0.762 0.762)
			(drill 0.359918)
			(layers "*.Cu" "*.Mask")
			(remove_unused_layers no)
			(net "I2C_BMC_B_EXP_A_SDA")
			(clearance 0.1651)
			(thermal_gap 0.1651)
		)
		(pad "C7" thru_hole circle
			(at 10.80008 -3.599942)
			(size 0.762 0.762)
			(drill 0.359918)
			(layers "*.Cu" "*.Mask")
			(remove_unused_layers no)
			(net "UART_SDB_B_RX")
			(clearance 0.1651)
			(thermal_gap 0.1651)
		)
		(pad "C8" thru_hole circle
			(at 12.599924 -4.59994)
			(size 0.762 0.762)
			(drill 0.359918)
			(layers "*.Cu" "*.Mask")
			(remove_unused_layers no)
			(net "P12V_B")
			(clearance 0.1651)
			(thermal_gap 0.1651)
		)
		(pad "C9" thru_hole circle
			(at 21.599906 -3.599942)
			(size 0.762 0.762)
			(drill 0.359918)
			(layers "*.Cu" "*.Mask")
			(remove_unused_layers no)
			(net "COMP_B_BMC_B_ALERT_N")
			(clearance 0.1651)
			(thermal_gap 0.1651)
		)
		(pad "C10" thru_hole circle
			(at 23.400004 -4.59994)
			(size 0.762 0.762)
			(drill 0.359918)
			(layers "*.Cu" "*.Mask")
			(remove_unused_layers no)
			(net "I2C_BMC_B_COMP_B_SDA_BUF")
			(clearance 0.1651)
			(thermal_gap 0.1651)
		)
		(pad "C11" thru_hole circle
			(at 25.200102 -3.599942)
			(size 0.762 0.762)
			(drill 0.359918)
			(layers "*.Cu" "*.Mask")
			(remove_unused_layers no)
			(net "UART_COMP_B_RX")
			(clearance 0.1651)
			(thermal_gap 0.1651)
		)
		(pad "C12" thru_hole circle
			(at 26.999946 -4.59994)
			(size 0.762 0.762)
			(drill 0.359918)
			(layers "*.Cu" "*.Mask")
			(remove_unused_layers no)
			(net "COMP_B_PWR_EN")
			(clearance 0.1651)
			(thermal_gap 0.1651)
		)
		(pad "C13" thru_hole circle
			(at 28.800044 -3.599942)
			(size 0.762 0.762)
			(drill 0.359918)
			(layers "*.Cu" "*.Mask")
			(remove_unused_layers no)
			(net "COMP_B_POWER_FAIL_N")
			(clearance 0.1651)
			(thermal_gap 0.1651)
		)
		(pad "C14" thru_hole circle
			(at 30.599888 -4.59994)
			(size 0.762 0.762)
			(drill 0.359918)
			(layers "*.Cu" "*.Mask")
			(remove_unused_layers no)
			(net "Net_16")
			(clearance 0.1651)
			(thermal_gap 0.1651)
		)
		(pad "C15" thru_hole circle
			(at 32.399986 -3.599942)
			(size 0.762 0.762)
			(drill 0.359918)
			(layers "*.Cu" "*.Mask")
			(remove_unused_layers no)
			(net "Net_17")
			(clearance 0.1651)
			(thermal_gap 0.1651)
		)
		(pad "C16" thru_hole circle
			(at 34.200084 -4.59994)
			(size 0.762 0.762)
			(drill 0.359918)
			(layers "*.Cu" "*.Mask")
			(remove_unused_layers no)
			(net "PWM_BMC_B_ZONE_C")
			(clearance 0.1651)
			(thermal_gap 0.1651)
		)
		(pad "D1" thru_hole circle
			(at 0 -4.99999)
			(size 0.762 0.762)
			(drill 0.359918)
			(layers "*.Cu" "*.Mask")
			(remove_unused_layers no)
			(net "PCIE_COMP_B_TO_IOM_B_RST_2")
			(clearance 0.1651)
			(thermal_gap 0.1651)
		)
		(pad "D2" thru_hole circle
			(at 1.800098 -5.999988)
			(size 0.762 0.762)
			(drill 0.359918)
			(layers "*.Cu" "*.Mask")
			(remove_unused_layers no)
			(net "I2C_SCC_B_SCL")
			(clearance 0.1651)
			(thermal_gap 0.1651)
		)
		(pad "D3" thru_hole circle
			(at 3.599942 -4.99999)
			(size 0.762 0.762)
			(drill 0.359918)
			(layers "*.Cu" "*.Mask")
			(remove_unused_layers no)
			(net "SCC_B_HEARTBEAT")
			(clearance 0.1651)
			(thermal_gap 0.1651)
		)
		(pad "D4" thru_hole circle
			(at 5.40004 -5.999988)
			(size 0.762 0.762)
			(drill 0.359918)
			(layers "*.Cu" "*.Mask")
			(remove_unused_layers no)
			(net "SCC_B_STBY_PWR_EN")
			(clearance 0.1651)
			(thermal_gap 0.1651)
		)
		(pad "D5" thru_hole circle
			(at 7.199884 -4.99999)
			(size 0.762 0.762)
			(drill 0.359918)
			(layers "*.Cu" "*.Mask")
			(remove_unused_layers no)
			(net "PCIE_COMP_B_TO_IOM_B_RST_3")
			(clearance 0.1651)
			(thermal_gap 0.1651)
		)
		(pad "D6" thru_hole circle
			(at 8.999982 -5.999988)
			(size 0.762 0.762)
			(drill 0.359918)
			(layers "*.Cu" "*.Mask")
			(remove_unused_layers no)
			(net "I2C_BMC_B_EXP_A_SCL")
			(clearance 0.1651)
			(thermal_gap 0.1651)
		)
		(pad "D7" thru_hole circle
			(at 10.80008 -4.99999)
			(size 0.762 0.762)
			(drill 0.359918)
			(layers "*.Cu" "*.Mask")
			(remove_unused_layers no)
			(net "UART_SDB_B_TX")
			(clearance 0.1651)
			(thermal_gap 0.1651)
		)
		(pad "D8" thru_hole circle
			(at 12.599924 -5.999988)
			(size 0.762 0.762)
			(drill 0.359918)
			(layers "*.Cu" "*.Mask")
			(remove_unused_layers no)
			(net "P12V_B")
			(clearance 0.1651)
			(thermal_gap 0.1651)
		)
		(pad "D9" thru_hole circle
			(at 21.599906 -4.99999)
			(size 0.762 0.762)
			(drill 0.359918)
			(layers "*.Cu" "*.Mask")
			(remove_unused_layers no)
			(net "PCIE_COMP_B_TO_IOM_B_RST_4")
			(clearance 0.1651)
			(thermal_gap 0.1651)
		)
		(pad "D10" thru_hole circle
			(at 23.400004 -5.999988)
			(size 0.762 0.762)
			(drill 0.359918)
			(layers "*.Cu" "*.Mask")
			(remove_unused_layers no)
			(net "I2C_BMC_B_COMP_B_SCL_BUF")
			(clearance 0.1651)
			(thermal_gap 0.1651)
		)
		(pad "D11" thru_hole circle
			(at 25.200102 -4.99999)
			(size 0.762 0.762)
			(drill 0.359918)
			(layers "*.Cu" "*.Mask")
			(remove_unused_layers no)
			(net "UART_COMP_B_TX")
			(clearance 0.1651)
			(thermal_gap 0.1651)
		)
		(pad "D12" thru_hole circle
			(at 26.999946 -5.999988)
			(size 0.762 0.762)
			(drill 0.359918)
			(layers "*.Cu" "*.Mask")
			(remove_unused_layers no)
			(net "SCC_A_TYPE_0")
			(clearance 0.1651)
			(thermal_gap 0.1651)
		)
		(pad "D13" thru_hole circle
			(at 28.800044 -4.99999)
			(size 0.762 0.762)
			(drill 0.359918)
			(layers "*.Cu" "*.Mask")
			(remove_unused_layers no)
			(net "COMP_B_FAST_THROTTLE_N")
			(clearance 0.1651)
			(thermal_gap 0.1651)
		)
		(pad "D14" thru_hole circle
			(at 30.599888 -5.999988)
			(size 0.762 0.762)
			(drill 0.359918)
			(layers "*.Cu" "*.Mask")
			(remove_unused_layers no)
			(net "COMP_B_PWR_BTN_N")
			(clearance 0.1651)
			(thermal_gap 0.1651)
		)
		(pad "D15" thru_hole circle
			(at 32.399986 -4.99999)
			(size 0.762 0.762)
			(drill 0.359918)
			(layers "*.Cu" "*.Mask")
			(remove_unused_layers no)
			(net "IOM_B_FAULT_LED")
			(clearance 0.1651)
			(thermal_gap 0.1651)
		)
		(pad "D16" thru_hole circle
			(at 34.200084 -5.999988)
			(size 0.762 0.762)
			(drill 0.359918)
			(layers "*.Cu" "*.Mask")
			(remove_unused_layers no)
			(net "PWM_BMC_B_ZONE_D")
			(clearance 0.1651)
			(thermal_gap 0.1651)
		)
		(pad "E1" thru_hole circle
			(at 0 -7.199884)
			(size 0.664718 0.664718)
			(drill 0.359918)
			(layers "*.Cu" "*.Mask")
			(remove_unused_layers no)
			(net "PCIE_IOM_B_TO_COMP_B_8_DN")
			(clearance 0.264414)
			(padstack
				(mode custom)
				(layer "In1.Cu"
					(shape circle)
					(size 0.664718 0.664718)
					(clearance 0.264414)
				)
				(layer "In2.Cu"
					(shape circle)
					(size 0.664718 0.664718)
					(clearance 0.264414)
				)
				(layer "In3.Cu"
					(shape circle)
					(size 0.664718 0.664718)
					(clearance 0.264414)
				)
				(layer "In4.Cu"
					(shape circle)
					(size 0.664718 0.664718)
					(clearance 0.264414)
				)
				(layer "In5.Cu"
					(shape circle)
					(size 0.664718 0.664718)
					(clearance 0.264414)
				)
				(layer "In6.Cu"
					(shape circle)
					(size 0.762 0.762)
					(clearance 0.1651)
				)
				(layer "In7.Cu"
					(shape circle)
					(size 0.762 0.762)
					(clearance 0.1651)
				)
				(layer "In8.Cu"
					(shape circle)
					(size 0.762 0.762)
					(clearance 0.1651)
				)
				(layer "In9.Cu"
					(shape circle)
					(size 0.762 0.762)
					(clearance 0.1651)
				)
				(layer "In10.Cu"
					(shape circle)
					(size 0.762 0.762)
					(clearance 0.1651)
				)
				(layer "B.Cu"
					(shape circle)
					(size 0.762 0.762)
					(thermal_gap 0.1651)
					(clearance 0.1651)
				)
			)
		)
		(pad "E2" thru_hole circle
			(at 1.800098 -8.199882)
			(size 0.664718 0.664718)
			(drill 0.359918)
			(layers "*.Cu" "*.Mask")
			(remove_unused_layers no)
			(net "PCIE_IOM_B_TO_COMP_B_9_DN")
			(clearance 0.264414)
			(padstack
				(mode custom)
				(layer "In1.Cu"
					(shape circle)
					(size 0.664718 0.664718)
					(clearance 0.264414)
				)
				(layer "In2.Cu"
					(shape circle)
					(size 0.664718 0.664718)
					(clearance 0.264414)
				)
				(layer "In3.Cu"
					(shape circle)
					(size 0.664718 0.664718)
					(clearance 0.264414)
				)
				(layer "In4.Cu"
					(shape circle)
					(size 0.664718 0.664718)
					(clearance 0.264414)
				)
				(layer "In5.Cu"
					(shape circle)
					(size 0.664718 0.664718)
					(clearance 0.264414)
				)
				(layer "In6.Cu"
					(shape circle)
					(size 0.762 0.762)
					(clearance 0.1651)
				)
				(layer "In7.Cu"
					(shape circle)
					(size 0.762 0.762)
					(clearance 0.1651)
				)
				(layer "In8.Cu"
					(shape circle)
					(size 0.762 0.762)
					(clearance 0.1651)
				)
				(layer "In9.Cu"
					(shape circle)
					(size 0.762 0.762)
					(clearance 0.1651)
				)
				(layer "In10.Cu"
					(shape circle)
					(size 0.762 0.762)
					(clearance 0.1651)
				)
				(layer "B.Cu"
					(shape circle)
					(size 0.762 0.762)
					(thermal_gap 0.1651)
					(clearance 0.1651)
				)
			)
		)
		(pad "E3" thru_hole circle
			(at 3.599942 -7.199884)
			(size 0.664718 0.664718)
			(drill 0.359918)
			(layers "*.Cu" "*.Mask")
			(remove_unused_layers no)
			(net "PCIE_IOM_B_TO_COMP_B_10_DN")
			(clearance 0.264414)
			(padstack
				(mode custom)
				(layer "In1.Cu"
					(shape circle)
					(size 0.664718 0.664718)
					(clearance 0.264414)
				)
				(layer "In2.Cu"
					(shape circle)
					(size 0.664718 0.664718)
					(clearance 0.264414)
				)
				(layer "In3.Cu"
					(shape circle)
					(size 0.664718 0.664718)
					(clearance 0.264414)
				)
				(layer "In4.Cu"
					(shape circle)
					(size 0.664718 0.664718)
					(clearance 0.264414)
				)
				(layer "In5.Cu"
					(shape circle)
					(size 0.664718 0.664718)
					(clearance 0.264414)
				)
				(layer "In6.Cu"
					(shape circle)
					(size 0.762 0.762)
					(clearance 0.1651)
				)
				(layer "In7.Cu"
					(shape circle)
					(size 0.762 0.762)
					(clearance 0.1651)
				)
				(layer "In8.Cu"
					(shape circle)
					(size 0.762 0.762)
					(clearance 0.1651)
				)
				(layer "In9.Cu"
					(shape circle)
					(size 0.762 0.762)
					(clearance 0.1651)
				)
				(layer "In10.Cu"
					(shape circle)
					(size 0.762 0.762)
					(clearance 0.1651)
				)
				(layer "B.Cu"
					(shape circle)
					(size 0.762 0.762)
					(thermal_gap 0.1651)
					(clearance 0.1651)
				)
			)
		)
		(pad "E4" thru_hole circle
			(at 5.40004 -8.199882)
			(size 0.664718 0.664718)
			(drill 0.359918)
			(layers "*.Cu" "*.Mask")
			(remove_unused_layers no)
			(net "PCIE_IOM_B_TO_COMP_B_11_DN")
			(clearance 0.264414)
			(padstack
				(mode custom)
				(layer "In1.Cu"
					(shape circle)
					(size 0.664718 0.664718)
					(clearance 0.264414)
				)
				(layer "In2.Cu"
					(shape circle)
					(size 0.664718 0.664718)
					(clearance 0.264414)
				)
				(layer "In3.Cu"
					(shape circle)
					(size 0.664718 0.664718)
					(clearance 0.264414)
				)
				(layer "In4.Cu"
					(shape circle)
					(size 0.664718 0.664718)
					(clearance 0.264414)
				)
				(layer "In5.Cu"
					(shape circle)
					(size 0.664718 0.664718)
					(clearance 0.264414)
				)
				(layer "In6.Cu"
					(shape circle)
					(size 0.762 0.762)
					(clearance 0.1651)
				)
				(layer "In7.Cu"
					(shape circle)
					(size 0.762 0.762)
					(clearance 0.1651)
				)
				(layer "In8.Cu"
					(shape circle)
					(size 0.762 0.762)
					(clearance 0.1651)
				)
				(layer "In9.Cu"
					(shape circle)
					(size 0.762 0.762)
					(clearance 0.1651)
				)
				(layer "In10.Cu"
					(shape circle)
					(size 0.762 0.762)
					(clearance 0.1651)
				)
				(layer "B.Cu"
					(shape circle)
					(size 0.762 0.762)
					(thermal_gap 0.1651)
					(clearance 0.1651)
				)
			)
		)
		(pad "E5" thru_hole circle
			(at 7.199884 -7.199884)
			(size 0.664718 0.664718)
			(drill 0.359918)
			(layers "*.Cu" "*.Mask")
			(remove_unused_layers no)
			(net "PCIE_IOM_B_TO_COMP_B_12_DN")
			(clearance 0.264414)
			(padstack
				(mode custom)
				(layer "In1.Cu"
					(shape circle)
					(size 0.664718 0.664718)
					(clearance 0.264414)
				)
				(layer "In2.Cu"
					(shape circle)
					(size 0.664718 0.664718)
					(clearance 0.264414)
				)
				(layer "In3.Cu"
					(shape circle)
					(size 0.664718 0.664718)
					(clearance 0.264414)
				)
				(layer "In4.Cu"
					(shape circle)
					(size 0.664718 0.664718)
					(clearance 0.264414)
				)
				(layer "In5.Cu"
					(shape circle)
					(size 0.664718 0.664718)
					(clearance 0.264414)
				)
				(layer "In6.Cu"
					(shape circle)
					(size 0.762 0.762)
					(clearance 0.1651)
				)
				(layer "In7.Cu"
					(shape circle)
					(size 0.762 0.762)
					(clearance 0.1651)
				)
				(layer "In8.Cu"
					(shape circle)
					(size 0.762 0.762)
					(clearance 0.1651)
				)
				(layer "In9.Cu"
					(shape circle)
					(size 0.762 0.762)
					(clearance 0.1651)
				)
				(layer "In10.Cu"
					(shape circle)
					(size 0.762 0.762)
					(clearance 0.1651)
				)
				(layer "B.Cu"
					(shape circle)
					(size 0.762 0.762)
					(thermal_gap 0.1651)
					(clearance 0.1651)
				)
			)
		)
		(pad "E6" thru_hole circle
			(at 8.999982 -8.199882)
			(size 0.664718 0.664718)
			(drill 0.359918)
			(layers "*.Cu" "*.Mask")
			(remove_unused_layers no)
			(net "PCIE_IOM_B_TO_COMP_B_13_DN")
			(clearance 0.264414)
			(padstack
				(mode custom)
				(layer "In1.Cu"
					(shape circle)
					(size 0.664718 0.664718)
					(clearance 0.264414)
				)
				(layer "In2.Cu"
					(shape circle)
					(size 0.664718 0.664718)
					(clearance 0.264414)
				)
				(layer "In3.Cu"
					(shape circle)
					(size 0.664718 0.664718)
					(clearance 0.264414)
				)
				(layer "In4.Cu"
					(shape circle)
					(size 0.664718 0.664718)
					(clearance 0.264414)
				)
				(layer "In5.Cu"
					(shape circle)
					(size 0.664718 0.664718)
					(clearance 0.264414)
				)
				(layer "In6.Cu"
					(shape circle)
					(size 0.762 0.762)
					(clearance 0.1651)
				)
				(layer "In7.Cu"
					(shape circle)
					(size 0.762 0.762)
					(clearance 0.1651)
				)
				(layer "In8.Cu"
					(shape circle)
					(size 0.762 0.762)
					(clearance 0.1651)
				)
				(layer "In9.Cu"
					(shape circle)
					(size 0.762 0.762)
					(clearance 0.1651)
				)
				(layer "In10.Cu"
					(shape circle)
					(size 0.762 0.762)
					(clearance 0.1651)
				)
				(layer "B.Cu"
					(shape circle)
					(size 0.762 0.762)
					(thermal_gap 0.1651)
					(clearance 0.1651)
				)
			)
		)
		(pad "E7" thru_hole circle
			(at 10.80008 -7.199884)
			(size 0.664718 0.664718)
			(drill 0.359918)
			(layers "*.Cu" "*.Mask")
			(remove_unused_layers no)
			(net "PCIE_IOM_B_TO_COMP_B_14_DN")
			(clearance 0.264414)
			(padstack
				(mode custom)
				(layer "In1.Cu"
					(shape circle)
					(size 0.664718 0.664718)
					(clearance 0.264414)
				)
				(layer "In2.Cu"
					(shape circle)
					(size 0.664718 0.664718)
					(clearance 0.264414)
				)
				(layer "In3.Cu"
					(shape circle)
					(size 0.664718 0.664718)
					(clearance 0.264414)
				)
				(layer "In4.Cu"
					(shape circle)
					(size 0.664718 0.664718)
					(clearance 0.264414)
				)
				(layer "In5.Cu"
					(shape circle)
					(size 0.664718 0.664718)
					(clearance 0.264414)
				)
				(layer "In6.Cu"
					(shape circle)
					(size 0.762 0.762)
					(clearance 0.1651)
				)
				(layer "In7.Cu"
					(shape circle)
					(size 0.762 0.762)
					(clearance 0.1651)
				)
				(layer "In8.Cu"
					(shape circle)
					(size 0.762 0.762)
					(clearance 0.1651)
				)
				(layer "In9.Cu"
					(shape circle)
					(size 0.762 0.762)
					(clearance 0.1651)
				)
				(layer "In10.Cu"
					(shape circle)
					(size 0.762 0.762)
					(clearance 0.1651)
				)
				(layer "B.Cu"
					(shape circle)
					(size 0.762 0.762)
					(thermal_gap 0.1651)
					(clearance 0.1651)
				)
			)
		)
		(pad "E8" thru_hole circle
			(at 12.599924 -8.199882)
			(size 0.664718 0.664718)
			(drill 0.359918)
			(layers "*.Cu" "*.Mask")
			(remove_unused_layers no)
			(net "PCIE_IOM_B_TO_COMP_B_15_DN")
			(clearance 0.264414)
			(padstack
				(mode custom)
				(layer "In1.Cu"
					(shape circle)
					(size 0.664718 0.664718)
					(clearance 0.264414)
				)
				(layer "In2.Cu"
					(shape circle)
					(size 0.664718 0.664718)
					(clearance 0.264414)
				)
				(layer "In3.Cu"
					(shape circle)
					(size 0.664718 0.664718)
					(clearance 0.264414)
				)
				(layer "In4.Cu"
					(shape circle)
					(size 0.664718 0.664718)
					(clearance 0.264414)
				)
				(layer "In5.Cu"
					(shape circle)
					(size 0.664718 0.664718)
					(clearance 0.264414)
				)
				(layer "In6.Cu"
					(shape circle)
					(size 0.762 0.762)
					(clearance 0.1651)
				)
				(layer "In7.Cu"
					(shape circle)
					(size 0.762 0.762)
					(clearance 0.1651)
				)
				(layer "In8.Cu"
					(shape circle)
					(size 0.762 0.762)
					(clearance 0.1651)
				)
				(layer "In9.Cu"
					(shape circle)
					(size 0.762 0.762)
					(clearance 0.1651)
				)
				(layer "In10.Cu"
					(shape circle)
					(size 0.762 0.762)
					(clearance 0.1651)
				)
				(layer "B.Cu"
					(shape circle)
					(size 0.762 0.762)
					(thermal_gap 0.1651)
					(clearance 0.1651)
				)
			)
		)
		(pad "E9" thru_hole circle
			(at 21.599906 -7.199884)
			(size 0.664718 0.664718)
			(drill 0.359918)
			(layers "*.Cu" "*.Mask")
			(remove_unused_layers no)
			(net "PCIE_IOM_B_TO_COMP_B_23_DN")
			(clearance 0.264414)
			(padstack
				(mode custom)
				(layer "In1.Cu"
					(shape circle)
					(size 0.664718 0.664718)
					(clearance 0.264414)
				)
				(layer "In2.Cu"
					(shape circle)
					(size 0.664718 0.664718)
					(clearance 0.264414)
				)
				(layer "In3.Cu"
					(shape circle)
					(size 0.664718 0.664718)
					(clearance 0.264414)
				)
				(layer "In4.Cu"
					(shape circle)
					(size 0.664718 0.664718)
					(clearance 0.264414)
				)
				(layer "In5.Cu"
					(shape circle)
					(size 0.664718 0.664718)
					(clearance 0.264414)
				)
				(layer "In6.Cu"
					(shape circle)
					(size 0.762 0.762)
					(clearance 0.1651)
				)
				(layer "In7.Cu"
					(shape circle)
					(size 0.762 0.762)
					(clearance 0.1651)
				)
				(layer "In8.Cu"
					(shape circle)
					(size 0.762 0.762)
					(clearance 0.1651)
				)
				(layer "In9.Cu"
					(shape circle)
					(size 0.762 0.762)
					(clearance 0.1651)
				)
				(layer "In10.Cu"
					(shape circle)
					(size 0.762 0.762)
					(clearance 0.1651)
				)
				(layer "B.Cu"
					(shape circle)
					(size 0.762 0.762)
					(thermal_gap 0.1651)
					(clearance 0.1651)
				)
			)
		)
		(pad "E10" thru_hole circle
			(at 23.400004 -8.199882)
			(size 0.664718 0.664718)
			(drill 0.359918)
			(layers "*.Cu" "*.Mask")
			(remove_unused_layers no)
			(net "PCIE_IOM_B_TO_COMP_B_22_DN")
			(clearance 0.264414)
			(padstack
				(mode custom)
				(layer "In1.Cu"
					(shape circle)
					(size 0.664718 0.664718)
					(clearance 0.264414)
				)
				(layer "In2.Cu"
					(shape circle)
					(size 0.664718 0.664718)
					(clearance 0.264414)
				)
				(layer "In3.Cu"
					(shape circle)
					(size 0.664718 0.664718)
					(clearance 0.264414)
				)
				(layer "In4.Cu"
					(shape circle)
					(size 0.664718 0.664718)
					(clearance 0.264414)
				)
				(layer "In5.Cu"
					(shape circle)
					(size 0.664718 0.664718)
					(clearance 0.264414)
				)
				(layer "In6.Cu"
					(shape circle)
					(size 0.762 0.762)
					(clearance 0.1651)
				)
				(layer "In7.Cu"
					(shape circle)
					(size 0.762 0.762)
					(clearance 0.1651)
				)
				(layer "In8.Cu"
					(shape circle)
					(size 0.762 0.762)
					(clearance 0.1651)
				)
				(layer "In9.Cu"
					(shape circle)
					(size 0.762 0.762)
					(clearance 0.1651)
				)
				(layer "In10.Cu"
					(shape circle)
					(size 0.762 0.762)
					(clearance 0.1651)
				)
				(layer "B.Cu"
					(shape circle)
					(size 0.762 0.762)
					(thermal_gap 0.1651)
					(clearance 0.1651)
				)
			)
		)
		(pad "E11" thru_hole circle
			(at 25.200102 -7.199884)
			(size 0.664718 0.664718)
			(drill 0.359918)
			(layers "*.Cu" "*.Mask")
			(remove_unused_layers no)
			(net "PCIE_IOM_B_TO_COMP_B_21_DN")
			(clearance 0.264414)
			(padstack
				(mode custom)
				(layer "In1.Cu"
					(shape circle)
					(size 0.664718 0.664718)
					(clearance 0.264414)
				)
				(layer "In2.Cu"
					(shape circle)
					(size 0.664718 0.664718)
					(clearance 0.264414)
				)
				(layer "In3.Cu"
					(shape circle)
					(size 0.664718 0.664718)
					(clearance 0.264414)
				)
				(layer "In4.Cu"
					(shape circle)
					(size 0.664718 0.664718)
					(clearance 0.264414)
				)
				(layer "In5.Cu"
					(shape circle)
					(size 0.664718 0.664718)
					(clearance 0.264414)
				)
				(layer "In6.Cu"
					(shape circle)
					(size 0.762 0.762)
					(clearance 0.1651)
				)
				(layer "In7.Cu"
					(shape circle)
					(size 0.762 0.762)
					(clearance 0.1651)
				)
				(layer "In8.Cu"
					(shape circle)
					(size 0.762 0.762)
					(clearance 0.1651)
				)
				(layer "In9.Cu"
					(shape circle)
					(size 0.762 0.762)
					(clearance 0.1651)
				)
				(layer "In10.Cu"
					(shape circle)
					(size 0.762 0.762)
					(clearance 0.1651)
				)
				(layer "B.Cu"
					(shape circle)
					(size 0.762 0.762)
					(thermal_gap 0.1651)
					(clearance 0.1651)
				)
			)
		)
		(pad "E12" thru_hole circle
			(at 26.999946 -8.199882)
			(size 0.664718 0.664718)
			(drill 0.359918)
			(layers "*.Cu" "*.Mask")
			(remove_unused_layers no)
			(net "PCIE_IOM_B_TO_COMP_B_20_DN")
			(clearance 0.264414)
			(padstack
				(mode custom)
				(layer "In1.Cu"
					(shape circle)
					(size 0.664718 0.664718)
					(clearance 0.264414)
				)
				(layer "In2.Cu"
					(shape circle)
					(size 0.664718 0.664718)
					(clearance 0.264414)
				)
				(layer "In3.Cu"
					(shape circle)
					(size 0.664718 0.664718)
					(clearance 0.264414)
				)
				(layer "In4.Cu"
					(shape circle)
					(size 0.664718 0.664718)
					(clearance 0.264414)
				)
				(layer "In5.Cu"
					(shape circle)
					(size 0.664718 0.664718)
					(clearance 0.264414)
				)
				(layer "In6.Cu"
					(shape circle)
					(size 0.762 0.762)
					(clearance 0.1651)
				)
				(layer "In7.Cu"
					(shape circle)
					(size 0.762 0.762)
					(clearance 0.1651)
				)
				(layer "In8.Cu"
					(shape circle)
					(size 0.762 0.762)
					(clearance 0.1651)
				)
				(layer "In9.Cu"
					(shape circle)
					(size 0.762 0.762)
					(clearance 0.1651)
				)
				(layer "In10.Cu"
					(shape circle)
					(size 0.762 0.762)
					(clearance 0.1651)
				)
				(layer "B.Cu"
					(shape circle)
					(size 0.762 0.762)
					(thermal_gap 0.1651)
					(clearance 0.1651)
				)
			)
		)
		(pad "E13" thru_hole circle
			(at 28.800044 -7.199884)
			(size 0.664718 0.664718)
			(drill 0.359918)
			(layers "*.Cu" "*.Mask")
			(remove_unused_layers no)
			(net "PCIE_IOM_B_TO_COMP_B_19_DN")
			(clearance 0.264414)
			(padstack
				(mode custom)
				(layer "In1.Cu"
					(shape circle)
					(size 0.664718 0.664718)
					(clearance 0.264414)
				)
				(layer "In2.Cu"
					(shape circle)
					(size 0.664718 0.664718)
					(clearance 0.264414)
				)
				(layer "In3.Cu"
					(shape circle)
					(size 0.664718 0.664718)
					(clearance 0.264414)
				)
				(layer "In4.Cu"
					(shape circle)
					(size 0.664718 0.664718)
					(clearance 0.264414)
				)
				(layer "In5.Cu"
					(shape circle)
					(size 0.664718 0.664718)
					(clearance 0.264414)
				)
				(layer "In6.Cu"
					(shape circle)
					(size 0.762 0.762)
					(clearance 0.1651)
				)
				(layer "In7.Cu"
					(shape circle)
					(size 0.762 0.762)
					(clearance 0.1651)
				)
				(layer "In8.Cu"
					(shape circle)
					(size 0.762 0.762)
					(clearance 0.1651)
				)
				(layer "In9.Cu"
					(shape circle)
					(size 0.762 0.762)
					(clearance 0.1651)
				)
				(layer "In10.Cu"
					(shape circle)
					(size 0.762 0.762)
					(clearance 0.1651)
				)
				(layer "B.Cu"
					(shape circle)
					(size 0.762 0.762)
					(thermal_gap 0.1651)
					(clearance 0.1651)
				)
			)
		)
		(pad "E14" thru_hole circle
			(at 30.599888 -8.199882)
			(size 0.664718 0.664718)
			(drill 0.359918)
			(layers "*.Cu" "*.Mask")
			(remove_unused_layers no)
			(net "PCIE_IOM_B_TO_COMP_B_18_DN")
			(clearance 0.264414)
			(padstack
				(mode custom)
				(layer "In1.Cu"
					(shape circle)
					(size 0.664718 0.664718)
					(clearance 0.264414)
				)
				(layer "In2.Cu"
					(shape circle)
					(size 0.664718 0.664718)
					(clearance 0.264414)
				)
				(layer "In3.Cu"
					(shape circle)
					(size 0.664718 0.664718)
					(clearance 0.264414)
				)
				(layer "In4.Cu"
					(shape circle)
					(size 0.664718 0.664718)
					(clearance 0.264414)
				)
				(layer "In5.Cu"
					(shape circle)
					(size 0.664718 0.664718)
					(clearance 0.264414)
				)
				(layer "In6.Cu"
					(shape circle)
					(size 0.762 0.762)
					(clearance 0.1651)
				)
				(layer "In7.Cu"
					(shape circle)
					(size 0.762 0.762)
					(clearance 0.1651)
				)
				(layer "In8.Cu"
					(shape circle)
					(size 0.762 0.762)
					(clearance 0.1651)
				)
				(layer "In9.Cu"
					(shape circle)
					(size 0.762 0.762)
					(clearance 0.1651)
				)
				(layer "In10.Cu"
					(shape circle)
					(size 0.762 0.762)
					(clearance 0.1651)
				)
				(layer "B.Cu"
					(shape circle)
					(size 0.762 0.762)
					(thermal_gap 0.1651)
					(clearance 0.1651)
				)
			)
		)
		(pad "E15" thru_hole circle
			(at 32.399986 -7.199884)
			(size 0.664718 0.664718)
			(drill 0.359918)
			(layers "*.Cu" "*.Mask")
			(remove_unused_layers no)
			(net "PCIE_IOM_B_TO_COMP_B_17_DN")
			(clearance 0.264414)
			(padstack
				(mode custom)
				(layer "In1.Cu"
					(shape circle)
					(size 0.664718 0.664718)
					(clearance 0.264414)
				)
				(layer "In2.Cu"
					(shape circle)
					(size 0.664718 0.664718)
					(clearance 0.264414)
				)
				(layer "In3.Cu"
					(shape circle)
					(size 0.664718 0.664718)
					(clearance 0.264414)
				)
				(layer "In4.Cu"
					(shape circle)
					(size 0.664718 0.664718)
					(clearance 0.264414)
				)
				(layer "In5.Cu"
					(shape circle)
					(size 0.664718 0.664718)
					(clearance 0.264414)
				)
				(layer "In6.Cu"
					(shape circle)
					(size 0.762 0.762)
					(clearance 0.1651)
				)
				(layer "In7.Cu"
					(shape circle)
					(size 0.762 0.762)
					(clearance 0.1651)
				)
				(layer "In8.Cu"
					(shape circle)
					(size 0.762 0.762)
					(clearance 0.1651)
				)
				(layer "In9.Cu"
					(shape circle)
					(size 0.762 0.762)
					(clearance 0.1651)
				)
				(layer "In10.Cu"
					(shape circle)
					(size 0.762 0.762)
					(clearance 0.1651)
				)
				(layer "B.Cu"
					(shape circle)
					(size 0.762 0.762)
					(thermal_gap 0.1651)
					(clearance 0.1651)
				)
			)
		)
		(pad "E16" thru_hole circle
			(at 34.200084 -8.199882)
			(size 0.664718 0.664718)
			(drill 0.359918)
			(layers "*.Cu" "*.Mask")
			(remove_unused_layers no)
			(net "PCIE_IOM_B_TO_COMP_B_16_DN")
			(clearance 0.264414)
			(padstack
				(mode custom)
				(layer "In1.Cu"
					(shape circle)
					(size 0.664718 0.664718)
					(clearance 0.264414)
				)
				(layer "In2.Cu"
					(shape circle)
					(size 0.664718 0.664718)
					(clearance 0.264414)
				)
				(layer "In3.Cu"
					(shape circle)
					(size 0.664718 0.664718)
					(clearance 0.264414)
				)
				(layer "In4.Cu"
					(shape circle)
					(size 0.664718 0.664718)
					(clearance 0.264414)
				)
				(layer "In5.Cu"
					(shape circle)
					(size 0.664718 0.664718)
					(clearance 0.264414)
				)
				(layer "In6.Cu"
					(shape circle)
					(size 0.762 0.762)
					(clearance 0.1651)
				)
				(layer "In7.Cu"
					(shape circle)
					(size 0.762 0.762)
					(clearance 0.1651)
				)
				(layer "In8.Cu"
					(shape circle)
					(size 0.762 0.762)
					(clearance 0.1651)
				)
				(layer "In9.Cu"
					(shape circle)
					(size 0.762 0.762)
					(clearance 0.1651)
				)
				(layer "In10.Cu"
					(shape circle)
					(size 0.762 0.762)
					(clearance 0.1651)
				)
				(layer "B.Cu"
					(shape circle)
					(size 0.762 0.762)
					(thermal_gap 0.1651)
					(clearance 0.1651)
				)
			)
		)
		(pad "F1" thru_hole circle
			(at 0 -8.599932)
			(size 0.664718 0.664718)
			(drill 0.359918)
			(layers "*.Cu" "*.Mask")
			(remove_unused_layers no)
			(net "PCIE_IOM_B_TO_COMP_B_8_DP")
			(clearance 0.264414)
			(padstack
				(mode custom)
				(layer "In1.Cu"
					(shape circle)
					(size 0.664718 0.664718)
					(clearance 0.264414)
				)
				(layer "In2.Cu"
					(shape circle)
					(size 0.664718 0.664718)
					(clearance 0.264414)
				)
				(layer "In3.Cu"
					(shape circle)
					(size 0.664718 0.664718)
					(clearance 0.264414)
				)
				(layer "In4.Cu"
					(shape circle)
					(size 0.664718 0.664718)
					(clearance 0.264414)
				)
				(layer "In5.Cu"
					(shape circle)
					(size 0.664718 0.664718)
					(clearance 0.264414)
				)
				(layer "In6.Cu"
					(shape circle)
					(size 0.762 0.762)
					(clearance 0.1651)
				)
				(layer "In7.Cu"
					(shape circle)
					(size 0.762 0.762)
					(clearance 0.1651)
				)
				(layer "In8.Cu"
					(shape circle)
					(size 0.762 0.762)
					(clearance 0.1651)
				)
				(layer "In9.Cu"
					(shape circle)
					(size 0.762 0.762)
					(clearance 0.1651)
				)
				(layer "In10.Cu"
					(shape circle)
					(size 0.762 0.762)
					(clearance 0.1651)
				)
				(layer "B.Cu"
					(shape circle)
					(size 0.762 0.762)
					(thermal_gap 0.1651)
					(clearance 0.1651)
				)
			)
		)
		(pad "F2" thru_hole circle
			(at 1.800098 -9.59993)
			(size 0.664718 0.664718)
			(drill 0.359918)
			(layers "*.Cu" "*.Mask")
			(remove_unused_layers no)
			(net "PCIE_IOM_B_TO_COMP_B_9_DP")
			(clearance 0.264414)
			(padstack
				(mode custom)
				(layer "In1.Cu"
					(shape circle)
					(size 0.664718 0.664718)
					(clearance 0.264414)
				)
				(layer "In2.Cu"
					(shape circle)
					(size 0.664718 0.664718)
					(clearance 0.264414)
				)
				(layer "In3.Cu"
					(shape circle)
					(size 0.664718 0.664718)
					(clearance 0.264414)
				)
				(layer "In4.Cu"
					(shape circle)
					(size 0.664718 0.664718)
					(clearance 0.264414)
				)
				(layer "In5.Cu"
					(shape circle)
					(size 0.664718 0.664718)
					(clearance 0.264414)
				)
				(layer "In6.Cu"
					(shape circle)
					(size 0.762 0.762)
					(clearance 0.1651)
				)
				(layer "In7.Cu"
					(shape circle)
					(size 0.762 0.762)
					(clearance 0.1651)
				)
				(layer "In8.Cu"
					(shape circle)
					(size 0.762 0.762)
					(clearance 0.1651)
				)
				(layer "In9.Cu"
					(shape circle)
					(size 0.762 0.762)
					(clearance 0.1651)
				)
				(layer "In10.Cu"
					(shape circle)
					(size 0.762 0.762)
					(clearance 0.1651)
				)
				(layer "B.Cu"
					(shape circle)
					(size 0.762 0.762)
					(thermal_gap 0.1651)
					(clearance 0.1651)
				)
			)
		)
		(pad "F3" thru_hole circle
			(at 3.599942 -8.599932)
			(size 0.664718 0.664718)
			(drill 0.359918)
			(layers "*.Cu" "*.Mask")
			(remove_unused_layers no)
			(net "PCIE_IOM_B_TO_COMP_B_10_DP")
			(clearance 0.264414)
			(padstack
				(mode custom)
				(layer "In1.Cu"
					(shape circle)
					(size 0.664718 0.664718)
					(clearance 0.264414)
				)
				(layer "In2.Cu"
					(shape circle)
					(size 0.664718 0.664718)
					(clearance 0.264414)
				)
				(layer "In3.Cu"
					(shape circle)
					(size 0.664718 0.664718)
					(clearance 0.264414)
				)
				(layer "In4.Cu"
					(shape circle)
					(size 0.664718 0.664718)
					(clearance 0.264414)
				)
				(layer "In5.Cu"
					(shape circle)
					(size 0.664718 0.664718)
					(clearance 0.264414)
				)
				(layer "In6.Cu"
					(shape circle)
					(size 0.762 0.762)
					(clearance 0.1651)
				)
				(layer "In7.Cu"
					(shape circle)
					(size 0.762 0.762)
					(clearance 0.1651)
				)
				(layer "In8.Cu"
					(shape circle)
					(size 0.762 0.762)
					(clearance 0.1651)
				)
				(layer "In9.Cu"
					(shape circle)
					(size 0.762 0.762)
					(clearance 0.1651)
				)
				(layer "In10.Cu"
					(shape circle)
					(size 0.762 0.762)
					(clearance 0.1651)
				)
				(layer "B.Cu"
					(shape circle)
					(size 0.762 0.762)
					(thermal_gap 0.1651)
					(clearance 0.1651)
				)
			)
		)
		(pad "F4" thru_hole circle
			(at 5.40004 -9.59993)
			(size 0.664718 0.664718)
			(drill 0.359918)
			(layers "*.Cu" "*.Mask")
			(remove_unused_layers no)
			(net "PCIE_IOM_B_TO_COMP_B_11_DP")
			(clearance 0.264414)
			(padstack
				(mode custom)
				(layer "In1.Cu"
					(shape circle)
					(size 0.664718 0.664718)
					(clearance 0.264414)
				)
				(layer "In2.Cu"
					(shape circle)
					(size 0.664718 0.664718)
					(clearance 0.264414)
				)
				(layer "In3.Cu"
					(shape circle)
					(size 0.664718 0.664718)
					(clearance 0.264414)
				)
				(layer "In4.Cu"
					(shape circle)
					(size 0.664718 0.664718)
					(clearance 0.264414)
				)
				(layer "In5.Cu"
					(shape circle)
					(size 0.664718 0.664718)
					(clearance 0.264414)
				)
				(layer "In6.Cu"
					(shape circle)
					(size 0.762 0.762)
					(clearance 0.1651)
				)
				(layer "In7.Cu"
					(shape circle)
					(size 0.762 0.762)
					(clearance 0.1651)
				)
				(layer "In8.Cu"
					(shape circle)
					(size 0.762 0.762)
					(clearance 0.1651)
				)
				(layer "In9.Cu"
					(shape circle)
					(size 0.762 0.762)
					(clearance 0.1651)
				)
				(layer "In10.Cu"
					(shape circle)
					(size 0.762 0.762)
					(clearance 0.1651)
				)
				(layer "B.Cu"
					(shape circle)
					(size 0.762 0.762)
					(thermal_gap 0.1651)
					(clearance 0.1651)
				)
			)
		)
		(pad "F5" thru_hole circle
			(at 7.199884 -8.599932)
			(size 0.664718 0.664718)
			(drill 0.359918)
			(layers "*.Cu" "*.Mask")
			(remove_unused_layers no)
			(net "PCIE_IOM_B_TO_COMP_B_12_DP")
			(clearance 0.264414)
			(padstack
				(mode custom)
				(layer "In1.Cu"
					(shape circle)
					(size 0.664718 0.664718)
					(clearance 0.264414)
				)
				(layer "In2.Cu"
					(shape circle)
					(size 0.664718 0.664718)
					(clearance 0.264414)
				)
				(layer "In3.Cu"
					(shape circle)
					(size 0.664718 0.664718)
					(clearance 0.264414)
				)
				(layer "In4.Cu"
					(shape circle)
					(size 0.664718 0.664718)
					(clearance 0.264414)
				)
				(layer "In5.Cu"
					(shape circle)
					(size 0.664718 0.664718)
					(clearance 0.264414)
				)
				(layer "In6.Cu"
					(shape circle)
					(size 0.762 0.762)
					(clearance 0.1651)
				)
				(layer "In7.Cu"
					(shape circle)
					(size 0.762 0.762)
					(clearance 0.1651)
				)
				(layer "In8.Cu"
					(shape circle)
					(size 0.762 0.762)
					(clearance 0.1651)
				)
				(layer "In9.Cu"
					(shape circle)
					(size 0.762 0.762)
					(clearance 0.1651)
				)
				(layer "In10.Cu"
					(shape circle)
					(size 0.762 0.762)
					(clearance 0.1651)
				)
				(layer "B.Cu"
					(shape circle)
					(size 0.762 0.762)
					(thermal_gap 0.1651)
					(clearance 0.1651)
				)
			)
		)
		(pad "F6" thru_hole circle
			(at 8.999982 -9.59993)
			(size 0.664718 0.664718)
			(drill 0.359918)
			(layers "*.Cu" "*.Mask")
			(remove_unused_layers no)
			(net "PCIE_IOM_B_TO_COMP_B_13_DP")
			(clearance 0.264414)
			(padstack
				(mode custom)
				(layer "In1.Cu"
					(shape circle)
					(size 0.664718 0.664718)
					(clearance 0.264414)
				)
				(layer "In2.Cu"
					(shape circle)
					(size 0.664718 0.664718)
					(clearance 0.264414)
				)
				(layer "In3.Cu"
					(shape circle)
					(size 0.664718 0.664718)
					(clearance 0.264414)
				)
				(layer "In4.Cu"
					(shape circle)
					(size 0.664718 0.664718)
					(clearance 0.264414)
				)
				(layer "In5.Cu"
					(shape circle)
					(size 0.664718 0.664718)
					(clearance 0.264414)
				)
				(layer "In6.Cu"
					(shape circle)
					(size 0.762 0.762)
					(clearance 0.1651)
				)
				(layer "In7.Cu"
					(shape circle)
					(size 0.762 0.762)
					(clearance 0.1651)
				)
				(layer "In8.Cu"
					(shape circle)
					(size 0.762 0.762)
					(clearance 0.1651)
				)
				(layer "In9.Cu"
					(shape circle)
					(size 0.762 0.762)
					(clearance 0.1651)
				)
				(layer "In10.Cu"
					(shape circle)
					(size 0.762 0.762)
					(clearance 0.1651)
				)
				(layer "B.Cu"
					(shape circle)
					(size 0.762 0.762)
					(thermal_gap 0.1651)
					(clearance 0.1651)
				)
			)
		)
		(pad "F7" thru_hole circle
			(at 10.80008 -8.599932)
			(size 0.664718 0.664718)
			(drill 0.359918)
			(layers "*.Cu" "*.Mask")
			(remove_unused_layers no)
			(net "PCIE_IOM_B_TO_COMP_B_14_DP")
			(clearance 0.264414)
			(padstack
				(mode custom)
				(layer "In1.Cu"
					(shape circle)
					(size 0.664718 0.664718)
					(clearance 0.264414)
				)
				(layer "In2.Cu"
					(shape circle)
					(size 0.664718 0.664718)
					(clearance 0.264414)
				)
				(layer "In3.Cu"
					(shape circle)
					(size 0.664718 0.664718)
					(clearance 0.264414)
				)
				(layer "In4.Cu"
					(shape circle)
					(size 0.664718 0.664718)
					(clearance 0.264414)
				)
				(layer "In5.Cu"
					(shape circle)
					(size 0.664718 0.664718)
					(clearance 0.264414)
				)
				(layer "In6.Cu"
					(shape circle)
					(size 0.762 0.762)
					(clearance 0.1651)
				)
				(layer "In7.Cu"
					(shape circle)
					(size 0.762 0.762)
					(clearance 0.1651)
				)
				(layer "In8.Cu"
					(shape circle)
					(size 0.762 0.762)
					(clearance 0.1651)
				)
				(layer "In9.Cu"
					(shape circle)
					(size 0.762 0.762)
					(clearance 0.1651)
				)
				(layer "In10.Cu"
					(shape circle)
					(size 0.762 0.762)
					(clearance 0.1651)
				)
				(layer "B.Cu"
					(shape circle)
					(size 0.762 0.762)
					(thermal_gap 0.1651)
					(clearance 0.1651)
				)
			)
		)
		(pad "F8" thru_hole circle
			(at 12.599924 -9.59993)
			(size 0.664718 0.664718)
			(drill 0.359918)
			(layers "*.Cu" "*.Mask")
			(remove_unused_layers no)
			(net "PCIE_IOM_B_TO_COMP_B_15_DP")
			(clearance 0.264414)
			(padstack
				(mode custom)
				(layer "In1.Cu"
					(shape circle)
					(size 0.664718 0.664718)
					(clearance 0.264414)
				)
				(layer "In2.Cu"
					(shape circle)
					(size 0.664718 0.664718)
					(clearance 0.264414)
				)
				(layer "In3.Cu"
					(shape circle)
					(size 0.664718 0.664718)
					(clearance 0.264414)
				)
				(layer "In4.Cu"
					(shape circle)
					(size 0.664718 0.664718)
					(clearance 0.264414)
				)
				(layer "In5.Cu"
					(shape circle)
					(size 0.664718 0.664718)
					(clearance 0.264414)
				)
				(layer "In6.Cu"
					(shape circle)
					(size 0.762 0.762)
					(clearance 0.1651)
				)
				(layer "In7.Cu"
					(shape circle)
					(size 0.762 0.762)
					(clearance 0.1651)
				)
				(layer "In8.Cu"
					(shape circle)
					(size 0.762 0.762)
					(clearance 0.1651)
				)
				(layer "In9.Cu"
					(shape circle)
					(size 0.762 0.762)
					(clearance 0.1651)
				)
				(layer "In10.Cu"
					(shape circle)
					(size 0.762 0.762)
					(clearance 0.1651)
				)
				(layer "B.Cu"
					(shape circle)
					(size 0.762 0.762)
					(thermal_gap 0.1651)
					(clearance 0.1651)
				)
			)
		)
		(pad "F9" thru_hole circle
			(at 21.599906 -8.599932)
			(size 0.664718 0.664718)
			(drill 0.359918)
			(layers "*.Cu" "*.Mask")
			(remove_unused_layers no)
			(net "PCIE_IOM_B_TO_COMP_B_23_DP")
			(clearance 0.264414)
			(padstack
				(mode custom)
				(layer "In1.Cu"
					(shape circle)
					(size 0.664718 0.664718)
					(clearance 0.264414)
				)
				(layer "In2.Cu"
					(shape circle)
					(size 0.664718 0.664718)
					(clearance 0.264414)
				)
				(layer "In3.Cu"
					(shape circle)
					(size 0.664718 0.664718)
					(clearance 0.264414)
				)
				(layer "In4.Cu"
					(shape circle)
					(size 0.664718 0.664718)
					(clearance 0.264414)
				)
				(layer "In5.Cu"
					(shape circle)
					(size 0.664718 0.664718)
					(clearance 0.264414)
				)
				(layer "In6.Cu"
					(shape circle)
					(size 0.762 0.762)
					(clearance 0.1651)
				)
				(layer "In7.Cu"
					(shape circle)
					(size 0.762 0.762)
					(clearance 0.1651)
				)
				(layer "In8.Cu"
					(shape circle)
					(size 0.762 0.762)
					(clearance 0.1651)
				)
				(layer "In9.Cu"
					(shape circle)
					(size 0.762 0.762)
					(clearance 0.1651)
				)
				(layer "In10.Cu"
					(shape circle)
					(size 0.762 0.762)
					(clearance 0.1651)
				)
				(layer "B.Cu"
					(shape circle)
					(size 0.762 0.762)
					(thermal_gap 0.1651)
					(clearance 0.1651)
				)
			)
		)
		(pad "F10" thru_hole circle
			(at 23.400004 -9.59993)
			(size 0.664718 0.664718)
			(drill 0.359918)
			(layers "*.Cu" "*.Mask")
			(remove_unused_layers no)
			(net "PCIE_IOM_B_TO_COMP_B_22_DP")
			(clearance 0.264414)
			(padstack
				(mode custom)
				(layer "In1.Cu"
					(shape circle)
					(size 0.664718 0.664718)
					(clearance 0.264414)
				)
				(layer "In2.Cu"
					(shape circle)
					(size 0.664718 0.664718)
					(clearance 0.264414)
				)
				(layer "In3.Cu"
					(shape circle)
					(size 0.664718 0.664718)
					(clearance 0.264414)
				)
				(layer "In4.Cu"
					(shape circle)
					(size 0.664718 0.664718)
					(clearance 0.264414)
				)
				(layer "In5.Cu"
					(shape circle)
					(size 0.664718 0.664718)
					(clearance 0.264414)
				)
				(layer "In6.Cu"
					(shape circle)
					(size 0.762 0.762)
					(clearance 0.1651)
				)
				(layer "In7.Cu"
					(shape circle)
					(size 0.762 0.762)
					(clearance 0.1651)
				)
				(layer "In8.Cu"
					(shape circle)
					(size 0.762 0.762)
					(clearance 0.1651)
				)
				(layer "In9.Cu"
					(shape circle)
					(size 0.762 0.762)
					(clearance 0.1651)
				)
				(layer "In10.Cu"
					(shape circle)
					(size 0.762 0.762)
					(clearance 0.1651)
				)
				(layer "B.Cu"
					(shape circle)
					(size 0.762 0.762)
					(thermal_gap 0.1651)
					(clearance 0.1651)
				)
			)
		)
		(pad "F11" thru_hole circle
			(at 25.200102 -8.599932)
			(size 0.664718 0.664718)
			(drill 0.359918)
			(layers "*.Cu" "*.Mask")
			(remove_unused_layers no)
			(net "PCIE_IOM_B_TO_COMP_B_21_DP")
			(clearance 0.264414)
			(padstack
				(mode custom)
				(layer "In1.Cu"
					(shape circle)
					(size 0.664718 0.664718)
					(clearance 0.264414)
				)
				(layer "In2.Cu"
					(shape circle)
					(size 0.664718 0.664718)
					(clearance 0.264414)
				)
				(layer "In3.Cu"
					(shape circle)
					(size 0.664718 0.664718)
					(clearance 0.264414)
				)
				(layer "In4.Cu"
					(shape circle)
					(size 0.664718 0.664718)
					(clearance 0.264414)
				)
				(layer "In5.Cu"
					(shape circle)
					(size 0.664718 0.664718)
					(clearance 0.264414)
				)
				(layer "In6.Cu"
					(shape circle)
					(size 0.762 0.762)
					(clearance 0.1651)
				)
				(layer "In7.Cu"
					(shape circle)
					(size 0.762 0.762)
					(clearance 0.1651)
				)
				(layer "In8.Cu"
					(shape circle)
					(size 0.762 0.762)
					(clearance 0.1651)
				)
				(layer "In9.Cu"
					(shape circle)
					(size 0.762 0.762)
					(clearance 0.1651)
				)
				(layer "In10.Cu"
					(shape circle)
					(size 0.762 0.762)
					(clearance 0.1651)
				)
				(layer "B.Cu"
					(shape circle)
					(size 0.762 0.762)
					(thermal_gap 0.1651)
					(clearance 0.1651)
				)
			)
		)
		(pad "F12" thru_hole circle
			(at 26.999946 -9.59993)
			(size 0.664718 0.664718)
			(drill 0.359918)
			(layers "*.Cu" "*.Mask")
			(remove_unused_layers no)
			(net "PCIE_IOM_B_TO_COMP_B_20_DP")
			(clearance 0.264414)
			(padstack
				(mode custom)
				(layer "In1.Cu"
					(shape circle)
					(size 0.664718 0.664718)
					(clearance 0.264414)
				)
				(layer "In2.Cu"
					(shape circle)
					(size 0.664718 0.664718)
					(clearance 0.264414)
				)
				(layer "In3.Cu"
					(shape circle)
					(size 0.664718 0.664718)
					(clearance 0.264414)
				)
				(layer "In4.Cu"
					(shape circle)
					(size 0.664718 0.664718)
					(clearance 0.264414)
				)
				(layer "In5.Cu"
					(shape circle)
					(size 0.664718 0.664718)
					(clearance 0.264414)
				)
				(layer "In6.Cu"
					(shape circle)
					(size 0.762 0.762)
					(clearance 0.1651)
				)
				(layer "In7.Cu"
					(shape circle)
					(size 0.762 0.762)
					(clearance 0.1651)
				)
				(layer "In8.Cu"
					(shape circle)
					(size 0.762 0.762)
					(clearance 0.1651)
				)
				(layer "In9.Cu"
					(shape circle)
					(size 0.762 0.762)
					(clearance 0.1651)
				)
				(layer "In10.Cu"
					(shape circle)
					(size 0.762 0.762)
					(clearance 0.1651)
				)
				(layer "B.Cu"
					(shape circle)
					(size 0.762 0.762)
					(thermal_gap 0.1651)
					(clearance 0.1651)
				)
			)
		)
		(pad "F13" thru_hole circle
			(at 28.800044 -8.599932)
			(size 0.664718 0.664718)
			(drill 0.359918)
			(layers "*.Cu" "*.Mask")
			(remove_unused_layers no)
			(net "PCIE_IOM_B_TO_COMP_B_19_DP")
			(clearance 0.264414)
			(padstack
				(mode custom)
				(layer "In1.Cu"
					(shape circle)
					(size 0.664718 0.664718)
					(clearance 0.264414)
				)
				(layer "In2.Cu"
					(shape circle)
					(size 0.664718 0.664718)
					(clearance 0.264414)
				)
				(layer "In3.Cu"
					(shape circle)
					(size 0.664718 0.664718)
					(clearance 0.264414)
				)
				(layer "In4.Cu"
					(shape circle)
					(size 0.664718 0.664718)
					(clearance 0.264414)
				)
				(layer "In5.Cu"
					(shape circle)
					(size 0.664718 0.664718)
					(clearance 0.264414)
				)
				(layer "In6.Cu"
					(shape circle)
					(size 0.762 0.762)
					(clearance 0.1651)
				)
				(layer "In7.Cu"
					(shape circle)
					(size 0.762 0.762)
					(clearance 0.1651)
				)
				(layer "In8.Cu"
					(shape circle)
					(size 0.762 0.762)
					(clearance 0.1651)
				)
				(layer "In9.Cu"
					(shape circle)
					(size 0.762 0.762)
					(clearance 0.1651)
				)
				(layer "In10.Cu"
					(shape circle)
					(size 0.762 0.762)
					(clearance 0.1651)
				)
				(layer "B.Cu"
					(shape circle)
					(size 0.762 0.762)
					(thermal_gap 0.1651)
					(clearance 0.1651)
				)
			)
		)
		(pad "F14" thru_hole circle
			(at 30.599888 -9.59993)
			(size 0.664718 0.664718)
			(drill 0.359918)
			(layers "*.Cu" "*.Mask")
			(remove_unused_layers no)
			(net "PCIE_IOM_B_TO_COMP_B_18_DP")
			(clearance 0.264414)
			(padstack
				(mode custom)
				(layer "In1.Cu"
					(shape circle)
					(size 0.664718 0.664718)
					(clearance 0.264414)
				)
				(layer "In2.Cu"
					(shape circle)
					(size 0.664718 0.664718)
					(clearance 0.264414)
				)
				(layer "In3.Cu"
					(shape circle)
					(size 0.664718 0.664718)
					(clearance 0.264414)
				)
				(layer "In4.Cu"
					(shape circle)
					(size 0.664718 0.664718)
					(clearance 0.264414)
				)
				(layer "In5.Cu"
					(shape circle)
					(size 0.664718 0.664718)
					(clearance 0.264414)
				)
				(layer "In6.Cu"
					(shape circle)
					(size 0.762 0.762)
					(clearance 0.1651)
				)
				(layer "In7.Cu"
					(shape circle)
					(size 0.762 0.762)
					(clearance 0.1651)
				)
				(layer "In8.Cu"
					(shape circle)
					(size 0.762 0.762)
					(clearance 0.1651)
				)
				(layer "In9.Cu"
					(shape circle)
					(size 0.762 0.762)
					(clearance 0.1651)
				)
				(layer "In10.Cu"
					(shape circle)
					(size 0.762 0.762)
					(clearance 0.1651)
				)
				(layer "B.Cu"
					(shape circle)
					(size 0.762 0.762)
					(thermal_gap 0.1651)
					(clearance 0.1651)
				)
			)
		)
		(pad "F15" thru_hole circle
			(at 32.399986 -8.599932)
			(size 0.664718 0.664718)
			(drill 0.359918)
			(layers "*.Cu" "*.Mask")
			(remove_unused_layers no)
			(net "PCIE_IOM_B_TO_COMP_B_17_DP")
			(clearance 0.264414)
			(padstack
				(mode custom)
				(layer "In1.Cu"
					(shape circle)
					(size 0.664718 0.664718)
					(clearance 0.264414)
				)
				(layer "In2.Cu"
					(shape circle)
					(size 0.664718 0.664718)
					(clearance 0.264414)
				)
				(layer "In3.Cu"
					(shape circle)
					(size 0.664718 0.664718)
					(clearance 0.264414)
				)
				(layer "In4.Cu"
					(shape circle)
					(size 0.664718 0.664718)
					(clearance 0.264414)
				)
				(layer "In5.Cu"
					(shape circle)
					(size 0.664718 0.664718)
					(clearance 0.264414)
				)
				(layer "In6.Cu"
					(shape circle)
					(size 0.762 0.762)
					(clearance 0.1651)
				)
				(layer "In7.Cu"
					(shape circle)
					(size 0.762 0.762)
					(clearance 0.1651)
				)
				(layer "In8.Cu"
					(shape circle)
					(size 0.762 0.762)
					(clearance 0.1651)
				)
				(layer "In9.Cu"
					(shape circle)
					(size 0.762 0.762)
					(clearance 0.1651)
				)
				(layer "In10.Cu"
					(shape circle)
					(size 0.762 0.762)
					(clearance 0.1651)
				)
				(layer "B.Cu"
					(shape circle)
					(size 0.762 0.762)
					(thermal_gap 0.1651)
					(clearance 0.1651)
				)
			)
		)
		(pad "F16" thru_hole circle
			(at 34.200084 -9.59993)
			(size 0.664718 0.664718)
			(drill 0.359918)
			(layers "*.Cu" "*.Mask")
			(remove_unused_layers no)
			(net "PCIE_IOM_B_TO_COMP_B_16_DP")
			(clearance 0.264414)
			(padstack
				(mode custom)
				(layer "In1.Cu"
					(shape circle)
					(size 0.664718 0.664718)
					(clearance 0.264414)
				)
				(layer "In2.Cu"
					(shape circle)
					(size 0.664718 0.664718)
					(clearance 0.264414)
				)
				(layer "In3.Cu"
					(shape circle)
					(size 0.664718 0.664718)
					(clearance 0.264414)
				)
				(layer "In4.Cu"
					(shape circle)
					(size 0.664718 0.664718)
					(clearance 0.264414)
				)
				(layer "In5.Cu"
					(shape circle)
					(size 0.664718 0.664718)
					(clearance 0.264414)
				)
				(layer "In6.Cu"
					(shape circle)
					(size 0.762 0.762)
					(clearance 0.1651)
				)
				(layer "In7.Cu"
					(shape circle)
					(size 0.762 0.762)
					(clearance 0.1651)
				)
				(layer "In8.Cu"
					(shape circle)
					(size 0.762 0.762)
					(clearance 0.1651)
				)
				(layer "In9.Cu"
					(shape circle)
					(size 0.762 0.762)
					(clearance 0.1651)
				)
				(layer "In10.Cu"
					(shape circle)
					(size 0.762 0.762)
					(clearance 0.1651)
				)
				(layer "B.Cu"
					(shape circle)
					(size 0.762 0.762)
					(thermal_gap 0.1651)
					(clearance 0.1651)
				)
			)
		)
		(pad "G1" thru_hole circle
			(at 0 -10.80008)
			(size 0.664718 0.664718)
			(drill 0.359918)
			(layers "*.Cu" "*.Mask")
			(remove_unused_layers no)
			(net "PCIE_COMP_B_TO_IOM_B_8_DN")
			(clearance 0.264414)
			(padstack
				(mode custom)
				(layer "In1.Cu"
					(shape circle)
					(size 0.664718 0.664718)
					(clearance 0.264414)
				)
				(layer "In2.Cu"
					(shape circle)
					(size 0.664718 0.664718)
					(clearance 0.264414)
				)
				(layer "In3.Cu"
					(shape circle)
					(size 0.664718 0.664718)
					(clearance 0.264414)
				)
				(layer "In4.Cu"
					(shape circle)
					(size 0.664718 0.664718)
					(clearance 0.264414)
				)
				(layer "In5.Cu"
					(shape circle)
					(size 0.664718 0.664718)
					(clearance 0.264414)
				)
				(layer "In6.Cu"
					(shape circle)
					(size 0.762 0.762)
					(clearance 0.1651)
				)
				(layer "In7.Cu"
					(shape circle)
					(size 0.762 0.762)
					(clearance 0.1651)
				)
				(layer "In8.Cu"
					(shape circle)
					(size 0.762 0.762)
					(clearance 0.1651)
				)
				(layer "In9.Cu"
					(shape circle)
					(size 0.762 0.762)
					(clearance 0.1651)
				)
				(layer "In10.Cu"
					(shape circle)
					(size 0.762 0.762)
					(clearance 0.1651)
				)
				(layer "B.Cu"
					(shape circle)
					(size 0.762 0.762)
					(thermal_gap 0.1651)
					(clearance 0.1651)
				)
			)
		)
		(pad "G2" thru_hole circle
			(at 1.800098 -11.800078)
			(size 0.664718 0.664718)
			(drill 0.359918)
			(layers "*.Cu" "*.Mask")
			(remove_unused_layers no)
			(net "PCIE_COMP_B_TO_IOM_B_9_DN")
			(clearance 0.264414)
			(padstack
				(mode custom)
				(layer "In1.Cu"
					(shape circle)
					(size 0.664718 0.664718)
					(clearance 0.264414)
				)
				(layer "In2.Cu"
					(shape circle)
					(size 0.664718 0.664718)
					(clearance 0.264414)
				)
				(layer "In3.Cu"
					(shape circle)
					(size 0.664718 0.664718)
					(clearance 0.264414)
				)
				(layer "In4.Cu"
					(shape circle)
					(size 0.664718 0.664718)
					(clearance 0.264414)
				)
				(layer "In5.Cu"
					(shape circle)
					(size 0.664718 0.664718)
					(clearance 0.264414)
				)
				(layer "In6.Cu"
					(shape circle)
					(size 0.762 0.762)
					(clearance 0.1651)
				)
				(layer "In7.Cu"
					(shape circle)
					(size 0.762 0.762)
					(clearance 0.1651)
				)
				(layer "In8.Cu"
					(shape circle)
					(size 0.762 0.762)
					(clearance 0.1651)
				)
				(layer "In9.Cu"
					(shape circle)
					(size 0.762 0.762)
					(clearance 0.1651)
				)
				(layer "In10.Cu"
					(shape circle)
					(size 0.762 0.762)
					(clearance 0.1651)
				)
				(layer "B.Cu"
					(shape circle)
					(size 0.762 0.762)
					(thermal_gap 0.1651)
					(clearance 0.1651)
				)
			)
		)
		(pad "G3" thru_hole circle
			(at 3.599942 -10.80008)
			(size 0.664718 0.664718)
			(drill 0.359918)
			(layers "*.Cu" "*.Mask")
			(remove_unused_layers no)
			(net "PCIE_COMP_B_TO_IOM_B_10_DN")
			(clearance 0.264414)
			(padstack
				(mode custom)
				(layer "In1.Cu"
					(shape circle)
					(size 0.664718 0.664718)
					(clearance 0.264414)
				)
				(layer "In2.Cu"
					(shape circle)
					(size 0.664718 0.664718)
					(clearance 0.264414)
				)
				(layer "In3.Cu"
					(shape circle)
					(size 0.664718 0.664718)
					(clearance 0.264414)
				)
				(layer "In4.Cu"
					(shape circle)
					(size 0.664718 0.664718)
					(clearance 0.264414)
				)
				(layer "In5.Cu"
					(shape circle)
					(size 0.664718 0.664718)
					(clearance 0.264414)
				)
				(layer "In6.Cu"
					(shape circle)
					(size 0.762 0.762)
					(clearance 0.1651)
				)
				(layer "In7.Cu"
					(shape circle)
					(size 0.762 0.762)
					(clearance 0.1651)
				)
				(layer "In8.Cu"
					(shape circle)
					(size 0.762 0.762)
					(clearance 0.1651)
				)
				(layer "In9.Cu"
					(shape circle)
					(size 0.762 0.762)
					(clearance 0.1651)
				)
				(layer "In10.Cu"
					(shape circle)
					(size 0.762 0.762)
					(clearance 0.1651)
				)
				(layer "B.Cu"
					(shape circle)
					(size 0.762 0.762)
					(thermal_gap 0.1651)
					(clearance 0.1651)
				)
			)
		)
		(pad "G4" thru_hole circle
			(at 5.40004 -11.800078)
			(size 0.664718 0.664718)
			(drill 0.359918)
			(layers "*.Cu" "*.Mask")
			(remove_unused_layers no)
			(net "PCIE_COMP_B_TO_IOM_B_11_DN")
			(clearance 0.264414)
			(padstack
				(mode custom)
				(layer "In1.Cu"
					(shape circle)
					(size 0.664718 0.664718)
					(clearance 0.264414)
				)
				(layer "In2.Cu"
					(shape circle)
					(size 0.664718 0.664718)
					(clearance 0.264414)
				)
				(layer "In3.Cu"
					(shape circle)
					(size 0.664718 0.664718)
					(clearance 0.264414)
				)
				(layer "In4.Cu"
					(shape circle)
					(size 0.664718 0.664718)
					(clearance 0.264414)
				)
				(layer "In5.Cu"
					(shape circle)
					(size 0.664718 0.664718)
					(clearance 0.264414)
				)
				(layer "In6.Cu"
					(shape circle)
					(size 0.762 0.762)
					(clearance 0.1651)
				)
				(layer "In7.Cu"
					(shape circle)
					(size 0.762 0.762)
					(clearance 0.1651)
				)
				(layer "In8.Cu"
					(shape circle)
					(size 0.762 0.762)
					(clearance 0.1651)
				)
				(layer "In9.Cu"
					(shape circle)
					(size 0.762 0.762)
					(clearance 0.1651)
				)
				(layer "In10.Cu"
					(shape circle)
					(size 0.762 0.762)
					(clearance 0.1651)
				)
				(layer "B.Cu"
					(shape circle)
					(size 0.762 0.762)
					(thermal_gap 0.1651)
					(clearance 0.1651)
				)
			)
		)
		(pad "G5" thru_hole circle
			(at 7.199884 -10.80008)
			(size 0.664718 0.664718)
			(drill 0.359918)
			(layers "*.Cu" "*.Mask")
			(remove_unused_layers no)
			(net "PCIE_COMP_B_TO_IOM_B_12_DN")
			(clearance 0.264414)
			(padstack
				(mode custom)
				(layer "In1.Cu"
					(shape circle)
					(size 0.664718 0.664718)
					(clearance 0.264414)
				)
				(layer "In2.Cu"
					(shape circle)
					(size 0.664718 0.664718)
					(clearance 0.264414)
				)
				(layer "In3.Cu"
					(shape circle)
					(size 0.664718 0.664718)
					(clearance 0.264414)
				)
				(layer "In4.Cu"
					(shape circle)
					(size 0.664718 0.664718)
					(clearance 0.264414)
				)
				(layer "In5.Cu"
					(shape circle)
					(size 0.664718 0.664718)
					(clearance 0.264414)
				)
				(layer "In6.Cu"
					(shape circle)
					(size 0.762 0.762)
					(clearance 0.1651)
				)
				(layer "In7.Cu"
					(shape circle)
					(size 0.762 0.762)
					(clearance 0.1651)
				)
				(layer "In8.Cu"
					(shape circle)
					(size 0.762 0.762)
					(clearance 0.1651)
				)
				(layer "In9.Cu"
					(shape circle)
					(size 0.762 0.762)
					(clearance 0.1651)
				)
				(layer "In10.Cu"
					(shape circle)
					(size 0.762 0.762)
					(clearance 0.1651)
				)
				(layer "B.Cu"
					(shape circle)
					(size 0.762 0.762)
					(thermal_gap 0.1651)
					(clearance 0.1651)
				)
			)
		)
		(pad "G6" thru_hole circle
			(at 8.999982 -11.800078)
			(size 0.664718 0.664718)
			(drill 0.359918)
			(layers "*.Cu" "*.Mask")
			(remove_unused_layers no)
			(net "PCIE_COMP_B_TO_IOM_B_13_DN")
			(clearance 0.264414)
			(padstack
				(mode custom)
				(layer "In1.Cu"
					(shape circle)
					(size 0.664718 0.664718)
					(clearance 0.264414)
				)
				(layer "In2.Cu"
					(shape circle)
					(size 0.664718 0.664718)
					(clearance 0.264414)
				)
				(layer "In3.Cu"
					(shape circle)
					(size 0.664718 0.664718)
					(clearance 0.264414)
				)
				(layer "In4.Cu"
					(shape circle)
					(size 0.664718 0.664718)
					(clearance 0.264414)
				)
				(layer "In5.Cu"
					(shape circle)
					(size 0.664718 0.664718)
					(clearance 0.264414)
				)
				(layer "In6.Cu"
					(shape circle)
					(size 0.762 0.762)
					(clearance 0.1651)
				)
				(layer "In7.Cu"
					(shape circle)
					(size 0.762 0.762)
					(clearance 0.1651)
				)
				(layer "In8.Cu"
					(shape circle)
					(size 0.762 0.762)
					(clearance 0.1651)
				)
				(layer "In9.Cu"
					(shape circle)
					(size 0.762 0.762)
					(clearance 0.1651)
				)
				(layer "In10.Cu"
					(shape circle)
					(size 0.762 0.762)
					(clearance 0.1651)
				)
				(layer "B.Cu"
					(shape circle)
					(size 0.762 0.762)
					(thermal_gap 0.1651)
					(clearance 0.1651)
				)
			)
		)
		(pad "G7" thru_hole circle
			(at 10.80008 -10.80008)
			(size 0.664718 0.664718)
			(drill 0.359918)
			(layers "*.Cu" "*.Mask")
			(remove_unused_layers no)
			(net "PCIE_COMP_B_TO_IOM_B_14_DN")
			(clearance 0.264414)
			(padstack
				(mode custom)
				(layer "In1.Cu"
					(shape circle)
					(size 0.664718 0.664718)
					(clearance 0.264414)
				)
				(layer "In2.Cu"
					(shape circle)
					(size 0.664718 0.664718)
					(clearance 0.264414)
				)
				(layer "In3.Cu"
					(shape circle)
					(size 0.664718 0.664718)
					(clearance 0.264414)
				)
				(layer "In4.Cu"
					(shape circle)
					(size 0.664718 0.664718)
					(clearance 0.264414)
				)
				(layer "In5.Cu"
					(shape circle)
					(size 0.664718 0.664718)
					(clearance 0.264414)
				)
				(layer "In6.Cu"
					(shape circle)
					(size 0.762 0.762)
					(clearance 0.1651)
				)
				(layer "In7.Cu"
					(shape circle)
					(size 0.762 0.762)
					(clearance 0.1651)
				)
				(layer "In8.Cu"
					(shape circle)
					(size 0.762 0.762)
					(clearance 0.1651)
				)
				(layer "In9.Cu"
					(shape circle)
					(size 0.762 0.762)
					(clearance 0.1651)
				)
				(layer "In10.Cu"
					(shape circle)
					(size 0.762 0.762)
					(clearance 0.1651)
				)
				(layer "B.Cu"
					(shape circle)
					(size 0.762 0.762)
					(thermal_gap 0.1651)
					(clearance 0.1651)
				)
			)
		)
		(pad "G8" thru_hole circle
			(at 12.599924 -11.800078)
			(size 0.664718 0.664718)
			(drill 0.359918)
			(layers "*.Cu" "*.Mask")
			(remove_unused_layers no)
			(net "PCIE_COMP_B_TO_IOM_B_15_DN")
			(clearance 0.264414)
			(padstack
				(mode custom)
				(layer "In1.Cu"
					(shape circle)
					(size 0.664718 0.664718)
					(clearance 0.264414)
				)
				(layer "In2.Cu"
					(shape circle)
					(size 0.664718 0.664718)
					(clearance 0.264414)
				)
				(layer "In3.Cu"
					(shape circle)
					(size 0.664718 0.664718)
					(clearance 0.264414)
				)
				(layer "In4.Cu"
					(shape circle)
					(size 0.664718 0.664718)
					(clearance 0.264414)
				)
				(layer "In5.Cu"
					(shape circle)
					(size 0.664718 0.664718)
					(clearance 0.264414)
				)
				(layer "In6.Cu"
					(shape circle)
					(size 0.762 0.762)
					(clearance 0.1651)
				)
				(layer "In7.Cu"
					(shape circle)
					(size 0.762 0.762)
					(clearance 0.1651)
				)
				(layer "In8.Cu"
					(shape circle)
					(size 0.762 0.762)
					(clearance 0.1651)
				)
				(layer "In9.Cu"
					(shape circle)
					(size 0.762 0.762)
					(clearance 0.1651)
				)
				(layer "In10.Cu"
					(shape circle)
					(size 0.762 0.762)
					(clearance 0.1651)
				)
				(layer "B.Cu"
					(shape circle)
					(size 0.762 0.762)
					(thermal_gap 0.1651)
					(clearance 0.1651)
				)
			)
		)
		(pad "G9" thru_hole circle
			(at 21.599906 -10.80008)
			(size 0.664718 0.664718)
			(drill 0.359918)
			(layers "*.Cu" "*.Mask")
			(remove_unused_layers no)
			(net "PCIE_COMP_B_TO_IOM_B_23_DN")
			(clearance 0.264414)
			(padstack
				(mode custom)
				(layer "In1.Cu"
					(shape circle)
					(size 0.664718 0.664718)
					(clearance 0.264414)
				)
				(layer "In2.Cu"
					(shape circle)
					(size 0.664718 0.664718)
					(clearance 0.264414)
				)
				(layer "In3.Cu"
					(shape circle)
					(size 0.664718 0.664718)
					(clearance 0.264414)
				)
				(layer "In4.Cu"
					(shape circle)
					(size 0.664718 0.664718)
					(clearance 0.264414)
				)
				(layer "In5.Cu"
					(shape circle)
					(size 0.664718 0.664718)
					(clearance 0.264414)
				)
				(layer "In6.Cu"
					(shape circle)
					(size 0.762 0.762)
					(clearance 0.1651)
				)
				(layer "In7.Cu"
					(shape circle)
					(size 0.762 0.762)
					(clearance 0.1651)
				)
				(layer "In8.Cu"
					(shape circle)
					(size 0.762 0.762)
					(clearance 0.1651)
				)
				(layer "In9.Cu"
					(shape circle)
					(size 0.762 0.762)
					(clearance 0.1651)
				)
				(layer "In10.Cu"
					(shape circle)
					(size 0.762 0.762)
					(clearance 0.1651)
				)
				(layer "B.Cu"
					(shape circle)
					(size 0.762 0.762)
					(thermal_gap 0.1651)
					(clearance 0.1651)
				)
			)
		)
		(pad "G10" thru_hole circle
			(at 23.400004 -11.800078)
			(size 0.664718 0.664718)
			(drill 0.359918)
			(layers "*.Cu" "*.Mask")
			(remove_unused_layers no)
			(net "PCIE_COMP_B_TO_IOM_B_22_DN")
			(clearance 0.264414)
			(padstack
				(mode custom)
				(layer "In1.Cu"
					(shape circle)
					(size 0.664718 0.664718)
					(clearance 0.264414)
				)
				(layer "In2.Cu"
					(shape circle)
					(size 0.664718 0.664718)
					(clearance 0.264414)
				)
				(layer "In3.Cu"
					(shape circle)
					(size 0.664718 0.664718)
					(clearance 0.264414)
				)
				(layer "In4.Cu"
					(shape circle)
					(size 0.664718 0.664718)
					(clearance 0.264414)
				)
				(layer "In5.Cu"
					(shape circle)
					(size 0.664718 0.664718)
					(clearance 0.264414)
				)
				(layer "In6.Cu"
					(shape circle)
					(size 0.762 0.762)
					(clearance 0.1651)
				)
				(layer "In7.Cu"
					(shape circle)
					(size 0.762 0.762)
					(clearance 0.1651)
				)
				(layer "In8.Cu"
					(shape circle)
					(size 0.762 0.762)
					(clearance 0.1651)
				)
				(layer "In9.Cu"
					(shape circle)
					(size 0.762 0.762)
					(clearance 0.1651)
				)
				(layer "In10.Cu"
					(shape circle)
					(size 0.762 0.762)
					(clearance 0.1651)
				)
				(layer "B.Cu"
					(shape circle)
					(size 0.762 0.762)
					(thermal_gap 0.1651)
					(clearance 0.1651)
				)
			)
		)
		(pad "G11" thru_hole circle
			(at 25.200102 -10.80008)
			(size 0.664718 0.664718)
			(drill 0.359918)
			(layers "*.Cu" "*.Mask")
			(remove_unused_layers no)
			(net "PCIE_COMP_B_TO_IOM_B_21_DN")
			(clearance 0.264414)
			(padstack
				(mode custom)
				(layer "In1.Cu"
					(shape circle)
					(size 0.664718 0.664718)
					(clearance 0.264414)
				)
				(layer "In2.Cu"
					(shape circle)
					(size 0.664718 0.664718)
					(clearance 0.264414)
				)
				(layer "In3.Cu"
					(shape circle)
					(size 0.664718 0.664718)
					(clearance 0.264414)
				)
				(layer "In4.Cu"
					(shape circle)
					(size 0.664718 0.664718)
					(clearance 0.264414)
				)
				(layer "In5.Cu"
					(shape circle)
					(size 0.664718 0.664718)
					(clearance 0.264414)
				)
				(layer "In6.Cu"
					(shape circle)
					(size 0.762 0.762)
					(clearance 0.1651)
				)
				(layer "In7.Cu"
					(shape circle)
					(size 0.762 0.762)
					(clearance 0.1651)
				)
				(layer "In8.Cu"
					(shape circle)
					(size 0.762 0.762)
					(clearance 0.1651)
				)
				(layer "In9.Cu"
					(shape circle)
					(size 0.762 0.762)
					(clearance 0.1651)
				)
				(layer "In10.Cu"
					(shape circle)
					(size 0.762 0.762)
					(clearance 0.1651)
				)
				(layer "B.Cu"
					(shape circle)
					(size 0.762 0.762)
					(thermal_gap 0.1651)
					(clearance 0.1651)
				)
			)
		)
		(pad "G12" thru_hole circle
			(at 26.999946 -11.800078)
			(size 0.664718 0.664718)
			(drill 0.359918)
			(layers "*.Cu" "*.Mask")
			(remove_unused_layers no)
			(net "PCIE_COMP_B_TO_IOM_B_20_DN")
			(clearance 0.264414)
			(padstack
				(mode custom)
				(layer "In1.Cu"
					(shape circle)
					(size 0.664718 0.664718)
					(clearance 0.264414)
				)
				(layer "In2.Cu"
					(shape circle)
					(size 0.664718 0.664718)
					(clearance 0.264414)
				)
				(layer "In3.Cu"
					(shape circle)
					(size 0.664718 0.664718)
					(clearance 0.264414)
				)
				(layer "In4.Cu"
					(shape circle)
					(size 0.664718 0.664718)
					(clearance 0.264414)
				)
				(layer "In5.Cu"
					(shape circle)
					(size 0.664718 0.664718)
					(clearance 0.264414)
				)
				(layer "In6.Cu"
					(shape circle)
					(size 0.762 0.762)
					(clearance 0.1651)
				)
				(layer "In7.Cu"
					(shape circle)
					(size 0.762 0.762)
					(clearance 0.1651)
				)
				(layer "In8.Cu"
					(shape circle)
					(size 0.762 0.762)
					(clearance 0.1651)
				)
				(layer "In9.Cu"
					(shape circle)
					(size 0.762 0.762)
					(clearance 0.1651)
				)
				(layer "In10.Cu"
					(shape circle)
					(size 0.762 0.762)
					(clearance 0.1651)
				)
				(layer "B.Cu"
					(shape circle)
					(size 0.762 0.762)
					(thermal_gap 0.1651)
					(clearance 0.1651)
				)
			)
		)
		(pad "G13" thru_hole circle
			(at 28.800044 -10.80008)
			(size 0.664718 0.664718)
			(drill 0.359918)
			(layers "*.Cu" "*.Mask")
			(remove_unused_layers no)
			(net "PCIE_COMP_B_TO_IOM_B_19_DN")
			(clearance 0.264414)
			(padstack
				(mode custom)
				(layer "In1.Cu"
					(shape circle)
					(size 0.664718 0.664718)
					(clearance 0.264414)
				)
				(layer "In2.Cu"
					(shape circle)
					(size 0.664718 0.664718)
					(clearance 0.264414)
				)
				(layer "In3.Cu"
					(shape circle)
					(size 0.664718 0.664718)
					(clearance 0.264414)
				)
				(layer "In4.Cu"
					(shape circle)
					(size 0.664718 0.664718)
					(clearance 0.264414)
				)
				(layer "In5.Cu"
					(shape circle)
					(size 0.664718 0.664718)
					(clearance 0.264414)
				)
				(layer "In6.Cu"
					(shape circle)
					(size 0.762 0.762)
					(clearance 0.1651)
				)
				(layer "In7.Cu"
					(shape circle)
					(size 0.762 0.762)
					(clearance 0.1651)
				)
				(layer "In8.Cu"
					(shape circle)
					(size 0.762 0.762)
					(clearance 0.1651)
				)
				(layer "In9.Cu"
					(shape circle)
					(size 0.762 0.762)
					(clearance 0.1651)
				)
				(layer "In10.Cu"
					(shape circle)
					(size 0.762 0.762)
					(clearance 0.1651)
				)
				(layer "B.Cu"
					(shape circle)
					(size 0.762 0.762)
					(thermal_gap 0.1651)
					(clearance 0.1651)
				)
			)
		)
		(pad "G14" thru_hole circle
			(at 30.599888 -11.800078)
			(size 0.664718 0.664718)
			(drill 0.359918)
			(layers "*.Cu" "*.Mask")
			(remove_unused_layers no)
			(net "PCIE_COMP_B_TO_IOM_B_18_DN")
			(clearance 0.264414)
			(padstack
				(mode custom)
				(layer "In1.Cu"
					(shape circle)
					(size 0.664718 0.664718)
					(clearance 0.264414)
				)
				(layer "In2.Cu"
					(shape circle)
					(size 0.664718 0.664718)
					(clearance 0.264414)
				)
				(layer "In3.Cu"
					(shape circle)
					(size 0.664718 0.664718)
					(clearance 0.264414)
				)
				(layer "In4.Cu"
					(shape circle)
					(size 0.664718 0.664718)
					(clearance 0.264414)
				)
				(layer "In5.Cu"
					(shape circle)
					(size 0.664718 0.664718)
					(clearance 0.264414)
				)
				(layer "In6.Cu"
					(shape circle)
					(size 0.762 0.762)
					(clearance 0.1651)
				)
				(layer "In7.Cu"
					(shape circle)
					(size 0.762 0.762)
					(clearance 0.1651)
				)
				(layer "In8.Cu"
					(shape circle)
					(size 0.762 0.762)
					(clearance 0.1651)
				)
				(layer "In9.Cu"
					(shape circle)
					(size 0.762 0.762)
					(clearance 0.1651)
				)
				(layer "In10.Cu"
					(shape circle)
					(size 0.762 0.762)
					(clearance 0.1651)
				)
				(layer "B.Cu"
					(shape circle)
					(size 0.762 0.762)
					(thermal_gap 0.1651)
					(clearance 0.1651)
				)
			)
		)
		(pad "G15" thru_hole circle
			(at 32.399986 -10.80008)
			(size 0.664718 0.664718)
			(drill 0.359918)
			(layers "*.Cu" "*.Mask")
			(remove_unused_layers no)
			(net "PCIE_COMP_B_TO_IOM_B_17_DN")
			(clearance 0.264414)
			(padstack
				(mode custom)
				(layer "In1.Cu"
					(shape circle)
					(size 0.664718 0.664718)
					(clearance 0.264414)
				)
				(layer "In2.Cu"
					(shape circle)
					(size 0.664718 0.664718)
					(clearance 0.264414)
				)
				(layer "In3.Cu"
					(shape circle)
					(size 0.664718 0.664718)
					(clearance 0.264414)
				)
				(layer "In4.Cu"
					(shape circle)
					(size 0.664718 0.664718)
					(clearance 0.264414)
				)
				(layer "In5.Cu"
					(shape circle)
					(size 0.664718 0.664718)
					(clearance 0.264414)
				)
				(layer "In6.Cu"
					(shape circle)
					(size 0.762 0.762)
					(clearance 0.1651)
				)
				(layer "In7.Cu"
					(shape circle)
					(size 0.762 0.762)
					(clearance 0.1651)
				)
				(layer "In8.Cu"
					(shape circle)
					(size 0.762 0.762)
					(clearance 0.1651)
				)
				(layer "In9.Cu"
					(shape circle)
					(size 0.762 0.762)
					(clearance 0.1651)
				)
				(layer "In10.Cu"
					(shape circle)
					(size 0.762 0.762)
					(clearance 0.1651)
				)
				(layer "B.Cu"
					(shape circle)
					(size 0.762 0.762)
					(thermal_gap 0.1651)
					(clearance 0.1651)
				)
			)
		)
		(pad "G16" thru_hole circle
			(at 34.200084 -11.800078)
			(size 0.664718 0.664718)
			(drill 0.359918)
			(layers "*.Cu" "*.Mask")
			(remove_unused_layers no)
			(net "PCIE_COMP_B_TO_IOM_B_16_DN")
			(clearance 0.264414)
			(padstack
				(mode custom)
				(layer "In1.Cu"
					(shape circle)
					(size 0.664718 0.664718)
					(clearance 0.264414)
				)
				(layer "In2.Cu"
					(shape circle)
					(size 0.664718 0.664718)
					(clearance 0.264414)
				)
				(layer "In3.Cu"
					(shape circle)
					(size 0.664718 0.664718)
					(clearance 0.264414)
				)
				(layer "In4.Cu"
					(shape circle)
					(size 0.664718 0.664718)
					(clearance 0.264414)
				)
				(layer "In5.Cu"
					(shape circle)
					(size 0.664718 0.664718)
					(clearance 0.264414)
				)
				(layer "In6.Cu"
					(shape circle)
					(size 0.762 0.762)
					(clearance 0.1651)
				)
				(layer "In7.Cu"
					(shape circle)
					(size 0.762 0.762)
					(clearance 0.1651)
				)
				(layer "In8.Cu"
					(shape circle)
					(size 0.762 0.762)
					(clearance 0.1651)
				)
				(layer "In9.Cu"
					(shape circle)
					(size 0.762 0.762)
					(clearance 0.1651)
				)
				(layer "In10.Cu"
					(shape circle)
					(size 0.762 0.762)
					(clearance 0.1651)
				)
				(layer "B.Cu"
					(shape circle)
					(size 0.762 0.762)
					(thermal_gap 0.1651)
					(clearance 0.1651)
				)
			)
		)
		(pad "GND1" thru_hole circle
			(at 0 -2.500122)
			(size 0.762 0.762)
			(drill 0.359918)
			(layers "*.Cu" "*.Mask")
			(remove_unused_layers no)
			(net "GND")
			(clearance 0.1651)
			(thermal_gap 0.1651)
		)
		(pad "GND2" thru_hole circle
			(at 0 -6.100064)
			(size 0.762 0.762)
			(drill 0.359918)
			(layers "*.Cu" "*.Mask")
			(remove_unused_layers no)
			(net "GND")
			(clearance 0.1651)
			(thermal_gap 0.1651)
		)
		(pad "GND3" thru_hole circle
			(at 0 -9.700006)
			(size 0.762 0.762)
			(drill 0.359918)
			(layers "*.Cu" "*.Mask")
			(remove_unused_layers no)
			(net "GND")
			(clearance 0.1651)
			(thermal_gap 0.1651)
		)
		(pad "GND4" thru_hole circle
			(at 0 -13.299948)
			(size 0.762 0.762)
			(drill 0.359918)
			(layers "*.Cu" "*.Mask")
			(remove_unused_layers no)
			(net "GND")
			(clearance 0.1651)
			(thermal_gap 0.1651)
		)
		(pad "GND5" thru_hole circle
			(at 1.800098 0.100076)
			(size 0.762 0.762)
			(drill 0.359918)
			(layers "*.Cu" "*.Mask")
			(remove_unused_layers no)
			(net "GND")
			(clearance 0.1651)
			(thermal_gap 0.1651)
		)
		(pad "GND6" thru_hole circle
			(at 1.800098 -3.50012)
			(size 0.762 0.762)
			(drill 0.359918)
			(layers "*.Cu" "*.Mask")
			(remove_unused_layers no)
			(net "GND")
			(clearance 0.1651)
			(thermal_gap 0.1651)
		)
		(pad "GND7" thru_hole circle
			(at 1.800098 -7.100062)
			(size 0.762 0.762)
			(drill 0.359918)
			(layers "*.Cu" "*.Mask")
			(remove_unused_layers no)
			(net "GND")
			(clearance 0.1651)
			(thermal_gap 0.1651)
		)
		(pad "GND8" thru_hole circle
			(at 1.800098 -10.700004)
			(size 0.762 0.762)
			(drill 0.359918)
			(layers "*.Cu" "*.Mask")
			(remove_unused_layers no)
			(net "GND")
			(clearance 0.1651)
			(thermal_gap 0.1651)
		)
		(pad "GND9" thru_hole circle
			(at 1.800098 -14.299946)
			(size 0.762 0.762)
			(drill 0.359918)
			(layers "*.Cu" "*.Mask")
			(remove_unused_layers no)
			(net "GND")
			(clearance 0.1651)
			(thermal_gap 0.1651)
		)
		(pad "GND10" thru_hole circle
			(at 3.599942 -2.500122)
			(size 0.762 0.762)
			(drill 0.359918)
			(layers "*.Cu" "*.Mask")
			(remove_unused_layers no)
			(net "GND")
			(clearance 0.1651)
			(thermal_gap 0.1651)
		)
		(pad "GND11" thru_hole circle
			(at 3.599942 -6.100064)
			(size 0.762 0.762)
			(drill 0.359918)
			(layers "*.Cu" "*.Mask")
			(remove_unused_layers no)
			(net "GND")
			(clearance 0.1651)
			(thermal_gap 0.1651)
		)
		(pad "GND12" thru_hole circle
			(at 3.599942 -9.700006)
			(size 0.762 0.762)
			(drill 0.359918)
			(layers "*.Cu" "*.Mask")
			(remove_unused_layers no)
			(net "GND")
			(clearance 0.1651)
			(thermal_gap 0.1651)
		)
		(pad "GND13" thru_hole circle
			(at 3.599942 -13.299948)
			(size 0.762 0.762)
			(drill 0.359918)
			(layers "*.Cu" "*.Mask")
			(remove_unused_layers no)
			(net "GND")
			(clearance 0.1651)
			(thermal_gap 0.1651)
		)
		(pad "GND14" thru_hole circle
			(at 5.40004 0.100076)
			(size 0.762 0.762)
			(drill 0.359918)
			(layers "*.Cu" "*.Mask")
			(remove_unused_layers no)
			(net "GND")
			(clearance 0.1651)
			(thermal_gap 0.1651)
		)
		(pad "GND15" thru_hole circle
			(at 5.40004 -3.50012)
			(size 0.762 0.762)
			(drill 0.359918)
			(layers "*.Cu" "*.Mask")
			(remove_unused_layers no)
			(net "GND")
			(clearance 0.1651)
			(thermal_gap 0.1651)
		)
		(pad "GND16" thru_hole circle
			(at 5.40004 -7.100062)
			(size 0.762 0.762)
			(drill 0.359918)
			(layers "*.Cu" "*.Mask")
			(remove_unused_layers no)
			(net "GND")
			(clearance 0.1651)
			(thermal_gap 0.1651)
		)
		(pad "GND17" thru_hole circle
			(at 5.40004 -10.700004)
			(size 0.762 0.762)
			(drill 0.359918)
			(layers "*.Cu" "*.Mask")
			(remove_unused_layers no)
			(net "GND")
			(clearance 0.1651)
			(thermal_gap 0.1651)
		)
		(pad "GND18" thru_hole circle
			(at 5.40004 -14.299946)
			(size 0.762 0.762)
			(drill 0.359918)
			(layers "*.Cu" "*.Mask")
			(remove_unused_layers no)
			(net "GND")
			(clearance 0.1651)
			(thermal_gap 0.1651)
		)
		(pad "GND19" thru_hole circle
			(at 7.199884 -2.500122)
			(size 0.762 0.762)
			(drill 0.359918)
			(layers "*.Cu" "*.Mask")
			(remove_unused_layers no)
			(net "GND")
			(clearance 0.1651)
			(thermal_gap 0.1651)
		)
		(pad "GND20" thru_hole circle
			(at 7.199884 -6.100064)
			(size 0.762 0.762)
			(drill 0.359918)
			(layers "*.Cu" "*.Mask")
			(remove_unused_layers no)
			(net "GND")
			(clearance 0.1651)
			(thermal_gap 0.1651)
		)
		(pad "GND21" thru_hole circle
			(at 7.199884 -9.700006)
			(size 0.762 0.762)
			(drill 0.359918)
			(layers "*.Cu" "*.Mask")
			(remove_unused_layers no)
			(net "GND")
			(clearance 0.1651)
			(thermal_gap 0.1651)
		)
		(pad "GND22" thru_hole circle
			(at 7.199884 -13.299948)
			(size 0.762 0.762)
			(drill 0.359918)
			(layers "*.Cu" "*.Mask")
			(remove_unused_layers no)
			(net "GND")
			(clearance 0.1651)
			(thermal_gap 0.1651)
		)
		(pad "GND23" thru_hole circle
			(at 8.999982 0.100076)
			(size 0.762 0.762)
			(drill 0.359918)
			(layers "*.Cu" "*.Mask")
			(remove_unused_layers no)
			(net "GND")
			(clearance 0.1651)
			(thermal_gap 0.1651)
		)
		(pad "GND24" thru_hole circle
			(at 8.999982 -3.50012)
			(size 0.762 0.762)
			(drill 0.359918)
			(layers "*.Cu" "*.Mask")
			(remove_unused_layers no)
			(net "GND")
			(clearance 0.1651)
			(thermal_gap 0.1651)
		)
		(pad "GND25" thru_hole circle
			(at 8.999982 -7.100062)
			(size 0.762 0.762)
			(drill 0.359918)
			(layers "*.Cu" "*.Mask")
			(remove_unused_layers no)
			(net "GND")
			(clearance 0.1651)
			(thermal_gap 0.1651)
		)
		(pad "GND26" thru_hole circle
			(at 8.999982 -10.700004)
			(size 0.762 0.762)
			(drill 0.359918)
			(layers "*.Cu" "*.Mask")
			(remove_unused_layers no)
			(net "GND")
			(clearance 0.1651)
			(thermal_gap 0.1651)
		)
		(pad "GND27" thru_hole circle
			(at 8.999982 -14.299946)
			(size 0.762 0.762)
			(drill 0.359918)
			(layers "*.Cu" "*.Mask")
			(remove_unused_layers no)
			(net "GND")
			(clearance 0.1651)
			(thermal_gap 0.1651)
		)
		(pad "GND28" thru_hole circle
			(at 10.80008 -2.500122)
			(size 0.762 0.762)
			(drill 0.359918)
			(layers "*.Cu" "*.Mask")
			(remove_unused_layers no)
			(net "GND")
			(clearance 0.1651)
			(thermal_gap 0.1651)
		)
		(pad "GND29" thru_hole circle
			(at 10.80008 -6.100064)
			(size 0.762 0.762)
			(drill 0.359918)
			(layers "*.Cu" "*.Mask")
			(remove_unused_layers no)
			(net "GND")
			(clearance 0.1651)
			(thermal_gap 0.1651)
		)
		(pad "GND30" thru_hole circle
			(at 10.80008 -9.700006)
			(size 0.762 0.762)
			(drill 0.359918)
			(layers "*.Cu" "*.Mask")
			(remove_unused_layers no)
			(net "GND")
			(clearance 0.1651)
			(thermal_gap 0.1651)
		)
		(pad "GND31" thru_hole circle
			(at 10.80008 -13.299948)
			(size 0.762 0.762)
			(drill 0.359918)
			(layers "*.Cu" "*.Mask")
			(remove_unused_layers no)
			(net "GND")
			(clearance 0.1651)
			(thermal_gap 0.1651)
		)
		(pad "GND32" thru_hole circle
			(at 12.599924 0.100076)
			(size 0.762 0.762)
			(drill 0.359918)
			(layers "*.Cu" "*.Mask")
			(remove_unused_layers no)
			(net "GND")
			(clearance 0.1651)
			(thermal_gap 0.1651)
		)
		(pad "GND33" thru_hole circle
			(at 12.599924 -3.50012)
			(size 0.762 0.762)
			(drill 0.359918)
			(layers "*.Cu" "*.Mask")
			(remove_unused_layers no)
			(net "GND")
			(clearance 0.1651)
			(thermal_gap 0.1651)
		)
		(pad "GND34" thru_hole circle
			(at 12.599924 -7.100062)
			(size 0.762 0.762)
			(drill 0.359918)
			(layers "*.Cu" "*.Mask")
			(remove_unused_layers no)
			(net "GND")
			(clearance 0.1651)
			(thermal_gap 0.1651)
		)
		(pad "GND35" thru_hole circle
			(at 12.599924 -10.700004)
			(size 0.762 0.762)
			(drill 0.359918)
			(layers "*.Cu" "*.Mask")
			(remove_unused_layers no)
			(net "GND")
			(clearance 0.1651)
			(thermal_gap 0.1651)
		)
		(pad "GND36" thru_hole circle
			(at 12.599924 -14.299946)
			(size 0.762 0.762)
			(drill 0.359918)
			(layers "*.Cu" "*.Mask")
			(remove_unused_layers no)
			(net "GND")
			(clearance 0.1651)
			(thermal_gap 0.1651)
		)
		(pad "GND37" thru_hole circle
			(at 21.599906 -2.500122)
			(size 0.762 0.762)
			(drill 0.359918)
			(layers "*.Cu" "*.Mask")
			(remove_unused_layers no)
			(net "GND")
			(clearance 0.1651)
			(thermal_gap 0.1651)
		)
		(pad "GND38" thru_hole circle
			(at 21.599906 -6.100064)
			(size 0.762 0.762)
			(drill 0.359918)
			(layers "*.Cu" "*.Mask")
			(remove_unused_layers no)
			(net "GND")
			(clearance 0.1651)
			(thermal_gap 0.1651)
		)
		(pad "GND39" thru_hole circle
			(at 21.599906 -9.700006)
			(size 0.762 0.762)
			(drill 0.359918)
			(layers "*.Cu" "*.Mask")
			(remove_unused_layers no)
			(net "GND")
			(clearance 0.1651)
			(thermal_gap 0.1651)
		)
		(pad "GND40" thru_hole circle
			(at 21.599906 -13.299948)
			(size 0.762 0.762)
			(drill 0.359918)
			(layers "*.Cu" "*.Mask")
			(remove_unused_layers no)
			(net "GND")
			(clearance 0.1651)
			(thermal_gap 0.1651)
		)
		(pad "GND41" thru_hole circle
			(at 23.400004 0.100076)
			(size 0.762 0.762)
			(drill 0.359918)
			(layers "*.Cu" "*.Mask")
			(remove_unused_layers no)
			(net "GND")
			(clearance 0.1651)
			(thermal_gap 0.1651)
		)
		(pad "GND42" thru_hole circle
			(at 23.400004 -3.50012)
			(size 0.762 0.762)
			(drill 0.359918)
			(layers "*.Cu" "*.Mask")
			(remove_unused_layers no)
			(net "GND")
			(clearance 0.1651)
			(thermal_gap 0.1651)
		)
		(pad "GND43" thru_hole circle
			(at 23.400004 -7.100062)
			(size 0.762 0.762)
			(drill 0.359918)
			(layers "*.Cu" "*.Mask")
			(remove_unused_layers no)
			(net "GND")
			(clearance 0.1651)
			(thermal_gap 0.1651)
		)
		(pad "GND44" thru_hole circle
			(at 23.400004 -10.700004)
			(size 0.762 0.762)
			(drill 0.359918)
			(layers "*.Cu" "*.Mask")
			(remove_unused_layers no)
			(net "GND")
			(clearance 0.1651)
			(thermal_gap 0.1651)
		)
		(pad "GND45" thru_hole circle
			(at 23.400004 -14.299946)
			(size 0.762 0.762)
			(drill 0.359918)
			(layers "*.Cu" "*.Mask")
			(remove_unused_layers no)
			(net "GND")
			(clearance 0.1651)
			(thermal_gap 0.1651)
		)
		(pad "GND46" thru_hole circle
			(at 25.200102 -2.500122)
			(size 0.762 0.762)
			(drill 0.359918)
			(layers "*.Cu" "*.Mask")
			(remove_unused_layers no)
			(net "GND")
			(clearance 0.1651)
			(thermal_gap 0.1651)
		)
		(pad "GND47" thru_hole circle
			(at 25.200102 -6.100064)
			(size 0.762 0.762)
			(drill 0.359918)
			(layers "*.Cu" "*.Mask")
			(remove_unused_layers no)
			(net "GND")
			(clearance 0.1651)
			(thermal_gap 0.1651)
		)
		(pad "GND48" thru_hole circle
			(at 25.200102 -9.700006)
			(size 0.762 0.762)
			(drill 0.359918)
			(layers "*.Cu" "*.Mask")
			(remove_unused_layers no)
			(net "GND")
			(clearance 0.1651)
			(thermal_gap 0.1651)
		)
		(pad "GND49" thru_hole circle
			(at 25.200102 -13.299948)
			(size 0.762 0.762)
			(drill 0.359918)
			(layers "*.Cu" "*.Mask")
			(remove_unused_layers no)
			(net "GND")
			(clearance 0.1651)
			(thermal_gap 0.1651)
		)
		(pad "GND50" thru_hole circle
			(at 26.999946 0.100076)
			(size 0.762 0.762)
			(drill 0.359918)
			(layers "*.Cu" "*.Mask")
			(remove_unused_layers no)
			(net "GND")
			(clearance 0.1651)
			(thermal_gap 0.1651)
		)
		(pad "GND51" thru_hole circle
			(at 26.999946 -3.50012)
			(size 0.762 0.762)
			(drill 0.359918)
			(layers "*.Cu" "*.Mask")
			(remove_unused_layers no)
			(net "GND")
			(clearance 0.1651)
			(thermal_gap 0.1651)
		)
		(pad "GND52" thru_hole circle
			(at 26.999946 -7.100062)
			(size 0.762 0.762)
			(drill 0.359918)
			(layers "*.Cu" "*.Mask")
			(remove_unused_layers no)
			(net "GND")
			(clearance 0.1651)
			(thermal_gap 0.1651)
		)
		(pad "GND53" thru_hole circle
			(at 26.999946 -10.700004)
			(size 0.762 0.762)
			(drill 0.359918)
			(layers "*.Cu" "*.Mask")
			(remove_unused_layers no)
			(net "GND")
			(clearance 0.1651)
			(thermal_gap 0.1651)
		)
		(pad "GND54" thru_hole circle
			(at 26.999946 -14.299946)
			(size 0.762 0.762)
			(drill 0.359918)
			(layers "*.Cu" "*.Mask")
			(remove_unused_layers no)
			(net "GND")
			(clearance 0.1651)
			(thermal_gap 0.1651)
		)
		(pad "GND55" thru_hole circle
			(at 28.800044 -2.500122)
			(size 0.762 0.762)
			(drill 0.359918)
			(layers "*.Cu" "*.Mask")
			(remove_unused_layers no)
			(net "GND")
			(clearance 0.1651)
			(thermal_gap 0.1651)
		)
		(pad "GND56" thru_hole circle
			(at 28.800044 -6.100064)
			(size 0.762 0.762)
			(drill 0.359918)
			(layers "*.Cu" "*.Mask")
			(remove_unused_layers no)
			(net "GND")
			(clearance 0.1651)
			(thermal_gap 0.1651)
		)
		(pad "GND57" thru_hole circle
			(at 28.800044 -9.700006)
			(size 0.762 0.762)
			(drill 0.359918)
			(layers "*.Cu" "*.Mask")
			(remove_unused_layers no)
			(net "GND")
			(clearance 0.1651)
			(thermal_gap 0.1651)
		)
		(pad "GND58" thru_hole circle
			(at 28.800044 -13.299948)
			(size 0.762 0.762)
			(drill 0.359918)
			(layers "*.Cu" "*.Mask")
			(remove_unused_layers no)
			(net "GND")
			(clearance 0.1651)
			(thermal_gap 0.1651)
		)
		(pad "GND59" thru_hole circle
			(at 30.599888 0.100076)
			(size 0.762 0.762)
			(drill 0.359918)
			(layers "*.Cu" "*.Mask")
			(remove_unused_layers no)
			(net "GND")
			(clearance 0.1651)
			(thermal_gap 0.1651)
		)
		(pad "GND60" thru_hole circle
			(at 30.599888 -3.50012)
			(size 0.762 0.762)
			(drill 0.359918)
			(layers "*.Cu" "*.Mask")
			(remove_unused_layers no)
			(net "GND")
			(clearance 0.1651)
			(thermal_gap 0.1651)
		)
		(pad "GND61" thru_hole circle
			(at 30.599888 -7.100062)
			(size 0.762 0.762)
			(drill 0.359918)
			(layers "*.Cu" "*.Mask")
			(remove_unused_layers no)
			(net "GND")
			(clearance 0.1651)
			(thermal_gap 0.1651)
		)
		(pad "GND62" thru_hole circle
			(at 30.599888 -10.700004)
			(size 0.762 0.762)
			(drill 0.359918)
			(layers "*.Cu" "*.Mask")
			(remove_unused_layers no)
			(net "GND")
			(clearance 0.1651)
			(thermal_gap 0.1651)
		)
		(pad "GND63" thru_hole circle
			(at 30.599888 -14.299946)
			(size 0.762 0.762)
			(drill 0.359918)
			(layers "*.Cu" "*.Mask")
			(remove_unused_layers no)
			(net "GND")
			(clearance 0.1651)
			(thermal_gap 0.1651)
		)
		(pad "GND64" thru_hole circle
			(at 32.399986 -2.500122)
			(size 0.762 0.762)
			(drill 0.359918)
			(layers "*.Cu" "*.Mask")
			(remove_unused_layers no)
			(net "GND")
			(clearance 0.1651)
			(thermal_gap 0.1651)
		)
		(pad "GND65" thru_hole circle
			(at 32.399986 -6.100064)
			(size 0.762 0.762)
			(drill 0.359918)
			(layers "*.Cu" "*.Mask")
			(remove_unused_layers no)
			(net "GND")
			(clearance 0.1651)
			(thermal_gap 0.1651)
		)
		(pad "GND66" thru_hole circle
			(at 32.399986 -9.700006)
			(size 0.762 0.762)
			(drill 0.359918)
			(layers "*.Cu" "*.Mask")
			(remove_unused_layers no)
			(net "GND")
			(clearance 0.1651)
			(thermal_gap 0.1651)
		)
		(pad "GND67" thru_hole circle
			(at 32.399986 -13.299948)
			(size 0.762 0.762)
			(drill 0.359918)
			(layers "*.Cu" "*.Mask")
			(remove_unused_layers no)
			(net "GND")
			(clearance 0.1651)
			(thermal_gap 0.1651)
		)
		(pad "GND68" thru_hole circle
			(at 34.200084 0.100076)
			(size 0.762 0.762)
			(drill 0.359918)
			(layers "*.Cu" "*.Mask")
			(remove_unused_layers no)
			(net "GND")
			(clearance 0.1651)
			(thermal_gap 0.1651)
		)
		(pad "GND69" thru_hole circle
			(at 34.200084 -3.50012)
			(size 0.762 0.762)
			(drill 0.359918)
			(layers "*.Cu" "*.Mask")
			(remove_unused_layers no)
			(net "GND")
			(clearance 0.1651)
			(thermal_gap 0.1651)
		)
		(pad "GND70" thru_hole circle
			(at 34.200084 -7.100062)
			(size 0.762 0.762)
			(drill 0.359918)
			(layers "*.Cu" "*.Mask")
			(remove_unused_layers no)
			(net "GND")
			(clearance 0.1651)
			(thermal_gap 0.1651)
		)
		(pad "GND71" thru_hole circle
			(at 34.200084 -10.700004)
			(size 0.762 0.762)
			(drill 0.359918)
			(layers "*.Cu" "*.Mask")
			(remove_unused_layers no)
			(net "GND")
			(clearance 0.1651)
			(thermal_gap 0.1651)
		)
		(pad "GND72" thru_hole circle
			(at 34.200084 -14.299946)
			(size 0.762 0.762)
			(drill 0.359918)
			(layers "*.Cu" "*.Mask")
			(remove_unused_layers no)
			(net "GND")
			(clearance 0.1651)
			(thermal_gap 0.1651)
		)
		(pad "H1" thru_hole circle
			(at 0 -12.199874)
			(size 0.664718 0.664718)
			(drill 0.359918)
			(layers "*.Cu" "*.Mask")
			(remove_unused_layers no)
			(net "PCIE_COMP_B_TO_IOM_B_8_DP")
			(clearance 0.264414)
			(padstack
				(mode custom)
				(layer "In1.Cu"
					(shape circle)
					(size 0.664718 0.664718)
					(clearance 0.264414)
				)
				(layer "In2.Cu"
					(shape circle)
					(size 0.664718 0.664718)
					(clearance 0.264414)
				)
				(layer "In3.Cu"
					(shape circle)
					(size 0.664718 0.664718)
					(clearance 0.264414)
				)
				(layer "In4.Cu"
					(shape circle)
					(size 0.664718 0.664718)
					(clearance 0.264414)
				)
				(layer "In5.Cu"
					(shape circle)
					(size 0.664718 0.664718)
					(clearance 0.264414)
				)
				(layer "In6.Cu"
					(shape circle)
					(size 0.762 0.762)
					(clearance 0.1651)
				)
				(layer "In7.Cu"
					(shape circle)
					(size 0.762 0.762)
					(clearance 0.1651)
				)
				(layer "In8.Cu"
					(shape circle)
					(size 0.762 0.762)
					(clearance 0.1651)
				)
				(layer "In9.Cu"
					(shape circle)
					(size 0.762 0.762)
					(clearance 0.1651)
				)
				(layer "In10.Cu"
					(shape circle)
					(size 0.762 0.762)
					(clearance 0.1651)
				)
				(layer "B.Cu"
					(shape circle)
					(size 0.762 0.762)
					(thermal_gap 0.1651)
					(clearance 0.1651)
				)
			)
		)
		(pad "H2" thru_hole circle
			(at 1.800098 -13.200126)
			(size 0.664718 0.664718)
			(drill 0.359918)
			(layers "*.Cu" "*.Mask")
			(remove_unused_layers no)
			(net "PCIE_COMP_B_TO_IOM_B_9_DP")
			(clearance 0.264414)
			(padstack
				(mode custom)
				(layer "In1.Cu"
					(shape circle)
					(size 0.664718 0.664718)
					(clearance 0.264414)
				)
				(layer "In2.Cu"
					(shape circle)
					(size 0.664718 0.664718)
					(clearance 0.264414)
				)
				(layer "In3.Cu"
					(shape circle)
					(size 0.664718 0.664718)
					(clearance 0.264414)
				)
				(layer "In4.Cu"
					(shape circle)
					(size 0.664718 0.664718)
					(clearance 0.264414)
				)
				(layer "In5.Cu"
					(shape circle)
					(size 0.664718 0.664718)
					(clearance 0.264414)
				)
				(layer "In6.Cu"
					(shape circle)
					(size 0.762 0.762)
					(clearance 0.1651)
				)
				(layer "In7.Cu"
					(shape circle)
					(size 0.762 0.762)
					(clearance 0.1651)
				)
				(layer "In8.Cu"
					(shape circle)
					(size 0.762 0.762)
					(clearance 0.1651)
				)
				(layer "In9.Cu"
					(shape circle)
					(size 0.762 0.762)
					(clearance 0.1651)
				)
				(layer "In10.Cu"
					(shape circle)
					(size 0.762 0.762)
					(clearance 0.1651)
				)
				(layer "B.Cu"
					(shape circle)
					(size 0.762 0.762)
					(thermal_gap 0.1651)
					(clearance 0.1651)
				)
			)
		)
		(pad "H3" thru_hole circle
			(at 3.599942 -12.199874)
			(size 0.664718 0.664718)
			(drill 0.359918)
			(layers "*.Cu" "*.Mask")
			(remove_unused_layers no)
			(net "PCIE_COMP_B_TO_IOM_B_10_DP")
			(clearance 0.264414)
			(padstack
				(mode custom)
				(layer "In1.Cu"
					(shape circle)
					(size 0.664718 0.664718)
					(clearance 0.264414)
				)
				(layer "In2.Cu"
					(shape circle)
					(size 0.664718 0.664718)
					(clearance 0.264414)
				)
				(layer "In3.Cu"
					(shape circle)
					(size 0.664718 0.664718)
					(clearance 0.264414)
				)
				(layer "In4.Cu"
					(shape circle)
					(size 0.664718 0.664718)
					(clearance 0.264414)
				)
				(layer "In5.Cu"
					(shape circle)
					(size 0.664718 0.664718)
					(clearance 0.264414)
				)
				(layer "In6.Cu"
					(shape circle)
					(size 0.762 0.762)
					(clearance 0.1651)
				)
				(layer "In7.Cu"
					(shape circle)
					(size 0.762 0.762)
					(clearance 0.1651)
				)
				(layer "In8.Cu"
					(shape circle)
					(size 0.762 0.762)
					(clearance 0.1651)
				)
				(layer "In9.Cu"
					(shape circle)
					(size 0.762 0.762)
					(clearance 0.1651)
				)
				(layer "In10.Cu"
					(shape circle)
					(size 0.762 0.762)
					(clearance 0.1651)
				)
				(layer "B.Cu"
					(shape circle)
					(size 0.762 0.762)
					(thermal_gap 0.1651)
					(clearance 0.1651)
				)
			)
		)
		(pad "H4" thru_hole circle
			(at 5.40004 -13.200126)
			(size 0.664718 0.664718)
			(drill 0.359918)
			(layers "*.Cu" "*.Mask")
			(remove_unused_layers no)
			(net "PCIE_COMP_B_TO_IOM_B_11_DP")
			(clearance 0.264414)
			(padstack
				(mode custom)
				(layer "In1.Cu"
					(shape circle)
					(size 0.664718 0.664718)
					(clearance 0.264414)
				)
				(layer "In2.Cu"
					(shape circle)
					(size 0.664718 0.664718)
					(clearance 0.264414)
				)
				(layer "In3.Cu"
					(shape circle)
					(size 0.664718 0.664718)
					(clearance 0.264414)
				)
				(layer "In4.Cu"
					(shape circle)
					(size 0.664718 0.664718)
					(clearance 0.264414)
				)
				(layer "In5.Cu"
					(shape circle)
					(size 0.664718 0.664718)
					(clearance 0.264414)
				)
				(layer "In6.Cu"
					(shape circle)
					(size 0.762 0.762)
					(clearance 0.1651)
				)
				(layer "In7.Cu"
					(shape circle)
					(size 0.762 0.762)
					(clearance 0.1651)
				)
				(layer "In8.Cu"
					(shape circle)
					(size 0.762 0.762)
					(clearance 0.1651)
				)
				(layer "In9.Cu"
					(shape circle)
					(size 0.762 0.762)
					(clearance 0.1651)
				)
				(layer "In10.Cu"
					(shape circle)
					(size 0.762 0.762)
					(clearance 0.1651)
				)
				(layer "B.Cu"
					(shape circle)
					(size 0.762 0.762)
					(thermal_gap 0.1651)
					(clearance 0.1651)
				)
			)
		)
		(pad "H5" thru_hole circle
			(at 7.199884 -12.199874)
			(size 0.664718 0.664718)
			(drill 0.359918)
			(layers "*.Cu" "*.Mask")
			(remove_unused_layers no)
			(net "PCIE_COMP_B_TO_IOM_B_12_DP")
			(clearance 0.264414)
			(padstack
				(mode custom)
				(layer "In1.Cu"
					(shape circle)
					(size 0.664718 0.664718)
					(clearance 0.264414)
				)
				(layer "In2.Cu"
					(shape circle)
					(size 0.664718 0.664718)
					(clearance 0.264414)
				)
				(layer "In3.Cu"
					(shape circle)
					(size 0.664718 0.664718)
					(clearance 0.264414)
				)
				(layer "In4.Cu"
					(shape circle)
					(size 0.664718 0.664718)
					(clearance 0.264414)
				)
				(layer "In5.Cu"
					(shape circle)
					(size 0.664718 0.664718)
					(clearance 0.264414)
				)
				(layer "In6.Cu"
					(shape circle)
					(size 0.762 0.762)
					(clearance 0.1651)
				)
				(layer "In7.Cu"
					(shape circle)
					(size 0.762 0.762)
					(clearance 0.1651)
				)
				(layer "In8.Cu"
					(shape circle)
					(size 0.762 0.762)
					(clearance 0.1651)
				)
				(layer "In9.Cu"
					(shape circle)
					(size 0.762 0.762)
					(clearance 0.1651)
				)
				(layer "In10.Cu"
					(shape circle)
					(size 0.762 0.762)
					(clearance 0.1651)
				)
				(layer "B.Cu"
					(shape circle)
					(size 0.762 0.762)
					(thermal_gap 0.1651)
					(clearance 0.1651)
				)
			)
		)
		(pad "H6" thru_hole circle
			(at 8.999982 -13.200126)
			(size 0.664718 0.664718)
			(drill 0.359918)
			(layers "*.Cu" "*.Mask")
			(remove_unused_layers no)
			(net "PCIE_COMP_B_TO_IOM_B_13_DP")
			(clearance 0.264414)
			(padstack
				(mode custom)
				(layer "In1.Cu"
					(shape circle)
					(size 0.664718 0.664718)
					(clearance 0.264414)
				)
				(layer "In2.Cu"
					(shape circle)
					(size 0.664718 0.664718)
					(clearance 0.264414)
				)
				(layer "In3.Cu"
					(shape circle)
					(size 0.664718 0.664718)
					(clearance 0.264414)
				)
				(layer "In4.Cu"
					(shape circle)
					(size 0.664718 0.664718)
					(clearance 0.264414)
				)
				(layer "In5.Cu"
					(shape circle)
					(size 0.664718 0.664718)
					(clearance 0.264414)
				)
				(layer "In6.Cu"
					(shape circle)
					(size 0.762 0.762)
					(clearance 0.1651)
				)
				(layer "In7.Cu"
					(shape circle)
					(size 0.762 0.762)
					(clearance 0.1651)
				)
				(layer "In8.Cu"
					(shape circle)
					(size 0.762 0.762)
					(clearance 0.1651)
				)
				(layer "In9.Cu"
					(shape circle)
					(size 0.762 0.762)
					(clearance 0.1651)
				)
				(layer "In10.Cu"
					(shape circle)
					(size 0.762 0.762)
					(clearance 0.1651)
				)
				(layer "B.Cu"
					(shape circle)
					(size 0.762 0.762)
					(thermal_gap 0.1651)
					(clearance 0.1651)
				)
			)
		)
		(pad "H7" thru_hole circle
			(at 10.80008 -12.199874)
			(size 0.664718 0.664718)
			(drill 0.359918)
			(layers "*.Cu" "*.Mask")
			(remove_unused_layers no)
			(net "PCIE_COMP_B_TO_IOM_B_14_DP")
			(clearance 0.264414)
			(padstack
				(mode custom)
				(layer "In1.Cu"
					(shape circle)
					(size 0.664718 0.664718)
					(clearance 0.264414)
				)
				(layer "In2.Cu"
					(shape circle)
					(size 0.664718 0.664718)
					(clearance 0.264414)
				)
				(layer "In3.Cu"
					(shape circle)
					(size 0.664718 0.664718)
					(clearance 0.264414)
				)
				(layer "In4.Cu"
					(shape circle)
					(size 0.664718 0.664718)
					(clearance 0.264414)
				)
				(layer "In5.Cu"
					(shape circle)
					(size 0.664718 0.664718)
					(clearance 0.264414)
				)
				(layer "In6.Cu"
					(shape circle)
					(size 0.762 0.762)
					(clearance 0.1651)
				)
				(layer "In7.Cu"
					(shape circle)
					(size 0.762 0.762)
					(clearance 0.1651)
				)
				(layer "In8.Cu"
					(shape circle)
					(size 0.762 0.762)
					(clearance 0.1651)
				)
				(layer "In9.Cu"
					(shape circle)
					(size 0.762 0.762)
					(clearance 0.1651)
				)
				(layer "In10.Cu"
					(shape circle)
					(size 0.762 0.762)
					(clearance 0.1651)
				)
				(layer "B.Cu"
					(shape circle)
					(size 0.762 0.762)
					(thermal_gap 0.1651)
					(clearance 0.1651)
				)
			)
		)
		(pad "H8" thru_hole circle
			(at 12.599924 -13.200126)
			(size 0.664718 0.664718)
			(drill 0.359918)
			(layers "*.Cu" "*.Mask")
			(remove_unused_layers no)
			(net "PCIE_COMP_B_TO_IOM_B_15_DP")
			(clearance 0.264414)
			(padstack
				(mode custom)
				(layer "In1.Cu"
					(shape circle)
					(size 0.664718 0.664718)
					(clearance 0.264414)
				)
				(layer "In2.Cu"
					(shape circle)
					(size 0.664718 0.664718)
					(clearance 0.264414)
				)
				(layer "In3.Cu"
					(shape circle)
					(size 0.664718 0.664718)
					(clearance 0.264414)
				)
				(layer "In4.Cu"
					(shape circle)
					(size 0.664718 0.664718)
					(clearance 0.264414)
				)
				(layer "In5.Cu"
					(shape circle)
					(size 0.664718 0.664718)
					(clearance 0.264414)
				)
				(layer "In6.Cu"
					(shape circle)
					(size 0.762 0.762)
					(clearance 0.1651)
				)
				(layer "In7.Cu"
					(shape circle)
					(size 0.762 0.762)
					(clearance 0.1651)
				)
				(layer "In8.Cu"
					(shape circle)
					(size 0.762 0.762)
					(clearance 0.1651)
				)
				(layer "In9.Cu"
					(shape circle)
					(size 0.762 0.762)
					(clearance 0.1651)
				)
				(layer "In10.Cu"
					(shape circle)
					(size 0.762 0.762)
					(clearance 0.1651)
				)
				(layer "B.Cu"
					(shape circle)
					(size 0.762 0.762)
					(thermal_gap 0.1651)
					(clearance 0.1651)
				)
			)
		)
		(pad "H9" thru_hole circle
			(at 21.599906 -12.199874)
			(size 0.664718 0.664718)
			(drill 0.359918)
			(layers "*.Cu" "*.Mask")
			(remove_unused_layers no)
			(net "PCIE_COMP_B_TO_IOM_B_23_DP")
			(clearance 0.264414)
			(padstack
				(mode custom)
				(layer "In1.Cu"
					(shape circle)
					(size 0.664718 0.664718)
					(clearance 0.264414)
				)
				(layer "In2.Cu"
					(shape circle)
					(size 0.664718 0.664718)
					(clearance 0.264414)
				)
				(layer "In3.Cu"
					(shape circle)
					(size 0.664718 0.664718)
					(clearance 0.264414)
				)
				(layer "In4.Cu"
					(shape circle)
					(size 0.664718 0.664718)
					(clearance 0.264414)
				)
				(layer "In5.Cu"
					(shape circle)
					(size 0.664718 0.664718)
					(clearance 0.264414)
				)
				(layer "In6.Cu"
					(shape circle)
					(size 0.762 0.762)
					(clearance 0.1651)
				)
				(layer "In7.Cu"
					(shape circle)
					(size 0.762 0.762)
					(clearance 0.1651)
				)
				(layer "In8.Cu"
					(shape circle)
					(size 0.762 0.762)
					(clearance 0.1651)
				)
				(layer "In9.Cu"
					(shape circle)
					(size 0.762 0.762)
					(clearance 0.1651)
				)
				(layer "In10.Cu"
					(shape circle)
					(size 0.762 0.762)
					(clearance 0.1651)
				)
				(layer "B.Cu"
					(shape circle)
					(size 0.762 0.762)
					(thermal_gap 0.1651)
					(clearance 0.1651)
				)
			)
		)
		(pad "H10" thru_hole circle
			(at 23.400004 -13.200126)
			(size 0.664718 0.664718)
			(drill 0.359918)
			(layers "*.Cu" "*.Mask")
			(remove_unused_layers no)
			(net "PCIE_COMP_B_TO_IOM_B_22_DP")
			(clearance 0.264414)
			(padstack
				(mode custom)
				(layer "In1.Cu"
					(shape circle)
					(size 0.664718 0.664718)
					(clearance 0.264414)
				)
				(layer "In2.Cu"
					(shape circle)
					(size 0.664718 0.664718)
					(clearance 0.264414)
				)
				(layer "In3.Cu"
					(shape circle)
					(size 0.664718 0.664718)
					(clearance 0.264414)
				)
				(layer "In4.Cu"
					(shape circle)
					(size 0.664718 0.664718)
					(clearance 0.264414)
				)
				(layer "In5.Cu"
					(shape circle)
					(size 0.664718 0.664718)
					(clearance 0.264414)
				)
				(layer "In6.Cu"
					(shape circle)
					(size 0.762 0.762)
					(clearance 0.1651)
				)
				(layer "In7.Cu"
					(shape circle)
					(size 0.762 0.762)
					(clearance 0.1651)
				)
				(layer "In8.Cu"
					(shape circle)
					(size 0.762 0.762)
					(clearance 0.1651)
				)
				(layer "In9.Cu"
					(shape circle)
					(size 0.762 0.762)
					(clearance 0.1651)
				)
				(layer "In10.Cu"
					(shape circle)
					(size 0.762 0.762)
					(clearance 0.1651)
				)
				(layer "B.Cu"
					(shape circle)
					(size 0.762 0.762)
					(thermal_gap 0.1651)
					(clearance 0.1651)
				)
			)
		)
		(pad "H11" thru_hole circle
			(at 25.200102 -12.199874)
			(size 0.664718 0.664718)
			(drill 0.359918)
			(layers "*.Cu" "*.Mask")
			(remove_unused_layers no)
			(net "PCIE_COMP_B_TO_IOM_B_21_DP")
			(clearance 0.264414)
			(padstack
				(mode custom)
				(layer "In1.Cu"
					(shape circle)
					(size 0.664718 0.664718)
					(clearance 0.264414)
				)
				(layer "In2.Cu"
					(shape circle)
					(size 0.664718 0.664718)
					(clearance 0.264414)
				)
				(layer "In3.Cu"
					(shape circle)
					(size 0.664718 0.664718)
					(clearance 0.264414)
				)
				(layer "In4.Cu"
					(shape circle)
					(size 0.664718 0.664718)
					(clearance 0.264414)
				)
				(layer "In5.Cu"
					(shape circle)
					(size 0.664718 0.664718)
					(clearance 0.264414)
				)
				(layer "In6.Cu"
					(shape circle)
					(size 0.762 0.762)
					(clearance 0.1651)
				)
				(layer "In7.Cu"
					(shape circle)
					(size 0.762 0.762)
					(clearance 0.1651)
				)
				(layer "In8.Cu"
					(shape circle)
					(size 0.762 0.762)
					(clearance 0.1651)
				)
				(layer "In9.Cu"
					(shape circle)
					(size 0.762 0.762)
					(clearance 0.1651)
				)
				(layer "In10.Cu"
					(shape circle)
					(size 0.762 0.762)
					(clearance 0.1651)
				)
				(layer "B.Cu"
					(shape circle)
					(size 0.762 0.762)
					(thermal_gap 0.1651)
					(clearance 0.1651)
				)
			)
		)
		(pad "H12" thru_hole circle
			(at 26.999946 -13.200126)
			(size 0.664718 0.664718)
			(drill 0.359918)
			(layers "*.Cu" "*.Mask")
			(remove_unused_layers no)
			(net "PCIE_COMP_B_TO_IOM_B_20_DP")
			(clearance 0.264414)
			(padstack
				(mode custom)
				(layer "In1.Cu"
					(shape circle)
					(size 0.664718 0.664718)
					(clearance 0.264414)
				)
				(layer "In2.Cu"
					(shape circle)
					(size 0.664718 0.664718)
					(clearance 0.264414)
				)
				(layer "In3.Cu"
					(shape circle)
					(size 0.664718 0.664718)
					(clearance 0.264414)
				)
				(layer "In4.Cu"
					(shape circle)
					(size 0.664718 0.664718)
					(clearance 0.264414)
				)
				(layer "In5.Cu"
					(shape circle)
					(size 0.664718 0.664718)
					(clearance 0.264414)
				)
				(layer "In6.Cu"
					(shape circle)
					(size 0.762 0.762)
					(clearance 0.1651)
				)
				(layer "In7.Cu"
					(shape circle)
					(size 0.762 0.762)
					(clearance 0.1651)
				)
				(layer "In8.Cu"
					(shape circle)
					(size 0.762 0.762)
					(clearance 0.1651)
				)
				(layer "In9.Cu"
					(shape circle)
					(size 0.762 0.762)
					(clearance 0.1651)
				)
				(layer "In10.Cu"
					(shape circle)
					(size 0.762 0.762)
					(clearance 0.1651)
				)
				(layer "B.Cu"
					(shape circle)
					(size 0.762 0.762)
					(thermal_gap 0.1651)
					(clearance 0.1651)
				)
			)
		)
		(pad "H13" thru_hole circle
			(at 28.800044 -12.199874)
			(size 0.664718 0.664718)
			(drill 0.359918)
			(layers "*.Cu" "*.Mask")
			(remove_unused_layers no)
			(net "PCIE_COMP_B_TO_IOM_B_19_DP")
			(clearance 0.264414)
			(padstack
				(mode custom)
				(layer "In1.Cu"
					(shape circle)
					(size 0.664718 0.664718)
					(clearance 0.264414)
				)
				(layer "In2.Cu"
					(shape circle)
					(size 0.664718 0.664718)
					(clearance 0.264414)
				)
				(layer "In3.Cu"
					(shape circle)
					(size 0.664718 0.664718)
					(clearance 0.264414)
				)
				(layer "In4.Cu"
					(shape circle)
					(size 0.664718 0.664718)
					(clearance 0.264414)
				)
				(layer "In5.Cu"
					(shape circle)
					(size 0.664718 0.664718)
					(clearance 0.264414)
				)
				(layer "In6.Cu"
					(shape circle)
					(size 0.762 0.762)
					(clearance 0.1651)
				)
				(layer "In7.Cu"
					(shape circle)
					(size 0.762 0.762)
					(clearance 0.1651)
				)
				(layer "In8.Cu"
					(shape circle)
					(size 0.762 0.762)
					(clearance 0.1651)
				)
				(layer "In9.Cu"
					(shape circle)
					(size 0.762 0.762)
					(clearance 0.1651)
				)
				(layer "In10.Cu"
					(shape circle)
					(size 0.762 0.762)
					(clearance 0.1651)
				)
				(layer "B.Cu"
					(shape circle)
					(size 0.762 0.762)
					(thermal_gap 0.1651)
					(clearance 0.1651)
				)
			)
		)
		(pad "H14" thru_hole circle
			(at 30.599888 -13.200126)
			(size 0.664718 0.664718)
			(drill 0.359918)
			(layers "*.Cu" "*.Mask")
			(remove_unused_layers no)
			(net "PCIE_COMP_B_TO_IOM_B_18_DP")
			(clearance 0.264414)
			(padstack
				(mode custom)
				(layer "In1.Cu"
					(shape circle)
					(size 0.664718 0.664718)
					(clearance 0.264414)
				)
				(layer "In2.Cu"
					(shape circle)
					(size 0.664718 0.664718)
					(clearance 0.264414)
				)
				(layer "In3.Cu"
					(shape circle)
					(size 0.664718 0.664718)
					(clearance 0.264414)
				)
				(layer "In4.Cu"
					(shape circle)
					(size 0.664718 0.664718)
					(clearance 0.264414)
				)
				(layer "In5.Cu"
					(shape circle)
					(size 0.664718 0.664718)
					(clearance 0.264414)
				)
				(layer "In6.Cu"
					(shape circle)
					(size 0.762 0.762)
					(clearance 0.1651)
				)
				(layer "In7.Cu"
					(shape circle)
					(size 0.762 0.762)
					(clearance 0.1651)
				)
				(layer "In8.Cu"
					(shape circle)
					(size 0.762 0.762)
					(clearance 0.1651)
				)
				(layer "In9.Cu"
					(shape circle)
					(size 0.762 0.762)
					(clearance 0.1651)
				)
				(layer "In10.Cu"
					(shape circle)
					(size 0.762 0.762)
					(clearance 0.1651)
				)
				(layer "B.Cu"
					(shape circle)
					(size 0.762 0.762)
					(thermal_gap 0.1651)
					(clearance 0.1651)
				)
			)
		)
		(pad "H15" thru_hole circle
			(at 32.399986 -12.199874)
			(size 0.664718 0.664718)
			(drill 0.359918)
			(layers "*.Cu" "*.Mask")
			(remove_unused_layers no)
			(net "PCIE_COMP_B_TO_IOM_B_17_DP")
			(clearance 0.264414)
			(padstack
				(mode custom)
				(layer "In1.Cu"
					(shape circle)
					(size 0.664718 0.664718)
					(clearance 0.264414)
				)
				(layer "In2.Cu"
					(shape circle)
					(size 0.664718 0.664718)
					(clearance 0.264414)
				)
				(layer "In3.Cu"
					(shape circle)
					(size 0.664718 0.664718)
					(clearance 0.264414)
				)
				(layer "In4.Cu"
					(shape circle)
					(size 0.664718 0.664718)
					(clearance 0.264414)
				)
				(layer "In5.Cu"
					(shape circle)
					(size 0.664718 0.664718)
					(clearance 0.264414)
				)
				(layer "In6.Cu"
					(shape circle)
					(size 0.762 0.762)
					(clearance 0.1651)
				)
				(layer "In7.Cu"
					(shape circle)
					(size 0.762 0.762)
					(clearance 0.1651)
				)
				(layer "In8.Cu"
					(shape circle)
					(size 0.762 0.762)
					(clearance 0.1651)
				)
				(layer "In9.Cu"
					(shape circle)
					(size 0.762 0.762)
					(clearance 0.1651)
				)
				(layer "In10.Cu"
					(shape circle)
					(size 0.762 0.762)
					(clearance 0.1651)
				)
				(layer "B.Cu"
					(shape circle)
					(size 0.762 0.762)
					(thermal_gap 0.1651)
					(clearance 0.1651)
				)
			)
		)
		(pad "H16" thru_hole circle
			(at 34.200084 -13.200126)
			(size 0.664718 0.664718)
			(drill 0.359918)
			(layers "*.Cu" "*.Mask")
			(remove_unused_layers no)
			(net "PCIE_COMP_B_TO_IOM_B_16_DP")
			(clearance 0.264414)
			(padstack
				(mode custom)
				(layer "In1.Cu"
					(shape circle)
					(size 0.664718 0.664718)
					(clearance 0.264414)
				)
				(layer "In2.Cu"
					(shape circle)
					(size 0.664718 0.664718)
					(clearance 0.264414)
				)
				(layer "In3.Cu"
					(shape circle)
					(size 0.664718 0.664718)
					(clearance 0.264414)
				)
				(layer "In4.Cu"
					(shape circle)
					(size 0.664718 0.664718)
					(clearance 0.264414)
				)
				(layer "In5.Cu"
					(shape circle)
					(size 0.664718 0.664718)
					(clearance 0.264414)
				)
				(layer "In6.Cu"
					(shape circle)
					(size 0.762 0.762)
					(clearance 0.1651)
				)
				(layer "In7.Cu"
					(shape circle)
					(size 0.762 0.762)
					(clearance 0.1651)
				)
				(layer "In8.Cu"
					(shape circle)
					(size 0.762 0.762)
					(clearance 0.1651)
				)
				(layer "In9.Cu"
					(shape circle)
					(size 0.762 0.762)
					(clearance 0.1651)
				)
				(layer "In10.Cu"
					(shape circle)
					(size 0.762 0.762)
					(clearance 0.1651)
				)
				(layer "B.Cu"
					(shape circle)
					(size 0.762 0.762)
					(thermal_gap 0.1651)
					(clearance 0.1651)
				)
			)
		)
		(zone
			(layer "F.Cu")
			(hatch none 0.5)
			(connect_pads
				(clearance 0)
			)
			(min_thickness 0.25)
			(keepout
				(tracks not_allowed)
				(vias allowed)
				(pads allowed)
				(copperpour not_allowed)
				(footprints allowed)
			)
			(placement
				(enabled no)
				(sheetname "")
			)
			(fill
				(thermal_gap 0.5)
				(thermal_bridge_width 0.5)
				(island_removal_mode 0)
			)
			(polygon
				(pts
					(arc
						(start 355.746812 -22.350222)
						(mid 354.553012 -22.350222)
						(end 355.746812 -22.350222)
					)
				)
			)
		)
		(zone
			(layer "F.Cu")
			(hatch none 0.5)
			(connect_pads
				(clearance 0)
			)
			(min_thickness 0.25)
			(keepout
				(tracks allowed)
				(vias not_allowed)
				(pads allowed)
				(copperpour not_allowed)
				(footprints allowed)
			)
			(placement
				(enabled no)
				(sheetname "")
			)
			(fill
				(thermal_gap 0.5)
				(thermal_bridge_width 0.5)
				(island_removal_mode 0)
			)
			(polygon
				(pts
					(arc
						(start 355.746812 -22.350222)
						(mid 354.553012 -22.350222)
						(end 355.746812 -22.350222)
					)
				)
			)
		)
		(zone
			(layer "F.Cu")
			(hatch none 0.5)
			(connect_pads
				(clearance 0)
			)
			(min_thickness 0.25)
			(keepout
				(tracks not_allowed)
				(vias allowed)
				(pads allowed)
				(copperpour not_allowed)
				(footprints allowed)
			)
			(placement
				(enabled no)
				(sheetname "")
			)
			(fill
				(thermal_gap 0.5)
				(thermal_bridge_width 0.5)
				(island_removal_mode 0)
			)
			(polygon
				(pts
					(arc
						(start 355.746812 -20.950174)
						(mid 354.553012 -20.950174)
						(end 355.746812 -20.950174)
					)
				)
			)
		)
		(zone
			(layer "F.Cu")
			(hatch none 0.5)
			(connect_pads
				(clearance 0)
			)
			(min_thickness 0.25)
			(keepout
				(tracks allowed)
				(vias not_allowed)
				(pads allowed)
				(copperpour not_allowed)
				(footprints allowed)
			)
			(placement
				(enabled no)
				(sheetname "")
			)
			(fill
				(thermal_gap 0.5)
				(thermal_bridge_width 0.5)
				(island_removal_mode 0)
			)
			(polygon
				(pts
					(arc
						(start 355.746812 -20.950174)
						(mid 354.553012 -20.950174)
						(end 355.746812 -20.950174)
					)
				)
			)
		)
		(zone
			(layer "F.Cu")
			(hatch none 0.5)
			(connect_pads
				(clearance 0)
			)
			(min_thickness 0.25)
			(keepout
				(tracks not_allowed)
				(vias allowed)
				(pads allowed)
				(copperpour not_allowed)
				(footprints allowed)
			)
			(placement
				(enabled no)
				(sheetname "")
			)
			(fill
				(thermal_gap 0.5)
				(thermal_bridge_width 0.5)
				(island_removal_mode 0)
			)
			(polygon
				(pts
					(arc
						(start 355.746812 -18.750026)
						(mid 354.553012 -18.750026)
						(end 355.746812 -18.750026)
					)
				)
			)
		)
		(zone
			(layer "F.Cu")
			(hatch none 0.5)
			(connect_pads
				(clearance 0)
			)
			(min_thickness 0.25)
			(keepout
				(tracks allowed)
				(vias not_allowed)
				(pads allowed)
				(copperpour not_allowed)
				(footprints allowed)
			)
			(placement
				(enabled no)
				(sheetname "")
			)
			(fill
				(thermal_gap 0.5)
				(thermal_bridge_width 0.5)
				(island_removal_mode 0)
			)
			(polygon
				(pts
					(arc
						(start 355.746812 -18.750026)
						(mid 354.553012 -18.750026)
						(end 355.746812 -18.750026)
					)
				)
			)
		)
		(zone
			(layer "F.Cu")
			(hatch none 0.5)
			(connect_pads
				(clearance 0)
			)
			(min_thickness 0.25)
			(keepout
				(tracks not_allowed)
				(vias allowed)
				(pads allowed)
				(copperpour not_allowed)
				(footprints allowed)
			)
			(placement
				(enabled no)
				(sheetname "")
			)
			(fill
				(thermal_gap 0.5)
				(thermal_bridge_width 0.5)
				(island_removal_mode 0)
			)
			(polygon
				(pts
					(arc
						(start 355.746812 -17.349978)
						(mid 354.553012 -17.349978)
						(end 355.746812 -17.349978)
					)
				)
			)
		)
		(zone
			(layer "F.Cu")
			(hatch none 0.5)
			(connect_pads
				(clearance 0)
			)
			(min_thickness 0.25)
			(keepout
				(tracks allowed)
				(vias not_allowed)
				(pads allowed)
				(copperpour not_allowed)
				(footprints allowed)
			)
			(placement
				(enabled no)
				(sheetname "")
			)
			(fill
				(thermal_gap 0.5)
				(thermal_bridge_width 0.5)
				(island_removal_mode 0)
			)
			(polygon
				(pts
					(arc
						(start 355.746812 -17.349978)
						(mid 354.553012 -17.349978)
						(end 355.746812 -17.349978)
					)
				)
			)
		)
		(zone
			(layer "F.Cu")
			(hatch none 0.5)
			(connect_pads
				(clearance 0)
			)
			(min_thickness 0.25)
			(keepout
				(tracks allowed)
				(vias not_allowed)
				(pads allowed)
				(copperpour not_allowed)
				(footprints allowed)
			)
			(placement
				(enabled no)
				(sheetname "")
			)
			(fill
				(thermal_gap 0.5)
				(thermal_bridge_width 0.5)
				(island_removal_mode 0)
			)
			(polygon
				(pts
					(arc
						(start 357.54691 -23.35022)
						(mid 356.35311 -23.35022)
						(end 357.54691 -23.35022)
					)
				)
			)
		)
		(zone
			(layer "F.Cu")
			(hatch none 0.5)
			(connect_pads
				(clearance 0)
			)
			(min_thickness 0.25)
			(keepout
				(tracks not_allowed)
				(vias allowed)
				(pads allowed)
				(copperpour not_allowed)
				(footprints allowed)
			)
			(placement
				(enabled no)
				(sheetname "")
			)
			(fill
				(thermal_gap 0.5)
				(thermal_bridge_width 0.5)
				(island_removal_mode 0)
			)
			(polygon
				(pts
					(arc
						(start 357.54691 -23.35022)
						(mid 356.35311 -23.35022)
						(end 357.54691 -23.35022)
					)
				)
			)
		)
		(zone
			(layer "F.Cu")
			(hatch none 0.5)
			(connect_pads
				(clearance 0)
			)
			(min_thickness 0.25)
			(keepout
				(tracks allowed)
				(vias not_allowed)
				(pads allowed)
				(copperpour not_allowed)
				(footprints allowed)
			)
			(placement
				(enabled no)
				(sheetname "")
			)
			(fill
				(thermal_gap 0.5)
				(thermal_bridge_width 0.5)
				(island_removal_mode 0)
			)
			(polygon
				(pts
					(arc
						(start 357.54691 -21.950172)
						(mid 356.35311 -21.950172)
						(end 357.54691 -21.950172)
					)
				)
			)
		)
		(zone
			(layer "F.Cu")
			(hatch none 0.5)
			(connect_pads
				(clearance 0)
			)
			(min_thickness 0.25)
			(keepout
				(tracks not_allowed)
				(vias allowed)
				(pads allowed)
				(copperpour not_allowed)
				(footprints allowed)
			)
			(placement
				(enabled no)
				(sheetname "")
			)
			(fill
				(thermal_gap 0.5)
				(thermal_bridge_width 0.5)
				(island_removal_mode 0)
			)
			(polygon
				(pts
					(arc
						(start 357.54691 -21.950172)
						(mid 356.35311 -21.950172)
						(end 357.54691 -21.950172)
					)
				)
			)
		)
		(zone
			(layer "F.Cu")
			(hatch none 0.5)
			(connect_pads
				(clearance 0)
			)
			(min_thickness 0.25)
			(keepout
				(tracks allowed)
				(vias not_allowed)
				(pads allowed)
				(copperpour not_allowed)
				(footprints allowed)
			)
			(placement
				(enabled no)
				(sheetname "")
			)
			(fill
				(thermal_gap 0.5)
				(thermal_bridge_width 0.5)
				(island_removal_mode 0)
			)
			(polygon
				(pts
					(arc
						(start 357.54691 -19.750024)
						(mid 356.35311 -19.750024)
						(end 357.54691 -19.750024)
					)
				)
			)
		)
		(zone
			(layer "F.Cu")
			(hatch none 0.5)
			(connect_pads
				(clearance 0)
			)
			(min_thickness 0.25)
			(keepout
				(tracks not_allowed)
				(vias allowed)
				(pads allowed)
				(copperpour not_allowed)
				(footprints allowed)
			)
			(placement
				(enabled no)
				(sheetname "")
			)
			(fill
				(thermal_gap 0.5)
				(thermal_bridge_width 0.5)
				(island_removal_mode 0)
			)
			(polygon
				(pts
					(arc
						(start 357.54691 -19.750024)
						(mid 356.35311 -19.750024)
						(end 357.54691 -19.750024)
					)
				)
			)
		)
		(zone
			(layer "F.Cu")
			(hatch none 0.5)
			(connect_pads
				(clearance 0)
			)
			(min_thickness 0.25)
			(keepout
				(tracks not_allowed)
				(vias allowed)
				(pads allowed)
				(copperpour not_allowed)
				(footprints allowed)
			)
			(placement
				(enabled no)
				(sheetname "")
			)
			(fill
				(thermal_gap 0.5)
				(thermal_bridge_width 0.5)
				(island_removal_mode 0)
			)
			(polygon
				(pts
					(arc
						(start 357.54691 -18.35023)
						(mid 356.35311 -18.35023)
						(end 357.54691 -18.35023)
					)
				)
			)
		)
		(zone
			(layer "F.Cu")
			(hatch none 0.5)
			(connect_pads
				(clearance 0)
			)
			(min_thickness 0.25)
			(keepout
				(tracks allowed)
				(vias not_allowed)
				(pads allowed)
				(copperpour not_allowed)
				(footprints allowed)
			)
			(placement
				(enabled no)
				(sheetname "")
			)
			(fill
				(thermal_gap 0.5)
				(thermal_bridge_width 0.5)
				(island_removal_mode 0)
			)
			(polygon
				(pts
					(arc
						(start 357.54691 -18.35023)
						(mid 356.35311 -18.35023)
						(end 357.54691 -18.35023)
					)
				)
			)
		)
		(zone
			(layer "F.Cu")
			(hatch none 0.5)
			(connect_pads
				(clearance 0)
			)
			(min_thickness 0.25)
			(keepout
				(tracks allowed)
				(vias not_allowed)
				(pads allowed)
				(copperpour not_allowed)
				(footprints allowed)
			)
			(placement
				(enabled no)
				(sheetname "")
			)
			(fill
				(thermal_gap 0.5)
				(thermal_bridge_width 0.5)
				(island_removal_mode 0)
			)
			(polygon
				(pts
					(arc
						(start 359.347008 -22.350222)
						(mid 358.153208 -22.350222)
						(end 359.347008 -22.350222)
					)
				)
			)
		)
		(zone
			(layer "F.Cu")
			(hatch none 0.5)
			(connect_pads
				(clearance 0)
			)
			(min_thickness 0.25)
			(keepout
				(tracks not_allowed)
				(vias allowed)
				(pads allowed)
				(copperpour not_allowed)
				(footprints allowed)
			)
			(placement
				(enabled no)
				(sheetname "")
			)
			(fill
				(thermal_gap 0.5)
				(thermal_bridge_width 0.5)
				(island_removal_mode 0)
			)
			(polygon
				(pts
					(arc
						(start 359.347008 -22.350222)
						(mid 358.153208 -22.350222)
						(end 359.347008 -22.350222)
					)
				)
			)
		)
		(zone
			(layer "F.Cu")
			(hatch none 0.5)
			(connect_pads
				(clearance 0)
			)
			(min_thickness 0.25)
			(keepout
				(tracks not_allowed)
				(vias allowed)
				(pads allowed)
				(copperpour not_allowed)
				(footprints allowed)
			)
			(placement
				(enabled no)
				(sheetname "")
			)
			(fill
				(thermal_gap 0.5)
				(thermal_bridge_width 0.5)
				(island_removal_mode 0)
			)
			(polygon
				(pts
					(arc
						(start 359.347008 -20.950174)
						(mid 358.153208 -20.950174)
						(end 359.347008 -20.950174)
					)
				)
			)
		)
		(zone
			(layer "F.Cu")
			(hatch none 0.5)
			(connect_pads
				(clearance 0)
			)
			(min_thickness 0.25)
			(keepout
				(tracks allowed)
				(vias not_allowed)
				(pads allowed)
				(copperpour not_allowed)
				(footprints allowed)
			)
			(placement
				(enabled no)
				(sheetname "")
			)
			(fill
				(thermal_gap 0.5)
				(thermal_bridge_width 0.5)
				(island_removal_mode 0)
			)
			(polygon
				(pts
					(arc
						(start 359.347008 -20.950174)
						(mid 358.153208 -20.950174)
						(end 359.347008 -20.950174)
					)
				)
			)
		)
		(zone
			(layer "F.Cu")
			(hatch none 0.5)
			(connect_pads
				(clearance 0)
			)
			(min_thickness 0.25)
			(keepout
				(tracks not_allowed)
				(vias allowed)
				(pads allowed)
				(copperpour not_allowed)
				(footprints allowed)
			)
			(placement
				(enabled no)
				(sheetname "")
			)
			(fill
				(thermal_gap 0.5)
				(thermal_bridge_width 0.5)
				(island_removal_mode 0)
			)
			(polygon
				(pts
					(arc
						(start 359.347008 -18.750026)
						(mid 358.153208 -18.750026)
						(end 359.347008 -18.750026)
					)
				)
			)
		)
		(zone
			(layer "F.Cu")
			(hatch none 0.5)
			(connect_pads
				(clearance 0)
			)
			(min_thickness 0.25)
			(keepout
				(tracks allowed)
				(vias not_allowed)
				(pads allowed)
				(copperpour not_allowed)
				(footprints allowed)
			)
			(placement
				(enabled no)
				(sheetname "")
			)
			(fill
				(thermal_gap 0.5)
				(thermal_bridge_width 0.5)
				(island_removal_mode 0)
			)
			(polygon
				(pts
					(arc
						(start 359.347008 -18.750026)
						(mid 358.153208 -18.750026)
						(end 359.347008 -18.750026)
					)
				)
			)
		)
		(zone
			(layer "F.Cu")
			(hatch none 0.5)
			(connect_pads
				(clearance 0)
			)
			(min_thickness 0.25)
			(keepout
				(tracks not_allowed)
				(vias allowed)
				(pads allowed)
				(copperpour not_allowed)
				(footprints allowed)
			)
			(placement
				(enabled no)
				(sheetname "")
			)
			(fill
				(thermal_gap 0.5)
				(thermal_bridge_width 0.5)
				(island_removal_mode 0)
			)
			(polygon
				(pts
					(arc
						(start 359.347008 -17.349978)
						(mid 358.153208 -17.349978)
						(end 359.347008 -17.349978)
					)
				)
			)
		)
		(zone
			(layer "F.Cu")
			(hatch none 0.5)
			(connect_pads
				(clearance 0)
			)
			(min_thickness 0.25)
			(keepout
				(tracks allowed)
				(vias not_allowed)
				(pads allowed)
				(copperpour not_allowed)
				(footprints allowed)
			)
			(placement
				(enabled no)
				(sheetname "")
			)
			(fill
				(thermal_gap 0.5)
				(thermal_bridge_width 0.5)
				(island_removal_mode 0)
			)
			(polygon
				(pts
					(arc
						(start 359.347008 -17.349978)
						(mid 358.153208 -17.349978)
						(end 359.347008 -17.349978)
					)
				)
			)
		)
		(zone
			(layer "F.Cu")
			(hatch none 0.5)
			(connect_pads
				(clearance 0)
			)
			(min_thickness 0.25)
			(keepout
				(tracks allowed)
				(vias not_allowed)
				(pads allowed)
				(copperpour not_allowed)
				(footprints allowed)
			)
			(placement
				(enabled no)
				(sheetname "")
			)
			(fill
				(thermal_gap 0.5)
				(thermal_bridge_width 0.5)
				(island_removal_mode 0)
			)
			(polygon
				(pts
					(arc
						(start 361.146852 -23.35022)
						(mid 359.953052 -23.35022)
						(end 361.146852 -23.35022)
					)
				)
			)
		)
		(zone
			(layer "F.Cu")
			(hatch none 0.5)
			(connect_pads
				(clearance 0)
			)
			(min_thickness 0.25)
			(keepout
				(tracks not_allowed)
				(vias allowed)
				(pads allowed)
				(copperpour not_allowed)
				(footprints allowed)
			)
			(placement
				(enabled no)
				(sheetname "")
			)
			(fill
				(thermal_gap 0.5)
				(thermal_bridge_width 0.5)
				(island_removal_mode 0)
			)
			(polygon
				(pts
					(arc
						(start 361.146852 -23.35022)
						(mid 359.953052 -23.35022)
						(end 361.146852 -23.35022)
					)
				)
			)
		)
		(zone
			(layer "F.Cu")
			(hatch none 0.5)
			(connect_pads
				(clearance 0)
			)
			(min_thickness 0.25)
			(keepout
				(tracks allowed)
				(vias not_allowed)
				(pads allowed)
				(copperpour not_allowed)
				(footprints allowed)
			)
			(placement
				(enabled no)
				(sheetname "")
			)
			(fill
				(thermal_gap 0.5)
				(thermal_bridge_width 0.5)
				(island_removal_mode 0)
			)
			(polygon
				(pts
					(arc
						(start 361.146852 -21.950172)
						(mid 359.953052 -21.950172)
						(end 361.146852 -21.950172)
					)
				)
			)
		)
		(zone
			(layer "F.Cu")
			(hatch none 0.5)
			(connect_pads
				(clearance 0)
			)
			(min_thickness 0.25)
			(keepout
				(tracks not_allowed)
				(vias allowed)
				(pads allowed)
				(copperpour not_allowed)
				(footprints allowed)
			)
			(placement
				(enabled no)
				(sheetname "")
			)
			(fill
				(thermal_gap 0.5)
				(thermal_bridge_width 0.5)
				(island_removal_mode 0)
			)
			(polygon
				(pts
					(arc
						(start 361.146852 -21.950172)
						(mid 359.953052 -21.950172)
						(end 361.146852 -21.950172)
					)
				)
			)
		)
		(zone
			(layer "F.Cu")
			(hatch none 0.5)
			(connect_pads
				(clearance 0)
			)
			(min_thickness 0.25)
			(keepout
				(tracks allowed)
				(vias not_allowed)
				(pads allowed)
				(copperpour not_allowed)
				(footprints allowed)
			)
			(placement
				(enabled no)
				(sheetname "")
			)
			(fill
				(thermal_gap 0.5)
				(thermal_bridge_width 0.5)
				(island_removal_mode 0)
			)
			(polygon
				(pts
					(arc
						(start 361.146852 -19.750024)
						(mid 359.953052 -19.750024)
						(end 361.146852 -19.750024)
					)
				)
			)
		)
		(zone
			(layer "F.Cu")
			(hatch none 0.5)
			(connect_pads
				(clearance 0)
			)
			(min_thickness 0.25)
			(keepout
				(tracks not_allowed)
				(vias allowed)
				(pads allowed)
				(copperpour not_allowed)
				(footprints allowed)
			)
			(placement
				(enabled no)
				(sheetname "")
			)
			(fill
				(thermal_gap 0.5)
				(thermal_bridge_width 0.5)
				(island_removal_mode 0)
			)
			(polygon
				(pts
					(arc
						(start 361.146852 -19.750024)
						(mid 359.953052 -19.750024)
						(end 361.146852 -19.750024)
					)
				)
			)
		)
		(zone
			(layer "F.Cu")
			(hatch none 0.5)
			(connect_pads
				(clearance 0)
			)
			(min_thickness 0.25)
			(keepout
				(tracks not_allowed)
				(vias allowed)
				(pads allowed)
				(copperpour not_allowed)
				(footprints allowed)
			)
			(placement
				(enabled no)
				(sheetname "")
			)
			(fill
				(thermal_gap 0.5)
				(thermal_bridge_width 0.5)
				(island_removal_mode 0)
			)
			(polygon
				(pts
					(arc
						(start 361.146852 -18.35023)
						(mid 359.953052 -18.35023)
						(end 361.146852 -18.35023)
					)
				)
			)
		)
		(zone
			(layer "F.Cu")
			(hatch none 0.5)
			(connect_pads
				(clearance 0)
			)
			(min_thickness 0.25)
			(keepout
				(tracks allowed)
				(vias not_allowed)
				(pads allowed)
				(copperpour not_allowed)
				(footprints allowed)
			)
			(placement
				(enabled no)
				(sheetname "")
			)
			(fill
				(thermal_gap 0.5)
				(thermal_bridge_width 0.5)
				(island_removal_mode 0)
			)
			(polygon
				(pts
					(arc
						(start 361.146852 -18.35023)
						(mid 359.953052 -18.35023)
						(end 361.146852 -18.35023)
					)
				)
			)
		)
		(zone
			(layer "F.Cu")
			(hatch none 0.5)
			(connect_pads
				(clearance 0)
			)
			(min_thickness 0.25)
			(keepout
				(tracks not_allowed)
				(vias allowed)
				(pads allowed)
				(copperpour not_allowed)
				(footprints allowed)
			)
			(placement
				(enabled no)
				(sheetname "")
			)
			(fill
				(thermal_gap 0.5)
				(thermal_bridge_width 0.5)
				(island_removal_mode 0)
			)
			(polygon
				(pts
					(arc
						(start 362.94695 -22.350222)
						(mid 361.75315 -22.350222)
						(end 362.94695 -22.350222)
					)
				)
			)
		)
		(zone
			(layer "F.Cu")
			(hatch none 0.5)
			(connect_pads
				(clearance 0)
			)
			(min_thickness 0.25)
			(keepout
				(tracks allowed)
				(vias not_allowed)
				(pads allowed)
				(copperpour not_allowed)
				(footprints allowed)
			)
			(placement
				(enabled no)
				(sheetname "")
			)
			(fill
				(thermal_gap 0.5)
				(thermal_bridge_width 0.5)
				(island_removal_mode 0)
			)
			(polygon
				(pts
					(arc
						(start 362.94695 -22.350222)
						(mid 361.75315 -22.350222)
						(end 362.94695 -22.350222)
					)
				)
			)
		)
		(zone
			(layer "F.Cu")
			(hatch none 0.5)
			(connect_pads
				(clearance 0)
			)
			(min_thickness 0.25)
			(keepout
				(tracks allowed)
				(vias not_allowed)
				(pads allowed)
				(copperpour not_allowed)
				(footprints allowed)
			)
			(placement
				(enabled no)
				(sheetname "")
			)
			(fill
				(thermal_gap 0.5)
				(thermal_bridge_width 0.5)
				(island_removal_mode 0)
			)
			(polygon
				(pts
					(arc
						(start 362.94695 -20.950174)
						(mid 361.75315 -20.950174)
						(end 362.94695 -20.950174)
					)
				)
			)
		)
		(zone
			(layer "F.Cu")
			(hatch none 0.5)
			(connect_pads
				(clearance 0)
			)
			(min_thickness 0.25)
			(keepout
				(tracks not_allowed)
				(vias allowed)
				(pads allowed)
				(copperpour not_allowed)
				(footprints allowed)
			)
			(placement
				(enabled no)
				(sheetname "")
			)
			(fill
				(thermal_gap 0.5)
				(thermal_bridge_width 0.5)
				(island_removal_mode 0)
			)
			(polygon
				(pts
					(arc
						(start 362.94695 -20.950174)
						(mid 361.75315 -20.950174)
						(end 362.94695 -20.950174)
					)
				)
			)
		)
		(zone
			(layer "F.Cu")
			(hatch none 0.5)
			(connect_pads
				(clearance 0)
			)
			(min_thickness 0.25)
			(keepout
				(tracks not_allowed)
				(vias allowed)
				(pads allowed)
				(copperpour not_allowed)
				(footprints allowed)
			)
			(placement
				(enabled no)
				(sheetname "")
			)
			(fill
				(thermal_gap 0.5)
				(thermal_bridge_width 0.5)
				(island_removal_mode 0)
			)
			(polygon
				(pts
					(arc
						(start 362.94695 -18.750026)
						(mid 361.75315 -18.750026)
						(end 362.94695 -18.750026)
					)
				)
			)
		)
		(zone
			(layer "F.Cu")
			(hatch none 0.5)
			(connect_pads
				(clearance 0)
			)
			(min_thickness 0.25)
			(keepout
				(tracks allowed)
				(vias not_allowed)
				(pads allowed)
				(copperpour not_allowed)
				(footprints allowed)
			)
			(placement
				(enabled no)
				(sheetname "")
			)
			(fill
				(thermal_gap 0.5)
				(thermal_bridge_width 0.5)
				(island_removal_mode 0)
			)
			(polygon
				(pts
					(arc
						(start 362.94695 -18.750026)
						(mid 361.75315 -18.750026)
						(end 362.94695 -18.750026)
					)
				)
			)
		)
		(zone
			(layer "F.Cu")
			(hatch none 0.5)
			(connect_pads
				(clearance 0)
			)
			(min_thickness 0.25)
			(keepout
				(tracks not_allowed)
				(vias allowed)
				(pads allowed)
				(copperpour not_allowed)
				(footprints allowed)
			)
			(placement
				(enabled no)
				(sheetname "")
			)
			(fill
				(thermal_gap 0.5)
				(thermal_bridge_width 0.5)
				(island_removal_mode 0)
			)
			(polygon
				(pts
					(arc
						(start 362.94695 -17.349978)
						(mid 361.75315 -17.349978)
						(end 362.94695 -17.349978)
					)
				)
			)
		)
		(zone
			(layer "F.Cu")
			(hatch none 0.5)
			(connect_pads
				(clearance 0)
			)
			(min_thickness 0.25)
			(keepout
				(tracks allowed)
				(vias not_allowed)
				(pads allowed)
				(copperpour not_allowed)
				(footprints allowed)
			)
			(placement
				(enabled no)
				(sheetname "")
			)
			(fill
				(thermal_gap 0.5)
				(thermal_bridge_width 0.5)
				(island_removal_mode 0)
			)
			(polygon
				(pts
					(arc
						(start 362.94695 -17.349978)
						(mid 361.75315 -17.349978)
						(end 362.94695 -17.349978)
					)
				)
			)
		)
		(zone
			(layer "F.Cu")
			(hatch none 0.5)
			(connect_pads
				(clearance 0)
			)
			(min_thickness 0.25)
			(keepout
				(tracks allowed)
				(vias not_allowed)
				(pads allowed)
				(copperpour not_allowed)
				(footprints allowed)
			)
			(placement
				(enabled no)
				(sheetname "")
			)
			(fill
				(thermal_gap 0.5)
				(thermal_bridge_width 0.5)
				(island_removal_mode 0)
			)
			(polygon
				(pts
					(arc
						(start 364.746794 -23.35022)
						(mid 363.552994 -23.35022)
						(end 364.746794 -23.35022)
					)
				)
			)
		)
		(zone
			(layer "F.Cu")
			(hatch none 0.5)
			(connect_pads
				(clearance 0)
			)
			(min_thickness 0.25)
			(keepout
				(tracks not_allowed)
				(vias allowed)
				(pads allowed)
				(copperpour not_allowed)
				(footprints allowed)
			)
			(placement
				(enabled no)
				(sheetname "")
			)
			(fill
				(thermal_gap 0.5)
				(thermal_bridge_width 0.5)
				(island_removal_mode 0)
			)
			(polygon
				(pts
					(arc
						(start 364.746794 -23.35022)
						(mid 363.552994 -23.35022)
						(end 364.746794 -23.35022)
					)
				)
			)
		)
		(zone
			(layer "F.Cu")
			(hatch none 0.5)
			(connect_pads
				(clearance 0)
			)
			(min_thickness 0.25)
			(keepout
				(tracks allowed)
				(vias not_allowed)
				(pads allowed)
				(copperpour not_allowed)
				(footprints allowed)
			)
			(placement
				(enabled no)
				(sheetname "")
			)
			(fill
				(thermal_gap 0.5)
				(thermal_bridge_width 0.5)
				(island_removal_mode 0)
			)
			(polygon
				(pts
					(arc
						(start 364.746794 -21.950172)
						(mid 363.552994 -21.950172)
						(end 364.746794 -21.950172)
					)
				)
			)
		)
		(zone
			(layer "F.Cu")
			(hatch none 0.5)
			(connect_pads
				(clearance 0)
			)
			(min_thickness 0.25)
			(keepout
				(tracks not_allowed)
				(vias allowed)
				(pads allowed)
				(copperpour not_allowed)
				(footprints allowed)
			)
			(placement
				(enabled no)
				(sheetname "")
			)
			(fill
				(thermal_gap 0.5)
				(thermal_bridge_width 0.5)
				(island_removal_mode 0)
			)
			(polygon
				(pts
					(arc
						(start 364.746794 -21.950172)
						(mid 363.552994 -21.950172)
						(end 364.746794 -21.950172)
					)
				)
			)
		)
		(zone
			(layer "F.Cu")
			(hatch none 0.5)
			(connect_pads
				(clearance 0)
			)
			(min_thickness 0.25)
			(keepout
				(tracks not_allowed)
				(vias allowed)
				(pads allowed)
				(copperpour not_allowed)
				(footprints allowed)
			)
			(placement
				(enabled no)
				(sheetname "")
			)
			(fill
				(thermal_gap 0.5)
				(thermal_bridge_width 0.5)
				(island_removal_mode 0)
			)
			(polygon
				(pts
					(arc
						(start 364.746794 -19.750024)
						(mid 363.552994 -19.750024)
						(end 364.746794 -19.750024)
					)
				)
			)
		)
		(zone
			(layer "F.Cu")
			(hatch none 0.5)
			(connect_pads
				(clearance 0)
			)
			(min_thickness 0.25)
			(keepout
				(tracks allowed)
				(vias not_allowed)
				(pads allowed)
				(copperpour not_allowed)
				(footprints allowed)
			)
			(placement
				(enabled no)
				(sheetname "")
			)
			(fill
				(thermal_gap 0.5)
				(thermal_bridge_width 0.5)
				(island_removal_mode 0)
			)
			(polygon
				(pts
					(arc
						(start 364.746794 -19.750024)
						(mid 363.552994 -19.750024)
						(end 364.746794 -19.750024)
					)
				)
			)
		)
		(zone
			(layer "F.Cu")
			(hatch none 0.5)
			(connect_pads
				(clearance 0)
			)
			(min_thickness 0.25)
			(keepout
				(tracks allowed)
				(vias not_allowed)
				(pads allowed)
				(copperpour not_allowed)
				(footprints allowed)
			)
			(placement
				(enabled no)
				(sheetname "")
			)
			(fill
				(thermal_gap 0.5)
				(thermal_bridge_width 0.5)
				(island_removal_mode 0)
			)
			(polygon
				(pts
					(arc
						(start 364.746794 -18.35023)
						(mid 363.552994 -18.35023)
						(end 364.746794 -18.35023)
					)
				)
			)
		)
		(zone
			(layer "F.Cu")
			(hatch none 0.5)
			(connect_pads
				(clearance 0)
			)
			(min_thickness 0.25)
			(keepout
				(tracks not_allowed)
				(vias allowed)
				(pads allowed)
				(copperpour not_allowed)
				(footprints allowed)
			)
			(placement
				(enabled no)
				(sheetname "")
			)
			(fill
				(thermal_gap 0.5)
				(thermal_bridge_width 0.5)
				(island_removal_mode 0)
			)
			(polygon
				(pts
					(arc
						(start 364.746794 -18.35023)
						(mid 363.552994 -18.35023)
						(end 364.746794 -18.35023)
					)
				)
			)
		)
		(zone
			(layer "F.Cu")
			(hatch none 0.5)
			(connect_pads
				(clearance 0)
			)
			(min_thickness 0.25)
			(keepout
				(tracks not_allowed)
				(vias allowed)
				(pads allowed)
				(copperpour not_allowed)
				(footprints allowed)
			)
			(placement
				(enabled no)
				(sheetname "")
			)
			(fill
				(thermal_gap 0.5)
				(thermal_bridge_width 0.5)
				(island_removal_mode 0)
			)
			(polygon
				(pts
					(arc
						(start 366.546892 -22.350222)
						(mid 365.353092 -22.350222)
						(end 366.546892 -22.350222)
					)
				)
			)
		)
		(zone
			(layer "F.Cu")
			(hatch none 0.5)
			(connect_pads
				(clearance 0)
			)
			(min_thickness 0.25)
			(keepout
				(tracks allowed)
				(vias not_allowed)
				(pads allowed)
				(copperpour not_allowed)
				(footprints allowed)
			)
			(placement
				(enabled no)
				(sheetname "")
			)
			(fill
				(thermal_gap 0.5)
				(thermal_bridge_width 0.5)
				(island_removal_mode 0)
			)
			(polygon
				(pts
					(arc
						(start 366.546892 -22.350222)
						(mid 365.353092 -22.350222)
						(end 366.546892 -22.350222)
					)
				)
			)
		)
		(zone
			(layer "F.Cu")
			(hatch none 0.5)
			(connect_pads
				(clearance 0)
			)
			(min_thickness 0.25)
			(keepout
				(tracks allowed)
				(vias not_allowed)
				(pads allowed)
				(copperpour not_allowed)
				(footprints allowed)
			)
			(placement
				(enabled no)
				(sheetname "")
			)
			(fill
				(thermal_gap 0.5)
				(thermal_bridge_width 0.5)
				(island_removal_mode 0)
			)
			(polygon
				(pts
					(arc
						(start 366.546892 -20.950174)
						(mid 365.353092 -20.950174)
						(end 366.546892 -20.950174)
					)
				)
			)
		)
		(zone
			(layer "F.Cu")
			(hatch none 0.5)
			(connect_pads
				(clearance 0)
			)
			(min_thickness 0.25)
			(keepout
				(tracks not_allowed)
				(vias allowed)
				(pads allowed)
				(copperpour not_allowed)
				(footprints allowed)
			)
			(placement
				(enabled no)
				(sheetname "")
			)
			(fill
				(thermal_gap 0.5)
				(thermal_bridge_width 0.5)
				(island_removal_mode 0)
			)
			(polygon
				(pts
					(arc
						(start 366.546892 -20.950174)
						(mid 365.353092 -20.950174)
						(end 366.546892 -20.950174)
					)
				)
			)
		)
		(zone
			(layer "F.Cu")
			(hatch none 0.5)
			(connect_pads
				(clearance 0)
			)
			(min_thickness 0.25)
			(keepout
				(tracks not_allowed)
				(vias allowed)
				(pads allowed)
				(copperpour not_allowed)
				(footprints allowed)
			)
			(placement
				(enabled no)
				(sheetname "")
			)
			(fill
				(thermal_gap 0.5)
				(thermal_bridge_width 0.5)
				(island_removal_mode 0)
			)
			(polygon
				(pts
					(arc
						(start 366.546892 -18.750026)
						(mid 365.353092 -18.750026)
						(end 366.546892 -18.750026)
					)
				)
			)
		)
		(zone
			(layer "F.Cu")
			(hatch none 0.5)
			(connect_pads
				(clearance 0)
			)
			(min_thickness 0.25)
			(keepout
				(tracks allowed)
				(vias not_allowed)
				(pads allowed)
				(copperpour not_allowed)
				(footprints allowed)
			)
			(placement
				(enabled no)
				(sheetname "")
			)
			(fill
				(thermal_gap 0.5)
				(thermal_bridge_width 0.5)
				(island_removal_mode 0)
			)
			(polygon
				(pts
					(arc
						(start 366.546892 -18.750026)
						(mid 365.353092 -18.750026)
						(end 366.546892 -18.750026)
					)
				)
			)
		)
		(zone
			(layer "F.Cu")
			(hatch none 0.5)
			(connect_pads
				(clearance 0)
			)
			(min_thickness 0.25)
			(keepout
				(tracks not_allowed)
				(vias allowed)
				(pads allowed)
				(copperpour not_allowed)
				(footprints allowed)
			)
			(placement
				(enabled no)
				(sheetname "")
			)
			(fill
				(thermal_gap 0.5)
				(thermal_bridge_width 0.5)
				(island_removal_mode 0)
			)
			(polygon
				(pts
					(arc
						(start 366.546892 -17.349978)
						(mid 365.353092 -17.349978)
						(end 366.546892 -17.349978)
					)
				)
			)
		)
		(zone
			(layer "F.Cu")
			(hatch none 0.5)
			(connect_pads
				(clearance 0)
			)
			(min_thickness 0.25)
			(keepout
				(tracks allowed)
				(vias not_allowed)
				(pads allowed)
				(copperpour not_allowed)
				(footprints allowed)
			)
			(placement
				(enabled no)
				(sheetname "")
			)
			(fill
				(thermal_gap 0.5)
				(thermal_bridge_width 0.5)
				(island_removal_mode 0)
			)
			(polygon
				(pts
					(arc
						(start 366.546892 -17.349978)
						(mid 365.353092 -17.349978)
						(end 366.546892 -17.349978)
					)
				)
			)
		)
		(zone
			(layer "F.Cu")
			(hatch none 0.5)
			(connect_pads
				(clearance 0)
			)
			(min_thickness 0.25)
			(keepout
				(tracks allowed)
				(vias not_allowed)
				(pads allowed)
				(copperpour not_allowed)
				(footprints allowed)
			)
			(placement
				(enabled no)
				(sheetname "")
			)
			(fill
				(thermal_gap 0.5)
				(thermal_bridge_width 0.5)
				(island_removal_mode 0)
			)
			(polygon
				(pts
					(arc
						(start 368.34699 -23.35022)
						(mid 367.15319 -23.35022)
						(end 368.34699 -23.35022)
					)
				)
			)
		)
		(zone
			(layer "F.Cu")
			(hatch none 0.5)
			(connect_pads
				(clearance 0)
			)
			(min_thickness 0.25)
			(keepout
				(tracks not_allowed)
				(vias allowed)
				(pads allowed)
				(copperpour not_allowed)
				(footprints allowed)
			)
			(placement
				(enabled no)
				(sheetname "")
			)
			(fill
				(thermal_gap 0.5)
				(thermal_bridge_width 0.5)
				(island_removal_mode 0)
			)
			(polygon
				(pts
					(arc
						(start 368.34699 -23.35022)
						(mid 367.15319 -23.35022)
						(end 368.34699 -23.35022)
					)
				)
			)
		)
		(zone
			(layer "F.Cu")
			(hatch none 0.5)
			(connect_pads
				(clearance 0)
			)
			(min_thickness 0.25)
			(keepout
				(tracks not_allowed)
				(vias allowed)
				(pads allowed)
				(copperpour not_allowed)
				(footprints allowed)
			)
			(placement
				(enabled no)
				(sheetname "")
			)
			(fill
				(thermal_gap 0.5)
				(thermal_bridge_width 0.5)
				(island_removal_mode 0)
			)
			(polygon
				(pts
					(arc
						(start 368.34699 -21.950172)
						(mid 367.15319 -21.950172)
						(end 368.34699 -21.950172)
					)
				)
			)
		)
		(zone
			(layer "F.Cu")
			(hatch none 0.5)
			(connect_pads
				(clearance 0)
			)
			(min_thickness 0.25)
			(keepout
				(tracks allowed)
				(vias not_allowed)
				(pads allowed)
				(copperpour not_allowed)
				(footprints allowed)
			)
			(placement
				(enabled no)
				(sheetname "")
			)
			(fill
				(thermal_gap 0.5)
				(thermal_bridge_width 0.5)
				(island_removal_mode 0)
			)
			(polygon
				(pts
					(arc
						(start 368.34699 -21.950172)
						(mid 367.15319 -21.950172)
						(end 368.34699 -21.950172)
					)
				)
			)
		)
		(zone
			(layer "F.Cu")
			(hatch none 0.5)
			(connect_pads
				(clearance 0)
			)
			(min_thickness 0.25)
			(keepout
				(tracks allowed)
				(vias not_allowed)
				(pads allowed)
				(copperpour not_allowed)
				(footprints allowed)
			)
			(placement
				(enabled no)
				(sheetname "")
			)
			(fill
				(thermal_gap 0.5)
				(thermal_bridge_width 0.5)
				(island_removal_mode 0)
			)
			(polygon
				(pts
					(arc
						(start 368.34699 -19.750024)
						(mid 367.15319 -19.750024)
						(end 368.34699 -19.750024)
					)
				)
			)
		)
		(zone
			(layer "F.Cu")
			(hatch none 0.5)
			(connect_pads
				(clearance 0)
			)
			(min_thickness 0.25)
			(keepout
				(tracks not_allowed)
				(vias allowed)
				(pads allowed)
				(copperpour not_allowed)
				(footprints allowed)
			)
			(placement
				(enabled no)
				(sheetname "")
			)
			(fill
				(thermal_gap 0.5)
				(thermal_bridge_width 0.5)
				(island_removal_mode 0)
			)
			(polygon
				(pts
					(arc
						(start 368.34699 -19.750024)
						(mid 367.15319 -19.750024)
						(end 368.34699 -19.750024)
					)
				)
			)
		)
		(zone
			(layer "F.Cu")
			(hatch none 0.5)
			(connect_pads
				(clearance 0)
			)
			(min_thickness 0.25)
			(keepout
				(tracks not_allowed)
				(vias allowed)
				(pads allowed)
				(copperpour not_allowed)
				(footprints allowed)
			)
			(placement
				(enabled no)
				(sheetname "")
			)
			(fill
				(thermal_gap 0.5)
				(thermal_bridge_width 0.5)
				(island_removal_mode 0)
			)
			(polygon
				(pts
					(arc
						(start 368.34699 -18.35023)
						(mid 367.15319 -18.35023)
						(end 368.34699 -18.35023)
					)
				)
			)
		)
		(zone
			(layer "F.Cu")
			(hatch none 0.5)
			(connect_pads
				(clearance 0)
			)
			(min_thickness 0.25)
			(keepout
				(tracks allowed)
				(vias not_allowed)
				(pads allowed)
				(copperpour not_allowed)
				(footprints allowed)
			)
			(placement
				(enabled no)
				(sheetname "")
			)
			(fill
				(thermal_gap 0.5)
				(thermal_bridge_width 0.5)
				(island_removal_mode 0)
			)
			(polygon
				(pts
					(arc
						(start 368.34699 -18.35023)
						(mid 367.15319 -18.35023)
						(end 368.34699 -18.35023)
					)
				)
			)
		)
		(zone
			(layer "F.Cu")
			(hatch none 0.5)
			(connect_pads
				(clearance 0)
			)
			(min_thickness 0.25)
			(keepout
				(tracks allowed)
				(vias not_allowed)
				(pads allowed)
				(copperpour not_allowed)
				(footprints allowed)
			)
			(placement
				(enabled no)
				(sheetname "")
			)
			(fill
				(thermal_gap 0.5)
				(thermal_bridge_width 0.5)
				(island_removal_mode 0)
			)
			(polygon
				(pts
					(arc
						(start 377.346972 -22.350222)
						(mid 376.153172 -22.350222)
						(end 377.346972 -22.350222)
					)
				)
			)
		)
		(zone
			(layer "F.Cu")
			(hatch none 0.5)
			(connect_pads
				(clearance 0)
			)
			(min_thickness 0.25)
			(keepout
				(tracks not_allowed)
				(vias allowed)
				(pads allowed)
				(copperpour not_allowed)
				(footprints allowed)
			)
			(placement
				(enabled no)
				(sheetname "")
			)
			(fill
				(thermal_gap 0.5)
				(thermal_bridge_width 0.5)
				(island_removal_mode 0)
			)
			(polygon
				(pts
					(arc
						(start 377.346972 -22.350222)
						(mid 376.153172 -22.350222)
						(end 377.346972 -22.350222)
					)
				)
			)
		)
		(zone
			(layer "F.Cu")
			(hatch none 0.5)
			(connect_pads
				(clearance 0)
			)
			(min_thickness 0.25)
			(keepout
				(tracks allowed)
				(vias not_allowed)
				(pads allowed)
				(copperpour not_allowed)
				(footprints allowed)
			)
			(placement
				(enabled no)
				(sheetname "")
			)
			(fill
				(thermal_gap 0.5)
				(thermal_bridge_width 0.5)
				(island_removal_mode 0)
			)
			(polygon
				(pts
					(arc
						(start 377.346972 -20.950174)
						(mid 376.153172 -20.950174)
						(end 377.346972 -20.950174)
					)
				)
			)
		)
		(zone
			(layer "F.Cu")
			(hatch none 0.5)
			(connect_pads
				(clearance 0)
			)
			(min_thickness 0.25)
			(keepout
				(tracks not_allowed)
				(vias allowed)
				(pads allowed)
				(copperpour not_allowed)
				(footprints allowed)
			)
			(placement
				(enabled no)
				(sheetname "")
			)
			(fill
				(thermal_gap 0.5)
				(thermal_bridge_width 0.5)
				(island_removal_mode 0)
			)
			(polygon
				(pts
					(arc
						(start 377.346972 -20.950174)
						(mid 376.153172 -20.950174)
						(end 377.346972 -20.950174)
					)
				)
			)
		)
		(zone
			(layer "F.Cu")
			(hatch none 0.5)
			(connect_pads
				(clearance 0)
			)
			(min_thickness 0.25)
			(keepout
				(tracks not_allowed)
				(vias allowed)
				(pads allowed)
				(copperpour not_allowed)
				(footprints allowed)
			)
			(placement
				(enabled no)
				(sheetname "")
			)
			(fill
				(thermal_gap 0.5)
				(thermal_bridge_width 0.5)
				(island_removal_mode 0)
			)
			(polygon
				(pts
					(arc
						(start 377.346972 -18.750026)
						(mid 376.153172 -18.750026)
						(end 377.346972 -18.750026)
					)
				)
			)
		)
		(zone
			(layer "F.Cu")
			(hatch none 0.5)
			(connect_pads
				(clearance 0)
			)
			(min_thickness 0.25)
			(keepout
				(tracks allowed)
				(vias not_allowed)
				(pads allowed)
				(copperpour not_allowed)
				(footprints allowed)
			)
			(placement
				(enabled no)
				(sheetname "")
			)
			(fill
				(thermal_gap 0.5)
				(thermal_bridge_width 0.5)
				(island_removal_mode 0)
			)
			(polygon
				(pts
					(arc
						(start 377.346972 -18.750026)
						(mid 376.153172 -18.750026)
						(end 377.346972 -18.750026)
					)
				)
			)
		)
		(zone
			(layer "F.Cu")
			(hatch none 0.5)
			(connect_pads
				(clearance 0)
			)
			(min_thickness 0.25)
			(keepout
				(tracks not_allowed)
				(vias allowed)
				(pads allowed)
				(copperpour not_allowed)
				(footprints allowed)
			)
			(placement
				(enabled no)
				(sheetname "")
			)
			(fill
				(thermal_gap 0.5)
				(thermal_bridge_width 0.5)
				(island_removal_mode 0)
			)
			(polygon
				(pts
					(arc
						(start 377.346972 -17.349978)
						(mid 376.153172 -17.349978)
						(end 377.346972 -17.349978)
					)
				)
			)
		)
		(zone
			(layer "F.Cu")
			(hatch none 0.5)
			(connect_pads
				(clearance 0)
			)
			(min_thickness 0.25)
			(keepout
				(tracks allowed)
				(vias not_allowed)
				(pads allowed)
				(copperpour not_allowed)
				(footprints allowed)
			)
			(placement
				(enabled no)
				(sheetname "")
			)
			(fill
				(thermal_gap 0.5)
				(thermal_bridge_width 0.5)
				(island_removal_mode 0)
			)
			(polygon
				(pts
					(arc
						(start 377.346972 -17.349978)
						(mid 376.153172 -17.349978)
						(end 377.346972 -17.349978)
					)
				)
			)
		)
		(zone
			(layer "F.Cu")
			(hatch none 0.5)
			(connect_pads
				(clearance 0)
			)
			(min_thickness 0.25)
			(keepout
				(tracks allowed)
				(vias not_allowed)
				(pads allowed)
				(copperpour not_allowed)
				(footprints allowed)
			)
			(placement
				(enabled no)
				(sheetname "")
			)
			(fill
				(thermal_gap 0.5)
				(thermal_bridge_width 0.5)
				(island_removal_mode 0)
			)
			(polygon
				(pts
					(arc
						(start 379.146816 -23.35022)
						(mid 377.953016 -23.35022)
						(end 379.146816 -23.35022)
					)
				)
			)
		)
		(zone
			(layer "F.Cu")
			(hatch none 0.5)
			(connect_pads
				(clearance 0)
			)
			(min_thickness 0.25)
			(keepout
				(tracks not_allowed)
				(vias allowed)
				(pads allowed)
				(copperpour not_allowed)
				(footprints allowed)
			)
			(placement
				(enabled no)
				(sheetname "")
			)
			(fill
				(thermal_gap 0.5)
				(thermal_bridge_width 0.5)
				(island_removal_mode 0)
			)
			(polygon
				(pts
					(arc
						(start 379.146816 -23.35022)
						(mid 377.953016 -23.35022)
						(end 379.146816 -23.35022)
					)
				)
			)
		)
		(zone
			(layer "F.Cu")
			(hatch none 0.5)
			(connect_pads
				(clearance 0)
			)
			(min_thickness 0.25)
			(keepout
				(tracks not_allowed)
				(vias allowed)
				(pads allowed)
				(copperpour not_allowed)
				(footprints allowed)
			)
			(placement
				(enabled no)
				(sheetname "")
			)
			(fill
				(thermal_gap 0.5)
				(thermal_bridge_width 0.5)
				(island_removal_mode 0)
			)
			(polygon
				(pts
					(arc
						(start 379.146816 -21.950172)
						(mid 377.953016 -21.950172)
						(end 379.146816 -21.950172)
					)
				)
			)
		)
		(zone
			(layer "F.Cu")
			(hatch none 0.5)
			(connect_pads
				(clearance 0)
			)
			(min_thickness 0.25)
			(keepout
				(tracks allowed)
				(vias not_allowed)
				(pads allowed)
				(copperpour not_allowed)
				(footprints allowed)
			)
			(placement
				(enabled no)
				(sheetname "")
			)
			(fill
				(thermal_gap 0.5)
				(thermal_bridge_width 0.5)
				(island_removal_mode 0)
			)
			(polygon
				(pts
					(arc
						(start 379.146816 -21.950172)
						(mid 377.953016 -21.950172)
						(end 379.146816 -21.950172)
					)
				)
			)
		)
		(zone
			(layer "F.Cu")
			(hatch none 0.5)
			(connect_pads
				(clearance 0)
			)
			(min_thickness 0.25)
			(keepout
				(tracks allowed)
				(vias not_allowed)
				(pads allowed)
				(copperpour not_allowed)
				(footprints allowed)
			)
			(placement
				(enabled no)
				(sheetname "")
			)
			(fill
				(thermal_gap 0.5)
				(thermal_bridge_width 0.5)
				(island_removal_mode 0)
			)
			(polygon
				(pts
					(arc
						(start 379.146816 -19.750024)
						(mid 377.953016 -19.750024)
						(end 379.146816 -19.750024)
					)
				)
			)
		)
		(zone
			(layer "F.Cu")
			(hatch none 0.5)
			(connect_pads
				(clearance 0)
			)
			(min_thickness 0.25)
			(keepout
				(tracks not_allowed)
				(vias allowed)
				(pads allowed)
				(copperpour not_allowed)
				(footprints allowed)
			)
			(placement
				(enabled no)
				(sheetname "")
			)
			(fill
				(thermal_gap 0.5)
				(thermal_bridge_width 0.5)
				(island_removal_mode 0)
			)
			(polygon
				(pts
					(arc
						(start 379.146816 -19.750024)
						(mid 377.953016 -19.750024)
						(end 379.146816 -19.750024)
					)
				)
			)
		)
		(zone
			(layer "F.Cu")
			(hatch none 0.5)
			(connect_pads
				(clearance 0)
			)
			(min_thickness 0.25)
			(keepout
				(tracks not_allowed)
				(vias allowed)
				(pads allowed)
				(copperpour not_allowed)
				(footprints allowed)
			)
			(placement
				(enabled no)
				(sheetname "")
			)
			(fill
				(thermal_gap 0.5)
				(thermal_bridge_width 0.5)
				(island_removal_mode 0)
			)
			(polygon
				(pts
					(arc
						(start 379.146816 -18.35023)
						(mid 377.953016 -18.35023)
						(end 379.146816 -18.35023)
					)
				)
			)
		)
		(zone
			(layer "F.Cu")
			(hatch none 0.5)
			(connect_pads
				(clearance 0)
			)
			(min_thickness 0.25)
			(keepout
				(tracks allowed)
				(vias not_allowed)
				(pads allowed)
				(copperpour not_allowed)
				(footprints allowed)
			)
			(placement
				(enabled no)
				(sheetname "")
			)
			(fill
				(thermal_gap 0.5)
				(thermal_bridge_width 0.5)
				(island_removal_mode 0)
			)
			(polygon
				(pts
					(arc
						(start 379.146816 -18.35023)
						(mid 377.953016 -18.35023)
						(end 379.146816 -18.35023)
					)
				)
			)
		)
		(zone
			(layer "F.Cu")
			(hatch none 0.5)
			(connect_pads
				(clearance 0)
			)
			(min_thickness 0.25)
			(keepout
				(tracks not_allowed)
				(vias allowed)
				(pads allowed)
				(copperpour not_allowed)
				(footprints allowed)
			)
			(placement
				(enabled no)
				(sheetname "")
			)
			(fill
				(thermal_gap 0.5)
				(thermal_bridge_width 0.5)
				(island_removal_mode 0)
			)
			(polygon
				(pts
					(arc
						(start 380.946914 -22.350222)
						(mid 379.753114 -22.350222)
						(end 380.946914 -22.350222)
					)
				)
			)
		)
		(zone
			(layer "F.Cu")
			(hatch none 0.5)
			(connect_pads
				(clearance 0)
			)
			(min_thickness 0.25)
			(keepout
				(tracks allowed)
				(vias not_allowed)
				(pads allowed)
				(copperpour not_allowed)
				(footprints allowed)
			)
			(placement
				(enabled no)
				(sheetname "")
			)
			(fill
				(thermal_gap 0.5)
				(thermal_bridge_width 0.5)
				(island_removal_mode 0)
			)
			(polygon
				(pts
					(arc
						(start 380.946914 -22.350222)
						(mid 379.753114 -22.350222)
						(end 380.946914 -22.350222)
					)
				)
			)
		)
		(zone
			(layer "F.Cu")
			(hatch none 0.5)
			(connect_pads
				(clearance 0)
			)
			(min_thickness 0.25)
			(keepout
				(tracks not_allowed)
				(vias allowed)
				(pads allowed)
				(copperpour not_allowed)
				(footprints allowed)
			)
			(placement
				(enabled no)
				(sheetname "")
			)
			(fill
				(thermal_gap 0.5)
				(thermal_bridge_width 0.5)
				(island_removal_mode 0)
			)
			(polygon
				(pts
					(arc
						(start 380.946914 -20.950174)
						(mid 379.753114 -20.950174)
						(end 380.946914 -20.950174)
					)
				)
			)
		)
		(zone
			(layer "F.Cu")
			(hatch none 0.5)
			(connect_pads
				(clearance 0)
			)
			(min_thickness 0.25)
			(keepout
				(tracks allowed)
				(vias not_allowed)
				(pads allowed)
				(copperpour not_allowed)
				(footprints allowed)
			)
			(placement
				(enabled no)
				(sheetname "")
			)
			(fill
				(thermal_gap 0.5)
				(thermal_bridge_width 0.5)
				(island_removal_mode 0)
			)
			(polygon
				(pts
					(arc
						(start 380.946914 -20.950174)
						(mid 379.753114 -20.950174)
						(end 380.946914 -20.950174)
					)
				)
			)
		)
		(zone
			(layer "F.Cu")
			(hatch none 0.5)
			(connect_pads
				(clearance 0)
			)
			(min_thickness 0.25)
			(keepout
				(tracks allowed)
				(vias not_allowed)
				(pads allowed)
				(copperpour not_allowed)
				(footprints allowed)
			)
			(placement
				(enabled no)
				(sheetname "")
			)
			(fill
				(thermal_gap 0.5)
				(thermal_bridge_width 0.5)
				(island_removal_mode 0)
			)
			(polygon
				(pts
					(arc
						(start 380.946914 -18.750026)
						(mid 379.753114 -18.750026)
						(end 380.946914 -18.750026)
					)
				)
			)
		)
		(zone
			(layer "F.Cu")
			(hatch none 0.5)
			(connect_pads
				(clearance 0)
			)
			(min_thickness 0.25)
			(keepout
				(tracks not_allowed)
				(vias allowed)
				(pads allowed)
				(copperpour not_allowed)
				(footprints allowed)
			)
			(placement
				(enabled no)
				(sheetname "")
			)
			(fill
				(thermal_gap 0.5)
				(thermal_bridge_width 0.5)
				(island_removal_mode 0)
			)
			(polygon
				(pts
					(arc
						(start 380.946914 -18.750026)
						(mid 379.753114 -18.750026)
						(end 380.946914 -18.750026)
					)
				)
			)
		)
		(zone
			(layer "F.Cu")
			(hatch none 0.5)
			(connect_pads
				(clearance 0)
			)
			(min_thickness 0.25)
			(keepout
				(tracks not_allowed)
				(vias allowed)
				(pads allowed)
				(copperpour not_allowed)
				(footprints allowed)
			)
			(placement
				(enabled no)
				(sheetname "")
			)
			(fill
				(thermal_gap 0.5)
				(thermal_bridge_width 0.5)
				(island_removal_mode 0)
			)
			(polygon
				(pts
					(arc
						(start 380.946914 -17.349978)
						(mid 379.753114 -17.349978)
						(end 380.946914 -17.349978)
					)
				)
			)
		)
		(zone
			(layer "F.Cu")
			(hatch none 0.5)
			(connect_pads
				(clearance 0)
			)
			(min_thickness 0.25)
			(keepout
				(tracks allowed)
				(vias not_allowed)
				(pads allowed)
				(copperpour not_allowed)
				(footprints allowed)
			)
			(placement
				(enabled no)
				(sheetname "")
			)
			(fill
				(thermal_gap 0.5)
				(thermal_bridge_width 0.5)
				(island_removal_mode 0)
			)
			(polygon
				(pts
					(arc
						(start 380.946914 -17.349978)
						(mid 379.753114 -17.349978)
						(end 380.946914 -17.349978)
					)
				)
			)
		)
		(zone
			(layer "F.Cu")
			(hatch none 0.5)
			(connect_pads
				(clearance 0)
			)
			(min_thickness 0.25)
			(keepout
				(tracks not_allowed)
				(vias allowed)
				(pads allowed)
				(copperpour not_allowed)
				(footprints allowed)
			)
			(placement
				(enabled no)
				(sheetname "")
			)
			(fill
				(thermal_gap 0.5)
				(thermal_bridge_width 0.5)
				(island_removal_mode 0)
			)
			(polygon
				(pts
					(arc
						(start 382.747012 -23.35022)
						(mid 381.553212 -23.35022)
						(end 382.747012 -23.35022)
					)
				)
			)
		)
		(zone
			(layer "F.Cu")
			(hatch none 0.5)
			(connect_pads
				(clearance 0)
			)
			(min_thickness 0.25)
			(keepout
				(tracks allowed)
				(vias not_allowed)
				(pads allowed)
				(copperpour not_allowed)
				(footprints allowed)
			)
			(placement
				(enabled no)
				(sheetname "")
			)
			(fill
				(thermal_gap 0.5)
				(thermal_bridge_width 0.5)
				(island_removal_mode 0)
			)
			(polygon
				(pts
					(arc
						(start 382.747012 -23.35022)
						(mid 381.553212 -23.35022)
						(end 382.747012 -23.35022)
					)
				)
			)
		)
		(zone
			(layer "F.Cu")
			(hatch none 0.5)
			(connect_pads
				(clearance 0)
			)
			(min_thickness 0.25)
			(keepout
				(tracks not_allowed)
				(vias allowed)
				(pads allowed)
				(copperpour not_allowed)
				(footprints allowed)
			)
			(placement
				(enabled no)
				(sheetname "")
			)
			(fill
				(thermal_gap 0.5)
				(thermal_bridge_width 0.5)
				(island_removal_mode 0)
			)
			(polygon
				(pts
					(arc
						(start 382.747012 -21.950172)
						(mid 381.553212 -21.950172)
						(end 382.747012 -21.950172)
					)
				)
			)
		)
		(zone
			(layer "F.Cu")
			(hatch none 0.5)
			(connect_pads
				(clearance 0)
			)
			(min_thickness 0.25)
			(keepout
				(tracks allowed)
				(vias not_allowed)
				(pads allowed)
				(copperpour not_allowed)
				(footprints allowed)
			)
			(placement
				(enabled no)
				(sheetname "")
			)
			(fill
				(thermal_gap 0.5)
				(thermal_bridge_width 0.5)
				(island_removal_mode 0)
			)
			(polygon
				(pts
					(arc
						(start 382.747012 -21.950172)
						(mid 381.553212 -21.950172)
						(end 382.747012 -21.950172)
					)
				)
			)
		)
		(zone
			(layer "F.Cu")
			(hatch none 0.5)
			(connect_pads
				(clearance 0)
			)
			(min_thickness 0.25)
			(keepout
				(tracks not_allowed)
				(vias allowed)
				(pads allowed)
				(copperpour not_allowed)
				(footprints allowed)
			)
			(placement
				(enabled no)
				(sheetname "")
			)
			(fill
				(thermal_gap 0.5)
				(thermal_bridge_width 0.5)
				(island_removal_mode 0)
			)
			(polygon
				(pts
					(arc
						(start 382.747012 -19.750024)
						(mid 381.553212 -19.750024)
						(end 382.747012 -19.750024)
					)
				)
			)
		)
		(zone
			(layer "F.Cu")
			(hatch none 0.5)
			(connect_pads
				(clearance 0)
			)
			(min_thickness 0.25)
			(keepout
				(tracks allowed)
				(vias not_allowed)
				(pads allowed)
				(copperpour not_allowed)
				(footprints allowed)
			)
			(placement
				(enabled no)
				(sheetname "")
			)
			(fill
				(thermal_gap 0.5)
				(thermal_bridge_width 0.5)
				(island_removal_mode 0)
			)
			(polygon
				(pts
					(arc
						(start 382.747012 -19.750024)
						(mid 381.553212 -19.750024)
						(end 382.747012 -19.750024)
					)
				)
			)
		)
		(zone
			(layer "F.Cu")
			(hatch none 0.5)
			(connect_pads
				(clearance 0)
			)
			(min_thickness 0.25)
			(keepout
				(tracks not_allowed)
				(vias allowed)
				(pads allowed)
				(copperpour not_allowed)
				(footprints allowed)
			)
			(placement
				(enabled no)
				(sheetname "")
			)
			(fill
				(thermal_gap 0.5)
				(thermal_bridge_width 0.5)
				(island_removal_mode 0)
			)
			(polygon
				(pts
					(arc
						(start 382.747012 -18.35023)
						(mid 381.553212 -18.35023)
						(end 382.747012 -18.35023)
					)
				)
			)
		)
		(zone
			(layer "F.Cu")
			(hatch none 0.5)
			(connect_pads
				(clearance 0)
			)
			(min_thickness 0.25)
			(keepout
				(tracks allowed)
				(vias not_allowed)
				(pads allowed)
				(copperpour not_allowed)
				(footprints allowed)
			)
			(placement
				(enabled no)
				(sheetname "")
			)
			(fill
				(thermal_gap 0.5)
				(thermal_bridge_width 0.5)
				(island_removal_mode 0)
			)
			(polygon
				(pts
					(arc
						(start 382.747012 -18.35023)
						(mid 381.553212 -18.35023)
						(end 382.747012 -18.35023)
					)
				)
			)
		)
		(zone
			(layer "F.Cu")
			(hatch none 0.5)
			(connect_pads
				(clearance 0)
			)
			(min_thickness 0.25)
			(keepout
				(tracks allowed)
				(vias not_allowed)
				(pads allowed)
				(copperpour not_allowed)
				(footprints allowed)
			)
			(placement
				(enabled no)
				(sheetname "")
			)
			(fill
				(thermal_gap 0.5)
				(thermal_bridge_width 0.5)
				(island_removal_mode 0)
			)
			(polygon
				(pts
					(arc
						(start 384.546856 -22.350222)
						(mid 383.353056 -22.350222)
						(end 384.546856 -22.350222)
					)
				)
			)
		)
		(zone
			(layer "F.Cu")
			(hatch none 0.5)
			(connect_pads
				(clearance 0)
			)
			(min_thickness 0.25)
			(keepout
				(tracks not_allowed)
				(vias allowed)
				(pads allowed)
				(copperpour not_allowed)
				(footprints allowed)
			)
			(placement
				(enabled no)
				(sheetname "")
			)
			(fill
				(thermal_gap 0.5)
				(thermal_bridge_width 0.5)
				(island_removal_mode 0)
			)
			(polygon
				(pts
					(arc
						(start 384.546856 -22.350222)
						(mid 383.353056 -22.350222)
						(end 384.546856 -22.350222)
					)
				)
			)
		)
		(zone
			(layer "F.Cu")
			(hatch none 0.5)
			(connect_pads
				(clearance 0)
			)
			(min_thickness 0.25)
			(keepout
				(tracks allowed)
				(vias not_allowed)
				(pads allowed)
				(copperpour not_allowed)
				(footprints allowed)
			)
			(placement
				(enabled no)
				(sheetname "")
			)
			(fill
				(thermal_gap 0.5)
				(thermal_bridge_width 0.5)
				(island_removal_mode 0)
			)
			(polygon
				(pts
					(arc
						(start 384.546856 -20.950174)
						(mid 383.353056 -20.950174)
						(end 384.546856 -20.950174)
					)
				)
			)
		)
		(zone
			(layer "F.Cu")
			(hatch none 0.5)
			(connect_pads
				(clearance 0)
			)
			(min_thickness 0.25)
			(keepout
				(tracks not_allowed)
				(vias allowed)
				(pads allowed)
				(copperpour not_allowed)
				(footprints allowed)
			)
			(placement
				(enabled no)
				(sheetname "")
			)
			(fill
				(thermal_gap 0.5)
				(thermal_bridge_width 0.5)
				(island_removal_mode 0)
			)
			(polygon
				(pts
					(arc
						(start 384.546856 -20.950174)
						(mid 383.353056 -20.950174)
						(end 384.546856 -20.950174)
					)
				)
			)
		)
		(zone
			(layer "F.Cu")
			(hatch none 0.5)
			(connect_pads
				(clearance 0)
			)
			(min_thickness 0.25)
			(keepout
				(tracks not_allowed)
				(vias allowed)
				(pads allowed)
				(copperpour not_allowed)
				(footprints allowed)
			)
			(placement
				(enabled no)
				(sheetname "")
			)
			(fill
				(thermal_gap 0.5)
				(thermal_bridge_width 0.5)
				(island_removal_mode 0)
			)
			(polygon
				(pts
					(arc
						(start 384.546856 -18.750026)
						(mid 383.353056 -18.750026)
						(end 384.546856 -18.750026)
					)
				)
			)
		)
		(zone
			(layer "F.Cu")
			(hatch none 0.5)
			(connect_pads
				(clearance 0)
			)
			(min_thickness 0.25)
			(keepout
				(tracks allowed)
				(vias not_allowed)
				(pads allowed)
				(copperpour not_allowed)
				(footprints allowed)
			)
			(placement
				(enabled no)
				(sheetname "")
			)
			(fill
				(thermal_gap 0.5)
				(thermal_bridge_width 0.5)
				(island_removal_mode 0)
			)
			(polygon
				(pts
					(arc
						(start 384.546856 -18.750026)
						(mid 383.353056 -18.750026)
						(end 384.546856 -18.750026)
					)
				)
			)
		)
		(zone
			(layer "F.Cu")
			(hatch none 0.5)
			(connect_pads
				(clearance 0)
			)
			(min_thickness 0.25)
			(keepout
				(tracks allowed)
				(vias not_allowed)
				(pads allowed)
				(copperpour not_allowed)
				(footprints allowed)
			)
			(placement
				(enabled no)
				(sheetname "")
			)
			(fill
				(thermal_gap 0.5)
				(thermal_bridge_width 0.5)
				(island_removal_mode 0)
			)
			(polygon
				(pts
					(arc
						(start 384.546856 -17.349978)
						(mid 383.353056 -17.349978)
						(end 384.546856 -17.349978)
					)
				)
			)
		)
		(zone
			(layer "F.Cu")
			(hatch none 0.5)
			(connect_pads
				(clearance 0)
			)
			(min_thickness 0.25)
			(keepout
				(tracks not_allowed)
				(vias allowed)
				(pads allowed)
				(copperpour not_allowed)
				(footprints allowed)
			)
			(placement
				(enabled no)
				(sheetname "")
			)
			(fill
				(thermal_gap 0.5)
				(thermal_bridge_width 0.5)
				(island_removal_mode 0)
			)
			(polygon
				(pts
					(arc
						(start 384.546856 -17.349978)
						(mid 383.353056 -17.349978)
						(end 384.546856 -17.349978)
					)
				)
			)
		)
		(zone
			(layer "F.Cu")
			(hatch none 0.5)
			(connect_pads
				(clearance 0)
			)
			(min_thickness 0.25)
			(keepout
				(tracks not_allowed)
				(vias allowed)
				(pads allowed)
				(copperpour not_allowed)
				(footprints allowed)
			)
			(placement
				(enabled no)
				(sheetname "")
			)
			(fill
				(thermal_gap 0.5)
				(thermal_bridge_width 0.5)
				(island_removal_mode 0)
			)
			(polygon
				(pts
					(arc
						(start 386.346954 -23.35022)
						(mid 385.153154 -23.35022)
						(end 386.346954 -23.35022)
					)
				)
			)
		)
		(zone
			(layer "F.Cu")
			(hatch none 0.5)
			(connect_pads
				(clearance 0)
			)
			(min_thickness 0.25)
			(keepout
				(tracks allowed)
				(vias not_allowed)
				(pads allowed)
				(copperpour not_allowed)
				(footprints allowed)
			)
			(placement
				(enabled no)
				(sheetname "")
			)
			(fill
				(thermal_gap 0.5)
				(thermal_bridge_width 0.5)
				(island_removal_mode 0)
			)
			(polygon
				(pts
					(arc
						(start 386.346954 -23.35022)
						(mid 385.153154 -23.35022)
						(end 386.346954 -23.35022)
					)
				)
			)
		)
		(zone
			(layer "F.Cu")
			(hatch none 0.5)
			(connect_pads
				(clearance 0)
			)
			(min_thickness 0.25)
			(keepout
				(tracks allowed)
				(vias not_allowed)
				(pads allowed)
				(copperpour not_allowed)
				(footprints allowed)
			)
			(placement
				(enabled no)
				(sheetname "")
			)
			(fill
				(thermal_gap 0.5)
				(thermal_bridge_width 0.5)
				(island_removal_mode 0)
			)
			(polygon
				(pts
					(arc
						(start 386.346954 -21.950172)
						(mid 385.153154 -21.950172)
						(end 386.346954 -21.950172)
					)
				)
			)
		)
		(zone
			(layer "F.Cu")
			(hatch none 0.5)
			(connect_pads
				(clearance 0)
			)
			(min_thickness 0.25)
			(keepout
				(tracks not_allowed)
				(vias allowed)
				(pads allowed)
				(copperpour not_allowed)
				(footprints allowed)
			)
			(placement
				(enabled no)
				(sheetname "")
			)
			(fill
				(thermal_gap 0.5)
				(thermal_bridge_width 0.5)
				(island_removal_mode 0)
			)
			(polygon
				(pts
					(arc
						(start 386.346954 -21.950172)
						(mid 385.153154 -21.950172)
						(end 386.346954 -21.950172)
					)
				)
			)
		)
		(zone
			(layer "F.Cu")
			(hatch none 0.5)
			(connect_pads
				(clearance 0)
			)
			(min_thickness 0.25)
			(keepout
				(tracks not_allowed)
				(vias allowed)
				(pads allowed)
				(copperpour not_allowed)
				(footprints allowed)
			)
			(placement
				(enabled no)
				(sheetname "")
			)
			(fill
				(thermal_gap 0.5)
				(thermal_bridge_width 0.5)
				(island_removal_mode 0)
			)
			(polygon
				(pts
					(arc
						(start 386.346954 -19.750024)
						(mid 385.153154 -19.750024)
						(end 386.346954 -19.750024)
					)
				)
			)
		)
		(zone
			(layer "F.Cu")
			(hatch none 0.5)
			(connect_pads
				(clearance 0)
			)
			(min_thickness 0.25)
			(keepout
				(tracks allowed)
				(vias not_allowed)
				(pads allowed)
				(copperpour not_allowed)
				(footprints allowed)
			)
			(placement
				(enabled no)
				(sheetname "")
			)
			(fill
				(thermal_gap 0.5)
				(thermal_bridge_width 0.5)
				(island_removal_mode 0)
			)
			(polygon
				(pts
					(arc
						(start 386.346954 -19.750024)
						(mid 385.153154 -19.750024)
						(end 386.346954 -19.750024)
					)
				)
			)
		)
		(zone
			(layer "F.Cu")
			(hatch none 0.5)
			(connect_pads
				(clearance 0)
			)
			(min_thickness 0.25)
			(keepout
				(tracks allowed)
				(vias not_allowed)
				(pads allowed)
				(copperpour not_allowed)
				(footprints allowed)
			)
			(placement
				(enabled no)
				(sheetname "")
			)
			(fill
				(thermal_gap 0.5)
				(thermal_bridge_width 0.5)
				(island_removal_mode 0)
			)
			(polygon
				(pts
					(arc
						(start 386.346954 -18.35023)
						(mid 385.153154 -18.35023)
						(end 386.346954 -18.35023)
					)
				)
			)
		)
		(zone
			(layer "F.Cu")
			(hatch none 0.5)
			(connect_pads
				(clearance 0)
			)
			(min_thickness 0.25)
			(keepout
				(tracks not_allowed)
				(vias allowed)
				(pads allowed)
				(copperpour not_allowed)
				(footprints allowed)
			)
			(placement
				(enabled no)
				(sheetname "")
			)
			(fill
				(thermal_gap 0.5)
				(thermal_bridge_width 0.5)
				(island_removal_mode 0)
			)
			(polygon
				(pts
					(arc
						(start 386.346954 -18.35023)
						(mid 385.153154 -18.35023)
						(end 386.346954 -18.35023)
					)
				)
			)
		)
		(zone
			(layer "F.Cu")
			(hatch none 0.5)
			(connect_pads
				(clearance 0)
			)
			(min_thickness 0.25)
			(keepout
				(tracks not_allowed)
				(vias allowed)
				(pads allowed)
				(copperpour not_allowed)
				(footprints allowed)
			)
			(placement
				(enabled no)
				(sheetname "")
			)
			(fill
				(thermal_gap 0.5)
				(thermal_bridge_width 0.5)
				(island_removal_mode 0)
			)
			(polygon
				(pts
					(arc
						(start 388.146798 -22.350222)
						(mid 386.952998 -22.350222)
						(end 388.146798 -22.350222)
					)
				)
			)
		)
		(zone
			(layer "F.Cu")
			(hatch none 0.5)
			(connect_pads
				(clearance 0)
			)
			(min_thickness 0.25)
			(keepout
				(tracks allowed)
				(vias not_allowed)
				(pads allowed)
				(copperpour not_allowed)
				(footprints allowed)
			)
			(placement
				(enabled no)
				(sheetname "")
			)
			(fill
				(thermal_gap 0.5)
				(thermal_bridge_width 0.5)
				(island_removal_mode 0)
			)
			(polygon
				(pts
					(arc
						(start 388.146798 -22.350222)
						(mid 386.952998 -22.350222)
						(end 388.146798 -22.350222)
					)
				)
			)
		)
		(zone
			(layer "F.Cu")
			(hatch none 0.5)
			(connect_pads
				(clearance 0)
			)
			(min_thickness 0.25)
			(keepout
				(tracks allowed)
				(vias not_allowed)
				(pads allowed)
				(copperpour not_allowed)
				(footprints allowed)
			)
			(placement
				(enabled no)
				(sheetname "")
			)
			(fill
				(thermal_gap 0.5)
				(thermal_bridge_width 0.5)
				(island_removal_mode 0)
			)
			(polygon
				(pts
					(arc
						(start 388.146798 -20.950174)
						(mid 386.952998 -20.950174)
						(end 388.146798 -20.950174)
					)
				)
			)
		)
		(zone
			(layer "F.Cu")
			(hatch none 0.5)
			(connect_pads
				(clearance 0)
			)
			(min_thickness 0.25)
			(keepout
				(tracks not_allowed)
				(vias allowed)
				(pads allowed)
				(copperpour not_allowed)
				(footprints allowed)
			)
			(placement
				(enabled no)
				(sheetname "")
			)
			(fill
				(thermal_gap 0.5)
				(thermal_bridge_width 0.5)
				(island_removal_mode 0)
			)
			(polygon
				(pts
					(arc
						(start 388.146798 -20.950174)
						(mid 386.952998 -20.950174)
						(end 388.146798 -20.950174)
					)
				)
			)
		)
		(zone
			(layer "F.Cu")
			(hatch none 0.5)
			(connect_pads
				(clearance 0)
			)
			(min_thickness 0.25)
			(keepout
				(tracks allowed)
				(vias not_allowed)
				(pads allowed)
				(copperpour not_allowed)
				(footprints allowed)
			)
			(placement
				(enabled no)
				(sheetname "")
			)
			(fill
				(thermal_gap 0.5)
				(thermal_bridge_width 0.5)
				(island_removal_mode 0)
			)
			(polygon
				(pts
					(arc
						(start 388.146798 -18.750026)
						(mid 386.952998 -18.750026)
						(end 388.146798 -18.750026)
					)
				)
			)
		)
		(zone
			(layer "F.Cu")
			(hatch none 0.5)
			(connect_pads
				(clearance 0)
			)
			(min_thickness 0.25)
			(keepout
				(tracks not_allowed)
				(vias allowed)
				(pads allowed)
				(copperpour not_allowed)
				(footprints allowed)
			)
			(placement
				(enabled no)
				(sheetname "")
			)
			(fill
				(thermal_gap 0.5)
				(thermal_bridge_width 0.5)
				(island_removal_mode 0)
			)
			(polygon
				(pts
					(arc
						(start 388.146798 -18.750026)
						(mid 386.952998 -18.750026)
						(end 388.146798 -18.750026)
					)
				)
			)
		)
		(zone
			(layer "F.Cu")
			(hatch none 0.5)
			(connect_pads
				(clearance 0)
			)
			(min_thickness 0.25)
			(keepout
				(tracks not_allowed)
				(vias allowed)
				(pads allowed)
				(copperpour not_allowed)
				(footprints allowed)
			)
			(placement
				(enabled no)
				(sheetname "")
			)
			(fill
				(thermal_gap 0.5)
				(thermal_bridge_width 0.5)
				(island_removal_mode 0)
			)
			(polygon
				(pts
					(arc
						(start 388.146798 -17.349978)
						(mid 386.952998 -17.349978)
						(end 388.146798 -17.349978)
					)
				)
			)
		)
		(zone
			(layer "F.Cu")
			(hatch none 0.5)
			(connect_pads
				(clearance 0)
			)
			(min_thickness 0.25)
			(keepout
				(tracks allowed)
				(vias not_allowed)
				(pads allowed)
				(copperpour not_allowed)
				(footprints allowed)
			)
			(placement
				(enabled no)
				(sheetname "")
			)
			(fill
				(thermal_gap 0.5)
				(thermal_bridge_width 0.5)
				(island_removal_mode 0)
			)
			(polygon
				(pts
					(arc
						(start 388.146798 -17.349978)
						(mid 386.952998 -17.349978)
						(end 388.146798 -17.349978)
					)
				)
			)
		)
		(zone
			(layer "F.Cu")
			(hatch none 0.5)
			(connect_pads
				(clearance 0)
			)
			(min_thickness 0.25)
			(keepout
				(tracks not_allowed)
				(vias allowed)
				(pads allowed)
				(copperpour not_allowed)
				(footprints allowed)
			)
			(placement
				(enabled no)
				(sheetname "")
			)
			(fill
				(thermal_gap 0.5)
				(thermal_bridge_width 0.5)
				(island_removal_mode 0)
			)
			(polygon
				(pts
					(arc
						(start 389.946896 -23.35022)
						(mid 388.753096 -23.35022)
						(end 389.946896 -23.35022)
					)
				)
			)
		)
		(zone
			(layer "F.Cu")
			(hatch none 0.5)
			(connect_pads
				(clearance 0)
			)
			(min_thickness 0.25)
			(keepout
				(tracks allowed)
				(vias not_allowed)
				(pads allowed)
				(copperpour not_allowed)
				(footprints allowed)
			)
			(placement
				(enabled no)
				(sheetname "")
			)
			(fill
				(thermal_gap 0.5)
				(thermal_bridge_width 0.5)
				(island_removal_mode 0)
			)
			(polygon
				(pts
					(arc
						(start 389.946896 -23.35022)
						(mid 388.753096 -23.35022)
						(end 389.946896 -23.35022)
					)
				)
			)
		)
		(zone
			(layer "F.Cu")
			(hatch none 0.5)
			(connect_pads
				(clearance 0)
			)
			(min_thickness 0.25)
			(keepout
				(tracks not_allowed)
				(vias allowed)
				(pads allowed)
				(copperpour not_allowed)
				(footprints allowed)
			)
			(placement
				(enabled no)
				(sheetname "")
			)
			(fill
				(thermal_gap 0.5)
				(thermal_bridge_width 0.5)
				(island_removal_mode 0)
			)
			(polygon
				(pts
					(arc
						(start 389.946896 -21.950172)
						(mid 388.753096 -21.950172)
						(end 389.946896 -21.950172)
					)
				)
			)
		)
		(zone
			(layer "F.Cu")
			(hatch none 0.5)
			(connect_pads
				(clearance 0)
			)
			(min_thickness 0.25)
			(keepout
				(tracks allowed)
				(vias not_allowed)
				(pads allowed)
				(copperpour not_allowed)
				(footprints allowed)
			)
			(placement
				(enabled no)
				(sheetname "")
			)
			(fill
				(thermal_gap 0.5)
				(thermal_bridge_width 0.5)
				(island_removal_mode 0)
			)
			(polygon
				(pts
					(arc
						(start 389.946896 -21.950172)
						(mid 388.753096 -21.950172)
						(end 389.946896 -21.950172)
					)
				)
			)
		)
		(zone
			(layer "F.Cu")
			(hatch none 0.5)
			(connect_pads
				(clearance 0)
			)
			(min_thickness 0.25)
			(keepout
				(tracks allowed)
				(vias not_allowed)
				(pads allowed)
				(copperpour not_allowed)
				(footprints allowed)
			)
			(placement
				(enabled no)
				(sheetname "")
			)
			(fill
				(thermal_gap 0.5)
				(thermal_bridge_width 0.5)
				(island_removal_mode 0)
			)
			(polygon
				(pts
					(arc
						(start 389.946896 -19.750024)
						(mid 388.753096 -19.750024)
						(end 389.946896 -19.750024)
					)
				)
			)
		)
		(zone
			(layer "F.Cu")
			(hatch none 0.5)
			(connect_pads
				(clearance 0)
			)
			(min_thickness 0.25)
			(keepout
				(tracks not_allowed)
				(vias allowed)
				(pads allowed)
				(copperpour not_allowed)
				(footprints allowed)
			)
			(placement
				(enabled no)
				(sheetname "")
			)
			(fill
				(thermal_gap 0.5)
				(thermal_bridge_width 0.5)
				(island_removal_mode 0)
			)
			(polygon
				(pts
					(arc
						(start 389.946896 -19.750024)
						(mid 388.753096 -19.750024)
						(end 389.946896 -19.750024)
					)
				)
			)
		)
		(zone
			(layer "F.Cu")
			(hatch none 0.5)
			(connect_pads
				(clearance 0)
			)
			(min_thickness 0.25)
			(keepout
				(tracks not_allowed)
				(vias allowed)
				(pads allowed)
				(copperpour not_allowed)
				(footprints allowed)
			)
			(placement
				(enabled no)
				(sheetname "")
			)
			(fill
				(thermal_gap 0.5)
				(thermal_bridge_width 0.5)
				(island_removal_mode 0)
			)
			(polygon
				(pts
					(arc
						(start 389.946896 -18.35023)
						(mid 388.753096 -18.35023)
						(end 389.946896 -18.35023)
					)
				)
			)
		)
		(zone
			(layer "F.Cu")
			(hatch none 0.5)
			(connect_pads
				(clearance 0)
			)
			(min_thickness 0.25)
			(keepout
				(tracks allowed)
				(vias not_allowed)
				(pads allowed)
				(copperpour not_allowed)
				(footprints allowed)
			)
			(placement
				(enabled no)
				(sheetname "")
			)
			(fill
				(thermal_gap 0.5)
				(thermal_bridge_width 0.5)
				(island_removal_mode 0)
			)
			(polygon
				(pts
					(arc
						(start 389.946896 -18.35023)
						(mid 388.753096 -18.35023)
						(end 389.946896 -18.35023)
					)
				)
			)
		)
		(zone
			(layers "F.Cu" "B.Cu" "In1.Cu" "In2.Cu" "In3.Cu" "In4.Cu" "In5.Cu" "In6.Cu"
				"In7.Cu" "In8.Cu" "In9.Cu" "In10.Cu"
			)
			(hatch none 0.5)
			(connect_pads
				(clearance 0)
			)
			(min_thickness 0.25)
			(keepout
				(tracks not_allowed)
				(vias allowed)
				(pads allowed)
				(copperpour not_allowed)
				(footprints allowed)
			)
			(placement
				(enabled no)
				(sheetname "")
			)
			(fill
				(thermal_gap 0.5)
				(thermal_bridge_width 0.5)
				(island_removal_mode 0)
			)
			(polygon
				(pts
					(arc
						(start 373.648478 -20.550124)
						(mid 370.651278 -20.550124)
						(end 373.648478 -20.550124)
					)
				)
			)
		)
		(zone
			(layers "F.Cu" "B.Cu" "In1.Cu" "In2.Cu" "In3.Cu" "In4.Cu" "In5.Cu" "In6.Cu"
				"In7.Cu" "In8.Cu" "In9.Cu" "In10.Cu"
			)
			(hatch none 0.5)
			(connect_pads
				(clearance 0)
			)
			(min_thickness 0.25)
			(keepout
				(tracks not_allowed)
				(vias allowed)
				(pads allowed)
				(copperpour not_allowed)
				(footprints allowed)
			)
			(placement
				(enabled no)
				(sheetname "")
			)
			(fill
				(thermal_gap 0.5)
				(thermal_bridge_width 0.5)
				(island_removal_mode 0)
			)
			(polygon
				(pts
					(arc
						(start 373.686578 -28.080208)
						(mid 370.613178 -28.080208)
						(end 373.686578 -28.080208)
					)
				)
			)
		)
		(zone
			(layer "B.Cu")
			(hatch none 0.5)
			(connect_pads
				(clearance 0)
			)
			(min_thickness 0.25)
			(keepout
				(tracks not_allowed)
				(vias allowed)
				(pads allowed)
				(copperpour not_allowed)
				(footprints allowed)
			)
			(placement
				(enabled no)
				(sheetname "")
			)
			(fill
				(thermal_gap 0.5)
				(thermal_bridge_width 0.5)
				(island_removal_mode 0)
			)
			(polygon
				(pts
					(xy 368.730022 -34.29) (xy 375.480072 -34.29) (xy 375.480072 -15.000224) (xy 368.730022 -15.000224)
				)
			)
		)
		(zone
			(layer "B.Cu")
			(hatch none 0.5)
			(connect_pads
				(clearance 0)
			)
			(min_thickness 0.25)
			(keepout
				(tracks allowed)
				(vias not_allowed)
				(pads allowed)
				(copperpour not_allowed)
				(footprints allowed)
			)
			(placement
				(enabled no)
				(sheetname "")
			)
			(fill
				(thermal_gap 0.5)
				(thermal_bridge_width 0.5)
				(island_removal_mode 0)
			)
			(polygon
				(pts
					(xy 368.730022 -15.000224) (xy 368.730022 -34.29) (xy 375.480072 -34.29) (xy 375.480072 -15.000224)
				)
			)
		)
	)
	(footprint ""
		(layer "B.Cu")
		(at 184.00395 -221.880176 -90)
		(property "Reference" "C675"
			(at 0 0 90)
			(layer "B.SilkS")
			(hide yes)
			(effects
				(font
					(size 1.27 1.27)
				)
				(justify mirror)
			)
		)
		(property "Value" "SC3300P50V2KX-1GP"
			(at -1.1811 -2.7051 270)
			(unlocked yes)
			(layer "B.Fab")
			(hide yes)
			(effects
				(font
					(size 1.016 1.016)
					(thickness 0.1524)
				)
				(justify mirror)
			)
		)
		(property "Device Type" "C402H22"
			(at -1.1811 -4.2291 270)
			(unlocked yes)
			(layer "B.Fab")
			(hide yes)
			(effects
				(font
					(size 1.016 1.016)
					(thickness 0.1524)
				)
				(justify mirror)
			)
		)
		(duplicate_pad_numbers_are_jumpers no)
		(fp_rect
			(start 0.4318 0.9525)
			(end -0.4318 -0.9525)
			(stroke
				(width 0)
				(type default)
			)
			(fill no)
			(layer "B.CrtYd")
		)
		(fp_rect
			(start 0.4318 0.9525)
			(end -0.4318 -0.9525)
			(stroke
				(width 0)
				(type default)
			)
			(fill no)
			(layer "B.Fab")
		)
		(pad "1" smd custom
			(at 0 -0.4445 90)
			(size 0.1524 0.1524)
			(layers "B.Cu" "B.Mask" "B.Paste")
			(net "P3V3_STBY_SS")
			(options
				(clearance outline)
				(anchor circle)
			)
			(primitives
				(gr_poly
					(pts
						(arc
							(start 0.3048 0.2032)
							(mid 0.275042 0.275042)
							(end 0.2032 0.3048)
						)
						(arc
							(start -0.2032 0.3048)
							(mid -0.275042 0.275042)
							(end -0.3048 0.2032)
						)
						(arc
							(start -0.3048 -0.2032)
							(mid -0.275042 -0.275042)
							(end -0.2032 -0.3048)
						)
						(arc
							(start 0.2032 -0.3048)
							(mid 0.275042 -0.275042)
							(end 0.3048 -0.2032)
						)
					)
					(width 0)
					(fill yes)
				)
			)
		)
		(pad "2" smd custom
			(at 0 0.4445 90)
			(size 0.1524 0.1524)
			(layers "B.Cu" "B.Mask" "B.Paste")
			(net "AGND_P3V3_STBY")
			(options
				(clearance outline)
				(anchor circle)
			)
			(primitives
				(gr_poly
					(pts
						(arc
							(start 0.3048 0.2032)
							(mid 0.275042 0.275042)
							(end 0.2032 0.3048)
						)
						(arc
							(start -0.2032 0.3048)
							(mid -0.275042 0.275042)
							(end -0.3048 0.2032)
						)
						(arc
							(start -0.3048 -0.2032)
							(mid -0.275042 -0.275042)
							(end -0.2032 -0.3048)
						)
						(arc
							(start 0.2032 -0.3048)
							(mid 0.275042 -0.275042)
							(end 0.3048 -0.2032)
						)
					)
					(width 0)
					(fill yes)
				)
			)
		)
	)
	(footprint ""
		(layer "B.Cu")
		(at 18.161 -246.7864 180)
		(property "Reference" "C602"
			(at 0 0 0)
			(layer "B.SilkS")
			(hide yes)
			(effects
				(font
					(size 1.27 1.27)
				)
				(justify mirror)
			)
		)
		(property "Value" "SC10U16V5KX-7-GP-U"
			(at 0.0762 -6.1214 180)
			(unlocked yes)
			(layer "B.Fab")
			(hide yes)
			(effects
				(font
					(size 1.016 1.016)
					(thickness 0.1524)
				)
				(justify mirror)
			)
		)
		(property "Device Type" "C805H58"
			(at 0.0762 -8.1534 180)
			(unlocked yes)
			(layer "B.Fab")
			(hide yes)
			(effects
				(font
					(size 1.016 1.016)
					(thickness 0.1524)
				)
				(justify mirror)
			)
		)
		(duplicate_pad_numbers_are_jumpers no)
		(fp_line
			(start -0.635 0)
			(end 0.635 0)
			(stroke
				(width 0.508)
				(type default)
			)
			(layer "B.SilkS")
		)
		(fp_rect
			(start 0.9652 1.778)
			(end -0.9652 -1.778)
			(stroke
				(width 0)
				(type default)
			)
			(fill no)
			(layer "B.CrtYd")
		)
		(fp_poly
			(pts
				(xy 0.9652 -1.778) (xy -0.9652 -1.778) (xy -0.9652 1.778) (xy 0.9652 1.778)
			)
			(stroke
				(width 0)
				(type default)
			)
			(fill no)
			(layer "B.Fab")
		)
		(pad "1" smd rect
			(at 0 -0.9652)
			(size 1.397 1.143)
			(layers "B.Cu" "B.Mask" "B.Paste")
			(net "P12V_A_VIN_U20")
		)
		(pad "2" smd rect
			(at 0 0.9652)
			(size 1.397 1.143)
			(layers "B.Cu" "B.Mask" "B.Paste")
			(net "GND")
		)
	)
	(footprint ""
		(layer "B.Cu")
		(at 473.1512 -252.5522 180)
		(property "Reference" "C645"
			(at 0 0 0)
			(layer "B.SilkS")
			(hide yes)
			(effects
				(font
					(size 1.27 1.27)
				)
				(justify mirror)
			)
		)
		(property "Value" "SC10U16V5KX-7-GP-U"
			(at 0.0762 -6.1214 180)
			(unlocked yes)
			(layer "B.Fab")
			(hide yes)
			(effects
				(font
					(size 1.016 1.016)
					(thickness 0.1524)
				)
				(justify mirror)
			)
		)
		(property "Device Type" "C805H58"
			(at 0.0762 -8.1534 180)
			(unlocked yes)
			(layer "B.Fab")
			(hide yes)
			(effects
				(font
					(size 1.016 1.016)
					(thickness 0.1524)
				)
				(justify mirror)
			)
		)
		(duplicate_pad_numbers_are_jumpers no)
		(fp_line
			(start -0.635 0)
			(end 0.635 0)
			(stroke
				(width 0.508)
				(type default)
			)
			(layer "B.SilkS")
		)
		(fp_rect
			(start 0.9652 1.778)
			(end -0.9652 -1.778)
			(stroke
				(width 0)
				(type default)
			)
			(fill no)
			(layer "B.CrtYd")
		)
		(fp_poly
			(pts
				(xy 0.9652 -1.778) (xy -0.9652 -1.778) (xy -0.9652 1.778) (xy 0.9652 1.778)
			)
			(stroke
				(width 0)
				(type default)
			)
			(fill no)
			(layer "B.Fab")
		)
		(pad "1" smd rect
			(at 0 -0.9652)
			(size 1.397 1.143)
			(layers "B.Cu" "B.Mask" "B.Paste")
			(net "P5V_A_3")
		)
		(pad "2" smd rect
			(at 0 0.9652)
			(size 1.397 1.143)
			(layers "B.Cu" "B.Mask" "B.Paste")
			(net "GND")
		)
	)
	(footprint ""
		(layer "B.Cu")
		(at 362.6358 -142.7734 90)
		(property "Reference" "R1086"
			(at 0 0 90)
			(layer "B.SilkS")
			(hide yes)
			(effects
				(font
					(size 1.27 1.27)
				)
				(justify mirror)
			)
		)
		(property "Value" "10R2F-L-GP"
			(at -0.064008 -3.993896 90)
			(unlocked yes)
			(layer "B.Fab")
			(hide yes)
			(effects
				(font
					(size 1.016 1.016)
					(thickness 0.1524)
				)
				(justify mirror)
			)
		)
		(property "Device Type" "R402H14"
			(at -0.064008 -5.517896 90)
			(unlocked yes)
			(layer "B.Fab")
			(hide yes)
			(effects
				(font
					(size 1.016 1.016)
					(thickness 0.1524)
				)
				(justify mirror)
			)
		)
		(duplicate_pad_numbers_are_jumpers no)
		(fp_line
			(start 0.508 -0.9398)
			(end 0.508 0.9398)
			(stroke
				(width 0.1524)
				(type default)
			)
			(layer "B.SilkS")
		)
		(fp_line
			(start -0.508 -0.9398)
			(end 0.508 -0.9398)
			(stroke
				(width 0.1524)
				(type default)
			)
			(layer "B.SilkS")
		)
		(fp_rect
			(start 0.508 0.9398)
			(end -0.508 -0.9398)
			(stroke
				(width 0)
				(type default)
			)
			(fill no)
			(layer "B.CrtYd")
		)
		(fp_rect
			(start 0.508 0.9398)
			(end -0.508 -0.9398)
			(stroke
				(width 0)
				(type default)
			)
			(fill no)
			(layer "B.Fab")
		)
		(pad "1" smd custom
			(at 0 -0.4445 270)
			(size 0.1397 0.1397)
			(layers "B.Cu" "B.Mask" "B.Paste")
			(net "MB1_CM_SENSE_R1_P")
			(options
				(clearance outline)
				(anchor circle)
			)
			(primitives
				(gr_poly
					(pts
						(arc
							(start -0.1778 0.2794)
							(mid -0.249642 0.249642)
							(end -0.2794 0.1778)
						)
						(arc
							(start -0.2794 -0.1778)
							(mid -0.249642 -0.249642)
							(end -0.1778 -0.2794)
						)
						(arc
							(start 0.1778 -0.2794)
							(mid 0.249642 -0.249642)
							(end 0.2794 -0.1778)
						)
						(arc
							(start 0.2794 0.1778)
							(mid 0.249642 0.249642)
							(end 0.1778 0.2794)
						)
					)
					(width 0)
					(fill yes)
				)
			)
		)
		(pad "2" smd custom
			(at 0 0.4445 270)
			(size 0.1397 0.1397)
			(layers "B.Cu" "B.Mask" "B.Paste")
			(net "MB1_CM_SENSE_P")
			(options
				(clearance outline)
				(anchor circle)
			)
			(primitives
				(gr_poly
					(pts
						(arc
							(start -0.1778 0.2794)
							(mid -0.249642 0.249642)
							(end -0.2794 0.1778)
						)
						(arc
							(start -0.2794 -0.1778)
							(mid -0.249642 -0.249642)
							(end -0.1778 -0.2794)
						)
						(arc
							(start 0.1778 -0.2794)
							(mid 0.249642 -0.249642)
							(end 0.2794 -0.1778)
						)
						(arc
							(start 0.2794 0.1778)
							(mid 0.249642 0.249642)
							(end 0.1778 0.2794)
						)
					)
					(width 0)
					(fill yes)
				)
			)
		)
	)
	(footprint ""
		(layer "B.Cu")
		(at 38.490144 -252.901196 180)
		(property "Reference" "R1211"
			(at 0 0 0)
			(layer "B.SilkS")
			(hide yes)
			(effects
				(font
					(size 1.27 1.27)
				)
				(justify mirror)
			)
		)
		(property "Value" "2K7R2F-GP"
			(at -0.064008 -3.993896 180)
			(unlocked yes)
			(layer "B.Fab")
			(hide yes)
			(effects
				(font
					(size 1.016 1.016)
					(thickness 0.1524)
				)
				(justify mirror)
			)
		)
		(property "Device Type" "R402H16"
			(at -0.064008 -5.517896 180)
			(unlocked yes)
			(layer "B.Fab")
			(hide yes)
			(effects
				(font
					(size 1.016 1.016)
					(thickness 0.1524)
				)
				(justify mirror)
			)
		)
		(duplicate_pad_numbers_are_jumpers no)
		(fp_line
			(start 0.508 -0.9398)
			(end 0.508 0.9398)
			(stroke
				(width 0.1524)
				(type default)
			)
			(layer "B.SilkS")
		)
		(fp_line
			(start -0.508 -0.9398)
			(end 0.508 -0.9398)
			(stroke
				(width 0.1524)
				(type default)
			)
			(layer "B.SilkS")
		)
		(fp_rect
			(start 0.508 0.9398)
			(end -0.508 -0.9398)
			(stroke
				(width 0)
				(type default)
			)
			(fill no)
			(layer "B.CrtYd")
		)
		(fp_rect
			(start 0.508 0.9398)
			(end -0.508 -0.9398)
			(stroke
				(width 0)
				(type default)
			)
			(fill no)
			(layer "B.Fab")
		)
		(pad "1" smd custom
			(at 0 -0.4445)
			(size 0.1397 0.1397)
			(layers "B.Cu" "B.Mask" "B.Paste")
			(net "P5V_A_LL")
			(options
				(clearance outline)
				(anchor circle)
			)
			(primitives
				(gr_poly
					(pts
						(arc
							(start -0.1778 0.2794)
							(mid -0.249642 0.249642)
							(end -0.2794 0.1778)
						)
						(arc
							(start -0.2794 -0.1778)
							(mid -0.249642 -0.249642)
							(end -0.1778 -0.2794)
						)
						(arc
							(start 0.1778 -0.2794)
							(mid 0.249642 -0.249642)
							(end 0.2794 -0.1778)
						)
						(arc
							(start 0.2794 0.1778)
							(mid 0.249642 0.249642)
							(end 0.1778 0.2794)
						)
					)
					(width 0)
					(fill yes)
				)
			)
		)
		(pad "2" smd custom
			(at 0 0.4445)
			(size 0.1397 0.1397)
			(layers "B.Cu" "B.Mask" "B.Paste")
			(net "P5V_A_LL_R")
			(options
				(clearance outline)
				(anchor circle)
			)
			(primitives
				(gr_poly
					(pts
						(arc
							(start -0.1778 0.2794)
							(mid -0.249642 0.249642)
							(end -0.2794 0.1778)
						)
						(arc
							(start -0.2794 -0.1778)
							(mid -0.249642 -0.249642)
							(end -0.1778 -0.2794)
						)
						(arc
							(start 0.1778 -0.2794)
							(mid 0.249642 -0.249642)
							(end 0.2794 -0.1778)
						)
						(arc
							(start 0.2794 0.1778)
							(mid 0.249642 0.249642)
							(end 0.1778 0.2794)
						)
					)
					(width 0)
					(fill yes)
				)
			)
		)
	)
	(footprint ""
		(layer "B.Cu")
		(at 371.599968 -220.199966 180)
		(property "Reference" "NUT8"
			(at 0 0 0)
			(layer "B.SilkS")
			(hide yes)
			(effects
				(font
					(size 1.27 1.27)
				)
				(justify mirror)
			)
		)
		(property "Value" "STF256R168H278-GP"
			(at 4.826 0.0508 180)
			(unlocked yes)
			(layer "B.Fab")
			(hide yes)
			(effects
				(font
					(size 1.016 1.016)
					(thickness 0.1524)
				)
				(justify mirror)
			)
		)
		(property "Device Type" "STF256R168H278"
			(at 4.826 -1.4732 180)
			(unlocked yes)
			(layer "B.Fab")
			(hide yes)
			(effects
				(font
					(size 1.016 1.016)
					(thickness 0.1524)
				)
				(justify mirror)
			)
		)
		(duplicate_pad_numbers_are_jumpers no)
		(fp_circle
			(center 0 0)
			(end -3.6068 0)
			(stroke
				(width 0.3048)
				(type default)
			)
			(fill no)
			(layer "B.SilkS")
		)
		(fp_poly
			(pts
				(arc
					(start -2.5019 0)
					(mid 2.5019 0)
					(end -2.5019 0)
				)
			)
			(stroke
				(width 0)
				(type default)
			)
			(fill no)
			(layer "B.CrtYd")
		)
		(fp_poly
			(pts
				(arc
					(start -3.7592 0.00635)
					(mid 3.759205 0)
					(end -3.7592 -0.00635)
				)
				(arc
					(start -2.5019 -0.00635)
					(mid 2.501908 0)
					(end -2.5019 0.00635)
				)
			)
			(stroke
				(width 0)
				(type default)
			)
			(fill no)
			(layer "B.CrtYd")
		)
		(fp_poly
			(pts
				(arc
					(start -3.7592 0)
					(mid 3.7592 0)
					(end -3.7592 0)
				)
			)
			(stroke
				(width 0)
				(type default)
			)
			(fill no)
			(layer "F.CrtYd")
		)
		(fp_poly
			(pts
				(arc
					(start -3.7592 0)
					(mid 3.7592 0)
					(end -3.7592 0)
				)
			)
			(stroke
				(width 0)
				(type default)
			)
			(fill no)
			(layer "B.Fab")
		)
		(fp_poly
			(pts
				(arc
					(start -3.7592 0)
					(mid 3.7592 0)
					(end -3.7592 0)
				)
			)
			(stroke
				(width 0)
				(type default)
			)
			(fill no)
			(layer "F.Fab")
		)
		(pad "1" thru_hole circle
			(at 0 0)
			(size 6.5024 6.5024)
			(drill 4.2672)
			(layers "*.Cu" "*.Mask")
			(remove_unused_layers no)
			(net "Net_4")
			(clearance -0.6096)
			(padstack
				(mode front_inner_back)
				(layer "Inner"
					(shape circle)
					(size 4.6736 4.6736)
					(clearance 0.3048)
				)
				(layer "B.Cu"
					(shape circle)
					(size 6.5024 6.5024)
					(thermal_gap 0.3048)
					(clearance -0.6096)
				)
			)
		)
	)
	(footprint ""
		(layer "B.Cu")
		(at 470.408 -241.427 -90)
		(property "Reference" "C648"
			(at 0 0 90)
			(layer "B.SilkS")
			(hide yes)
			(effects
				(font
					(size 1.27 1.27)
				)
				(justify mirror)
			)
		)
		(property "Value" "SC10U16V5KX-7-GP-U"
			(at 0.0762 -6.1214 270)
			(unlocked yes)
			(layer "B.Fab")
			(hide yes)
			(effects
				(font
					(size 1.016 1.016)
					(thickness 0.1524)
				)
				(justify mirror)
			)
		)
		(property "Device Type" "C805H58"
			(at 0.0762 -8.1534 270)
			(unlocked yes)
			(layer "B.Fab")
			(hide yes)
			(effects
				(font
					(size 1.016 1.016)
					(thickness 0.1524)
				)
				(justify mirror)
			)
		)
		(duplicate_pad_numbers_are_jumpers no)
		(fp_line
			(start -0.635 0)
			(end 0.635 0)
			(stroke
				(width 0.508)
				(type default)
			)
			(layer "B.SilkS")
		)
		(fp_rect
			(start 0.9652 1.778)
			(end -0.9652 -1.778)
			(stroke
				(width 0)
				(type default)
			)
			(fill no)
			(layer "B.CrtYd")
		)
		(fp_poly
			(pts
				(xy 0.9652 -1.778) (xy -0.9652 -1.778) (xy -0.9652 1.778) (xy 0.9652 1.778)
			)
			(stroke
				(width 0)
				(type default)
			)
			(fill no)
			(layer "B.Fab")
		)
		(pad "1" smd rect
			(at 0 -0.9652 90)
			(size 1.397 1.143)
			(layers "B.Cu" "B.Mask" "B.Paste")
			(net "P12V_A_VIN_U27")
		)
		(pad "2" smd rect
			(at 0 0.9652 90)
			(size 1.397 1.143)
			(layers "B.Cu" "B.Mask" "B.Paste")
			(net "GND")
		)
	)
	(footprint ""
		(layer "B.Cu")
		(at 71.0946 -147.5486 180)
		(property "Reference" "C629"
			(at 0 0 0)
			(layer "B.SilkS")
			(hide yes)
			(effects
				(font
					(size 1.27 1.27)
				)
				(justify mirror)
			)
		)
		(property "Value" "SC10U16V5KX-7-GP-U"
			(at 0.0762 -6.1214 180)
			(unlocked yes)
			(layer "B.Fab")
			(hide yes)
			(effects
				(font
					(size 1.016 1.016)
					(thickness 0.1524)
				)
				(justify mirror)
			)
		)
		(property "Device Type" "C805H58"
			(at 0.0762 -8.1534 180)
			(unlocked yes)
			(layer "B.Fab")
			(hide yes)
			(effects
				(font
					(size 1.016 1.016)
					(thickness 0.1524)
				)
				(justify mirror)
			)
		)
		(duplicate_pad_numbers_are_jumpers no)
		(fp_line
			(start -0.635 0)
			(end 0.635 0)
			(stroke
				(width 0.508)
				(type default)
			)
			(layer "B.SilkS")
		)
		(fp_rect
			(start 0.9652 1.778)
			(end -0.9652 -1.778)
			(stroke
				(width 0)
				(type default)
			)
			(fill no)
			(layer "B.CrtYd")
		)
		(fp_poly
			(pts
				(xy 0.9652 -1.778) (xy -0.9652 -1.778) (xy -0.9652 1.778) (xy 0.9652 1.778)
			)
			(stroke
				(width 0)
				(type default)
			)
			(fill no)
			(layer "B.Fab")
		)
		(pad "1" smd rect
			(at 0 -0.9652)
			(size 1.397 1.143)
			(layers "B.Cu" "B.Mask" "B.Paste")
			(net "P5V_A_2")
		)
		(pad "2" smd rect
			(at 0 0.9652)
			(size 1.397 1.143)
			(layers "B.Cu" "B.Mask" "B.Paste")
			(net "GND")
		)
	)
	(footprint ""
		(layer "B.Cu")
		(at 220.188028 -103.2637 -90)
		(property "Reference" "C529"
			(at 0 0 90)
			(layer "B.SilkS")
			(hide yes)
			(effects
				(font
					(size 1.27 1.27)
				)
				(justify mirror)
			)
		)
		(property "Value" "SC22U25V6KX-2-GP-U"
			(at 2.860802 -5.279644 270)
			(unlocked yes)
			(layer "B.Fab")
			(hide yes)
			(effects
				(font
					(size 1.016 1.016)
					(thickness 0.1524)
				)
				(justify mirror)
			)
		)
		(property "Device Type" "C1206-TO0D3H75"
			(at 2.860802 -6.803644 270)
			(unlocked yes)
			(layer "B.Fab")
			(hide yes)
			(effects
				(font
					(size 1.016 1.016)
					(thickness 0.1524)
				)
				(justify mirror)
			)
		)
		(duplicate_pad_numbers_are_jumpers no)
		(fp_line
			(start -1.3081 2.3749)
			(end 1.3081 2.3749)
			(stroke
				(width 0.1524)
				(type default)
			)
			(layer "B.SilkS")
		)
		(fp_line
			(start 1.3081 2.3749)
			(end 1.3081 -2.3749)
			(stroke
				(width 0.1524)
				(type default)
			)
			(layer "B.SilkS")
		)
		(fp_line
			(start -1.3081 -2.3749)
			(end -1.3081 2.3749)
			(stroke
				(width 0.1524)
				(type default)
			)
			(layer "B.SilkS")
		)
		(fp_line
			(start 1.3081 -2.3749)
			(end -1.3081 -2.3749)
			(stroke
				(width 0.1524)
				(type default)
			)
			(layer "B.SilkS")
		)
		(fp_rect
			(start 0.8001 1.6002)
			(end -0.8001 -1.6002)
			(stroke
				(width 0)
				(type default)
			)
			(fill no)
			(layer "B.CrtYd")
		)
		(fp_poly
			(pts
				(xy 1.5621 2.4511) (xy 1.5621 1.6002) (xy -0.8001 1.6002) (xy -0.8001 -1.6002) (xy 0.8001 -1.6002)
				(xy 0.8001 1.5875) (xy 1.5621 1.5875) (xy 1.5621 -2.4511) (xy -1.5621 -2.4511) (xy -1.5621 2.4511)
			)
			(stroke
				(width 0)
				(type default)
			)
			(fill no)
			(layer "B.CrtYd")
		)
		(fp_rect
			(start 1.5621 2.4511)
			(end -1.5621 -2.4511)
			(stroke
				(width 0)
				(type default)
			)
			(fill no)
			(layer "B.Fab")
		)
		(pad "1" smd rect
			(at 0 -1.392936 90)
			(size 2.1082 1.4478)
			(layers "B.Cu" "B.Mask" "B.Paste")
			(net "P12V_A_COMP")
		)
		(pad "2" smd rect
			(at 0 1.392936 90)
			(size 2.1082 1.4478)
			(layers "B.Cu" "B.Mask" "B.Paste")
			(net "GND")
		)
	)
	(footprint ""
		(layer "B.Cu")
		(at 440.237372 -252.381766 180)
		(property "Reference" "C634"
			(at 0 0 0)
			(layer "B.SilkS")
			(hide yes)
			(effects
				(font
					(size 1.27 1.27)
				)
				(justify mirror)
			)
		)
		(property "Value" "SCD1U16V2KX-3GP"
			(at -1.1811 -2.7051 180)
			(unlocked yes)
			(layer "B.Fab")
			(hide yes)
			(effects
				(font
					(size 1.016 1.016)
					(thickness 0.1524)
				)
				(justify mirror)
			)
		)
		(property "Device Type" "C402H22"
			(at -1.1811 -4.2291 180)
			(unlocked yes)
			(layer "B.Fab")
			(hide yes)
			(effects
				(font
					(size 1.016 1.016)
					(thickness 0.1524)
				)
				(justify mirror)
			)
		)
		(duplicate_pad_numbers_are_jumpers no)
		(fp_rect
			(start 0.4318 0.9525)
			(end -0.4318 -0.9525)
			(stroke
				(width 0)
				(type default)
			)
			(fill no)
			(layer "B.CrtYd")
		)
		(fp_rect
			(start 0.4318 0.9525)
			(end -0.4318 -0.9525)
			(stroke
				(width 0)
				(type default)
			)
			(fill no)
			(layer "B.Fab")
		)
		(pad "1" smd custom
			(at 0 -0.4445)
			(size 0.1524 0.1524)
			(layers "B.Cu" "B.Mask" "B.Paste")
			(net "P12V_A_VIN_U22")
			(options
				(clearance outline)
				(anchor circle)
			)
			(primitives
				(gr_poly
					(pts
						(arc
							(start 0.3048 0.2032)
							(mid 0.275042 0.275042)
							(end 0.2032 0.3048)
						)
						(arc
							(start -0.2032 0.3048)
							(mid -0.275042 0.275042)
							(end -0.3048 0.2032)
						)
						(arc
							(start -0.3048 -0.2032)
							(mid -0.275042 -0.275042)
							(end -0.2032 -0.3048)
						)
						(arc
							(start 0.2032 -0.3048)
							(mid 0.275042 -0.275042)
							(end 0.3048 -0.2032)
						)
					)
					(width 0)
					(fill yes)
				)
			)
		)
		(pad "2" smd custom
			(at 0 0.4445)
			(size 0.1524 0.1524)
			(layers "B.Cu" "B.Mask" "B.Paste")
			(net "GND")
			(options
				(clearance outline)
				(anchor circle)
			)
			(primitives
				(gr_poly
					(pts
						(arc
							(start 0.3048 0.2032)
							(mid 0.275042 0.275042)
							(end 0.2032 0.3048)
						)
						(arc
							(start -0.2032 0.3048)
							(mid -0.275042 0.275042)
							(end -0.3048 0.2032)
						)
						(arc
							(start -0.3048 -0.2032)
							(mid -0.275042 -0.275042)
							(end -0.2032 -0.3048)
						)
						(arc
							(start 0.2032 -0.3048)
							(mid 0.275042 -0.275042)
							(end 0.3048 -0.2032)
						)
					)
					(width 0)
					(fill yes)
				)
			)
		)
	)
	(footprint ""
		(layer "B.Cu")
		(at 218.9226 -123.4694 180)
		(property "Reference" "R349"
			(at 0 0 0)
			(layer "B.SilkS")
			(hide yes)
			(effects
				(font
					(size 1.27 1.27)
				)
				(justify mirror)
			)
		)
		(property "Value" "0R2J-2-GP"
			(at -0.064008 -3.993896 180)
			(unlocked yes)
			(layer "B.Fab")
			(hide yes)
			(effects
				(font
					(size 1.016 1.016)
					(thickness 0.1524)
				)
				(justify mirror)
			)
		)
		(property "Device Type" "R402H16"
			(at -0.064008 -5.517896 180)
			(unlocked yes)
			(layer "B.Fab")
			(hide yes)
			(effects
				(font
					(size 1.016 1.016)
					(thickness 0.1524)
				)
				(justify mirror)
			)
		)
		(duplicate_pad_numbers_are_jumpers no)
		(fp_line
			(start 0.508 -0.9398)
			(end 0.508 0.9398)
			(stroke
				(width 0.1524)
				(type default)
			)
			(layer "B.SilkS")
		)
		(fp_line
			(start -0.508 -0.9398)
			(end 0.508 -0.9398)
			(stroke
				(width 0.1524)
				(type default)
			)
			(layer "B.SilkS")
		)
		(fp_rect
			(start 0.508 0.9398)
			(end -0.508 -0.9398)
			(stroke
				(width 0)
				(type default)
			)
			(fill no)
			(layer "B.CrtYd")
		)
		(fp_rect
			(start 0.508 0.9398)
			(end -0.508 -0.9398)
			(stroke
				(width 0)
				(type default)
			)
			(fill no)
			(layer "B.Fab")
		)
		(pad "1" smd custom
			(at 0 -0.4445)
			(size 0.1397 0.1397)
			(layers "B.Cu" "B.Mask" "B.Paste")
			(net "I2C_BMC_A_COMP_A_SCL")
			(options
				(clearance outline)
				(anchor circle)
			)
			(primitives
				(gr_poly
					(pts
						(arc
							(start -0.1778 0.2794)
							(mid -0.249642 0.249642)
							(end -0.2794 0.1778)
						)
						(arc
							(start -0.2794 -0.1778)
							(mid -0.249642 -0.249642)
							(end -0.1778 -0.2794)
						)
						(arc
							(start 0.1778 -0.2794)
							(mid 0.249642 -0.249642)
							(end 0.2794 -0.1778)
						)
						(arc
							(start 0.2794 0.1778)
							(mid 0.249642 0.249642)
							(end 0.1778 0.2794)
						)
					)
					(width 0)
					(fill yes)
				)
			)
		)
		(pad "2" smd custom
			(at 0 0.4445)
			(size 0.1397 0.1397)
			(layers "B.Cu" "B.Mask" "B.Paste")
			(net "I2C_BMC_A_COMP_A_SCL_R")
			(options
				(clearance outline)
				(anchor circle)
			)
			(primitives
				(gr_poly
					(pts
						(arc
							(start -0.1778 0.2794)
							(mid -0.249642 0.249642)
							(end -0.2794 0.1778)
						)
						(arc
							(start -0.2794 -0.1778)
							(mid -0.249642 -0.249642)
							(end -0.1778 -0.2794)
						)
						(arc
							(start 0.1778 -0.2794)
							(mid 0.249642 -0.249642)
							(end 0.2794 -0.1778)
						)
						(arc
							(start 0.2794 0.1778)
							(mid 0.249642 0.249642)
							(end 0.1778 0.2794)
						)
					)
					(width 0)
					(fill yes)
				)
			)
		)
	)
	(footprint ""
		(layer "B.Cu")
		(at 478.7265 -223.602042 90)
		(property "Reference" "R1268"
			(at 0 0 90)
			(layer "B.SilkS")
			(hide yes)
			(effects
				(font
					(size 1.27 1.27)
				)
				(justify mirror)
			)
		)
		(property "Value" "2K7R2F-GP"
			(at -0.064008 -3.993896 90)
			(unlocked yes)
			(layer "B.Fab")
			(hide yes)
			(effects
				(font
					(size 1.016 1.016)
					(thickness 0.1524)
				)
				(justify mirror)
			)
		)
		(property "Device Type" "R402H16"
			(at -0.064008 -5.517896 90)
			(unlocked yes)
			(layer "B.Fab")
			(hide yes)
			(effects
				(font
					(size 1.016 1.016)
					(thickness 0.1524)
				)
				(justify mirror)
			)
		)
		(duplicate_pad_numbers_are_jumpers no)
		(fp_line
			(start 0.508 -0.9398)
			(end 0.508 0.9398)
			(stroke
				(width 0.1524)
				(type default)
			)
			(layer "B.SilkS")
		)
		(fp_line
			(start -0.508 -0.9398)
			(end 0.508 -0.9398)
			(stroke
				(width 0.1524)
				(type default)
			)
			(layer "B.SilkS")
		)
		(fp_rect
			(start 0.508 0.9398)
			(end -0.508 -0.9398)
			(stroke
				(width 0)
				(type default)
			)
			(fill no)
			(layer "B.CrtYd")
		)
		(fp_rect
			(start 0.508 0.9398)
			(end -0.508 -0.9398)
			(stroke
				(width 0)
				(type default)
			)
			(fill no)
			(layer "B.Fab")
		)
		(pad "1" smd custom
			(at 0 -0.4445 270)
			(size 0.1397 0.1397)
			(layers "B.Cu" "B.Mask" "B.Paste")
			(net "P5V_D_LL")
			(options
				(clearance outline)
				(anchor circle)
			)
			(primitives
				(gr_poly
					(pts
						(arc
							(start -0.1778 0.2794)
							(mid -0.249642 0.249642)
							(end -0.2794 0.1778)
						)
						(arc
							(start -0.2794 -0.1778)
							(mid -0.249642 -0.249642)
							(end -0.1778 -0.2794)
						)
						(arc
							(start 0.1778 -0.2794)
							(mid 0.249642 -0.249642)
							(end 0.2794 -0.1778)
						)
						(arc
							(start 0.2794 0.1778)
							(mid 0.249642 0.249642)
							(end 0.1778 0.2794)
						)
					)
					(width 0)
					(fill yes)
				)
			)
		)
		(pad "2" smd custom
			(at 0 0.4445 270)
			(size 0.1397 0.1397)
			(layers "B.Cu" "B.Mask" "B.Paste")
			(net "P5V_D_LL_R")
			(options
				(clearance outline)
				(anchor circle)
			)
			(primitives
				(gr_poly
					(pts
						(arc
							(start -0.1778 0.2794)
							(mid -0.249642 0.249642)
							(end -0.2794 0.1778)
						)
						(arc
							(start -0.2794 -0.1778)
							(mid -0.249642 -0.249642)
							(end -0.1778 -0.2794)
						)
						(arc
							(start 0.1778 -0.2794)
							(mid 0.249642 -0.249642)
							(end 0.2794 -0.1778)
						)
						(arc
							(start 0.2794 0.1778)
							(mid 0.249642 0.249642)
							(end 0.1778 0.2794)
						)
					)
					(width 0)
					(fill yes)
				)
			)
		)
	)
	(footprint ""
		(layer "B.Cu")
		(at 189.377828 -238.277908 90)
		(property "Reference" "C682"
			(at 0 0 90)
			(layer "B.SilkS")
			(hide yes)
			(effects
				(font
					(size 1.27 1.27)
				)
				(justify mirror)
			)
		)
		(property "Value" "SC10U6D3V5KX-4GP"
			(at 0.0762 -6.1214 90)
			(unlocked yes)
			(layer "B.Fab")
			(hide yes)
			(effects
				(font
					(size 1.016 1.016)
					(thickness 0.1524)
				)
				(justify mirror)
			)
		)
		(property "Device Type" "C805H58"
			(at 0.0762 -8.1534 90)
			(unlocked yes)
			(layer "B.Fab")
			(hide yes)
			(effects
				(font
					(size 1.016 1.016)
					(thickness 0.1524)
				)
				(justify mirror)
			)
		)
		(duplicate_pad_numbers_are_jumpers no)
		(fp_line
			(start -0.635 0)
			(end 0.635 0)
			(stroke
				(width 0.508)
				(type default)
			)
			(layer "B.SilkS")
		)
		(fp_rect
			(start 0.9652 1.778)
			(end -0.9652 -1.778)
			(stroke
				(width 0)
				(type default)
			)
			(fill no)
			(layer "B.CrtYd")
		)
		(fp_poly
			(pts
				(xy 0.9652 -1.778) (xy -0.9652 -1.778) (xy -0.9652 1.778) (xy 0.9652 1.778)
			)
			(stroke
				(width 0)
				(type default)
			)
			(fill no)
			(layer "B.Fab")
		)
		(pad "1" smd rect
			(at 0 -0.9652 270)
			(size 1.397 1.143)
			(layers "B.Cu" "B.Mask" "B.Paste")
			(net "P3V3_STBY_A")
		)
		(pad "2" smd rect
			(at 0 0.9652 270)
			(size 1.397 1.143)
			(layers "B.Cu" "B.Mask" "B.Paste")
			(net "GND")
		)
	)
	(footprint ""
		(layer "B.Cu")
		(at 469.646 -230.505 -90)
		(property "Reference" "C657"
			(at 0 0 90)
			(layer "B.SilkS")
			(hide yes)
			(effects
				(font
					(size 1.27 1.27)
				)
				(justify mirror)
			)
		)
		(property "Value" "SC2200P50V2KX-2GP"
			(at -1.1811 -2.7051 270)
			(unlocked yes)
			(layer "B.Fab")
			(hide yes)
			(effects
				(font
					(size 1.016 1.016)
					(thickness 0.1524)
				)
				(justify mirror)
			)
		)
		(property "Device Type" "C402H22"
			(at -1.1811 -4.2291 270)
			(unlocked yes)
			(layer "B.Fab")
			(hide yes)
			(effects
				(font
					(size 1.016 1.016)
					(thickness 0.1524)
				)
				(justify mirror)
			)
		)
		(duplicate_pad_numbers_are_jumpers no)
		(fp_rect
			(start 0.4318 0.9525)
			(end -0.4318 -0.9525)
			(stroke
				(width 0)
				(type default)
			)
			(fill no)
			(layer "B.CrtYd")
		)
		(fp_rect
			(start 0.4318 0.9525)
			(end -0.4318 -0.9525)
			(stroke
				(width 0)
				(type default)
			)
			(fill no)
			(layer "B.Fab")
		)
		(pad "1" smd custom
			(at 0 -0.4445 90)
			(size 0.1524 0.1524)
			(layers "B.Cu" "B.Mask" "B.Paste")
			(net "P5V_D_LL")
			(options
				(clearance outline)
				(anchor circle)
			)
			(primitives
				(gr_poly
					(pts
						(arc
							(start 0.3048 0.2032)
							(mid 0.275042 0.275042)
							(end 0.2032 0.3048)
						)
						(arc
							(start -0.2032 0.3048)
							(mid -0.275042 0.275042)
							(end -0.3048 0.2032)
						)
						(arc
							(start -0.3048 -0.2032)
							(mid -0.275042 -0.275042)
							(end -0.2032 -0.3048)
						)
						(arc
							(start 0.2032 -0.3048)
							(mid 0.275042 -0.275042)
							(end 0.3048 -0.2032)
						)
					)
					(width 0)
					(fill yes)
				)
			)
		)
		(pad "2" smd custom
			(at 0 0.4445 90)
			(size 0.1524 0.1524)
			(layers "B.Cu" "B.Mask" "B.Paste")
			(net "P5V_D_SNB")
			(options
				(clearance outline)
				(anchor circle)
			)
			(primitives
				(gr_poly
					(pts
						(arc
							(start 0.3048 0.2032)
							(mid 0.275042 0.275042)
							(end 0.2032 0.3048)
						)
						(arc
							(start -0.2032 0.3048)
							(mid -0.275042 0.275042)
							(end -0.3048 0.2032)
						)
						(arc
							(start -0.3048 -0.2032)
							(mid -0.275042 -0.275042)
							(end -0.2032 -0.3048)
						)
						(arc
							(start 0.2032 -0.3048)
							(mid 0.275042 -0.275042)
							(end 0.3048 -0.2032)
						)
					)
					(width 0)
					(fill yes)
				)
			)
		)
	)
	(footprint ""
		(layer "B.Cu")
		(at 39.0652 -142.1384 180)
		(property "Reference" "C616"
			(at 0 0 0)
			(layer "B.SilkS")
			(hide yes)
			(effects
				(font
					(size 1.27 1.27)
				)
				(justify mirror)
			)
		)
		(property "Value" "SC10U16V5KX-7-GP-U"
			(at 0.0762 -6.1214 180)
			(unlocked yes)
			(layer "B.Fab")
			(hide yes)
			(effects
				(font
					(size 1.016 1.016)
					(thickness 0.1524)
				)
				(justify mirror)
			)
		)
		(property "Device Type" "C805H58"
			(at 0.0762 -8.1534 180)
			(unlocked yes)
			(layer "B.Fab")
			(hide yes)
			(effects
				(font
					(size 1.016 1.016)
					(thickness 0.1524)
				)
				(justify mirror)
			)
		)
		(duplicate_pad_numbers_are_jumpers no)
		(fp_line
			(start -0.635 0)
			(end 0.635 0)
			(stroke
				(width 0.508)
				(type default)
			)
			(layer "B.SilkS")
		)
		(fp_rect
			(start 0.9652 1.778)
			(end -0.9652 -1.778)
			(stroke
				(width 0)
				(type default)
			)
			(fill no)
			(layer "B.CrtYd")
		)
		(fp_poly
			(pts
				(xy 0.9652 -1.778) (xy -0.9652 -1.778) (xy -0.9652 1.778) (xy 0.9652 1.778)
			)
			(stroke
				(width 0)
				(type default)
			)
			(fill no)
			(layer "B.Fab")
		)
		(pad "1" smd rect
			(at 0 -0.9652)
			(size 1.397 1.143)
			(layers "B.Cu" "B.Mask" "B.Paste")
			(net "P12V_A_VIN_U21")
		)
		(pad "2" smd rect
			(at 0 0.9652)
			(size 1.397 1.143)
			(layers "B.Cu" "B.Mask" "B.Paste")
			(net "GND")
		)
	)
	(footprint ""
		(layer "B.Cu")
		(at 439.846974 -256.172716 -90)
		(property "Reference" "C639"
			(at 0 0 90)
			(layer "B.SilkS")
			(hide yes)
			(effects
				(font
					(size 1.27 1.27)
				)
				(justify mirror)
			)
		)
		(property "Value" "SC4D7U25V5KX-GP"
			(at 0.0762 -6.1214 270)
			(unlocked yes)
			(layer "B.Fab")
			(hide yes)
			(effects
				(font
					(size 1.016 1.016)
					(thickness 0.1524)
				)
				(justify mirror)
			)
		)
		(property "Device Type" "C805H54"
			(at 0.0762 -8.1534 270)
			(unlocked yes)
			(layer "B.Fab")
			(hide yes)
			(effects
				(font
					(size 1.016 1.016)
					(thickness 0.1524)
				)
				(justify mirror)
			)
		)
		(duplicate_pad_numbers_are_jumpers no)
		(fp_line
			(start -0.635 0)
			(end 0.635 0)
			(stroke
				(width 0.508)
				(type default)
			)
			(layer "B.SilkS")
		)
		(fp_rect
			(start 0.9652 1.778)
			(end -0.9652 -1.778)
			(stroke
				(width 0)
				(type default)
			)
			(fill no)
			(layer "B.CrtYd")
		)
		(fp_poly
			(pts
				(xy 0.9652 -1.778) (xy -0.9652 -1.778) (xy -0.9652 1.778) (xy 0.9652 1.778)
			)
			(stroke
				(width 0)
				(type default)
			)
			(fill no)
			(layer "B.Fab")
		)
		(pad "1" smd rect
			(at 0 -0.9652 90)
			(size 1.397 1.143)
			(layers "B.Cu" "B.Mask" "B.Paste")
			(net "P12V_A_VDD_U22")
		)
		(pad "2" smd rect
			(at 0 0.9652 90)
			(size 1.397 1.143)
			(layers "B.Cu" "B.Mask" "B.Paste")
			(net "GND")
		)
	)
	(footprint ""
		(layer "B.Cu")
		(at 222.1992 -118.2878)
		(property "Reference" "C3"
			(at 0 0 0)
			(layer "B.SilkS")
			(hide yes)
			(effects
				(font
					(size 1.27 1.27)
				)
				(justify mirror)
			)
		)
		(property "Value" "SCD1U16V2KX-3GP"
			(at -1.1811 -2.7051 0)
			(unlocked yes)
			(layer "B.Fab")
			(hide yes)
			(effects
				(font
					(size 1.016 1.016)
					(thickness 0.1524)
				)
				(justify mirror)
			)
		)
		(property "Device Type" "C402H22"
			(at -1.1811 -4.2291 0)
			(unlocked yes)
			(layer "B.Fab")
			(hide yes)
			(effects
				(font
					(size 1.016 1.016)
					(thickness 0.1524)
				)
				(justify mirror)
			)
		)
		(duplicate_pad_numbers_are_jumpers no)
		(fp_rect
			(start 0.4318 0.9525)
			(end -0.4318 -0.9525)
			(stroke
				(width 0)
				(type default)
			)
			(fill no)
			(layer "B.CrtYd")
		)
		(fp_rect
			(start 0.4318 0.9525)
			(end -0.4318 -0.9525)
			(stroke
				(width 0)
				(type default)
			)
			(fill no)
			(layer "B.Fab")
		)
		(pad "1" smd custom
			(at 0 -0.4445 180)
			(size 0.1524 0.1524)
			(layers "B.Cu" "B.Mask" "B.Paste")
			(net "P3V3_STBY_A")
			(options
				(clearance outline)
				(anchor circle)
			)
			(primitives
				(gr_poly
					(pts
						(arc
							(start 0.3048 0.2032)
							(mid 0.275042 0.275042)
							(end 0.2032 0.3048)
						)
						(arc
							(start -0.2032 0.3048)
							(mid -0.275042 0.275042)
							(end -0.3048 0.2032)
						)
						(arc
							(start -0.3048 -0.2032)
							(mid -0.275042 -0.275042)
							(end -0.2032 -0.3048)
						)
						(arc
							(start 0.2032 -0.3048)
							(mid 0.275042 -0.275042)
							(end 0.3048 -0.2032)
						)
					)
					(width 0)
					(fill yes)
				)
			)
		)
		(pad "2" smd custom
			(at 0 0.4445 180)
			(size 0.1524 0.1524)
			(layers "B.Cu" "B.Mask" "B.Paste")
			(net "GND")
			(options
				(clearance outline)
				(anchor circle)
			)
			(primitives
				(gr_poly
					(pts
						(arc
							(start 0.3048 0.2032)
							(mid 0.275042 0.275042)
							(end 0.2032 0.3048)
						)
						(arc
							(start -0.2032 0.3048)
							(mid -0.275042 0.275042)
							(end -0.3048 0.2032)
						)
						(arc
							(start -0.3048 -0.2032)
							(mid -0.275042 -0.275042)
							(end -0.2032 -0.3048)
						)
						(arc
							(start 0.2032 -0.3048)
							(mid 0.275042 -0.275042)
							(end 0.3048 -0.2032)
						)
					)
					(width 0)
					(fill yes)
				)
			)
		)
	)
	(footprint ""
		(layer "B.Cu")
		(at 482.219 -233.934 90)
		(property "Reference" "R1276"
			(at 0 0 90)
			(layer "B.SilkS")
			(hide yes)
			(effects
				(font
					(size 1.27 1.27)
				)
				(justify mirror)
			)
		)
		(property "Value" "309KR2F-GP"
			(at -0.064008 -3.993896 90)
			(unlocked yes)
			(layer "B.Fab")
			(hide yes)
			(effects
				(font
					(size 1.016 1.016)
					(thickness 0.1524)
				)
				(justify mirror)
			)
		)
		(property "Device Type" "R402H16"
			(at -0.064008 -5.517896 90)
			(unlocked yes)
			(layer "B.Fab")
			(hide yes)
			(effects
				(font
					(size 1.016 1.016)
					(thickness 0.1524)
				)
				(justify mirror)
			)
		)
		(duplicate_pad_numbers_are_jumpers no)
		(fp_line
			(start 0.508 -0.9398)
			(end 0.508 0.9398)
			(stroke
				(width 0.1524)
				(type default)
			)
			(layer "B.SilkS")
		)
		(fp_line
			(start -0.508 -0.9398)
			(end 0.508 -0.9398)
			(stroke
				(width 0.1524)
				(type default)
			)
			(layer "B.SilkS")
		)
		(fp_rect
			(start 0.508 0.9398)
			(end -0.508 -0.9398)
			(stroke
				(width 0)
				(type default)
			)
			(fill no)
			(layer "B.CrtYd")
		)
		(fp_rect
			(start 0.508 0.9398)
			(end -0.508 -0.9398)
			(stroke
				(width 0)
				(type default)
			)
			(fill no)
			(layer "B.Fab")
		)
		(pad "1" smd custom
			(at 0 -0.4445 270)
			(size 0.1397 0.1397)
			(layers "B.Cu" "B.Mask" "B.Paste")
			(net "P5V_D_RF")
			(options
				(clearance outline)
				(anchor circle)
			)
			(primitives
				(gr_poly
					(pts
						(arc
							(start -0.1778 0.2794)
							(mid -0.249642 0.249642)
							(end -0.2794 0.1778)
						)
						(arc
							(start -0.2794 -0.1778)
							(mid -0.249642 -0.249642)
							(end -0.1778 -0.2794)
						)
						(arc
							(start 0.1778 -0.2794)
							(mid 0.249642 -0.249642)
							(end 0.2794 -0.1778)
						)
						(arc
							(start 0.2794 0.1778)
							(mid 0.249642 0.249642)
							(end 0.1778 0.2794)
						)
					)
					(width 0)
					(fill yes)
				)
			)
		)
		(pad "2" smd custom
			(at 0 0.4445 270)
			(size 0.1397 0.1397)
			(layers "B.Cu" "B.Mask" "B.Paste")
			(net "P5V_D_VREG")
			(options
				(clearance outline)
				(anchor circle)
			)
			(primitives
				(gr_poly
					(pts
						(arc
							(start -0.1778 0.2794)
							(mid -0.249642 0.249642)
							(end -0.2794 0.1778)
						)
						(arc
							(start -0.2794 -0.1778)
							(mid -0.249642 -0.249642)
							(end -0.1778 -0.2794)
						)
						(arc
							(start 0.1778 -0.2794)
							(mid 0.249642 -0.249642)
							(end 0.2794 -0.1778)
						)
						(arc
							(start 0.2794 0.1778)
							(mid 0.249642 0.249642)
							(end 0.1778 0.2794)
						)
					)
					(width 0)
					(fill yes)
				)
			)
		)
	)
	(footprint ""
		(layer "B.Cu")
		(at 65.5574 -149.3012 180)
		(property "Reference" "TC6"
			(at 0 0 0)
			(layer "B.SilkS")
			(hide yes)
			(effects
				(font
					(size 1.27 1.27)
				)
				(justify mirror)
			)
		)
		(property "Value" "ST220U10VDM-LGP"
			(at 0 -9.6012 180)
			(unlocked yes)
			(layer "B.Fab")
			(hide yes)
			(effects
				(font
					(size 1.016 1.016)
					(thickness 0.1524)
				)
				(justify mirror)
			)
		)
		(property "Device Type" "CT7343H119"
			(at 0 -11.1252 180)
			(unlocked yes)
			(layer "B.Fab")
			(hide yes)
			(effects
				(font
					(size 1.016 1.016)
					(thickness 0.1524)
				)
				(justify mirror)
			)
		)
		(duplicate_pad_numbers_are_jumpers no)
		(fp_line
			(start 2.286 4.8768)
			(end 2.286 2.032)
			(stroke
				(width 0.1524)
				(type default)
			)
			(layer "B.SilkS")
		)
		(fp_line
			(start 2.286 -4.8768)
			(end 2.286 -2.032)
			(stroke
				(width 0.1524)
				(type default)
			)
			(layer "B.SilkS")
		)
		(fp_line
			(start -2.1082 -4.699)
			(end 2.1082 -4.699)
			(stroke
				(width 0.508)
				(type default)
			)
			(layer "B.SilkS")
		)
		(fp_line
			(start -2.286 4.8768)
			(end 2.286 4.8768)
			(stroke
				(width 0.1524)
				(type default)
			)
			(layer "B.SilkS")
		)
		(fp_line
			(start -2.286 2.032)
			(end -2.286 4.8768)
			(stroke
				(width 0.1524)
				(type default)
			)
			(layer "B.SilkS")
		)
		(fp_line
			(start -2.286 -2.032)
			(end -2.286 -4.8768)
			(stroke
				(width 0.1524)
				(type default)
			)
			(layer "B.SilkS")
		)
		(fp_line
			(start -2.286 -4.8768)
			(end 2.286 -4.8768)
			(stroke
				(width 0.1524)
				(type default)
			)
			(layer "B.SilkS")
		)
		(fp_rect
			(start 2.1463 3.6449)
			(end -2.1463 -3.6449)
			(stroke
				(width 0)
				(type default)
			)
			(fill no)
			(layer "B.CrtYd")
		)
		(fp_poly
			(pts
				(xy 2.54 4.953) (xy 2.54 4.2926) (xy 3.81 4.2926) (xy 3.81 -4.2926) (xy 2.54 -4.2926) (xy 2.54 -4.953)
				(xy -2.54 -4.953) (xy -2.54 -4.2926) (xy -3.81 -4.2926) (xy -3.81 -1.6256) (xy -2.1463 -1.6256)
				(xy -2.1463 -3.6449) (xy 2.1463 -3.6449) (xy 2.1463 3.6449) (xy -2.1463 3.6449) (xy -2.1463 -1.6129)
				(xy -3.81 -1.6129) (xy -3.81 4.2926) (xy -2.54 4.2926) (xy -2.54 4.953)
			)
			(stroke
				(width 0)
				(type default)
			)
			(fill no)
			(layer "B.CrtYd")
		)
		(fp_rect
			(start 3.81 4.2926)
			(end 2.54 -4.2926)
			(stroke
				(width 0)
				(type default)
			)
			(fill no)
			(layer "B.Fab")
		)
		(fp_rect
			(start 2.54 4.953)
			(end -2.54 -4.953)
			(stroke
				(width 0)
				(type default)
			)
			(fill no)
			(layer "B.Fab")
		)
		(fp_rect
			(start -2.54 4.2926)
			(end -3.81 -4.2926)
			(stroke
				(width 0)
				(type default)
			)
			(fill no)
			(layer "B.Fab")
		)
		(pad "1" smd rect
			(at 0 -3.1496)
			(size 2.413 2.286)
			(layers "B.Cu" "B.Mask" "B.Paste")
			(net "P5V_A_2")
		)
		(pad "2" smd rect
			(at 0 3.1496)
			(size 2.413 2.286)
			(layers "B.Cu" "B.Mask" "B.Paste")
			(net "GND")
		)
		(zone
			(layer "B.Cu")
			(hatch none 0.5)
			(connect_pads
				(clearance 0)
			)
			(min_thickness 0.25)
			(keepout
				(tracks allowed)
				(vias not_allowed)
				(pads allowed)
				(copperpour not_allowed)
				(footprints allowed)
			)
			(placement
				(enabled no)
				(sheetname "")
			)
			(fill
				(thermal_gap 0.5)
				(thermal_bridge_width 0.5)
				(island_removal_mode 0)
			)
			(polygon
				(pts
					(xy 64.0461 -153.8986) (xy 67.0687 -153.8986) (xy 67.0687 -151.003) (xy 67.0687 -150.6728) (xy 64.0461 -150.6728)
					(xy 64.0461 -151.003)
				)
			)
		)
		(zone
			(layer "B.Cu")
			(hatch none 0.5)
			(connect_pads
				(clearance 0)
			)
			(min_thickness 0.25)
			(keepout
				(tracks allowed)
				(vias not_allowed)
				(pads allowed)
				(copperpour not_allowed)
				(footprints allowed)
			)
			(placement
				(enabled no)
				(sheetname "")
			)
			(fill
				(thermal_gap 0.5)
				(thermal_bridge_width 0.5)
				(island_removal_mode 0)
			)
			(polygon
				(pts
					(xy 67.0687 -147.6121) (xy 67.0687 -144.7038) (xy 64.0461 -144.7038) (xy 64.0461 -147.5994) (xy 64.0461 -147.9296)
					(xy 67.0687 -147.9296)
				)
			)
		)
	)
	(footprint ""
		(layer "B.Cu")
		(at 479.933 -230.505)
		(property "Reference" "R1274"
			(at 0 0 0)
			(layer "B.SilkS")
			(hide yes)
			(effects
				(font
					(size 1.27 1.27)
				)
				(justify mirror)
			)
		)
		(property "Value" "71K5R2F-GP"
			(at -0.064008 -3.993896 0)
			(unlocked yes)
			(layer "B.Fab")
			(hide yes)
			(effects
				(font
					(size 1.016 1.016)
					(thickness 0.1524)
				)
				(justify mirror)
			)
		)
		(property "Device Type" "R402H16"
			(at -0.064008 -5.517896 0)
			(unlocked yes)
			(layer "B.Fab")
			(hide yes)
			(effects
				(font
					(size 1.016 1.016)
					(thickness 0.1524)
				)
				(justify mirror)
			)
		)
		(duplicate_pad_numbers_are_jumpers no)
		(fp_line
			(start -0.508 -0.9398)
			(end 0.508 -0.9398)
			(stroke
				(width 0.1524)
				(type default)
			)
			(layer "B.SilkS")
		)
		(fp_line
			(start 0.508 -0.9398)
			(end 0.508 0.9398)
			(stroke
				(width 0.1524)
				(type default)
			)
			(layer "B.SilkS")
		)
		(fp_rect
			(start 0.508 0.9398)
			(end -0.508 -0.9398)
			(stroke
				(width 0)
				(type default)
			)
			(fill no)
			(layer "B.CrtYd")
		)
		(fp_rect
			(start 0.508 0.9398)
			(end -0.508 -0.9398)
			(stroke
				(width 0)
				(type default)
			)
			(fill no)
			(layer "B.Fab")
		)
		(pad "1" smd custom
			(at 0 -0.4445 180)
			(size 0.1397 0.1397)
			(layers "B.Cu" "B.Mask" "B.Paste")
			(net "P5V_D_VFB")
			(options
				(clearance outline)
				(anchor circle)
			)
			(primitives
				(gr_poly
					(pts
						(arc
							(start -0.1778 0.2794)
							(mid -0.249642 0.249642)
							(end -0.2794 0.1778)
						)
						(arc
							(start -0.2794 -0.1778)
							(mid -0.249642 -0.249642)
							(end -0.1778 -0.2794)
						)
						(arc
							(start 0.1778 -0.2794)
							(mid 0.249642 -0.249642)
							(end 0.2794 -0.1778)
						)
						(arc
							(start 0.2794 0.1778)
							(mid 0.249642 0.249642)
							(end 0.1778 0.2794)
						)
					)
					(width 0)
					(fill yes)
				)
			)
		)
		(pad "2" smd custom
			(at 0 0.4445 180)
			(size 0.1397 0.1397)
			(layers "B.Cu" "B.Mask" "B.Paste")
			(net "P5V_D_VFB_R")
			(options
				(clearance outline)
				(anchor circle)
			)
			(primitives
				(gr_poly
					(pts
						(arc
							(start -0.1778 0.2794)
							(mid -0.249642 0.249642)
							(end -0.2794 0.1778)
						)
						(arc
							(start -0.2794 -0.1778)
							(mid -0.249642 -0.249642)
							(end -0.1778 -0.2794)
						)
						(arc
							(start 0.1778 -0.2794)
							(mid 0.249642 -0.249642)
							(end 0.2794 -0.1778)
						)
						(arc
							(start 0.2794 0.1778)
							(mid 0.249642 0.249642)
							(end 0.1778 0.2794)
						)
					)
					(width 0)
					(fill yes)
				)
			)
		)
	)
	(footprint ""
		(layer "B.Cu")
		(at 269.534132 -100.221796 -90)
		(property "Reference" "C39"
			(at 0 0 90)
			(layer "B.SilkS")
			(hide yes)
			(effects
				(font
					(size 1.27 1.27)
				)
				(justify mirror)
			)
		)
		(property "Value" "SC2D2U25V5KX-2-GP"
			(at 0.0762 -6.1214 270)
			(unlocked yes)
			(layer "B.Fab")
			(hide yes)
			(effects
				(font
					(size 1.016 1.016)
					(thickness 0.1524)
				)
				(justify mirror)
			)
		)
		(property "Device Type" "C805H54"
			(at 0.0762 -8.1534 270)
			(unlocked yes)
			(layer "B.Fab")
			(hide yes)
			(effects
				(font
					(size 1.016 1.016)
					(thickness 0.1524)
				)
				(justify mirror)
			)
		)
		(duplicate_pad_numbers_are_jumpers no)
		(fp_line
			(start -0.635 0)
			(end 0.635 0)
			(stroke
				(width 0.508)
				(type default)
			)
			(layer "B.SilkS")
		)
		(fp_rect
			(start 0.9652 1.778)
			(end -0.9652 -1.778)
			(stroke
				(width 0)
				(type default)
			)
			(fill no)
			(layer "B.CrtYd")
		)
		(fp_poly
			(pts
				(xy 0.9652 -1.778) (xy -0.9652 -1.778) (xy -0.9652 1.778) (xy 0.9652 1.778)
			)
			(stroke
				(width 0)
				(type default)
			)
			(fill no)
			(layer "B.Fab")
		)
		(pad "1" smd rect
			(at 0 -0.9652 90)
			(size 1.397 1.143)
			(layers "B.Cu" "B.Mask" "B.Paste")
			(net "P12V_B_COMP")
		)
		(pad "2" smd rect
			(at 0 0.9652 90)
			(size 1.397 1.143)
			(layers "B.Cu" "B.Mask" "B.Paste")
			(net "GND")
		)
	)
	(footprint ""
		(layer "B.Cu")
		(at 348.742 -151.4856 90)
		(property "Reference" "D38"
			(at 0 0 90)
			(layer "B.SilkS")
			(hide yes)
			(effects
				(font
					(size 1.27 1.27)
				)
				(justify mirror)
			)
		)
		(property "Value" "SMCJ14A-13-F-GP"
			(at 4.445 1.1684 90)
			(unlocked yes)
			(layer "B.Fab")
			(hide yes)
			(effects
				(font
					(size 1.016 1.016)
					(thickness 0.1524)
				)
				(justify mirror)
			)
		)
		(property "Device Type" "D795930AKH104"
			(at 4.445 -0.3556 90)
			(unlocked yes)
			(layer "B.Fab")
			(hide yes)
			(effects
				(font
					(size 1.016 1.016)
					(thickness 0.1524)
				)
				(justify mirror)
			)
		)
		(duplicate_pad_numbers_are_jumpers no)
		(fp_line
			(start 3.2004 -4.8641)
			(end 3.2004 4.8641)
			(stroke
				(width 0.1524)
				(type default)
			)
			(layer "B.SilkS")
		)
		(fp_line
			(start -3.2004 -4.8641)
			(end 3.2004 -4.8641)
			(stroke
				(width 0.1524)
				(type default)
			)
			(layer "B.SilkS")
		)
		(fp_line
			(start 3.2004 4.8641)
			(end -3.2004 4.8641)
			(stroke
				(width 0.1524)
				(type default)
			)
			(layer "B.SilkS")
		)
		(fp_line
			(start -3.2004 4.8641)
			(end -3.2004 -4.8641)
			(stroke
				(width 0.1524)
				(type default)
			)
			(layer "B.SilkS")
		)
		(fp_line
			(start -3.2004 5.0419)
			(end 3.2004 5.0419)
			(stroke
				(width 0.508)
				(type default)
			)
			(layer "B.SilkS")
		)
		(fp_poly
			(pts
				(xy 2.9464 3.429) (xy 1.4859 3.429) (xy 1.4859 3.9751) (xy -1.4859 3.9751) (xy -1.4859 3.429) (xy -2.9464 3.429)
				(xy -2.9464 -3.429) (xy -1.4859 -3.429) (xy -1.4859 -3.9751) (xy 1.4859 -3.9751) (xy 1.4859 -3.429)
				(xy 2.9464 -3.429)
			)
			(stroke
				(width 0)
				(type default)
			)
			(fill no)
			(layer "B.CrtYd")
		)
		(fp_poly
			(pts
				(xy 3.4544 4.9403) (xy 3.4544 -4.9403) (xy -3.4544 -4.9403) (xy -3.4544 -3.429) (xy -1.4859 -3.429)
				(xy -1.4859 -3.9751) (xy 1.4859 -3.9751) (xy 1.4859 -3.429) (xy 2.9464 -3.429) (xy 2.9464 3.429)
				(xy 1.4859 3.429) (xy 1.4859 3.9751) (xy -1.4859 3.9751) (xy -1.4859 3.429) (xy -2.9464 3.429) (xy -2.9464 -3.4163)
				(xy -3.4544 -3.4163) (xy -3.4544 4.9403)
			)
			(stroke
				(width 0)
				(type default)
			)
			(fill no)
			(layer "B.CrtYd")
		)
		(fp_rect
			(start 3.4544 4.9403)
			(end -3.4544 -4.9403)
			(stroke
				(width 0)
				(type default)
			)
			(fill no)
			(layer "B.Fab")
		)
		(pad "A" smd rect
			(at 0 -3.592068 270)
			(size 3.2258 2.032)
			(layers "B.Cu" "B.Mask" "B.Paste")
			(net "GND")
		)
		(pad "K" smd rect
			(at 0 3.592068 270)
			(size 3.2258 2.032)
			(layers "B.Cu" "B.Mask" "B.Paste")
			(net "P12V_B")
		)
	)
	(footprint ""
		(layer "B.Cu")
		(at 474.091 -237.871 90)
		(property "Reference" "C651"
			(at 0 0 90)
			(layer "B.SilkS")
			(hide yes)
			(effects
				(font
					(size 1.27 1.27)
				)
				(justify mirror)
			)
		)
		(property "Value" "SCD1U16V2KX-3GP"
			(at -1.1811 -2.7051 90)
			(unlocked yes)
			(layer "B.Fab")
			(hide yes)
			(effects
				(font
					(size 1.016 1.016)
					(thickness 0.1524)
				)
				(justify mirror)
			)
		)
		(property "Device Type" "C402H22"
			(at -1.1811 -4.2291 90)
			(unlocked yes)
			(layer "B.Fab")
			(hide yes)
			(effects
				(font
					(size 1.016 1.016)
					(thickness 0.1524)
				)
				(justify mirror)
			)
		)
		(duplicate_pad_numbers_are_jumpers no)
		(fp_rect
			(start 0.4318 0.9525)
			(end -0.4318 -0.9525)
			(stroke
				(width 0)
				(type default)
			)
			(fill no)
			(layer "B.CrtYd")
		)
		(fp_rect
			(start 0.4318 0.9525)
			(end -0.4318 -0.9525)
			(stroke
				(width 0)
				(type default)
			)
			(fill no)
			(layer "B.Fab")
		)
		(pad "1" smd custom
			(at 0 -0.4445 270)
			(size 0.1524 0.1524)
			(layers "B.Cu" "B.Mask" "B.Paste")
			(net "P12V_A_VIN_U27")
			(options
				(clearance outline)
				(anchor circle)
			)
			(primitives
				(gr_poly
					(pts
						(arc
							(start 0.3048 0.2032)
							(mid 0.275042 0.275042)
							(end 0.2032 0.3048)
						)
						(arc
							(start -0.2032 0.3048)
							(mid -0.275042 0.275042)
							(end -0.3048 0.2032)
						)
						(arc
							(start -0.3048 -0.2032)
							(mid -0.275042 -0.275042)
							(end -0.2032 -0.3048)
						)
						(arc
							(start 0.2032 -0.3048)
							(mid 0.275042 -0.275042)
							(end 0.3048 -0.2032)
						)
					)
					(width 0)
					(fill yes)
				)
			)
		)
		(pad "2" smd custom
			(at 0 0.4445 270)
			(size 0.1524 0.1524)
			(layers "B.Cu" "B.Mask" "B.Paste")
			(net "GND")
			(options
				(clearance outline)
				(anchor circle)
			)
			(primitives
				(gr_poly
					(pts
						(arc
							(start 0.3048 0.2032)
							(mid 0.275042 0.275042)
							(end 0.2032 0.3048)
						)
						(arc
							(start -0.2032 0.3048)
							(mid -0.275042 0.275042)
							(end -0.3048 0.2032)
						)
						(arc
							(start -0.3048 -0.2032)
							(mid -0.275042 -0.275042)
							(end -0.2032 -0.3048)
						)
						(arc
							(start 0.2032 -0.3048)
							(mid 0.275042 -0.275042)
							(end 0.3048 -0.2032)
						)
					)
					(width 0)
					(fill yes)
				)
			)
		)
	)
	(footprint ""
		(layer "B.Cu")
		(at 23.772622 -249.22353 90)
		(property "Reference" "C606"
			(at 0 0 90)
			(layer "B.SilkS")
			(hide yes)
			(effects
				(font
					(size 1.27 1.27)
				)
				(justify mirror)
			)
		)
		(property "Value" "SC1U16V3KX-5GP"
			(at 0 -2.8194 90)
			(unlocked yes)
			(layer "B.Fab")
			(hide yes)
			(effects
				(font
					(size 1.016 1.016)
					(thickness 0.1524)
				)
				(justify mirror)
			)
		)
		(property "Device Type" "C603H36"
			(at 0 -4.3434 90)
			(unlocked yes)
			(layer "B.Fab")
			(hide yes)
			(effects
				(font
					(size 1.016 1.016)
					(thickness 0.1524)
				)
				(justify mirror)
			)
		)
		(duplicate_pad_numbers_are_jumpers no)
		(fp_line
			(start -0.508 0)
			(end 0.508 0)
			(stroke
				(width 0.2032)
				(type default)
			)
			(layer "B.SilkS")
		)
		(fp_rect
			(start 0.5842 1.3335)
			(end -0.5842 -1.3335)
			(stroke
				(width 0)
				(type default)
			)
			(fill no)
			(layer "B.CrtYd")
		)
		(fp_rect
			(start 0.5842 1.3335)
			(end -0.5842 -1.3335)
			(stroke
				(width 0)
				(type default)
			)
			(fill no)
			(layer "B.Fab")
		)
		(pad "1" smd custom
			(at 0 -0.762 270)
			(size 0.2159 0.2159)
			(layers "B.Cu" "B.Mask" "B.Paste")
			(net "GND")
			(options
				(clearance outline)
				(anchor circle)
			)
			(primitives
				(gr_poly
					(pts
						(arc
							(start -0.3302 0.4318)
							(mid -0.402042 0.402042)
							(end -0.4318 0.3302)
						)
						(arc
							(start -0.4318 -0.3302)
							(mid -0.402042 -0.402042)
							(end -0.3302 -0.4318)
						)
						(arc
							(start 0.3302 -0.4318)
							(mid 0.402042 -0.402042)
							(end 0.4318 -0.3302)
						)
						(arc
							(start 0.4318 0.3302)
							(mid 0.402042 0.402042)
							(end 0.3302 0.4318)
						)
					)
					(width 0)
					(fill yes)
				)
			)
		)
		(pad "2" smd custom
			(at 0 0.762 270)
			(size 0.2159 0.2159)
			(layers "B.Cu" "B.Mask" "B.Paste")
			(net "P5V_A_VREG")
			(options
				(clearance outline)
				(anchor circle)
			)
			(primitives
				(gr_poly
					(pts
						(arc
							(start -0.3302 0.4318)
							(mid -0.402042 0.402042)
							(end -0.4318 0.3302)
						)
						(arc
							(start -0.4318 -0.3302)
							(mid -0.402042 -0.402042)
							(end -0.3302 -0.4318)
						)
						(arc
							(start 0.3302 -0.4318)
							(mid 0.402042 -0.402042)
							(end 0.4318 -0.3302)
						)
						(arc
							(start 0.4318 0.3302)
							(mid 0.402042 0.402042)
							(end 0.3302 0.4318)
						)
					)
					(width 0)
					(fill yes)
				)
			)
		)
	)
	(footprint ""
		(layer "B.Cu")
		(at 182.512208 -226.19208)
		(property "Reference" "C687"
			(at 0 0 0)
			(layer "B.SilkS")
			(hide yes)
			(effects
				(font
					(size 1.27 1.27)
				)
				(justify mirror)
			)
		)
		(property "Value" "SC1U16V3KX-5GP"
			(at 0 -2.8194 0)
			(unlocked yes)
			(layer "B.Fab")
			(hide yes)
			(effects
				(font
					(size 1.016 1.016)
					(thickness 0.1524)
				)
				(justify mirror)
			)
		)
		(property "Device Type" "C603H36"
			(at 0 -4.3434 0)
			(unlocked yes)
			(layer "B.Fab")
			(hide yes)
			(effects
				(font
					(size 1.016 1.016)
					(thickness 0.1524)
				)
				(justify mirror)
			)
		)
		(duplicate_pad_numbers_are_jumpers no)
		(fp_line
			(start -0.508 0)
			(end 0.508 0)
			(stroke
				(width 0.2032)
				(type default)
			)
			(layer "B.SilkS")
		)
		(fp_rect
			(start 0.5842 1.3335)
			(end -0.5842 -1.3335)
			(stroke
				(width 0)
				(type default)
			)
			(fill no)
			(layer "B.CrtYd")
		)
		(fp_rect
			(start 0.5842 1.3335)
			(end -0.5842 -1.3335)
			(stroke
				(width 0)
				(type default)
			)
			(fill no)
			(layer "B.Fab")
		)
		(pad "1" smd custom
			(at 0 -0.762 180)
			(size 0.2159 0.2159)
			(layers "B.Cu" "B.Mask" "B.Paste")
			(net "GND")
			(options
				(clearance outline)
				(anchor circle)
			)
			(primitives
				(gr_poly
					(pts
						(arc
							(start -0.3302 0.4318)
							(mid -0.402042 0.402042)
							(end -0.4318 0.3302)
						)
						(arc
							(start -0.4318 -0.3302)
							(mid -0.402042 -0.402042)
							(end -0.3302 -0.4318)
						)
						(arc
							(start 0.3302 -0.4318)
							(mid 0.402042 -0.402042)
							(end 0.4318 -0.3302)
						)
						(arc
							(start 0.4318 0.3302)
							(mid 0.402042 0.402042)
							(end 0.3302 0.4318)
						)
					)
					(width 0)
					(fill yes)
				)
			)
		)
		(pad "2" smd custom
			(at 0 0.762 180)
			(size 0.2159 0.2159)
			(layers "B.Cu" "B.Mask" "B.Paste")
			(net "P3V3_STBY_EN_R")
			(options
				(clearance outline)
				(anchor circle)
			)
			(primitives
				(gr_poly
					(pts
						(arc
							(start -0.3302 0.4318)
							(mid -0.402042 0.402042)
							(end -0.4318 0.3302)
						)
						(arc
							(start -0.4318 -0.3302)
							(mid -0.402042 -0.402042)
							(end -0.3302 -0.4318)
						)
						(arc
							(start 0.3302 -0.4318)
							(mid 0.402042 -0.402042)
							(end 0.4318 -0.3302)
						)
						(arc
							(start 0.4318 0.3302)
							(mid 0.402042 0.402042)
							(end 0.3302 0.4318)
						)
					)
					(width 0)
					(fill yes)
				)
			)
		)
	)
	(footprint ""
		(layer "B.Cu")
		(at 183.078628 -232.791508 180)
		(property "Reference" "L9"
			(at 0 0 0)
			(layer "B.SilkS")
			(hide yes)
			(effects
				(font
					(size 1.27 1.27)
				)
				(justify mirror)
			)
		)
		(property "Value" "COIL-4D7UH-33-GP"
			(at 4.699 -4.0132 180)
			(unlocked yes)
			(layer "B.Fab")
			(hide yes)
			(effects
				(font
					(size 1.016 1.016)
					(thickness 0.1524)
				)
				(justify mirror)
			)
		)
		(property "Device Type" "L7066-1830-UH119"
			(at 4.699 -5.5372 180)
			(unlocked yes)
			(layer "B.Fab")
			(hide yes)
			(effects
				(font
					(size 1.016 1.016)
					(thickness 0.1524)
				)
				(justify mirror)
			)
		)
		(duplicate_pad_numbers_are_jumpers no)
		(fp_line
			(start 3.556 4.4958)
			(end 3.556 -4.4958)
			(stroke
				(width 0.1524)
				(type default)
			)
			(layer "B.SilkS")
		)
		(fp_line
			(start 3.556 -4.4958)
			(end -3.556 -4.4958)
			(stroke
				(width 0.1524)
				(type default)
			)
			(layer "B.SilkS")
		)
		(fp_line
			(start -3.556 4.4958)
			(end 3.556 4.4958)
			(stroke
				(width 0.1524)
				(type default)
			)
			(layer "B.SilkS")
		)
		(fp_line
			(start -3.556 -4.4958)
			(end -3.556 4.4958)
			(stroke
				(width 0.1524)
				(type default)
			)
			(layer "B.SilkS")
		)
		(fp_rect
			(start 3.302 3.4798)
			(end -3.302 -3.4798)
			(stroke
				(width 0)
				(type default)
			)
			(fill no)
			(layer "B.CrtYd")
		)
		(fp_poly
			(pts
				(xy 3.81 4.572) (xy 3.81 -4.572) (xy -3.81 -4.572) (xy -3.81 -0.5588) (xy -3.302 -0.5588) (xy -3.302 -3.4798)
				(xy 3.302 -3.4798) (xy 3.302 3.4798) (xy -3.302 3.4798) (xy -3.302 -0.5461) (xy -3.81 -0.5461) (xy -3.81 4.572)
			)
			(stroke
				(width 0)
				(type default)
			)
			(fill no)
			(layer "B.CrtYd")
		)
		(fp_rect
			(start 3.81 4.572)
			(end -3.81 -4.572)
			(stroke
				(width 0)
				(type default)
			)
			(fill no)
			(layer "B.Fab")
		)
		(pad "1" smd rect
			(at 0 -2.779522)
			(size 3.5052 2.921)
			(layers "B.Cu" "B.Mask" "B.Paste")
			(net "P3V3_STBY_SW")
		)
		(pad "2" smd rect
			(at 0 2.779522)
			(size 3.5052 2.921)
			(layers "B.Cu" "B.Mask" "B.Paste")
			(net "P3V3_STBY_A")
		)
	)
	(footprint ""
		(layer "B.Cu")
		(at 22.1234 -246.7864 180)
		(property "Reference" "C599"
			(at 0 0 0)
			(layer "B.SilkS")
			(hide yes)
			(effects
				(font
					(size 1.27 1.27)
				)
				(justify mirror)
			)
		)
		(property "Value" "SC10U16V5KX-7-GP-U"
			(at 0.0762 -6.1214 180)
			(unlocked yes)
			(layer "B.Fab")
			(hide yes)
			(effects
				(font
					(size 1.016 1.016)
					(thickness 0.1524)
				)
				(justify mirror)
			)
		)
		(property "Device Type" "C805H58"
			(at 0.0762 -8.1534 180)
			(unlocked yes)
			(layer "B.Fab")
			(hide yes)
			(effects
				(font
					(size 1.016 1.016)
					(thickness 0.1524)
				)
				(justify mirror)
			)
		)
		(duplicate_pad_numbers_are_jumpers no)
		(fp_line
			(start -0.635 0)
			(end 0.635 0)
			(stroke
				(width 0.508)
				(type default)
			)
			(layer "B.SilkS")
		)
		(fp_rect
			(start 0.9652 1.778)
			(end -0.9652 -1.778)
			(stroke
				(width 0)
				(type default)
			)
			(fill no)
			(layer "B.CrtYd")
		)
		(fp_poly
			(pts
				(xy 0.9652 -1.778) (xy -0.9652 -1.778) (xy -0.9652 1.778) (xy 0.9652 1.778)
			)
			(stroke
				(width 0)
				(type default)
			)
			(fill no)
			(layer "B.Fab")
		)
		(pad "1" smd rect
			(at 0 -0.9652)
			(size 1.397 1.143)
			(layers "B.Cu" "B.Mask" "B.Paste")
			(net "P12V_A_VIN_U20")
		)
		(pad "2" smd rect
			(at 0 0.9652)
			(size 1.397 1.143)
			(layers "B.Cu" "B.Mask" "B.Paste")
			(net "GND")
		)
	)
	(footprint ""
		(layer "B.Cu")
		(at 189.530482 -230.807006)
		(property "Reference" "C674"
			(at 0 0 0)
			(layer "B.SilkS")
			(hide yes)
			(effects
				(font
					(size 1.27 1.27)
				)
				(justify mirror)
			)
		)
		(property "Value" "SC1U25V3KX-GP"
			(at 0 -2.8194 0)
			(unlocked yes)
			(layer "B.Fab")
			(hide yes)
			(effects
				(font
					(size 1.016 1.016)
					(thickness 0.1524)
				)
				(justify mirror)
			)
		)
		(property "Device Type" "C603H36"
			(at 0 -4.3434 0)
			(unlocked yes)
			(layer "B.Fab")
			(hide yes)
			(effects
				(font
					(size 1.016 1.016)
					(thickness 0.1524)
				)
				(justify mirror)
			)
		)
		(duplicate_pad_numbers_are_jumpers no)
		(fp_line
			(start -0.508 0)
			(end 0.508 0)
			(stroke
				(width 0.2032)
				(type default)
			)
			(layer "B.SilkS")
		)
		(fp_rect
			(start 0.5842 1.3335)
			(end -0.5842 -1.3335)
			(stroke
				(width 0)
				(type default)
			)
			(fill no)
			(layer "B.CrtYd")
		)
		(fp_rect
			(start 0.5842 1.3335)
			(end -0.5842 -1.3335)
			(stroke
				(width 0)
				(type default)
			)
			(fill no)
			(layer "B.Fab")
		)
		(pad "1" smd custom
			(at 0 -0.762 180)
			(size 0.2159 0.2159)
			(layers "B.Cu" "B.Mask" "B.Paste")
			(net "P3V3_STBY_SW")
			(options
				(clearance outline)
				(anchor circle)
			)
			(primitives
				(gr_poly
					(pts
						(arc
							(start -0.3302 0.4318)
							(mid -0.402042 0.402042)
							(end -0.4318 0.3302)
						)
						(arc
							(start -0.4318 -0.3302)
							(mid -0.402042 -0.402042)
							(end -0.3302 -0.4318)
						)
						(arc
							(start 0.3302 -0.4318)
							(mid 0.402042 -0.402042)
							(end 0.4318 -0.3302)
						)
						(arc
							(start 0.4318 0.3302)
							(mid 0.402042 0.402042)
							(end 0.3302 0.4318)
						)
					)
					(width 0)
					(fill yes)
				)
			)
		)
		(pad "2" smd custom
			(at 0 0.762 180)
			(size 0.2159 0.2159)
			(layers "B.Cu" "B.Mask" "B.Paste")
			(net "P3V3_STBY_VBST_RR")
			(options
				(clearance outline)
				(anchor circle)
			)
			(primitives
				(gr_poly
					(pts
						(arc
							(start -0.3302 0.4318)
							(mid -0.402042 0.402042)
							(end -0.4318 0.3302)
						)
						(arc
							(start -0.4318 -0.3302)
							(mid -0.402042 -0.402042)
							(end -0.3302 -0.4318)
						)
						(arc
							(start 0.3302 -0.4318)
							(mid 0.402042 -0.402042)
							(end 0.4318 -0.3302)
						)
						(arc
							(start 0.4318 0.3302)
							(mid 0.402042 0.402042)
							(end 0.3302 0.4318)
						)
					)
					(width 0)
					(fill yes)
				)
			)
		)
	)
	(footprint ""
		(layer "B.Cu")
		(at 267.66012 -106.966766 -90)
		(property "Reference" "TC21"
			(at 0 0 90)
			(layer "B.SilkS")
			(hide yes)
			(effects
				(font
					(size 1.27 1.27)
				)
				(justify mirror)
			)
		)
		(property "Value" "ST100U16VDM-3-GP"
			(at 0 -9.6012 270)
			(unlocked yes)
			(layer "B.Fab")
			(hide yes)
			(effects
				(font
					(size 1.016 1.016)
					(thickness 0.1524)
				)
				(justify mirror)
			)
		)
		(property "Device Type" "CT7343H79"
			(at 0 -11.1252 270)
			(unlocked yes)
			(layer "B.Fab")
			(hide yes)
			(effects
				(font
					(size 1.016 1.016)
					(thickness 0.1524)
				)
				(justify mirror)
			)
		)
		(duplicate_pad_numbers_are_jumpers no)
		(fp_line
			(start -2.286 4.8768)
			(end 2.286 4.8768)
			(stroke
				(width 0.1524)
				(type default)
			)
			(layer "B.SilkS")
		)
		(fp_line
			(start 2.286 4.8768)
			(end 2.286 2.032)
			(stroke
				(width 0.1524)
				(type default)
			)
			(layer "B.SilkS")
		)
		(fp_line
			(start -2.286 2.032)
			(end -2.286 4.8768)
			(stroke
				(width 0.1524)
				(type default)
			)
			(layer "B.SilkS")
		)
		(fp_line
			(start -2.286 -2.032)
			(end -2.286 -4.8768)
			(stroke
				(width 0.1524)
				(type default)
			)
			(layer "B.SilkS")
		)
		(fp_line
			(start -2.1082 -4.699)
			(end 2.1082 -4.699)
			(stroke
				(width 0.508)
				(type default)
			)
			(layer "B.SilkS")
		)
		(fp_line
			(start -2.286 -4.8768)
			(end 2.286 -4.8768)
			(stroke
				(width 0.1524)
				(type default)
			)
			(layer "B.SilkS")
		)
		(fp_line
			(start 2.286 -4.8768)
			(end 2.286 -2.032)
			(stroke
				(width 0.1524)
				(type default)
			)
			(layer "B.SilkS")
		)
		(fp_rect
			(start 2.1463 3.6449)
			(end -2.1463 -3.6449)
			(stroke
				(width 0)
				(type default)
			)
			(fill no)
			(layer "B.CrtYd")
		)
		(fp_poly
			(pts
				(xy 2.54 4.953) (xy 2.54 4.2926) (xy 3.81 4.2926) (xy 3.81 -4.2926) (xy 2.54 -4.2926) (xy 2.54 -4.953)
				(xy -2.54 -4.953) (xy -2.54 -4.2926) (xy -3.81 -4.2926) (xy -3.81 -1.6256) (xy -2.1463 -1.6256)
				(xy -2.1463 -3.6449) (xy 2.1463 -3.6449) (xy 2.1463 3.6449) (xy -2.1463 3.6449) (xy -2.1463 -1.6129)
				(xy -3.81 -1.6129) (xy -3.81 4.2926) (xy -2.54 4.2926) (xy -2.54 4.953)
			)
			(stroke
				(width 0)
				(type default)
			)
			(fill no)
			(layer "B.CrtYd")
		)
		(fp_rect
			(start 2.54 4.953)
			(end -2.54 -4.953)
			(stroke
				(width 0)
				(type default)
			)
			(fill no)
			(layer "B.Fab")
		)
		(fp_rect
			(start -2.54 4.2926)
			(end -3.81 -4.2926)
			(stroke
				(width 0)
				(type default)
			)
			(fill no)
			(layer "B.Fab")
		)
		(fp_rect
			(start 3.81 4.2926)
			(end 2.54 -4.2926)
			(stroke
				(width 0)
				(type default)
			)
			(fill no)
			(layer "B.Fab")
		)
		(pad "1" smd rect
			(at 0 -3.1496 90)
			(size 2.413 2.286)
			(layers "B.Cu" "B.Mask" "B.Paste")
			(net "P12V_B_COMP")
		)
		(pad "2" smd rect
			(at 0 3.1496 90)
			(size 2.413 2.286)
			(layers "B.Cu" "B.Mask" "B.Paste")
			(net "GND")
		)
		(zone
			(layer "B.Cu")
			(hatch none 0.5)
			(connect_pads
				(clearance 0)
			)
			(min_thickness 0.25)
			(keepout
				(tracks allowed)
				(vias not_allowed)
				(pads allowed)
				(copperpour not_allowed)
				(footprints allowed)
			)
			(placement
				(enabled no)
				(sheetname "")
			)
			(fill
				(thermal_gap 0.5)
				(thermal_bridge_width 0.5)
				(island_removal_mode 0)
			)
			(polygon
				(pts
					(xy 263.06272 -105.455466) (xy 263.06272 -108.478066) (xy 265.95832 -108.478066) (xy 266.28852 -108.478066)
					(xy 266.28852 -105.455466) (xy 265.95832 -105.455466)
				)
			)
		)
		(zone
			(layer "B.Cu")
			(hatch none 0.5)
			(connect_pads
				(clearance 0)
			)
			(min_thickness 0.25)
			(keepout
				(tracks allowed)
				(vias not_allowed)
				(pads allowed)
				(copperpour not_allowed)
				(footprints allowed)
			)
			(placement
				(enabled no)
				(sheetname "")
			)
			(fill
				(thermal_gap 0.5)
				(thermal_bridge_width 0.5)
				(island_removal_mode 0)
			)
			(polygon
				(pts
					(xy 269.34922 -108.478066) (xy 272.25752 -108.478066) (xy 272.25752 -105.455466) (xy 269.36192 -105.455466)
					(xy 269.03172 -105.455466) (xy 269.03172 -108.478066)
				)
			)
		)
	)
	(footprint ""
		(layer "B.Cu")
		(at 474.091 -239.395 90)
		(property "Reference" "C650"
			(at 0 0 90)
			(layer "B.SilkS")
			(hide yes)
			(effects
				(font
					(size 1.27 1.27)
				)
				(justify mirror)
			)
		)
		(property "Value" "SC10U16V5KX-7-GP-U"
			(at 0.0762 -6.1214 90)
			(unlocked yes)
			(layer "B.Fab")
			(hide yes)
			(effects
				(font
					(size 1.016 1.016)
					(thickness 0.1524)
				)
				(justify mirror)
			)
		)
		(property "Device Type" "C805H58"
			(at 0.0762 -8.1534 90)
			(unlocked yes)
			(layer "B.Fab")
			(hide yes)
			(effects
				(font
					(size 1.016 1.016)
					(thickness 0.1524)
				)
				(justify mirror)
			)
		)
		(duplicate_pad_numbers_are_jumpers no)
		(fp_line
			(start -0.635 0)
			(end 0.635 0)
			(stroke
				(width 0.508)
				(type default)
			)
			(layer "B.SilkS")
		)
		(fp_rect
			(start 0.9652 1.778)
			(end -0.9652 -1.778)
			(stroke
				(width 0)
				(type default)
			)
			(fill no)
			(layer "B.CrtYd")
		)
		(fp_poly
			(pts
				(xy 0.9652 -1.778) (xy -0.9652 -1.778) (xy -0.9652 1.778) (xy 0.9652 1.778)
			)
			(stroke
				(width 0)
				(type default)
			)
			(fill no)
			(layer "B.Fab")
		)
		(pad "1" smd rect
			(at 0 -0.9652 270)
			(size 1.397 1.143)
			(layers "B.Cu" "B.Mask" "B.Paste")
			(net "P12V_A_VIN_U27")
		)
		(pad "2" smd rect
			(at 0 0.9652 270)
			(size 1.397 1.143)
			(layers "B.Cu" "B.Mask" "B.Paste")
			(net "GND")
		)
	)
	(footprint ""
		(layer "B.Cu")
		(at 176.431702 -154.24277)
		(property "Reference" "D37"
			(at 0 0 0)
			(layer "B.SilkS")
			(hide yes)
			(effects
				(font
					(size 1.27 1.27)
				)
				(justify mirror)
			)
		)
		(property "Value" "SMCJ14A-13-F-GP"
			(at 4.445 1.1684 0)
			(unlocked yes)
			(layer "B.Fab")
			(hide yes)
			(effects
				(font
					(size 1.016 1.016)
					(thickness 0.1524)
				)
				(justify mirror)
			)
		)
		(property "Device Type" "D795930AKH104"
			(at 4.445 -0.3556 0)
			(unlocked yes)
			(layer "B.Fab")
			(hide yes)
			(effects
				(font
					(size 1.016 1.016)
					(thickness 0.1524)
				)
				(justify mirror)
			)
		)
		(duplicate_pad_numbers_are_jumpers no)
		(fp_line
			(start -3.2004 -4.8641)
			(end 3.2004 -4.8641)
			(stroke
				(width 0.1524)
				(type default)
			)
			(layer "B.SilkS")
		)
		(fp_line
			(start -3.2004 4.8641)
			(end -3.2004 -4.8641)
			(stroke
				(width 0.1524)
				(type default)
			)
			(layer "B.SilkS")
		)
		(fp_line
			(start -3.2004 5.0419)
			(end 3.2004 5.0419)
			(stroke
				(width 0.508)
				(type default)
			)
			(layer "B.SilkS")
		)
		(fp_line
			(start 3.2004 -4.8641)
			(end 3.2004 4.8641)
			(stroke
				(width 0.1524)
				(type default)
			)
			(layer "B.SilkS")
		)
		(fp_line
			(start 3.2004 4.8641)
			(end -3.2004 4.8641)
			(stroke
				(width 0.1524)
				(type default)
			)
			(layer "B.SilkS")
		)
		(fp_poly
			(pts
				(xy 2.9464 3.429) (xy 1.4859 3.429) (xy 1.4859 3.9751) (xy -1.4859 3.9751) (xy -1.4859 3.429) (xy -2.9464 3.429)
				(xy -2.9464 -3.429) (xy -1.4859 -3.429) (xy -1.4859 -3.9751) (xy 1.4859 -3.9751) (xy 1.4859 -3.429)
				(xy 2.9464 -3.429)
			)
			(stroke
				(width 0)
				(type default)
			)
			(fill no)
			(layer "B.CrtYd")
		)
		(fp_poly
			(pts
				(xy 3.4544 4.9403) (xy 3.4544 -4.9403) (xy -3.4544 -4.9403) (xy -3.4544 -3.429) (xy -1.4859 -3.429)
				(xy -1.4859 -3.9751) (xy 1.4859 -3.9751) (xy 1.4859 -3.429) (xy 2.9464 -3.429) (xy 2.9464 3.429)
				(xy 1.4859 3.429) (xy 1.4859 3.9751) (xy -1.4859 3.9751) (xy -1.4859 3.429) (xy -2.9464 3.429) (xy -2.9464 -3.4163)
				(xy -3.4544 -3.4163) (xy -3.4544 4.9403)
			)
			(stroke
				(width 0)
				(type default)
			)
			(fill no)
			(layer "B.CrtYd")
		)
		(fp_rect
			(start 3.4544 4.9403)
			(end -3.4544 -4.9403)
			(stroke
				(width 0)
				(type default)
			)
			(fill no)
			(layer "B.Fab")
		)
		(pad "A" smd rect
			(at 0 -3.592068 180)
			(size 3.2258 2.032)
			(layers "B.Cu" "B.Mask" "B.Paste")
			(net "GND")
		)
		(pad "K" smd rect
			(at 0 3.592068 180)
			(size 3.2258 2.032)
			(layers "B.Cu" "B.Mask" "B.Paste")
			(net "P12V_A")
		)
	)
	(footprint ""
		(layer "B.Cu")
		(at 188.7728 -222.5802)
		(property "Reference" "R1286"
			(at 0 0 0)
			(layer "B.SilkS")
			(hide yes)
			(effects
				(font
					(size 1.27 1.27)
				)
				(justify mirror)
			)
		)
		(property "Value" "0R2J-2-GP"
			(at -0.064008 -3.993896 0)
			(unlocked yes)
			(layer "B.Fab")
			(hide yes)
			(effects
				(font
					(size 1.016 1.016)
					(thickness 0.1524)
				)
				(justify mirror)
			)
		)
		(property "Device Type" "R402H16"
			(at -0.064008 -5.517896 0)
			(unlocked yes)
			(layer "B.Fab")
			(hide yes)
			(effects
				(font
					(size 1.016 1.016)
					(thickness 0.1524)
				)
				(justify mirror)
			)
		)
		(duplicate_pad_numbers_are_jumpers no)
		(fp_line
			(start -0.508 -0.9398)
			(end 0.508 -0.9398)
			(stroke
				(width 0.1524)
				(type default)
			)
			(layer "B.SilkS")
		)
		(fp_line
			(start 0.508 -0.9398)
			(end 0.508 0.9398)
			(stroke
				(width 0.1524)
				(type default)
			)
			(layer "B.SilkS")
		)
		(fp_rect
			(start 0.508 0.9398)
			(end -0.508 -0.9398)
			(stroke
				(width 0)
				(type default)
			)
			(fill no)
			(layer "B.CrtYd")
		)
		(fp_rect
			(start 0.508 0.9398)
			(end -0.508 -0.9398)
			(stroke
				(width 0)
				(type default)
			)
			(fill no)
			(layer "B.Fab")
		)
		(pad "1" smd custom
			(at 0 -0.4445 180)
			(size 0.1397 0.1397)
			(layers "B.Cu" "B.Mask" "B.Paste")
			(net "P3V3_STBY_VO")
			(options
				(clearance outline)
				(anchor circle)
			)
			(primitives
				(gr_poly
					(pts
						(arc
							(start -0.1778 0.2794)
							(mid -0.249642 0.249642)
							(end -0.2794 0.1778)
						)
						(arc
							(start -0.2794 -0.1778)
							(mid -0.249642 -0.249642)
							(end -0.1778 -0.2794)
						)
						(arc
							(start 0.1778 -0.2794)
							(mid 0.249642 -0.249642)
							(end 0.2794 -0.1778)
						)
						(arc
							(start 0.2794 0.1778)
							(mid 0.249642 0.249642)
							(end 0.1778 0.2794)
						)
					)
					(width 0)
					(fill yes)
				)
			)
		)
		(pad "2" smd custom
			(at 0 0.4445 180)
			(size 0.1397 0.1397)
			(layers "B.Cu" "B.Mask" "B.Paste")
			(net "P3V3_STBY_CC_R")
			(options
				(clearance outline)
				(anchor circle)
			)
			(primitives
				(gr_poly
					(pts
						(arc
							(start -0.1778 0.2794)
							(mid -0.249642 0.249642)
							(end -0.2794 0.1778)
						)
						(arc
							(start -0.2794 -0.1778)
							(mid -0.249642 -0.249642)
							(end -0.1778 -0.2794)
						)
						(arc
							(start 0.1778 -0.2794)
							(mid 0.249642 -0.249642)
							(end 0.2794 -0.1778)
						)
						(arc
							(start 0.2794 0.1778)
							(mid 0.249642 0.249642)
							(end 0.1778 0.2794)
						)
					)
					(width 0)
					(fill yes)
				)
			)
		)
	)
	(footprint ""
		(layer "B.Cu")
		(at 449.291202 -257.48615 90)
		(property "Reference" "C667"
			(at 0 0 90)
			(layer "B.SilkS")
			(hide yes)
			(effects
				(font
					(size 1.27 1.27)
				)
				(justify mirror)
			)
		)
		(property "Value" "SC68P50V2JN-2-GP"
			(at -1.1811 -2.7051 90)
			(unlocked yes)
			(layer "B.Fab")
			(hide yes)
			(effects
				(font
					(size 1.016 1.016)
					(thickness 0.1524)
				)
				(justify mirror)
			)
		)
		(property "Device Type" "C402H22"
			(at -1.1811 -4.2291 90)
			(unlocked yes)
			(layer "B.Fab")
			(hide yes)
			(effects
				(font
					(size 1.016 1.016)
					(thickness 0.1524)
				)
				(justify mirror)
			)
		)
		(duplicate_pad_numbers_are_jumpers no)
		(fp_rect
			(start 0.4318 0.9525)
			(end -0.4318 -0.9525)
			(stroke
				(width 0)
				(type default)
			)
			(fill no)
			(layer "B.CrtYd")
		)
		(fp_rect
			(start 0.4318 0.9525)
			(end -0.4318 -0.9525)
			(stroke
				(width 0)
				(type default)
			)
			(fill no)
			(layer "B.Fab")
		)
		(pad "1" smd custom
			(at 0 -0.4445 270)
			(size 0.1524 0.1524)
			(layers "B.Cu" "B.Mask" "B.Paste")
			(net "P5V_C_VFB")
			(options
				(clearance outline)
				(anchor circle)
			)
			(primitives
				(gr_poly
					(pts
						(arc
							(start 0.3048 0.2032)
							(mid 0.275042 0.275042)
							(end 0.2032 0.3048)
						)
						(arc
							(start -0.2032 0.3048)
							(mid -0.275042 0.275042)
							(end -0.3048 0.2032)
						)
						(arc
							(start -0.3048 -0.2032)
							(mid -0.275042 -0.275042)
							(end -0.2032 -0.3048)
						)
						(arc
							(start 0.2032 -0.3048)
							(mid 0.275042 -0.275042)
							(end 0.3048 -0.2032)
						)
					)
					(width 0)
					(fill yes)
				)
			)
		)
		(pad "2" smd custom
			(at 0 0.4445 270)
			(size 0.1524 0.1524)
			(layers "B.Cu" "B.Mask" "B.Paste")
			(net "P5V_C_VFB_R")
			(options
				(clearance outline)
				(anchor circle)
			)
			(primitives
				(gr_poly
					(pts
						(arc
							(start 0.3048 0.2032)
							(mid 0.275042 0.275042)
							(end 0.2032 0.3048)
						)
						(arc
							(start -0.2032 0.3048)
							(mid -0.275042 0.275042)
							(end -0.3048 0.2032)
						)
						(arc
							(start -0.3048 -0.2032)
							(mid -0.275042 -0.275042)
							(end -0.2032 -0.3048)
						)
						(arc
							(start 0.2032 -0.3048)
							(mid 0.275042 -0.275042)
							(end 0.3048 -0.2032)
						)
					)
					(width 0)
					(fill yes)
				)
			)
		)
	)
	(footprint ""
		(layer "B.Cu")
		(at 190.745872 -228.116892 180)
		(property "Reference" "C670"
			(at 0 0 0)
			(layer "B.SilkS")
			(hide yes)
			(effects
				(font
					(size 1.27 1.27)
				)
				(justify mirror)
			)
		)
		(property "Value" "SCD1U16V2KX-3GP"
			(at -1.1811 -2.7051 180)
			(unlocked yes)
			(layer "B.Fab")
			(hide yes)
			(effects
				(font
					(size 1.016 1.016)
					(thickness 0.1524)
				)
				(justify mirror)
			)
		)
		(property "Device Type" "C402H22"
			(at -1.1811 -4.2291 180)
			(unlocked yes)
			(layer "B.Fab")
			(hide yes)
			(effects
				(font
					(size 1.016 1.016)
					(thickness 0.1524)
				)
				(justify mirror)
			)
		)
		(duplicate_pad_numbers_are_jumpers no)
		(fp_rect
			(start 0.4318 0.9525)
			(end -0.4318 -0.9525)
			(stroke
				(width 0)
				(type default)
			)
			(fill no)
			(layer "B.CrtYd")
		)
		(fp_rect
			(start 0.4318 0.9525)
			(end -0.4318 -0.9525)
			(stroke
				(width 0)
				(type default)
			)
			(fill no)
			(layer "B.Fab")
		)
		(pad "1" smd custom
			(at 0 -0.4445)
			(size 0.1524 0.1524)
			(layers "B.Cu" "B.Mask" "B.Paste")
			(net "P3V3_STBY_VIN")
			(options
				(clearance outline)
				(anchor circle)
			)
			(primitives
				(gr_poly
					(pts
						(arc
							(start 0.3048 0.2032)
							(mid 0.275042 0.275042)
							(end 0.2032 0.3048)
						)
						(arc
							(start -0.2032 0.3048)
							(mid -0.275042 0.275042)
							(end -0.3048 0.2032)
						)
						(arc
							(start -0.3048 -0.2032)
							(mid -0.275042 -0.275042)
							(end -0.2032 -0.3048)
						)
						(arc
							(start 0.2032 -0.3048)
							(mid 0.275042 -0.275042)
							(end 0.3048 -0.2032)
						)
					)
					(width 0)
					(fill yes)
				)
			)
		)
		(pad "2" smd custom
			(at 0 0.4445)
			(size 0.1524 0.1524)
			(layers "B.Cu" "B.Mask" "B.Paste")
			(net "GND")
			(options
				(clearance outline)
				(anchor circle)
			)
			(primitives
				(gr_poly
					(pts
						(arc
							(start 0.3048 0.2032)
							(mid 0.275042 0.275042)
							(end 0.2032 0.3048)
						)
						(arc
							(start -0.2032 0.3048)
							(mid -0.275042 0.275042)
							(end -0.3048 0.2032)
						)
						(arc
							(start -0.3048 -0.2032)
							(mid -0.275042 -0.275042)
							(end -0.2032 -0.3048)
						)
						(arc
							(start 0.2032 -0.3048)
							(mid 0.275042 -0.275042)
							(end 0.3048 -0.2032)
						)
					)
					(width 0)
					(fill yes)
				)
			)
		)
	)
	(footprint ""
		(layer "B.Cu")
		(at 472.186 -245.11 90)
		(property "Reference" "R1264"
			(at 0 0 90)
			(layer "B.SilkS")
			(hide yes)
			(effects
				(font
					(size 1.27 1.27)
				)
				(justify mirror)
			)
		)
		(property "Value" "2D2R3-1-U-GP"
			(at 0.0254 -2.5146 90)
			(unlocked yes)
			(layer "B.Fab")
			(hide yes)
			(effects
				(font
					(size 1.016 1.016)
					(thickness 0.1524)
				)
				(justify mirror)
			)
		)
		(property "Device Type" "R603H22"
			(at 0.0254 -4.0386 90)
			(unlocked yes)
			(layer "B.Fab")
			(hide yes)
			(effects
				(font
					(size 1.016 1.016)
					(thickness 0.1524)
				)
				(justify mirror)
			)
		)
		(duplicate_pad_numbers_are_jumpers no)
		(fp_line
			(start 0.4826 0)
			(end 0.2032 0)
			(stroke
				(width 0.2032)
				(type default)
			)
			(layer "B.SilkS")
		)
		(fp_line
			(start -0.2032 0)
			(end -0.4826 0)
			(stroke
				(width 0.2032)
				(type default)
			)
			(layer "B.SilkS")
		)
		(fp_rect
			(start 0.5842 1.3335)
			(end -0.5842 -1.3335)
			(stroke
				(width 0)
				(type default)
			)
			(fill no)
			(layer "B.CrtYd")
		)
		(fp_rect
			(start 0.5842 1.3335)
			(end -0.5842 -1.3335)
			(stroke
				(width 0)
				(type default)
			)
			(fill no)
			(layer "B.Fab")
		)
		(pad "1" smd custom
			(at 0 -0.762 270)
			(size 0.2159 0.2159)
			(layers "B.Cu" "B.Mask" "B.Paste")
			(net "P12V_A")
			(options
				(clearance outline)
				(anchor circle)
			)
			(primitives
				(gr_poly
					(pts
						(arc
							(start -0.3302 0.4318)
							(mid -0.402042 0.402042)
							(end -0.4318 0.3302)
						)
						(arc
							(start -0.4318 -0.3302)
							(mid -0.402042 -0.402042)
							(end -0.3302 -0.4318)
						)
						(arc
							(start 0.3302 -0.4318)
							(mid 0.402042 -0.402042)
							(end 0.4318 -0.3302)
						)
						(arc
							(start 0.4318 0.3302)
							(mid 0.402042 0.402042)
							(end 0.3302 0.4318)
						)
					)
					(width 0)
					(fill yes)
				)
			)
		)
		(pad "2" smd custom
			(at 0 0.762 270)
			(size 0.2159 0.2159)
			(layers "B.Cu" "B.Mask" "B.Paste")
			(net "P12V_A_VDD_U27")
			(options
				(clearance outline)
				(anchor circle)
			)
			(primitives
				(gr_poly
					(pts
						(arc
							(start -0.3302 0.4318)
							(mid -0.402042 0.402042)
							(end -0.4318 0.3302)
						)
						(arc
							(start -0.4318 -0.3302)
							(mid -0.402042 -0.402042)
							(end -0.3302 -0.4318)
						)
						(arc
							(start 0.3302 -0.4318)
							(mid 0.402042 -0.402042)
							(end 0.4318 -0.3302)
						)
						(arc
							(start 0.4318 0.3302)
							(mid 0.402042 0.402042)
							(end 0.3302 0.4318)
						)
					)
					(width 0)
					(fill yes)
				)
			)
		)
	)
	(footprint ""
		(layer "B.Cu")
		(at 45.8978 -148.6662)
		(property "Reference" "PG13"
			(at 0 0 0)
			(layer "B.SilkS")
			(hide yes)
			(effects
				(font
					(size 1.27 1.27)
				)
				(justify mirror)
			)
		)
		(property "Value" "COPPER-CLOSE-GP-U"
			(at -0.0762 -2.8702 0)
			(unlocked yes)
			(layer "B.Fab")
			(hide yes)
			(effects
				(font
					(size 1.016 1.016)
					(thickness 0.1524)
				)
				(justify mirror)
			)
		)
		(property "Device Type" "CON2C-U"
			(at -0.0762 -4.3942 0)
			(unlocked yes)
			(layer "B.Fab")
			(hide yes)
			(effects
				(font
					(size 1.016 1.016)
					(thickness 0.1524)
				)
				(justify mirror)
			)
		)
		(duplicate_pad_numbers_are_jumpers no)
		(fp_rect
			(start 0.9398 0.9652)
			(end -0.9398 -0.9652)
			(stroke
				(width 0)
				(type default)
			)
			(fill no)
			(layer "B.CrtYd")
		)
		(fp_rect
			(start 0.9398 0.9652)
			(end -0.9398 -0.9652)
			(stroke
				(width 0)
				(type default)
			)
			(fill no)
			(layer "B.Fab")
		)
		(pad "1" smd custom
			(at 0 -0.5334 180)
			(size 0.17145 0.17145)
			(layers "B.Cu" "B.Mask" "B.Paste")
			(net "AGND_P5V_B")
			(options
				(clearance outline)
				(anchor circle)
			)
			(primitives
				(gr_poly
					(pts
						(xy -0.127 -0.3429) (xy -0.127 -0.1651) (xy -0.635 0.3429) (xy 0.635 0.3429) (xy 0.127 -0.1651)
						(xy 0.127 -0.3429)
					)
					(width 0)
					(fill yes)
				)
			)
		)
		(pad "2" smd custom
			(at 0 0.5334 180)
			(size 0.17145 0.17145)
			(layers "B.Cu" "B.Mask" "B.Paste")
			(net "GND")
			(options
				(clearance outline)
				(anchor circle)
			)
			(primitives
				(gr_poly
					(pts
						(xy -0.635 -0.3429) (xy -0.127 0.1651) (xy -0.127 0.3429) (xy 0.127 0.3429) (xy 0.127 0.1651)
						(xy 0.635 -0.3429)
					)
					(width 0)
					(fill yes)
				)
			)
		)
	)
	(footprint ""
		(layer "B.Cu")
		(at 455.507344 -255.949196 180)
		(property "Reference" "R1249"
			(at 0 0 0)
			(layer "B.SilkS")
			(hide yes)
			(effects
				(font
					(size 1.27 1.27)
				)
				(justify mirror)
			)
		)
		(property "Value" "2K7R2F-GP"
			(at -0.064008 -3.993896 180)
			(unlocked yes)
			(layer "B.Fab")
			(hide yes)
			(effects
				(font
					(size 1.016 1.016)
					(thickness 0.1524)
				)
				(justify mirror)
			)
		)
		(property "Device Type" "R402H16"
			(at -0.064008 -5.517896 180)
			(unlocked yes)
			(layer "B.Fab")
			(hide yes)
			(effects
				(font
					(size 1.016 1.016)
					(thickness 0.1524)
				)
				(justify mirror)
			)
		)
		(duplicate_pad_numbers_are_jumpers no)
		(fp_line
			(start 0.508 -0.9398)
			(end 0.508 0.9398)
			(stroke
				(width 0.1524)
				(type default)
			)
			(layer "B.SilkS")
		)
		(fp_line
			(start -0.508 -0.9398)
			(end 0.508 -0.9398)
			(stroke
				(width 0.1524)
				(type default)
			)
			(layer "B.SilkS")
		)
		(fp_rect
			(start 0.508 0.9398)
			(end -0.508 -0.9398)
			(stroke
				(width 0)
				(type default)
			)
			(fill no)
			(layer "B.CrtYd")
		)
		(fp_rect
			(start 0.508 0.9398)
			(end -0.508 -0.9398)
			(stroke
				(width 0)
				(type default)
			)
			(fill no)
			(layer "B.Fab")
		)
		(pad "1" smd custom
			(at 0 -0.4445)
			(size 0.1397 0.1397)
			(layers "B.Cu" "B.Mask" "B.Paste")
			(net "P5V_C_LL")
			(options
				(clearance outline)
				(anchor circle)
			)
			(primitives
				(gr_poly
					(pts
						(arc
							(start -0.1778 0.2794)
							(mid -0.249642 0.249642)
							(end -0.2794 0.1778)
						)
						(arc
							(start -0.2794 -0.1778)
							(mid -0.249642 -0.249642)
							(end -0.1778 -0.2794)
						)
						(arc
							(start 0.1778 -0.2794)
							(mid 0.249642 -0.249642)
							(end 0.2794 -0.1778)
						)
						(arc
							(start 0.2794 0.1778)
							(mid 0.249642 0.249642)
							(end 0.1778 0.2794)
						)
					)
					(width 0)
					(fill yes)
				)
			)
		)
		(pad "2" smd custom
			(at 0 0.4445)
			(size 0.1397 0.1397)
			(layers "B.Cu" "B.Mask" "B.Paste")
			(net "P5V_C_LL_R")
			(options
				(clearance outline)
				(anchor circle)
			)
			(primitives
				(gr_poly
					(pts
						(arc
							(start -0.1778 0.2794)
							(mid -0.249642 0.249642)
							(end -0.2794 0.1778)
						)
						(arc
							(start -0.2794 -0.1778)
							(mid -0.249642 -0.249642)
							(end -0.1778 -0.2794)
						)
						(arc
							(start 0.1778 -0.2794)
							(mid 0.249642 -0.249642)
							(end 0.2794 -0.1778)
						)
						(arc
							(start 0.2794 0.1778)
							(mid 0.249642 0.249642)
							(end 0.1778 0.2794)
						)
					)
					(width 0)
					(fill yes)
				)
			)
		)
	)
	(footprint ""
		(layer "B.Cu")
		(at 181.076092 -239.238028 180)
		(property "Reference" "C684"
			(at 0 0 0)
			(layer "B.SilkS")
			(hide yes)
			(effects
				(font
					(size 1.27 1.27)
				)
				(justify mirror)
			)
		)
		(property "Value" "SC10U6D3V5KX-4GP"
			(at 0.0762 -6.1214 180)
			(unlocked yes)
			(layer "B.Fab")
			(hide yes)
			(effects
				(font
					(size 1.016 1.016)
					(thickness 0.1524)
				)
				(justify mirror)
			)
		)
		(property "Device Type" "C805H58"
			(at 0.0762 -8.1534 180)
			(unlocked yes)
			(layer "B.Fab")
			(hide yes)
			(effects
				(font
					(size 1.016 1.016)
					(thickness 0.1524)
				)
				(justify mirror)
			)
		)
		(duplicate_pad_numbers_are_jumpers no)
		(fp_line
			(start -0.635 0)
			(end 0.635 0)
			(stroke
				(width 0.508)
				(type default)
			)
			(layer "B.SilkS")
		)
		(fp_rect
			(start 0.9652 1.778)
			(end -0.9652 -1.778)
			(stroke
				(width 0)
				(type default)
			)
			(fill no)
			(layer "B.CrtYd")
		)
		(fp_poly
			(pts
				(xy 0.9652 -1.778) (xy -0.9652 -1.778) (xy -0.9652 1.778) (xy 0.9652 1.778)
			)
			(stroke
				(width 0)
				(type default)
			)
			(fill no)
			(layer "B.Fab")
		)
		(pad "1" smd rect
			(at 0 -0.9652)
			(size 1.397 1.143)
			(layers "B.Cu" "B.Mask" "B.Paste")
			(net "P3V3_STBY_A")
		)
		(pad "2" smd rect
			(at 0 0.9652)
			(size 1.397 1.143)
			(layers "B.Cu" "B.Mask" "B.Paste")
			(net "GND")
		)
	)
	(footprint ""
		(layer "B.Cu")
		(at 192.304416 -219.703142 -90)
		(property "Reference" "R1284"
			(at 0 0 90)
			(layer "B.SilkS")
			(hide yes)
			(effects
				(font
					(size 1.27 1.27)
				)
				(justify mirror)
			)
		)
		(property "Value" "10R3F-GP"
			(at 0.0254 -2.5146 270)
			(unlocked yes)
			(layer "B.Fab")
			(hide yes)
			(effects
				(font
					(size 1.016 1.016)
					(thickness 0.1524)
				)
				(justify mirror)
			)
		)
		(property "Device Type" "R603H22"
			(at 0.0254 -4.0386 270)
			(unlocked yes)
			(layer "B.Fab")
			(hide yes)
			(effects
				(font
					(size 1.016 1.016)
					(thickness 0.1524)
				)
				(justify mirror)
			)
		)
		(duplicate_pad_numbers_are_jumpers no)
		(fp_line
			(start -0.2032 0)
			(end -0.4826 0)
			(stroke
				(width 0.2032)
				(type default)
			)
			(layer "B.SilkS")
		)
		(fp_line
			(start 0.4826 0)
			(end 0.2032 0)
			(stroke
				(width 0.2032)
				(type default)
			)
			(layer "B.SilkS")
		)
		(fp_rect
			(start 0.5842 1.3335)
			(end -0.5842 -1.3335)
			(stroke
				(width 0)
				(type default)
			)
			(fill no)
			(layer "B.CrtYd")
		)
		(fp_rect
			(start 0.5842 1.3335)
			(end -0.5842 -1.3335)
			(stroke
				(width 0)
				(type default)
			)
			(fill no)
			(layer "B.Fab")
		)
		(pad "1" smd custom
			(at 0 -0.762 90)
			(size 0.2159 0.2159)
			(layers "B.Cu" "B.Mask" "B.Paste")
			(net "P3V3_STBY_CC")
			(options
				(clearance outline)
				(anchor circle)
			)
			(primitives
				(gr_poly
					(pts
						(arc
							(start -0.3302 0.4318)
							(mid -0.402042 0.402042)
							(end -0.4318 0.3302)
						)
						(arc
							(start -0.4318 -0.3302)
							(mid -0.402042 -0.402042)
							(end -0.3302 -0.4318)
						)
						(arc
							(start 0.3302 -0.4318)
							(mid 0.402042 -0.402042)
							(end 0.4318 -0.3302)
						)
						(arc
							(start 0.4318 0.3302)
							(mid 0.402042 0.402042)
							(end 0.3302 0.4318)
						)
					)
					(width 0)
					(fill yes)
				)
			)
		)
		(pad "2" smd custom
			(at 0 0.762 90)
			(size 0.2159 0.2159)
			(layers "B.Cu" "B.Mask" "B.Paste")
			(net "P3V3_STBY_CC_R")
			(options
				(clearance outline)
				(anchor circle)
			)
			(primitives
				(gr_poly
					(pts
						(arc
							(start -0.3302 0.4318)
							(mid -0.402042 0.402042)
							(end -0.4318 0.3302)
						)
						(arc
							(start -0.4318 -0.3302)
							(mid -0.402042 -0.402042)
							(end -0.3302 -0.4318)
						)
						(arc
							(start 0.3302 -0.4318)
							(mid 0.402042 -0.402042)
							(end 0.4318 -0.3302)
						)
						(arc
							(start 0.4318 0.3302)
							(mid 0.402042 0.402042)
							(end 0.3302 0.4318)
						)
					)
					(width 0)
					(fill yes)
				)
			)
		)
	)
	(footprint ""
		(layer "B.Cu")
		(at 189.905894 -220.688916 -90)
		(property "Reference" "C673"
			(at 0 0 90)
			(layer "B.SilkS")
			(hide yes)
			(effects
				(font
					(size 1.27 1.27)
				)
				(justify mirror)
			)
		)
		(property "Value" "SC100P50V2JN-3GP"
			(at -1.1811 -2.7051 270)
			(unlocked yes)
			(layer "B.Fab")
			(hide yes)
			(effects
				(font
					(size 1.016 1.016)
					(thickness 0.1524)
				)
				(justify mirror)
			)
		)
		(property "Device Type" "C402H22"
			(at -1.1811 -4.2291 270)
			(unlocked yes)
			(layer "B.Fab")
			(hide yes)
			(effects
				(font
					(size 1.016 1.016)
					(thickness 0.1524)
				)
				(justify mirror)
			)
		)
		(duplicate_pad_numbers_are_jumpers no)
		(fp_rect
			(start 0.4318 0.9525)
			(end -0.4318 -0.9525)
			(stroke
				(width 0)
				(type default)
			)
			(fill no)
			(layer "B.CrtYd")
		)
		(fp_rect
			(start 0.4318 0.9525)
			(end -0.4318 -0.9525)
			(stroke
				(width 0)
				(type default)
			)
			(fill no)
			(layer "B.Fab")
		)
		(pad "1" smd custom
			(at 0 -0.4445 90)
			(size 0.1524 0.1524)
			(layers "B.Cu" "B.Mask" "B.Paste")
			(net "P3V3_STBY_CC_R")
			(options
				(clearance outline)
				(anchor circle)
			)
			(primitives
				(gr_poly
					(pts
						(arc
							(start 0.3048 0.2032)
							(mid 0.275042 0.275042)
							(end 0.2032 0.3048)
						)
						(arc
							(start -0.2032 0.3048)
							(mid -0.275042 0.275042)
							(end -0.3048 0.2032)
						)
						(arc
							(start -0.3048 -0.2032)
							(mid -0.275042 -0.275042)
							(end -0.2032 -0.3048)
						)
						(arc
							(start 0.2032 -0.3048)
							(mid 0.275042 -0.275042)
							(end 0.3048 -0.2032)
						)
					)
					(width 0)
					(fill yes)
				)
			)
		)
		(pad "2" smd custom
			(at 0 0.4445 90)
			(size 0.1524 0.1524)
			(layers "B.Cu" "B.Mask" "B.Paste")
			(net "P3V3_STBY_VFB")
			(options
				(clearance outline)
				(anchor circle)
			)
			(primitives
				(gr_poly
					(pts
						(arc
							(start 0.3048 0.2032)
							(mid 0.275042 0.275042)
							(end 0.2032 0.3048)
						)
						(arc
							(start -0.2032 0.3048)
							(mid -0.275042 0.275042)
							(end -0.3048 0.2032)
						)
						(arc
							(start -0.3048 -0.2032)
							(mid -0.275042 -0.275042)
							(end -0.2032 -0.3048)
						)
						(arc
							(start 0.2032 -0.3048)
							(mid 0.275042 -0.275042)
							(end 0.3048 -0.2032)
						)
					)
					(width 0)
					(fill yes)
				)
			)
		)
	)
	(gr_line
		(start 30.025086 -278.385016)
		(end 31.359602 -278.385016)
		(stroke
			(width 0.0635)
			(type default)
		)
		(layer "F.Cu")
	)
	(gr_line
		(start 30.025086 -277.115016)
		(end 31.359602 -277.115016)
		(stroke
			(width 0.0635)
			(type default)
		)
		(layer "F.Cu")
	)
	(gr_line
		(start 30.025086 -274.575016)
		(end 31.359602 -274.575016)
		(stroke
			(width 0.0635)
			(type default)
		)
		(layer "F.Cu")
	)
	(gr_line
		(start 30.025086 -273.305016)
		(end 31.359602 -273.305016)
		(stroke
			(width 0.0635)
			(type default)
		)
		(layer "F.Cu")
	)
	(gr_line
		(start 30.025086 -163.384992)
		(end 31.359602 -163.384992)
		(stroke
			(width 0.0635)
			(type default)
		)
		(layer "F.Cu")
	)
	(gr_line
		(start 30.025086 -162.114992)
		(end 31.359602 -162.114992)
		(stroke
			(width 0.0635)
			(type default)
		)
		(layer "F.Cu")
	)
	(gr_line
		(start 30.025086 -159.574992)
		(end 31.359602 -159.574992)
		(stroke
			(width 0.0635)
			(type default)
		)
		(layer "F.Cu")
	)
	(gr_line
		(start 30.025086 -158.304992)
		(end 31.359602 -158.304992)
		(stroke
			(width 0.0635)
			(type default)
		)
		(layer "F.Cu")
	)
	(gr_line
		(start 30.025086 -48.384968)
		(end 31.329122 -48.384968)
		(stroke
			(width 0.0635)
			(type default)
		)
		(layer "F.Cu")
	)
	(gr_line
		(start 30.025086 -47.114968)
		(end 31.359602 -47.114968)
		(stroke
			(width 0.0635)
			(type default)
		)
		(layer "F.Cu")
	)
	(gr_line
		(start 30.025086 -44.574968)
		(end 31.359602 -44.574968)
		(stroke
			(width 0.0635)
			(type default)
		)
		(layer "F.Cu")
	)
	(gr_line
		(start 30.025086 -43.304968)
		(end 31.359602 -43.304968)
		(stroke
			(width 0.0635)
			(type default)
		)
		(layer "F.Cu")
	)
	(gr_line
		(start 31.329122 -48.384968)
		(end 31.486602 -48.227488)
		(stroke
			(width 0.0635)
			(type default)
		)
		(layer "F.Cu")
	)
	(gr_line
		(start 31.359602 -278.385016)
		(end 31.486602 -278.258016)
		(stroke
			(width 0.0635)
			(type default)
		)
		(layer "F.Cu")
	)
	(gr_line
		(start 31.359602 -277.115016)
		(end 31.486602 -277.242016)
		(stroke
			(width 0.0635)
			(type default)
		)
		(layer "F.Cu")
	)
	(gr_line
		(start 31.359602 -274.575016)
		(end 31.486602 -274.448016)
		(stroke
			(width 0.0635)
			(type default)
		)
		(layer "F.Cu")
	)
	(gr_line
		(start 31.359602 -273.305016)
		(end 31.486602 -273.432016)
		(stroke
			(width 0.0635)
			(type default)
		)
		(layer "F.Cu")
	)
	(gr_line
		(start 31.359602 -163.384992)
		(end 31.486602 -163.257992)
		(stroke
			(width 0.0635)
			(type default)
		)
		(layer "F.Cu")
	)
	(gr_line
		(start 31.359602 -162.114992)
		(end 31.486602 -162.241992)
		(stroke
			(width 0.0635)
			(type default)
		)
		(layer "F.Cu")
	)
	(gr_line
		(start 31.359602 -159.574992)
		(end 31.486602 -159.447992)
		(stroke
			(width 0.0635)
			(type default)
		)
		(layer "F.Cu")
	)
	(gr_line
		(start 31.359602 -158.304992)
		(end 31.486602 -158.431992)
		(stroke
			(width 0.0635)
			(type default)
		)
		(layer "F.Cu")
	)
	(gr_line
		(start 31.359602 -47.114968)
		(end 31.486602 -47.241968)
		(stroke
			(width 0.0635)
			(type default)
		)
		(layer "F.Cu")
	)
	(gr_line
		(start 31.359602 -44.574968)
		(end 31.486602 -44.447968)
		(stroke
			(width 0.0635)
			(type default)
		)
		(layer "F.Cu")
	)
	(gr_line
		(start 31.359602 -43.304968)
		(end 31.486602 -43.431968)
		(stroke
			(width 0.0635)
			(type default)
		)
		(layer "F.Cu")
	)
	(gr_line
		(start 31.486602 -278.023066)
		(end 31.486602 -278.258016)
		(stroke
			(width 0.0635)
			(type default)
		)
		(layer "F.Cu")
	)
	(gr_line
		(start 31.486602 -278.023066)
		(end 31.551372 -277.958296)
		(stroke
			(width 0.0635)
			(type default)
		)
		(layer "F.Cu")
	)
	(gr_line
		(start 31.486602 -277.476966)
		(end 31.551372 -277.541736)
		(stroke
			(width 0.0635)
			(type default)
		)
		(layer "F.Cu")
	)
	(gr_line
		(start 31.486602 -277.242016)
		(end 31.486602 -277.476966)
		(stroke
			(width 0.0635)
			(type default)
		)
		(layer "F.Cu")
	)
	(gr_line
		(start 31.486602 -274.213066)
		(end 31.486602 -274.448016)
		(stroke
			(width 0.0635)
			(type default)
		)
		(layer "F.Cu")
	)
	(gr_line
		(start 31.486602 -274.213066)
		(end 31.551372 -274.148296)
		(stroke
			(width 0.0635)
			(type default)
		)
		(layer "F.Cu")
	)
	(gr_line
		(start 31.486602 -273.666966)
		(end 31.551372 -273.731736)
		(stroke
			(width 0.0635)
			(type default)
		)
		(layer "F.Cu")
	)
	(gr_line
		(start 31.486602 -273.432016)
		(end 31.486602 -273.666966)
		(stroke
			(width 0.0635)
			(type default)
		)
		(layer "F.Cu")
	)
	(gr_line
		(start 31.486602 -163.023042)
		(end 31.486602 -163.257992)
		(stroke
			(width 0.0635)
			(type default)
		)
		(layer "F.Cu")
	)
	(gr_line
		(start 31.486602 -163.023042)
		(end 31.551372 -162.958272)
		(stroke
			(width 0.0635)
			(type default)
		)
		(layer "F.Cu")
	)
	(gr_line
		(start 31.486602 -162.476942)
		(end 31.551372 -162.541712)
		(stroke
			(width 0.0635)
			(type default)
		)
		(layer "F.Cu")
	)
	(gr_line
		(start 31.486602 -162.241992)
		(end 31.486602 -162.476942)
		(stroke
			(width 0.0635)
			(type default)
		)
		(layer "F.Cu")
	)
	(gr_line
		(start 31.486602 -159.213042)
		(end 31.486602 -159.447992)
		(stroke
			(width 0.0635)
			(type default)
		)
		(layer "F.Cu")
	)
	(gr_line
		(start 31.486602 -159.213042)
		(end 31.551372 -159.148272)
		(stroke
			(width 0.0635)
			(type default)
		)
		(layer "F.Cu")
	)
	(gr_line
		(start 31.486602 -158.666942)
		(end 31.551372 -158.731712)
		(stroke
			(width 0.0635)
			(type default)
		)
		(layer "F.Cu")
	)
	(gr_line
		(start 31.486602 -158.431992)
		(end 31.486602 -158.666942)
		(stroke
			(width 0.0635)
			(type default)
		)
		(layer "F.Cu")
	)
	(gr_line
		(start 31.486602 -48.023018)
		(end 31.486602 -48.227488)
		(stroke
			(width 0.0635)
			(type default)
		)
		(layer "F.Cu")
	)
	(gr_line
		(start 31.486602 -48.023018)
		(end 31.551372 -47.958248)
		(stroke
			(width 0.0635)
			(type default)
		)
		(layer "F.Cu")
	)
	(gr_line
		(start 31.486602 -47.476918)
		(end 31.551372 -47.541688)
		(stroke
			(width 0.0635)
			(type default)
		)
		(layer "F.Cu")
	)
	(gr_line
		(start 31.486602 -47.241968)
		(end 31.486602 -47.476918)
		(stroke
			(width 0.0635)
			(type default)
		)
		(layer "F.Cu")
	)
	(gr_line
		(start 31.486602 -44.213018)
		(end 31.486602 -44.447968)
		(stroke
			(width 0.0635)
			(type default)
		)
		(layer "F.Cu")
	)
	(gr_line
		(start 31.486602 -44.213018)
		(end 31.551372 -44.148248)
		(stroke
			(width 0.0635)
			(type default)
		)
		(layer "F.Cu")
	)
	(gr_line
		(start 31.486602 -43.666918)
		(end 31.551372 -43.731688)
		(stroke
			(width 0.0635)
			(type default)
		)
		(layer "F.Cu")
	)
	(gr_line
		(start 31.486602 -43.431968)
		(end 31.486602 -43.666918)
		(stroke
			(width 0.0635)
			(type default)
		)
		(layer "F.Cu")
	)
	(gr_line
		(start 31.728918 -274.095464)
		(end 31.85287 -274.219416)
		(stroke
			(width 0.0635)
			(type default)
		)
		(layer "F.Cu")
	)
	(gr_line
		(start 31.728918 -273.784568)
		(end 31.85287 -273.660616)
		(stroke
			(width 0.0635)
			(type default)
		)
		(layer "F.Cu")
	)
	(gr_line
		(start 31.728918 -159.09544)
		(end 31.85287 -159.219392)
		(stroke
			(width 0.0635)
			(type default)
		)
		(layer "F.Cu")
	)
	(gr_line
		(start 31.728918 -158.784544)
		(end 31.85287 -158.660592)
		(stroke
			(width 0.0635)
			(type default)
		)
		(layer "F.Cu")
	)
	(gr_line
		(start 31.728918 -44.095416)
		(end 31.85287 -44.219368)
		(stroke
			(width 0.0635)
			(type default)
		)
		(layer "F.Cu")
	)
	(gr_line
		(start 31.728918 -43.78452)
		(end 31.85287 -43.660568)
		(stroke
			(width 0.0635)
			(type default)
		)
		(layer "F.Cu")
	)
	(gr_line
		(start 31.85287 -274.219416)
		(end 32.184086 -274.219416)
		(stroke
			(width 0.0635)
			(type default)
		)
		(layer "F.Cu")
	)
	(gr_line
		(start 31.85287 -273.660616)
		(end 32.184086 -273.660616)
		(stroke
			(width 0.0635)
			(type default)
		)
		(layer "F.Cu")
	)
	(gr_line
		(start 31.85287 -159.219392)
		(end 32.184086 -159.219392)
		(stroke
			(width 0.0635)
			(type default)
		)
		(layer "F.Cu")
	)
	(gr_line
		(start 31.85287 -158.660592)
		(end 32.184086 -158.660592)
		(stroke
			(width 0.0635)
			(type default)
		)
		(layer "F.Cu")
	)
	(gr_line
		(start 31.85287 -44.219368)
		(end 32.184086 -44.219368)
		(stroke
			(width 0.0635)
			(type default)
		)
		(layer "F.Cu")
	)
	(gr_line
		(start 31.85287 -43.660568)
		(end 32.184086 -43.660568)
		(stroke
			(width 0.0635)
			(type default)
		)
		(layer "F.Cu")
	)
	(gr_arc
		(start 32.381952 -277.603966)
		(mid 32.471774 -277.566783)
		(end 32.508952 -277.476966)
		(stroke
			(width 0.0635)
			(type default)
		)
		(layer "F.Cu")
	)
	(gr_arc
		(start 32.381952 -162.603942)
		(mid 32.4718 -162.566764)
		(end 32.508952 -162.476942)
		(stroke
			(width 0.0635)
			(type default)
		)
		(layer "F.Cu")
	)
	(gr_arc
		(start 32.381952 -47.603918)
		(mid 32.471792 -47.566739)
		(end 32.508952 -47.476918)
		(stroke
			(width 0.0635)
			(type default)
		)
		(layer "F.Cu")
	)
	(gr_arc
		(start 32.508952 -278.023066)
		(mid 32.471755 -277.933263)
		(end 32.381952 -277.896066)
		(stroke
			(width 0.0635)
			(type default)
		)
		(layer "F.Cu")
	)
	(gr_line
		(start 32.508952 -278.023066)
		(end 32.508952 -278.321516)
		(stroke
			(width 0.0635)
			(type default)
		)
		(layer "F.Cu")
	)
	(gr_line
		(start 32.508952 -277.178516)
		(end 32.508952 -277.476966)
		(stroke
			(width 0.0635)
			(type default)
		)
		(layer "F.Cu")
	)
	(gr_arc
		(start 32.508952 -163.023042)
		(mid 32.471755 -162.933239)
		(end 32.381952 -162.896042)
		(stroke
			(width 0.0635)
			(type default)
		)
		(layer "F.Cu")
	)
	(gr_line
		(start 32.508952 -163.023042)
		(end 32.508952 -163.321492)
		(stroke
			(width 0.0635)
			(type default)
		)
		(layer "F.Cu")
	)
	(gr_line
		(start 32.508952 -162.178492)
		(end 32.508952 -162.476942)
		(stroke
			(width 0.0635)
			(type default)
		)
		(layer "F.Cu")
	)
	(gr_arc
		(start 32.508952 -48.023018)
		(mid 32.471755 -47.933215)
		(end 32.381952 -47.896018)
		(stroke
			(width 0.0635)
			(type default)
		)
		(layer "F.Cu")
	)
	(gr_line
		(start 32.508952 -48.023018)
		(end 32.508952 -48.321468)
		(stroke
			(width 0.0635)
			(type default)
		)
		(layer "F.Cu")
	)
	(gr_line
		(start 32.508952 -47.178468)
		(end 32.508952 -47.476918)
		(stroke
			(width 0.0635)
			(type default)
		)
		(layer "F.Cu")
	)
	(gr_line
		(start 32.742886 -274.219416)
		(end 33.150302 -274.219416)
		(stroke
			(width 0.0635)
			(type default)
		)
		(layer "F.Cu")
	)
	(gr_line
		(start 32.742886 -273.660616)
		(end 33.150302 -273.660616)
		(stroke
			(width 0.0635)
			(type default)
		)
		(layer "F.Cu")
	)
	(gr_line
		(start 32.742886 -159.219392)
		(end 33.251902 -159.219392)
		(stroke
			(width 0.0635)
			(type default)
		)
		(layer "F.Cu")
	)
	(gr_line
		(start 32.742886 -158.660592)
		(end 33.251902 -158.660592)
		(stroke
			(width 0.0635)
			(type default)
		)
		(layer "F.Cu")
	)
	(gr_line
		(start 32.742886 -44.219368)
		(end 33.201102 -44.219368)
		(stroke
			(width 0.0635)
			(type default)
		)
		(layer "F.Cu")
	)
	(gr_line
		(start 32.742886 -43.660568)
		(end 33.201102 -43.660568)
		(stroke
			(width 0.0635)
			(type default)
		)
		(layer "F.Cu")
	)
	(gr_line
		(start 33.150302 -274.219416)
		(end 33.221422 -274.148296)
		(stroke
			(width 0.0635)
			(type default)
		)
		(layer "F.Cu")
	)
	(gr_line
		(start 33.150302 -273.660616)
		(end 33.221422 -273.731736)
		(stroke
			(width 0.0635)
			(type default)
		)
		(layer "F.Cu")
	)
	(gr_line
		(start 33.201102 -44.219368)
		(end 33.272222 -44.148248)
		(stroke
			(width 0.0635)
			(type default)
		)
		(layer "F.Cu")
	)
	(gr_line
		(start 33.201102 -43.660568)
		(end 33.272222 -43.731688)
		(stroke
			(width 0.0635)
			(type default)
		)
		(layer "F.Cu")
	)
	(gr_line
		(start 33.251902 -159.219392)
		(end 33.323022 -159.148272)
		(stroke
			(width 0.0635)
			(type default)
		)
		(layer "F.Cu")
	)
	(gr_line
		(start 33.251902 -158.660592)
		(end 33.323022 -158.731712)
		(stroke
			(width 0.0635)
			(type default)
		)
		(layer "F.Cu")
	)
	(gr_line
		(start 33.59023 -43.822874)
		(end 33.6296 -43.847766)
		(stroke
			(width 0.0635)
			(type default)
		)
		(layer "F.Cu")
	)
	(gr_line
		(start 33.980374 -44.069762)
		(end 33.996884 -44.080176)
		(stroke
			(width 0.0635)
			(type default)
		)
		(layer "F.Cu")
	)
	(gr_line
		(start 33.996884 -44.080176)
		(end 34.008314 -44.096178)
		(stroke
			(width 0.0635)
			(type default)
		)
		(layer "F.Cu")
	)
	(gr_line
		(start 34.012378 -273.825208)
		(end 34.051748 -273.8501)
		(stroke
			(width 0.0635)
			(type default)
		)
		(layer "F.Cu")
	)
	(gr_line
		(start 34.331656 -158.935166)
		(end 34.344102 -158.93796)
		(stroke
			(width 0.0635)
			(type default)
		)
		(layer "F.Cu")
	)
	(gr_line
		(start 34.344102 -158.93796)
		(end 34.355278 -158.945072)
		(stroke
			(width 0.0635)
			(type default)
		)
		(layer "F.Cu")
	)
	(gr_line
		(start 35.02533 -159.371792)
		(end 35.047428 -159.386016)
		(stroke
			(width 0.0635)
			(type default)
		)
		(layer "F.Cu")
	)
	(gr_line
		(start 35.047428 -159.386016)
		(end 35.061652 -159.408114)
		(stroke
			(width 0.0635)
			(type default)
		)
		(layer "F.Cu")
	)
	(gr_line
		(start 35.182556 -274.56638)
		(end 35.234372 -274.598892)
		(stroke
			(width 0.0635)
			(type default)
		)
		(layer "F.Cu")
	)
	(gr_line
		(start 35.234372 -274.598892)
		(end 35.255962 -274.657312)
		(stroke
			(width 0.0635)
			(type default)
		)
		(layer "F.Cu")
	)
	(gr_line
		(start 35.596322 -46.34738)
		(end 35.596576 -46.347888)
		(stroke
			(width 0.0635)
			(type default)
		)
		(layer "F.Cu")
	)
	(gr_line
		(start 35.596576 -46.347888)
		(end 35.59683 -46.348396)
		(stroke
			(width 0.0635)
			(type default)
		)
		(layer "F.Cu")
	)
	(gr_line
		(start 37.294312 -162.912806)
		(end 37.301424 -162.923982)
		(stroke
			(width 0.0635)
			(type default)
		)
		(layer "F.Cu")
	)
	(gr_line
		(start 37.301424 -162.923982)
		(end 37.304218 -162.936428)
		(stroke
			(width 0.0635)
			(type default)
		)
		(layer "F.Cu")
	)
	(gr_line
		(start 40.400986 -178.255676)
		(end 40.418766 -178.336702)
		(stroke
			(width 0.0635)
			(type default)
		)
		(layer "F.Cu")
	)
	(gr_line
		(start 40.418766 -178.336702)
		(end 40.461692 -178.364388)
		(stroke
			(width 0.0635)
			(type default)
		)
		(layer "F.Cu")
	)
	(gr_line
		(start 40.681656 -178.160934)
		(end 40.693594 -178.17973)
		(stroke
			(width 0.0635)
			(type default)
		)
		(layer "F.Cu")
	)
	(gr_line
		(start 41.630092 -63.547752)
		(end 41.632378 -63.553848)
		(stroke
			(width 0.0635)
			(type default)
		)
		(layer "F.Cu")
	)
	(gr_line
		(start 41.632378 -63.553848)
		(end 41.636442 -63.559182)
		(stroke
			(width 0.0635)
			(type default)
		)
		(layer "F.Cu")
	)
	(gr_line
		(start 54.23916 -199.98817)
		(end 54.253384 -200.010268)
		(stroke
			(width 0.0635)
			(type default)
		)
		(layer "F.Cu")
	)
	(gr_line
		(start 54.253384 -200.010268)
		(end 54.275482 -200.024492)
		(stroke
			(width 0.0635)
			(type default)
		)
		(layer "F.Cu")
	)
	(gr_line
		(start 56.607964 -317.483998)
		(end 56.624982 -317.509906)
		(stroke
			(width 0.0635)
			(type default)
		)
		(layer "F.Cu")
	)
	(gr_line
		(start 56.624982 -317.509906)
		(end 56.651398 -317.526162)
		(stroke
			(width 0.0635)
			(type default)
		)
		(layer "F.Cu")
	)
	(gr_line
		(start 58.902854 -85.841078)
		(end 58.911236 -85.851746)
		(stroke
			(width 0.0635)
			(type default)
		)
		(layer "F.Cu")
	)
	(gr_line
		(start 58.911236 -85.851746)
		(end 58.922666 -85.859112)
		(stroke
			(width 0.0635)
			(type default)
		)
		(layer "F.Cu")
	)
	(gr_line
		(start 61.574934 -278.385016)
		(end 62.90945 -278.385016)
		(stroke
			(width 0.0635)
			(type default)
		)
		(layer "F.Cu")
	)
	(gr_line
		(start 61.574934 -277.115016)
		(end 62.90945 -277.115016)
		(stroke
			(width 0.0635)
			(type default)
		)
		(layer "F.Cu")
	)
	(gr_line
		(start 61.574934 -274.575016)
		(end 62.90945 -274.575016)
		(stroke
			(width 0.0635)
			(type default)
		)
		(layer "F.Cu")
	)
	(gr_line
		(start 61.574934 -273.305016)
		(end 62.90945 -273.305016)
		(stroke
			(width 0.0635)
			(type default)
		)
		(layer "F.Cu")
	)
	(gr_line
		(start 61.574934 -163.384992)
		(end 62.90945 -163.384992)
		(stroke
			(width 0.0635)
			(type default)
		)
		(layer "F.Cu")
	)
	(gr_line
		(start 61.574934 -162.114992)
		(end 62.90945 -162.114992)
		(stroke
			(width 0.0635)
			(type default)
		)
		(layer "F.Cu")
	)
	(gr_line
		(start 61.574934 -159.574992)
		(end 62.90945 -159.574992)
		(stroke
			(width 0.0635)
			(type default)
		)
		(layer "F.Cu")
	)
	(gr_line
		(start 61.574934 -158.304992)
		(end 62.90945 -158.304992)
		(stroke
			(width 0.0635)
			(type default)
		)
		(layer "F.Cu")
	)
	(gr_line
		(start 61.574934 -48.384968)
		(end 62.90945 -48.384968)
		(stroke
			(width 0.0635)
			(type default)
		)
		(layer "F.Cu")
	)
	(gr_line
		(start 61.574934 -47.114968)
		(end 62.90945 -47.114968)
		(stroke
			(width 0.0635)
			(type default)
		)
		(layer "F.Cu")
	)
	(gr_line
		(start 61.574934 -44.574968)
		(end 62.90945 -44.574968)
		(stroke
			(width 0.0635)
			(type default)
		)
		(layer "F.Cu")
	)
	(gr_line
		(start 61.574934 -43.304968)
		(end 62.90945 -43.304968)
		(stroke
			(width 0.0635)
			(type default)
		)
		(layer "F.Cu")
	)
	(gr_line
		(start 62.90945 -278.385016)
		(end 63.03645 -278.258016)
		(stroke
			(width 0.0635)
			(type default)
		)
		(layer "F.Cu")
	)
	(gr_line
		(start 62.90945 -277.115016)
		(end 63.03645 -277.242016)
		(stroke
			(width 0.0635)
			(type default)
		)
		(layer "F.Cu")
	)
	(gr_line
		(start 62.90945 -274.575016)
		(end 63.03645 -274.448016)
		(stroke
			(width 0.0635)
			(type default)
		)
		(layer "F.Cu")
	)
	(gr_line
		(start 62.90945 -273.305016)
		(end 63.03645 -273.432016)
		(stroke
			(width 0.0635)
			(type default)
		)
		(layer "F.Cu")
	)
	(gr_line
		(start 62.90945 -163.384992)
		(end 63.03645 -163.257992)
		(stroke
			(width 0.0635)
			(type default)
		)
		(layer "F.Cu")
	)
	(gr_line
		(start 62.90945 -162.114992)
		(end 63.03645 -162.241992)
		(stroke
			(width 0.0635)
			(type default)
		)
		(layer "F.Cu")
	)
	(gr_line
		(start 62.90945 -159.574992)
		(end 63.03645 -159.447992)
		(stroke
			(width 0.0635)
			(type default)
		)
		(layer "F.Cu")
	)
	(gr_line
		(start 62.90945 -158.304992)
		(end 63.03645 -158.431992)
		(stroke
			(width 0.0635)
			(type default)
		)
		(layer "F.Cu")
	)
	(gr_line
		(start 62.90945 -48.384968)
		(end 63.03645 -48.257968)
		(stroke
			(width 0.0635)
			(type default)
		)
		(layer "F.Cu")
	)
	(gr_line
		(start 62.90945 -47.114968)
		(end 63.03645 -47.241968)
		(stroke
			(width 0.0635)
			(type default)
		)
		(layer "F.Cu")
	)
	(gr_line
		(start 62.90945 -44.574968)
		(end 63.03645 -44.447968)
		(stroke
			(width 0.0635)
			(type default)
		)
		(layer "F.Cu")
	)
	(gr_line
		(start 62.90945 -43.304968)
		(end 63.03645 -43.431968)
		(stroke
			(width 0.0635)
			(type default)
		)
		(layer "F.Cu")
	)
	(gr_line
		(start 63.03645 -278.023066)
		(end 63.03645 -278.258016)
		(stroke
			(width 0.0635)
			(type default)
		)
		(layer "F.Cu")
	)
	(gr_line
		(start 63.03645 -278.023066)
		(end 63.10122 -277.958296)
		(stroke
			(width 0.0635)
			(type default)
		)
		(layer "F.Cu")
	)
	(gr_line
		(start 63.03645 -277.476966)
		(end 63.10122 -277.541736)
		(stroke
			(width 0.0635)
			(type default)
		)
		(layer "F.Cu")
	)
	(gr_line
		(start 63.03645 -277.242016)
		(end 63.03645 -277.476966)
		(stroke
			(width 0.0635)
			(type default)
		)
		(layer "F.Cu")
	)
	(gr_line
		(start 63.03645 -274.213066)
		(end 63.03645 -274.448016)
		(stroke
			(width 0.0635)
			(type default)
		)
		(layer "F.Cu")
	)
	(gr_line
		(start 63.03645 -274.213066)
		(end 63.10122 -274.148296)
		(stroke
			(width 0.0635)
			(type default)
		)
		(layer "F.Cu")
	)
	(gr_line
		(start 63.03645 -273.666966)
		(end 63.10122 -273.731736)
		(stroke
			(width 0.0635)
			(type default)
		)
		(layer "F.Cu")
	)
	(gr_line
		(start 63.03645 -273.432016)
		(end 63.03645 -273.666966)
		(stroke
			(width 0.0635)
			(type default)
		)
		(layer "F.Cu")
	)
	(gr_line
		(start 63.03645 -163.023042)
		(end 63.03645 -163.257992)
		(stroke
			(width 0.0635)
			(type default)
		)
		(layer "F.Cu")
	)
	(gr_line
		(start 63.03645 -163.023042)
		(end 63.10122 -162.958272)
		(stroke
			(width 0.0635)
			(type default)
		)
		(layer "F.Cu")
	)
	(gr_line
		(start 63.03645 -162.476942)
		(end 63.10122 -162.541712)
		(stroke
			(width 0.0635)
			(type default)
		)
		(layer "F.Cu")
	)
	(gr_line
		(start 63.03645 -162.241992)
		(end 63.03645 -162.476942)
		(stroke
			(width 0.0635)
			(type default)
		)
		(layer "F.Cu")
	)
	(gr_line
		(start 63.03645 -159.213042)
		(end 63.03645 -159.447992)
		(stroke
			(width 0.0635)
			(type default)
		)
		(layer "F.Cu")
	)
	(gr_line
		(start 63.03645 -159.213042)
		(end 63.10122 -159.148272)
		(stroke
			(width 0.0635)
			(type default)
		)
		(layer "F.Cu")
	)
	(gr_line
		(start 63.03645 -158.666942)
		(end 63.10122 -158.731712)
		(stroke
			(width 0.0635)
			(type default)
		)
		(layer "F.Cu")
	)
	(gr_line
		(start 63.03645 -158.431992)
		(end 63.03645 -158.666942)
		(stroke
			(width 0.0635)
			(type default)
		)
		(layer "F.Cu")
	)
	(gr_line
		(start 63.03645 -48.05807)
		(end 63.03645 -48.257968)
		(stroke
			(width 0.0635)
			(type default)
		)
		(layer "F.Cu")
	)
	(gr_line
		(start 63.03645 -48.05807)
		(end 63.118746 -47.975774)
		(stroke
			(width 0.0635)
			(type default)
		)
		(layer "F.Cu")
	)
	(gr_line
		(start 63.03645 -47.476918)
		(end 63.118746 -47.559214)
		(stroke
			(width 0.0635)
			(type default)
		)
		(layer "F.Cu")
	)
	(gr_line
		(start 63.03645 -47.241968)
		(end 63.03645 -47.476918)
		(stroke
			(width 0.0635)
			(type default)
		)
		(layer "F.Cu")
	)
	(gr_line
		(start 63.03645 -44.213018)
		(end 63.03645 -44.447968)
		(stroke
			(width 0.0635)
			(type default)
		)
		(layer "F.Cu")
	)
	(gr_line
		(start 63.03645 -44.213018)
		(end 63.10122 -44.148248)
		(stroke
			(width 0.0635)
			(type default)
		)
		(layer "F.Cu")
	)
	(gr_line
		(start 63.03645 -43.666918)
		(end 63.10122 -43.731688)
		(stroke
			(width 0.0635)
			(type default)
		)
		(layer "F.Cu")
	)
	(gr_line
		(start 63.03645 -43.431968)
		(end 63.03645 -43.666918)
		(stroke
			(width 0.0635)
			(type default)
		)
		(layer "F.Cu")
	)
	(gr_line
		(start 63.278766 -274.095464)
		(end 63.402718 -274.219416)
		(stroke
			(width 0.0635)
			(type default)
		)
		(layer "F.Cu")
	)
	(gr_line
		(start 63.278766 -273.784568)
		(end 63.402718 -273.660616)
		(stroke
			(width 0.0635)
			(type default)
		)
		(layer "F.Cu")
	)
	(gr_line
		(start 63.278766 -159.09544)
		(end 63.402718 -159.219392)
		(stroke
			(width 0.0635)
			(type default)
		)
		(layer "F.Cu")
	)
	(gr_line
		(start 63.278766 -158.784544)
		(end 63.402718 -158.660592)
		(stroke
			(width 0.0635)
			(type default)
		)
		(layer "F.Cu")
	)
	(gr_line
		(start 63.278766 -44.095416)
		(end 63.402718 -44.219368)
		(stroke
			(width 0.0635)
			(type default)
		)
		(layer "F.Cu")
	)
	(gr_line
		(start 63.278766 -43.78452)
		(end 63.402718 -43.660568)
		(stroke
			(width 0.0635)
			(type default)
		)
		(layer "F.Cu")
	)
	(gr_line
		(start 63.402718 -274.219416)
		(end 63.733934 -274.219416)
		(stroke
			(width 0.0635)
			(type default)
		)
		(layer "F.Cu")
	)
	(gr_line
		(start 63.402718 -273.660616)
		(end 63.733934 -273.660616)
		(stroke
			(width 0.0635)
			(type default)
		)
		(layer "F.Cu")
	)
	(gr_line
		(start 63.402718 -159.219392)
		(end 63.733934 -159.219392)
		(stroke
			(width 0.0635)
			(type default)
		)
		(layer "F.Cu")
	)
	(gr_line
		(start 63.402718 -158.660592)
		(end 63.733934 -158.660592)
		(stroke
			(width 0.0635)
			(type default)
		)
		(layer "F.Cu")
	)
	(gr_line
		(start 63.402718 -44.219368)
		(end 63.733934 -44.219368)
		(stroke
			(width 0.0635)
			(type default)
		)
		(layer "F.Cu")
	)
	(gr_line
		(start 63.402718 -43.660568)
		(end 63.733934 -43.660568)
		(stroke
			(width 0.0635)
			(type default)
		)
		(layer "F.Cu")
	)
	(gr_arc
		(start 63.9318 -277.603966)
		(mid 64.021591 -277.566767)
		(end 64.0588 -277.476966)
		(stroke
			(width 0.0635)
			(type default)
		)
		(layer "F.Cu")
	)
	(gr_arc
		(start 63.9318 -162.603942)
		(mid 64.021617 -162.566747)
		(end 64.0588 -162.476942)
		(stroke
			(width 0.0635)
			(type default)
		)
		(layer "F.Cu")
	)
	(gr_arc
		(start 63.9318 -47.603918)
		(mid 64.021609 -47.566722)
		(end 64.0588 -47.476918)
		(stroke
			(width 0.0635)
			(type default)
		)
		(layer "F.Cu")
	)
	(gr_arc
		(start 64.0588 -278.023066)
		(mid 64.021603 -277.933263)
		(end 63.9318 -277.896066)
		(stroke
			(width 0.0635)
			(type default)
		)
		(layer "F.Cu")
	)
	(gr_line
		(start 64.0588 -278.023066)
		(end 64.0588 -278.321516)
		(stroke
			(width 0.0635)
			(type default)
		)
		(layer "F.Cu")
	)
	(gr_line
		(start 64.0588 -277.178516)
		(end 64.0588 -277.476966)
		(stroke
			(width 0.0635)
			(type default)
		)
		(layer "F.Cu")
	)
	(gr_arc
		(start 64.0588 -163.023042)
		(mid 64.021603 -162.933239)
		(end 63.9318 -162.896042)
		(stroke
			(width 0.0635)
			(type default)
		)
		(layer "F.Cu")
	)
	(gr_line
		(start 64.0588 -163.023042)
		(end 64.0588 -163.321492)
		(stroke
			(width 0.0635)
			(type default)
		)
		(layer "F.Cu")
	)
	(gr_line
		(start 64.0588 -162.178492)
		(end 64.0588 -162.476942)
		(stroke
			(width 0.0635)
			(type default)
		)
		(layer "F.Cu")
	)
	(gr_arc
		(start 64.0588 -48.023018)
		(mid 64.021603 -47.933215)
		(end 63.9318 -47.896018)
		(stroke
			(width 0.0635)
			(type default)
		)
		(layer "F.Cu")
	)
	(gr_line
		(start 64.0588 -48.023018)
		(end 64.0588 -48.321468)
		(stroke
			(width 0.0635)
			(type default)
		)
		(layer "F.Cu")
	)
	(gr_line
		(start 64.0588 -47.178468)
		(end 64.0588 -47.476918)
		(stroke
			(width 0.0635)
			(type default)
		)
		(layer "F.Cu")
	)
	(gr_line
		(start 64.292734 -274.219416)
		(end 64.85255 -274.219416)
		(stroke
			(width 0.0635)
			(type default)
		)
		(layer "F.Cu")
	)
	(gr_line
		(start 64.292734 -273.660616)
		(end 64.85255 -273.660616)
		(stroke
			(width 0.0635)
			(type default)
		)
		(layer "F.Cu")
	)
	(gr_line
		(start 64.292734 -159.219392)
		(end 64.90335 -159.219392)
		(stroke
			(width 0.0635)
			(type default)
		)
		(layer "F.Cu")
	)
	(gr_line
		(start 64.292734 -158.660592)
		(end 64.90335 -158.660592)
		(stroke
			(width 0.0635)
			(type default)
		)
		(layer "F.Cu")
	)
	(gr_line
		(start 64.292734 -44.219368)
		(end 64.75095 -44.219368)
		(stroke
			(width 0.0635)
			(type default)
		)
		(layer "F.Cu")
	)
	(gr_line
		(start 64.292734 -43.660568)
		(end 64.75095 -43.660568)
		(stroke
			(width 0.0635)
			(type default)
		)
		(layer "F.Cu")
	)
	(gr_line
		(start 64.75095 -44.219368)
		(end 64.82207 -44.148248)
		(stroke
			(width 0.0635)
			(type default)
		)
		(layer "F.Cu")
	)
	(gr_line
		(start 64.75095 -43.660568)
		(end 64.82207 -43.731688)
		(stroke
			(width 0.0635)
			(type default)
		)
		(layer "F.Cu")
	)
	(gr_line
		(start 64.85255 -274.219416)
		(end 64.92367 -274.148296)
		(stroke
			(width 0.0635)
			(type default)
		)
		(layer "F.Cu")
	)
	(gr_line
		(start 64.85255 -273.660616)
		(end 64.92367 -273.731736)
		(stroke
			(width 0.0635)
			(type default)
		)
		(layer "F.Cu")
	)
	(gr_line
		(start 64.90335 -159.219392)
		(end 64.97447 -159.148272)
		(stroke
			(width 0.0635)
			(type default)
		)
		(layer "F.Cu")
	)
	(gr_line
		(start 64.90335 -158.660592)
		(end 64.97447 -158.731712)
		(stroke
			(width 0.0635)
			(type default)
		)
		(layer "F.Cu")
	)
	(gr_line
		(start 65.386712 -43.817032)
		(end 65.426082 -43.841924)
		(stroke
			(width 0.0635)
			(type default)
		)
		(layer "F.Cu")
	)
	(gr_line
		(start 65.481708 -273.827494)
		(end 65.521078 -273.852386)
		(stroke
			(width 0.0635)
			(type default)
		)
		(layer "F.Cu")
	)
	(gr_line
		(start 65.823592 -158.889446)
		(end 65.836038 -158.89224)
		(stroke
			(width 0.0635)
			(type default)
		)
		(layer "F.Cu")
	)
	(gr_line
		(start 65.836038 -158.89224)
		(end 65.847214 -158.899352)
		(stroke
			(width 0.0635)
			(type default)
		)
		(layer "F.Cu")
	)
	(gr_line
		(start 66.32575 -44.4119)
		(end 66.377566 -44.444412)
		(stroke
			(width 0.0635)
			(type default)
		)
		(layer "F.Cu")
	)
	(gr_line
		(start 66.377566 -44.444412)
		(end 66.399156 -44.502832)
		(stroke
			(width 0.0635)
			(type default)
		)
		(layer "F.Cu")
	)
	(gr_line
		(start 66.5988 -274.534884)
		(end 66.651632 -274.568412)
		(stroke
			(width 0.0635)
			(type default)
		)
		(layer "F.Cu")
	)
	(gr_line
		(start 66.651632 -274.568412)
		(end 66.673222 -274.626832)
		(stroke
			(width 0.0635)
			(type default)
		)
		(layer "F.Cu")
	)
	(gr_line
		(start 66.948812 -159.601154)
		(end 66.97091 -159.615378)
		(stroke
			(width 0.0635)
			(type default)
		)
		(layer "F.Cu")
	)
	(gr_line
		(start 66.97091 -159.615378)
		(end 66.985134 -159.637476)
		(stroke
			(width 0.0635)
			(type default)
		)
		(layer "F.Cu")
	)
	(gr_line
		(start 68.297298 -161.6964)
		(end 68.30441 -161.707576)
		(stroke
			(width 0.0635)
			(type default)
		)
		(layer "F.Cu")
	)
	(gr_line
		(start 68.30441 -161.707576)
		(end 68.307204 -161.720022)
		(stroke
			(width 0.0635)
			(type default)
		)
		(layer "F.Cu")
	)
	(gr_line
		(start 72.155304 -180.433218)
		(end 72.155812 -180.433218)
		(stroke
			(width 0.0635)
			(type default)
		)
		(layer "F.Cu")
	)
	(gr_line
		(start 72.43572 -180.345842)
		(end 72.435974 -180.345842)
		(stroke
			(width 0.0635)
			(type default)
		)
		(layer "F.Cu")
	)
	(gr_line
		(start 83.046824 -78.948534)
		(end 83.058254 -78.96606)
		(stroke
			(width 0.0635)
			(type default)
		)
		(layer "F.Cu")
	)
	(gr_line
		(start 83.058254 -78.96606)
		(end 83.075526 -78.977998)
		(stroke
			(width 0.0635)
			(type default)
		)
		(layer "F.Cu")
	)
	(gr_line
		(start 87.926926 -82.322416)
		(end 87.943944 -82.3341)
		(stroke
			(width 0.0635)
			(type default)
		)
		(layer "F.Cu")
	)
	(gr_line
		(start 87.943944 -82.3341)
		(end 87.963248 -82.338164)
		(stroke
			(width 0.0635)
			(type default)
		)
		(layer "F.Cu")
	)
	(gr_line
		(start 88.608662 -334.956404)
		(end 88.629236 -335.012284)
		(stroke
			(width 0.0635)
			(type default)
		)
		(layer "F.Cu")
	)
	(gr_line
		(start 88.629236 -335.012284)
		(end 88.68029 -335.044542)
		(stroke
			(width 0.0635)
			(type default)
		)
		(layer "F.Cu")
	)
	(gr_line
		(start 89.027762 -219.797122)
		(end 89.04478 -219.823792)
		(stroke
			(width 0.0635)
			(type default)
		)
		(layer "F.Cu")
	)
	(gr_line
		(start 89.04478 -219.823792)
		(end 89.071704 -219.840302)
		(stroke
			(width 0.0635)
			(type default)
		)
		(layer "F.Cu")
	)
	(gr_line
		(start 93.125036 -278.385016)
		(end 94.459552 -278.385016)
		(stroke
			(width 0.0635)
			(type default)
		)
		(layer "F.Cu")
	)
	(gr_line
		(start 93.125036 -277.115016)
		(end 94.459552 -277.115016)
		(stroke
			(width 0.0635)
			(type default)
		)
		(layer "F.Cu")
	)
	(gr_line
		(start 93.125036 -274.575016)
		(end 94.459552 -274.575016)
		(stroke
			(width 0.0635)
			(type default)
		)
		(layer "F.Cu")
	)
	(gr_line
		(start 93.125036 -273.305016)
		(end 94.459552 -273.305016)
		(stroke
			(width 0.0635)
			(type default)
		)
		(layer "F.Cu")
	)
	(gr_line
		(start 93.125036 -163.384992)
		(end 94.459552 -163.384992)
		(stroke
			(width 0.0635)
			(type default)
		)
		(layer "F.Cu")
	)
	(gr_line
		(start 93.125036 -162.114992)
		(end 94.459552 -162.114992)
		(stroke
			(width 0.0635)
			(type default)
		)
		(layer "F.Cu")
	)
	(gr_line
		(start 93.125036 -159.574992)
		(end 94.459552 -159.574992)
		(stroke
			(width 0.0635)
			(type default)
		)
		(layer "F.Cu")
	)
	(gr_line
		(start 93.125036 -158.304992)
		(end 94.459552 -158.304992)
		(stroke
			(width 0.0635)
			(type default)
		)
		(layer "F.Cu")
	)
	(gr_line
		(start 93.125036 -48.384968)
		(end 94.459552 -48.384968)
		(stroke
			(width 0.0635)
			(type default)
		)
		(layer "F.Cu")
	)
	(gr_line
		(start 93.125036 -47.114968)
		(end 94.459552 -47.114968)
		(stroke
			(width 0.0635)
			(type default)
		)
		(layer "F.Cu")
	)
	(gr_line
		(start 93.125036 -44.574968)
		(end 94.459552 -44.574968)
		(stroke
			(width 0.0635)
			(type default)
		)
		(layer "F.Cu")
	)
	(gr_line
		(start 93.125036 -43.304968)
		(end 94.459552 -43.304968)
		(stroke
			(width 0.0635)
			(type default)
		)
		(layer "F.Cu")
	)
	(gr_line
		(start 93.445584 -339.922612)
		(end 93.457268 -339.929724)
		(stroke
			(width 0.0635)
			(type default)
		)
		(layer "F.Cu")
	)
	(gr_line
		(start 93.457268 -339.929724)
		(end 93.469714 -339.93201)
		(stroke
			(width 0.0635)
			(type default)
		)
		(layer "F.Cu")
	)
	(gr_line
		(start 93.897196 -338.345018)
		(end 93.910912 -338.353654)
		(stroke
			(width 0.0635)
			(type default)
		)
		(layer "F.Cu")
	)
	(gr_line
		(start 93.910912 -338.353654)
		(end 93.925898 -338.356448)
		(stroke
			(width 0.0635)
			(type default)
		)
		(layer "F.Cu")
	)
	(gr_line
		(start 94.40291 -108.462572)
		(end 94.411292 -108.467906)
		(stroke
			(width 0.0635)
			(type default)
		)
		(layer "F.Cu")
	)
	(gr_line
		(start 94.411292 -108.467906)
		(end 94.420436 -108.470192)
		(stroke
			(width 0.0635)
			(type default)
		)
		(layer "F.Cu")
	)
	(gr_line
		(start 94.459552 -278.385016)
		(end 94.586552 -278.258016)
		(stroke
			(width 0.0635)
			(type default)
		)
		(layer "F.Cu")
	)
	(gr_line
		(start 94.459552 -277.115016)
		(end 94.586552 -277.242016)
		(stroke
			(width 0.0635)
			(type default)
		)
		(layer "F.Cu")
	)
	(gr_line
		(start 94.459552 -274.575016)
		(end 94.586552 -274.448016)
		(stroke
			(width 0.0635)
			(type default)
		)
		(layer "F.Cu")
	)
	(gr_line
		(start 94.459552 -273.305016)
		(end 94.586552 -273.432016)
		(stroke
			(width 0.0635)
			(type default)
		)
		(layer "F.Cu")
	)
	(gr_line
		(start 94.459552 -163.384992)
		(end 94.586552 -163.257992)
		(stroke
			(width 0.0635)
			(type default)
		)
		(layer "F.Cu")
	)
	(gr_line
		(start 94.459552 -162.114992)
		(end 94.586552 -162.241992)
		(stroke
			(width 0.0635)
			(type default)
		)
		(layer "F.Cu")
	)
	(gr_line
		(start 94.459552 -159.574992)
		(end 94.586552 -159.447992)
		(stroke
			(width 0.0635)
			(type default)
		)
		(layer "F.Cu")
	)
	(gr_line
		(start 94.459552 -158.304992)
		(end 94.586552 -158.431992)
		(stroke
			(width 0.0635)
			(type default)
		)
		(layer "F.Cu")
	)
	(gr_line
		(start 94.459552 -48.384968)
		(end 94.586552 -48.257968)
		(stroke
			(width 0.0635)
			(type default)
		)
		(layer "F.Cu")
	)
	(gr_line
		(start 94.459552 -47.114968)
		(end 94.586552 -47.241968)
		(stroke
			(width 0.0635)
			(type default)
		)
		(layer "F.Cu")
	)
	(gr_line
		(start 94.459552 -44.574968)
		(end 94.586552 -44.447968)
		(stroke
			(width 0.0635)
			(type default)
		)
		(layer "F.Cu")
	)
	(gr_line
		(start 94.459552 -43.304968)
		(end 94.586552 -43.431968)
		(stroke
			(width 0.0635)
			(type default)
		)
		(layer "F.Cu")
	)
	(gr_line
		(start 94.586552 -278.023066)
		(end 94.586552 -278.258016)
		(stroke
			(width 0.0635)
			(type default)
		)
		(layer "F.Cu")
	)
	(gr_line
		(start 94.586552 -278.023066)
		(end 94.651322 -277.958296)
		(stroke
			(width 0.0635)
			(type default)
		)
		(layer "F.Cu")
	)
	(gr_line
		(start 94.586552 -277.476966)
		(end 94.651322 -277.541736)
		(stroke
			(width 0.0635)
			(type default)
		)
		(layer "F.Cu")
	)
	(gr_line
		(start 94.586552 -277.242016)
		(end 94.586552 -277.476966)
		(stroke
			(width 0.0635)
			(type default)
		)
		(layer "F.Cu")
	)
	(gr_line
		(start 94.586552 -274.213066)
		(end 94.586552 -274.448016)
		(stroke
			(width 0.0635)
			(type default)
		)
		(layer "F.Cu")
	)
	(gr_line
		(start 94.586552 -274.213066)
		(end 94.651322 -274.148296)
		(stroke
			(width 0.0635)
			(type default)
		)
		(layer "F.Cu")
	)
	(gr_line
		(start 94.586552 -273.666966)
		(end 94.651322 -273.731736)
		(stroke
			(width 0.0635)
			(type default)
		)
		(layer "F.Cu")
	)
	(gr_line
		(start 94.586552 -273.432016)
		(end 94.586552 -273.666966)
		(stroke
			(width 0.0635)
			(type default)
		)
		(layer "F.Cu")
	)
	(gr_line
		(start 94.586552 -163.023042)
		(end 94.586552 -163.257992)
		(stroke
			(width 0.0635)
			(type default)
		)
		(layer "F.Cu")
	)
	(gr_line
		(start 94.586552 -163.023042)
		(end 94.651322 -162.958272)
		(stroke
			(width 0.0635)
			(type default)
		)
		(layer "F.Cu")
	)
	(gr_line
		(start 94.586552 -162.476942)
		(end 94.651322 -162.541712)
		(stroke
			(width 0.0635)
			(type default)
		)
		(layer "F.Cu")
	)
	(gr_line
		(start 94.586552 -162.241992)
		(end 94.586552 -162.476942)
		(stroke
			(width 0.0635)
			(type default)
		)
		(layer "F.Cu")
	)
	(gr_line
		(start 94.586552 -159.213042)
		(end 94.586552 -159.447992)
		(stroke
			(width 0.0635)
			(type default)
		)
		(layer "F.Cu")
	)
	(gr_line
		(start 94.586552 -159.213042)
		(end 94.651322 -159.148272)
		(stroke
			(width 0.0635)
			(type default)
		)
		(layer "F.Cu")
	)
	(gr_line
		(start 94.586552 -158.666942)
		(end 94.651322 -158.731712)
		(stroke
			(width 0.0635)
			(type default)
		)
		(layer "F.Cu")
	)
	(gr_line
		(start 94.586552 -158.431992)
		(end 94.586552 -158.666942)
		(stroke
			(width 0.0635)
			(type default)
		)
		(layer "F.Cu")
	)
	(gr_line
		(start 94.586552 -48.023018)
		(end 94.586552 -48.257968)
		(stroke
			(width 0.0635)
			(type default)
		)
		(layer "F.Cu")
	)
	(gr_line
		(start 94.586552 -48.023018)
		(end 94.651322 -47.958248)
		(stroke
			(width 0.0635)
			(type default)
		)
		(layer "F.Cu")
	)
	(gr_line
		(start 94.586552 -47.476918)
		(end 94.651322 -47.541688)
		(stroke
			(width 0.0635)
			(type default)
		)
		(layer "F.Cu")
	)
	(gr_line
		(start 94.586552 -47.241968)
		(end 94.586552 -47.476918)
		(stroke
			(width 0.0635)
			(type default)
		)
		(layer "F.Cu")
	)
	(gr_line
		(start 94.586552 -44.213018)
		(end 94.586552 -44.447968)
		(stroke
			(width 0.0635)
			(type default)
		)
		(layer "F.Cu")
	)
	(gr_line
		(start 94.586552 -44.213018)
		(end 94.651322 -44.148248)
		(stroke
			(width 0.0635)
			(type default)
		)
		(layer "F.Cu")
	)
	(gr_line
		(start 94.586552 -43.666918)
		(end 94.651322 -43.731688)
		(stroke
			(width 0.0635)
			(type default)
		)
		(layer "F.Cu")
	)
	(gr_line
		(start 94.586552 -43.431968)
		(end 94.586552 -43.666918)
		(stroke
			(width 0.0635)
			(type default)
		)
		(layer "F.Cu")
	)
	(gr_line
		(start 94.731586 -225.826066)
		(end 94.746318 -225.835464)
		(stroke
			(width 0.0635)
			(type default)
		)
		(layer "F.Cu")
	)
	(gr_line
		(start 94.746318 -225.835464)
		(end 94.762574 -225.838512)
		(stroke
			(width 0.0635)
			(type default)
		)
		(layer "F.Cu")
	)
	(gr_line
		(start 94.828868 -274.095464)
		(end 94.95282 -274.219416)
		(stroke
			(width 0.0635)
			(type default)
		)
		(layer "F.Cu")
	)
	(gr_line
		(start 94.828868 -273.784568)
		(end 94.95282 -273.660616)
		(stroke
			(width 0.0635)
			(type default)
		)
		(layer "F.Cu")
	)
	(gr_line
		(start 94.828868 -159.09544)
		(end 94.95282 -159.219392)
		(stroke
			(width 0.0635)
			(type default)
		)
		(layer "F.Cu")
	)
	(gr_line
		(start 94.828868 -158.784544)
		(end 94.95282 -158.660592)
		(stroke
			(width 0.0635)
			(type default)
		)
		(layer "F.Cu")
	)
	(gr_line
		(start 94.828868 -44.095416)
		(end 94.95282 -44.219368)
		(stroke
			(width 0.0635)
			(type default)
		)
		(layer "F.Cu")
	)
	(gr_line
		(start 94.828868 -43.78452)
		(end 94.95282 -43.660568)
		(stroke
			(width 0.0635)
			(type default)
		)
		(layer "F.Cu")
	)
	(gr_line
		(start 94.95282 -274.219416)
		(end 95.284036 -274.219416)
		(stroke
			(width 0.0635)
			(type default)
		)
		(layer "F.Cu")
	)
	(gr_line
		(start 94.95282 -273.660616)
		(end 95.284036 -273.660616)
		(stroke
			(width 0.0635)
			(type default)
		)
		(layer "F.Cu")
	)
	(gr_line
		(start 94.95282 -159.219392)
		(end 95.284036 -159.219392)
		(stroke
			(width 0.0635)
			(type default)
		)
		(layer "F.Cu")
	)
	(gr_line
		(start 94.95282 -158.660592)
		(end 95.284036 -158.660592)
		(stroke
			(width 0.0635)
			(type default)
		)
		(layer "F.Cu")
	)
	(gr_line
		(start 94.95282 -44.219368)
		(end 95.284036 -44.219368)
		(stroke
			(width 0.0635)
			(type default)
		)
		(layer "F.Cu")
	)
	(gr_line
		(start 94.95282 -43.660568)
		(end 95.284036 -43.660568)
		(stroke
			(width 0.0635)
			(type default)
		)
		(layer "F.Cu")
	)
	(gr_line
		(start 95.424244 -223.731074)
		(end 95.436436 -223.738694)
		(stroke
			(width 0.0635)
			(type default)
		)
		(layer "F.Cu")
	)
	(gr_line
		(start 95.436436 -223.738694)
		(end 95.450152 -223.741234)
		(stroke
			(width 0.0635)
			(type default)
		)
		(layer "F.Cu")
	)
	(gr_arc
		(start 95.481902 -277.603966)
		(mid 95.571691 -277.566766)
		(end 95.608902 -277.476966)
		(stroke
			(width 0.0635)
			(type default)
		)
		(layer "F.Cu")
	)
	(gr_arc
		(start 95.481902 -162.603942)
		(mid 95.571718 -162.566746)
		(end 95.608902 -162.476942)
		(stroke
			(width 0.0635)
			(type default)
		)
		(layer "F.Cu")
	)
	(gr_arc
		(start 95.481902 -47.603918)
		(mid 95.57171 -47.566721)
		(end 95.608902 -47.476918)
		(stroke
			(width 0.0635)
			(type default)
		)
		(layer "F.Cu")
	)
	(gr_arc
		(start 95.608902 -278.023066)
		(mid 95.571693 -277.933285)
		(end 95.481902 -277.896066)
		(stroke
			(width 0.0635)
			(type default)
		)
		(layer "F.Cu")
	)
	(gr_line
		(start 95.608902 -278.023066)
		(end 95.608902 -278.321516)
		(stroke
			(width 0.0635)
			(type default)
		)
		(layer "F.Cu")
	)
	(gr_line
		(start 95.608902 -277.178516)
		(end 95.608902 -277.476966)
		(stroke
			(width 0.0635)
			(type default)
		)
		(layer "F.Cu")
	)
	(gr_arc
		(start 95.608902 -163.023042)
		(mid 95.57172 -162.933212)
		(end 95.481902 -162.896042)
		(stroke
			(width 0.0635)
			(type default)
		)
		(layer "F.Cu")
	)
	(gr_line
		(start 95.608902 -163.023042)
		(end 95.608902 -163.321492)
		(stroke
			(width 0.0635)
			(type default)
		)
		(layer "F.Cu")
	)
	(gr_line
		(start 95.608902 -162.178492)
		(end 95.608902 -162.476942)
		(stroke
			(width 0.0635)
			(type default)
		)
		(layer "F.Cu")
	)
	(gr_arc
		(start 95.608902 -48.023018)
		(mid 95.571705 -47.933215)
		(end 95.481902 -47.896018)
		(stroke
			(width 0.0635)
			(type default)
		)
		(layer "F.Cu")
	)
	(gr_line
		(start 95.608902 -48.023018)
		(end 95.608902 -48.321468)
		(stroke
			(width 0.0635)
			(type default)
		)
		(layer "F.Cu")
	)
	(gr_line
		(start 95.608902 -47.178468)
		(end 95.608902 -47.476918)
		(stroke
			(width 0.0635)
			(type default)
		)
		(layer "F.Cu")
	)
	(gr_line
		(start 95.842836 -274.219416)
		(end 96.326452 -274.219416)
		(stroke
			(width 0.0635)
			(type default)
		)
		(layer "F.Cu")
	)
	(gr_line
		(start 95.842836 -273.660616)
		(end 96.326452 -273.660616)
		(stroke
			(width 0.0635)
			(type default)
		)
		(layer "F.Cu")
	)
	(gr_line
		(start 95.842836 -159.219392)
		(end 96.275652 -159.219392)
		(stroke
			(width 0.0635)
			(type default)
		)
		(layer "F.Cu")
	)
	(gr_line
		(start 95.842836 -158.660592)
		(end 96.215708 -158.660592)
		(stroke
			(width 0.0635)
			(type default)
		)
		(layer "F.Cu")
	)
	(gr_line
		(start 95.842836 -44.219368)
		(end 96.301052 -44.219368)
		(stroke
			(width 0.0635)
			(type default)
		)
		(layer "F.Cu")
	)
	(gr_line
		(start 95.842836 -43.660568)
		(end 96.301052 -43.660568)
		(stroke
			(width 0.0635)
			(type default)
		)
		(layer "F.Cu")
	)
	(gr_line
		(start 96.215708 -158.660592)
		(end 96.3168 -158.761684)
		(stroke
			(width 0.0635)
			(type default)
		)
		(layer "F.Cu")
	)
	(gr_line
		(start 96.275652 -159.219392)
		(end 96.3168 -159.178244)
		(stroke
			(width 0.0635)
			(type default)
		)
		(layer "F.Cu")
	)
	(gr_line
		(start 96.301052 -44.219368)
		(end 96.372172 -44.148248)
		(stroke
			(width 0.0635)
			(type default)
		)
		(layer "F.Cu")
	)
	(gr_line
		(start 96.301052 -43.660568)
		(end 96.372172 -43.731688)
		(stroke
			(width 0.0635)
			(type default)
		)
		(layer "F.Cu")
	)
	(gr_line
		(start 96.326452 -274.219416)
		(end 96.397572 -274.148296)
		(stroke
			(width 0.0635)
			(type default)
		)
		(layer "F.Cu")
	)
	(gr_line
		(start 96.326452 -273.660616)
		(end 96.397572 -273.731736)
		(stroke
			(width 0.0635)
			(type default)
		)
		(layer "F.Cu")
	)
	(gr_line
		(start 96.785938 -43.830494)
		(end 96.825308 -43.855386)
		(stroke
			(width 0.0635)
			(type default)
		)
		(layer "F.Cu")
	)
	(gr_line
		(start 96.87433 -273.836638)
		(end 96.913954 -273.861784)
		(stroke
			(width 0.0635)
			(type default)
		)
		(layer "F.Cu")
	)
	(gr_line
		(start 97.27184 -274.08886)
		(end 97.323656 -274.12188)
		(stroke
			(width 0.0635)
			(type default)
		)
		(layer "F.Cu")
	)
	(gr_line
		(start 97.323656 -274.12188)
		(end 97.344992 -274.179538)
		(stroke
			(width 0.0635)
			(type default)
		)
		(layer "F.Cu")
	)
	(gr_line
		(start 97.630996 -158.975044)
		(end 97.643442 -158.977838)
		(stroke
			(width 0.0635)
			(type default)
		)
		(layer "F.Cu")
	)
	(gr_line
		(start 97.643442 -158.977838)
		(end 97.654618 -158.98495)
		(stroke
			(width 0.0635)
			(type default)
		)
		(layer "F.Cu")
	)
	(gr_line
		(start 98.172016 -44.70781)
		(end 98.224594 -44.741084)
		(stroke
			(width 0.0635)
			(type default)
		)
		(layer "F.Cu")
	)
	(gr_line
		(start 98.224594 -44.741084)
		(end 98.246184 -44.799504)
		(stroke
			(width 0.0635)
			(type default)
		)
		(layer "F.Cu")
	)
	(gr_line
		(start 98.631502 -159.606742)
		(end 98.65487 -159.621728)
		(stroke
			(width 0.0635)
			(type default)
		)
		(layer "F.Cu")
	)
	(gr_line
		(start 98.65487 -159.621728)
		(end 98.669856 -159.645096)
		(stroke
			(width 0.0635)
			(type default)
		)
		(layer "F.Cu")
	)
	(gr_line
		(start 99.37369 -160.748472)
		(end 99.380802 -160.759648)
		(stroke
			(width 0.0635)
			(type default)
		)
		(layer "F.Cu")
	)
	(gr_line
		(start 99.380802 -160.759648)
		(end 99.383596 -160.772094)
		(stroke
			(width 0.0635)
			(type default)
		)
		(layer "F.Cu")
	)
	(gr_line
		(start 100.492052 -290.34486)
		(end 100.502974 -290.29152)
		(stroke
			(width 0.0635)
			(type default)
		)
		(layer "F.Cu")
	)
	(gr_line
		(start 100.492052 -290.34486)
		(end 100.51415 -290.395152)
		(stroke
			(width 0.0635)
			(type default)
		)
		(layer "F.Cu")
	)
	(gr_line
		(start 101.669088 -285.901892)
		(end 101.68509 -285.945072)
		(stroke
			(width 0.0635)
			(type default)
		)
		(layer "F.Cu")
	)
	(gr_line
		(start 101.675946 -285.990538)
		(end 101.68509 -285.945072)
		(stroke
			(width 0.0635)
			(type default)
		)
		(layer "F.Cu")
	)
	(gr_line
		(start 106.101642 -303.104804)
		(end 106.115358 -303.136554)
		(stroke
			(width 0.0635)
			(type default)
		)
		(layer "F.Cu")
	)
	(gr_line
		(start 106.115358 -303.136554)
		(end 106.143044 -303.158144)
		(stroke
			(width 0.0635)
			(type default)
		)
		(layer "F.Cu")
	)
	(gr_line
		(start 112.460024 -343.733628)
		(end 112.481614 -343.737946)
		(stroke
			(width 0.0635)
			(type default)
		)
		(layer "F.Cu")
	)
	(gr_line
		(start 112.46866 -342.06815)
		(end 112.48771 -342.07196)
		(stroke
			(width 0.0635)
			(type default)
		)
		(layer "F.Cu")
	)
	(gr_line
		(start 112.481614 -343.737946)
		(end 112.503204 -343.733628)
		(stroke
			(width 0.0635)
			(type default)
		)
		(layer "F.Cu")
	)
	(gr_line
		(start 112.48771 -342.07196)
		(end 112.50676 -342.06815)
		(stroke
			(width 0.0635)
			(type default)
		)
		(layer "F.Cu")
	)
	(gr_line
		(start 115.498118 -223.394016)
		(end 115.513612 -223.425512)
		(stroke
			(width 0.0635)
			(type default)
		)
		(layer "F.Cu")
	)
	(gr_line
		(start 115.513612 -223.425512)
		(end 115.542822 -223.44634)
		(stroke
			(width 0.0635)
			(type default)
		)
		(layer "F.Cu")
	)
	(gr_line
		(start 116.350034 -29.123132)
		(end 116.350034 -29.550106)
		(stroke
			(width 0.08255)
			(type default)
		)
		(layer "F.Cu")
	)
	(gr_arc
		(start 116.350034 -28.577032)
		(mid 116.387245 -28.666802)
		(end 116.477034 -28.704032)
		(stroke
			(width 0.08255)
			(type default)
		)
		(layer "F.Cu")
	)
	(gr_line
		(start 116.350034 -28.150058)
		(end 116.350034 -28.577032)
		(stroke
			(width 0.08255)
			(type default)
		)
		(layer "F.Cu")
	)
	(gr_arc
		(start 116.477034 -28.996132)
		(mid 116.387231 -29.033329)
		(end 116.350034 -29.123132)
		(stroke
			(width 0.08255)
			(type default)
		)
		(layer "F.Cu")
	)
	(gr_line
		(start 117.103906 -31.744412)
		(end 117.137434 -31.790894)
		(stroke
			(width 0.08255)
			(type default)
		)
		(layer "F.Cu")
	)
	(gr_line
		(start 117.612922 -32.447738)
		(end 117.658388 -32.510476)
		(stroke
			(width 0.08255)
			(type default)
		)
		(layer "F.Cu")
	)
	(gr_line
		(start 117.658388 -32.510476)
		(end 117.73408 -32.525208)
		(stroke
			(width 0.08255)
			(type default)
		)
		(layer "F.Cu")
	)
	(gr_line
		(start 118.013988 -88.615266)
		(end 118.033546 -88.619584)
		(stroke
			(width 0.0635)
			(type default)
		)
		(layer "F.Cu")
	)
	(gr_line
		(start 118.033546 -88.619584)
		(end 118.050056 -88.63076)
		(stroke
			(width 0.0635)
			(type default)
		)
		(layer "F.Cu")
	)
	(gr_line
		(start 119.926608 -87.534496)
		(end 119.937784 -87.551768)
		(stroke
			(width 0.0635)
			(type default)
		)
		(layer "F.Cu")
	)
	(gr_line
		(start 119.937784 -87.551768)
		(end 119.954802 -87.563452)
		(stroke
			(width 0.0635)
			(type default)
		)
		(layer "F.Cu")
	)
	(gr_line
		(start 120.204738 -226.743768)
		(end 120.223788 -226.75723)
		(stroke
			(width 0.0635)
			(type default)
		)
		(layer "F.Cu")
	)
	(gr_line
		(start 120.223788 -226.75723)
		(end 120.246394 -226.762056)
		(stroke
			(width 0.0635)
			(type default)
		)
		(layer "F.Cu")
	)
	(gr_line
		(start 124.674884 -278.385016)
		(end 125.987048 -278.385016)
		(stroke
			(width 0.0635)
			(type default)
		)
		(layer "F.Cu")
	)
	(gr_line
		(start 124.674884 -277.115016)
		(end 126.0094 -277.115016)
		(stroke
			(width 0.0635)
			(type default)
		)
		(layer "F.Cu")
	)
	(gr_line
		(start 124.674884 -274.575016)
		(end 126.0094 -274.575016)
		(stroke
			(width 0.0635)
			(type default)
		)
		(layer "F.Cu")
	)
	(gr_line
		(start 124.674884 -273.305016)
		(end 126.0094 -273.305016)
		(stroke
			(width 0.0635)
			(type default)
		)
		(layer "F.Cu")
	)
	(gr_line
		(start 124.674884 -163.384992)
		(end 126.0094 -163.384992)
		(stroke
			(width 0.0635)
			(type default)
		)
		(layer "F.Cu")
	)
	(gr_line
		(start 124.674884 -162.114992)
		(end 126.0094 -162.114992)
		(stroke
			(width 0.0635)
			(type default)
		)
		(layer "F.Cu")
	)
	(gr_line
		(start 124.674884 -159.574992)
		(end 126.0094 -159.574992)
		(stroke
			(width 0.0635)
			(type default)
		)
		(layer "F.Cu")
	)
	(gr_line
		(start 124.674884 -158.304992)
		(end 126.0094 -158.304992)
		(stroke
			(width 0.0635)
			(type default)
		)
		(layer "F.Cu")
	)
	(gr_line
		(start 124.674884 -48.384968)
		(end 126.0094 -48.384968)
		(stroke
			(width 0.0635)
			(type default)
		)
		(layer "F.Cu")
	)
	(gr_line
		(start 124.674884 -47.114968)
		(end 126.0094 -47.114968)
		(stroke
			(width 0.0635)
			(type default)
		)
		(layer "F.Cu")
	)
	(gr_line
		(start 124.674884 -44.574968)
		(end 126.0094 -44.574968)
		(stroke
			(width 0.0635)
			(type default)
		)
		(layer "F.Cu")
	)
	(gr_line
		(start 124.674884 -43.304968)
		(end 126.0094 -43.304968)
		(stroke
			(width 0.0635)
			(type default)
		)
		(layer "F.Cu")
	)
	(gr_line
		(start 125.736096 -34.100262)
		(end 125.755908 -34.104072)
		(stroke
			(width 0.08255)
			(type default)
		)
		(layer "F.Cu")
	)
	(gr_line
		(start 125.755908 -34.104072)
		(end 125.775466 -34.100008)
		(stroke
			(width 0.08255)
			(type default)
		)
		(layer "F.Cu")
	)
	(gr_line
		(start 125.987048 -278.385016)
		(end 126.1364 -278.235664)
		(stroke
			(width 0.0635)
			(type default)
		)
		(layer "F.Cu")
	)
	(gr_line
		(start 126.0094 -277.115016)
		(end 126.1364 -277.242016)
		(stroke
			(width 0.0635)
			(type default)
		)
		(layer "F.Cu")
	)
	(gr_line
		(start 126.0094 -274.575016)
		(end 126.1364 -274.448016)
		(stroke
			(width 0.0635)
			(type default)
		)
		(layer "F.Cu")
	)
	(gr_line
		(start 126.0094 -273.305016)
		(end 126.1364 -273.432016)
		(stroke
			(width 0.0635)
			(type default)
		)
		(layer "F.Cu")
	)
	(gr_line
		(start 126.0094 -163.384992)
		(end 126.1364 -163.257992)
		(stroke
			(width 0.0635)
			(type default)
		)
		(layer "F.Cu")
	)
	(gr_line
		(start 126.0094 -162.114992)
		(end 126.1364 -162.241992)
		(stroke
			(width 0.0635)
			(type default)
		)
		(layer "F.Cu")
	)
	(gr_line
		(start 126.0094 -159.574992)
		(end 126.1364 -159.447992)
		(stroke
			(width 0.0635)
			(type default)
		)
		(layer "F.Cu")
	)
	(gr_line
		(start 126.0094 -158.304992)
		(end 126.1364 -158.431992)
		(stroke
			(width 0.0635)
			(type default)
		)
		(layer "F.Cu")
	)
	(gr_line
		(start 126.0094 -48.384968)
		(end 126.1364 -48.257968)
		(stroke
			(width 0.0635)
			(type default)
		)
		(layer "F.Cu")
	)
	(gr_line
		(start 126.0094 -47.114968)
		(end 126.1364 -47.241968)
		(stroke
			(width 0.0635)
			(type default)
		)
		(layer "F.Cu")
	)
	(gr_line
		(start 126.0094 -44.574968)
		(end 126.1364 -44.447968)
		(stroke
			(width 0.0635)
			(type default)
		)
		(layer "F.Cu")
	)
	(gr_line
		(start 126.0094 -43.304968)
		(end 126.1364 -43.431968)
		(stroke
			(width 0.0635)
			(type default)
		)
		(layer "F.Cu")
	)
	(gr_line
		(start 126.1364 -278.05507)
		(end 126.1364 -278.235664)
		(stroke
			(width 0.0635)
			(type default)
		)
		(layer "F.Cu")
	)
	(gr_line
		(start 126.1364 -278.05507)
		(end 126.217172 -277.974298)
		(stroke
			(width 0.0635)
			(type default)
		)
		(layer "F.Cu")
	)
	(gr_line
		(start 126.1364 -277.476966)
		(end 126.217172 -277.557738)
		(stroke
			(width 0.0635)
			(type default)
		)
		(layer "F.Cu")
	)
	(gr_line
		(start 126.1364 -277.242016)
		(end 126.1364 -277.476966)
		(stroke
			(width 0.0635)
			(type default)
		)
		(layer "F.Cu")
	)
	(gr_line
		(start 126.1364 -274.213066)
		(end 126.1364 -274.448016)
		(stroke
			(width 0.0635)
			(type default)
		)
		(layer "F.Cu")
	)
	(gr_line
		(start 126.1364 -274.213066)
		(end 126.20117 -274.148296)
		(stroke
			(width 0.0635)
			(type default)
		)
		(layer "F.Cu")
	)
	(gr_line
		(start 126.1364 -273.666966)
		(end 126.20117 -273.731736)
		(stroke
			(width 0.0635)
			(type default)
		)
		(layer "F.Cu")
	)
	(gr_line
		(start 126.1364 -273.432016)
		(end 126.1364 -273.666966)
		(stroke
			(width 0.0635)
			(type default)
		)
		(layer "F.Cu")
	)
	(gr_line
		(start 126.1364 -163.023042)
		(end 126.1364 -163.257992)
		(stroke
			(width 0.0635)
			(type default)
		)
		(layer "F.Cu")
	)
	(gr_line
		(start 126.1364 -163.023042)
		(end 126.20117 -162.958272)
		(stroke
			(width 0.0635)
			(type default)
		)
		(layer "F.Cu")
	)
	(gr_line
		(start 126.1364 -162.476942)
		(end 126.20117 -162.541712)
		(stroke
			(width 0.0635)
			(type default)
		)
		(layer "F.Cu")
	)
	(gr_line
		(start 126.1364 -162.241992)
		(end 126.1364 -162.476942)
		(stroke
			(width 0.0635)
			(type default)
		)
		(layer "F.Cu")
	)
	(gr_line
		(start 126.1364 -159.213042)
		(end 126.1364 -159.447992)
		(stroke
			(width 0.0635)
			(type default)
		)
		(layer "F.Cu")
	)
	(gr_line
		(start 126.1364 -159.213042)
		(end 126.20117 -159.148272)
		(stroke
			(width 0.0635)
			(type default)
		)
		(layer "F.Cu")
	)
	(gr_line
		(start 126.1364 -158.666942)
		(end 126.20117 -158.731712)
		(stroke
			(width 0.0635)
			(type default)
		)
		(layer "F.Cu")
	)
	(gr_line
		(start 126.1364 -158.431992)
		(end 126.1364 -158.666942)
		(stroke
			(width 0.0635)
			(type default)
		)
		(layer "F.Cu")
	)
	(gr_line
		(start 126.1364 -48.023018)
		(end 126.1364 -48.257968)
		(stroke
			(width 0.0635)
			(type default)
		)
		(layer "F.Cu")
	)
	(gr_line
		(start 126.1364 -48.023018)
		(end 126.20117 -47.958248)
		(stroke
			(width 0.0635)
			(type default)
		)
		(layer "F.Cu")
	)
	(gr_line
		(start 126.1364 -47.476918)
		(end 126.20117 -47.541688)
		(stroke
			(width 0.0635)
			(type default)
		)
		(layer "F.Cu")
	)
	(gr_line
		(start 126.1364 -47.241968)
		(end 126.1364 -47.476918)
		(stroke
			(width 0.0635)
			(type default)
		)
		(layer "F.Cu")
	)
	(gr_line
		(start 126.1364 -44.213018)
		(end 126.1364 -44.447968)
		(stroke
			(width 0.0635)
			(type default)
		)
		(layer "F.Cu")
	)
	(gr_line
		(start 126.1364 -44.213018)
		(end 126.20117 -44.148248)
		(stroke
			(width 0.0635)
			(type default)
		)
		(layer "F.Cu")
	)
	(gr_line
		(start 126.1364 -43.666918)
		(end 126.20117 -43.731688)
		(stroke
			(width 0.0635)
			(type default)
		)
		(layer "F.Cu")
	)
	(gr_line
		(start 126.1364 -43.431968)
		(end 126.1364 -43.666918)
		(stroke
			(width 0.0635)
			(type default)
		)
		(layer "F.Cu")
	)
	(gr_line
		(start 126.378716 -274.095464)
		(end 126.502668 -274.219416)
		(stroke
			(width 0.0635)
			(type default)
		)
		(layer "F.Cu")
	)
	(gr_line
		(start 126.378716 -273.784568)
		(end 126.502668 -273.660616)
		(stroke
			(width 0.0635)
			(type default)
		)
		(layer "F.Cu")
	)
	(gr_line
		(start 126.378716 -159.09544)
		(end 126.502668 -159.219392)
		(stroke
			(width 0.0635)
			(type default)
		)
		(layer "F.Cu")
	)
	(gr_line
		(start 126.378716 -158.784544)
		(end 126.502668 -158.660592)
		(stroke
			(width 0.0635)
			(type default)
		)
		(layer "F.Cu")
	)
	(gr_line
		(start 126.378716 -44.095416)
		(end 126.502668 -44.219368)
		(stroke
			(width 0.0635)
			(type default)
		)
		(layer "F.Cu")
	)
	(gr_line
		(start 126.378716 -43.78452)
		(end 126.502668 -43.660568)
		(stroke
			(width 0.0635)
			(type default)
		)
		(layer "F.Cu")
	)
	(gr_line
		(start 126.502668 -274.219416)
		(end 126.833884 -274.219416)
		(stroke
			(width 0.0635)
			(type default)
		)
		(layer "F.Cu")
	)
	(gr_line
		(start 126.502668 -273.660616)
		(end 126.833884 -273.660616)
		(stroke
			(width 0.0635)
			(type default)
		)
		(layer "F.Cu")
	)
	(gr_line
		(start 126.502668 -159.219392)
		(end 126.833884 -159.219392)
		(stroke
			(width 0.0635)
			(type default)
		)
		(layer "F.Cu")
	)
	(gr_line
		(start 126.502668 -158.660592)
		(end 126.833884 -158.660592)
		(stroke
			(width 0.0635)
			(type default)
		)
		(layer "F.Cu")
	)
	(gr_line
		(start 126.502668 -44.219368)
		(end 126.833884 -44.219368)
		(stroke
			(width 0.0635)
			(type default)
		)
		(layer "F.Cu")
	)
	(gr_line
		(start 126.502668 -43.660568)
		(end 126.833884 -43.660568)
		(stroke
			(width 0.0635)
			(type default)
		)
		(layer "F.Cu")
	)
	(gr_arc
		(start 127.03175 -277.603966)
		(mid 127.121573 -277.566784)
		(end 127.15875 -277.476966)
		(stroke
			(width 0.0635)
			(type default)
		)
		(layer "F.Cu")
	)
	(gr_arc
		(start 127.03175 -162.603942)
		(mid 127.1216 -162.566765)
		(end 127.15875 -162.476942)
		(stroke
			(width 0.0635)
			(type default)
		)
		(layer "F.Cu")
	)
	(gr_arc
		(start 127.03175 -47.603918)
		(mid 127.121591 -47.566739)
		(end 127.15875 -47.476918)
		(stroke
			(width 0.0635)
			(type default)
		)
		(layer "F.Cu")
	)
	(gr_arc
		(start 127.15875 -278.023066)
		(mid 127.121553 -277.933263)
		(end 127.03175 -277.896066)
		(stroke
			(width 0.0635)
			(type default)
		)
		(layer "F.Cu")
	)
	(gr_line
		(start 127.15875 -278.023066)
		(end 127.15875 -278.321516)
		(stroke
			(width 0.0635)
			(type default)
		)
		(layer "F.Cu")
	)
	(gr_line
		(start 127.15875 -277.178516)
		(end 127.15875 -277.476966)
		(stroke
			(width 0.0635)
			(type default)
		)
		(layer "F.Cu")
	)
	(gr_arc
		(start 127.15875 -163.023042)
		(mid 127.121553 -162.933239)
		(end 127.03175 -162.896042)
		(stroke
			(width 0.0635)
			(type default)
		)
		(layer "F.Cu")
	)
	(gr_line
		(start 127.15875 -163.023042)
		(end 127.15875 -163.321492)
		(stroke
			(width 0.0635)
			(type default)
		)
		(layer "F.Cu")
	)
	(gr_line
		(start 127.15875 -162.178492)
		(end 127.15875 -162.476942)
		(stroke
			(width 0.0635)
			(type default)
		)
		(layer "F.Cu")
	)
	(gr_arc
		(start 127.15875 -48.023018)
		(mid 127.121553 -47.933215)
		(end 127.03175 -47.896018)
		(stroke
			(width 0.0635)
			(type default)
		)
		(layer "F.Cu")
	)
	(gr_line
		(start 127.15875 -48.023018)
		(end 127.15875 -48.321468)
		(stroke
			(width 0.0635)
			(type default)
		)
		(layer "F.Cu")
	)
	(gr_line
		(start 127.15875 -47.178468)
		(end 127.15875 -47.476918)
		(stroke
			(width 0.0635)
			(type default)
		)
		(layer "F.Cu")
	)
	(gr_line
		(start 127.392684 -274.219416)
		(end 127.8763 -274.219416)
		(stroke
			(width 0.0635)
			(type default)
		)
		(layer "F.Cu")
	)
	(gr_line
		(start 127.392684 -273.660616)
		(end 127.8763 -273.660616)
		(stroke
			(width 0.0635)
			(type default)
		)
		(layer "F.Cu")
	)
	(gr_line
		(start 127.392684 -159.219392)
		(end 127.761492 -159.219392)
		(stroke
			(width 0.0635)
			(type default)
		)
		(layer "F.Cu")
	)
	(gr_line
		(start 127.392684 -158.660592)
		(end 127.727456 -158.660592)
		(stroke
			(width 0.0635)
			(type default)
		)
		(layer "F.Cu")
	)
	(gr_line
		(start 127.392684 -44.219368)
		(end 127.8763 -44.219368)
		(stroke
			(width 0.0635)
			(type default)
		)
		(layer "F.Cu")
	)
	(gr_line
		(start 127.392684 -43.660568)
		(end 127.80518 -43.660568)
		(stroke
			(width 0.0635)
			(type default)
		)
		(layer "F.Cu")
	)
	(gr_line
		(start 127.727456 -158.660592)
		(end 127.815594 -158.74873)
		(stroke
			(width 0.0635)
			(type default)
		)
		(layer "F.Cu")
	)
	(gr_line
		(start 127.761492 -159.219392)
		(end 127.815594 -159.16529)
		(stroke
			(width 0.0635)
			(type default)
		)
		(layer "F.Cu")
	)
	(gr_line
		(start 127.80518 -43.660568)
		(end 127.91186 -43.767248)
		(stroke
			(width 0.0635)
			(type default)
		)
		(layer "F.Cu")
	)
	(gr_line
		(start 127.8763 -274.219416)
		(end 127.94742 -274.148296)
		(stroke
			(width 0.0635)
			(type default)
		)
		(layer "F.Cu")
	)
	(gr_line
		(start 127.8763 -273.660616)
		(end 127.94742 -273.731736)
		(stroke
			(width 0.0635)
			(type default)
		)
		(layer "F.Cu")
	)
	(gr_line
		(start 127.8763 -44.219368)
		(end 127.91186 -44.183808)
		(stroke
			(width 0.0635)
			(type default)
		)
		(layer "F.Cu")
	)
	(gr_line
		(start 128.36017 -273.84121)
		(end 128.399032 -273.866102)
		(stroke
			(width 0.0635)
			(type default)
		)
		(layer "F.Cu")
	)
	(gr_line
		(start 128.771142 -43.825922)
		(end 128.810512 -43.850814)
		(stroke
			(width 0.0635)
			(type default)
		)
		(layer "F.Cu")
	)
	(gr_line
		(start 128.877568 -158.951168)
		(end 128.890014 -158.953962)
		(stroke
			(width 0.0635)
			(type default)
		)
		(layer "F.Cu")
	)
	(gr_line
		(start 128.890014 -158.953962)
		(end 128.90119 -158.961074)
		(stroke
			(width 0.0635)
			(type default)
		)
		(layer "F.Cu")
	)
	(gr_line
		(start 129.666492 -44.393104)
		(end 129.718308 -44.425616)
		(stroke
			(width 0.0635)
			(type default)
		)
		(layer "F.Cu")
	)
	(gr_line
		(start 129.718308 -44.425616)
		(end 129.739898 -44.484036)
		(stroke
			(width 0.0635)
			(type default)
		)
		(layer "F.Cu")
	)
	(gr_line
		(start 129.947162 -159.62757)
		(end 129.96926 -159.641794)
		(stroke
			(width 0.0635)
			(type default)
		)
		(layer "F.Cu")
	)
	(gr_line
		(start 129.96926 -159.641794)
		(end 129.983484 -159.663892)
		(stroke
			(width 0.0635)
			(type default)
		)
		(layer "F.Cu")
	)
	(gr_line
		(start 132.084826 -162.96259)
		(end 132.091938 -162.973766)
		(stroke
			(width 0.0635)
			(type default)
		)
		(layer "F.Cu")
	)
	(gr_line
		(start 132.091938 -162.973766)
		(end 132.094732 -162.986212)
		(stroke
			(width 0.0635)
			(type default)
		)
		(layer "F.Cu")
	)
	(gr_line
		(start 133.615684 -32.202882)
		(end 133.635242 -32.198818)
		(stroke
			(width 0.08255)
			(type default)
		)
		(layer "F.Cu")
	)
	(gr_line
		(start 133.635242 -32.198818)
		(end 133.655054 -32.202628)
		(stroke
			(width 0.08255)
			(type default)
		)
		(layer "F.Cu")
	)
	(gr_line
		(start 135.680704 -278.509984)
		(end 135.702802 -278.524208)
		(stroke
			(width 0.0635)
			(type default)
		)
		(layer "F.Cu")
	)
	(gr_line
		(start 135.702802 -278.524208)
		(end 135.717026 -278.546306)
		(stroke
			(width 0.0635)
			(type default)
		)
		(layer "F.Cu")
	)
	(gr_line
		(start 136.213596 -287.616646)
		(end 136.219184 -287.6423)
		(stroke
			(width 0.0635)
			(type default)
		)
		(layer "F.Cu")
	)
	(gr_line
		(start 136.213596 -287.616646)
		(end 136.219438 -287.59023)
		(stroke
			(width 0.0635)
			(type default)
		)
		(layer "F.Cu")
	)
	(gr_line
		(start 136.297924 -294.306244)
		(end 136.303512 -294.331898)
		(stroke
			(width 0.0635)
			(type default)
		)
		(layer "F.Cu")
	)
	(gr_line
		(start 136.297924 -294.306244)
		(end 136.303766 -294.279828)
		(stroke
			(width 0.0635)
			(type default)
		)
		(layer "F.Cu")
	)
	(gr_line
		(start 136.750552 -280.166572)
		(end 136.757664 -280.177748)
		(stroke
			(width 0.0635)
			(type default)
		)
		(layer "F.Cu")
	)
	(gr_line
		(start 136.757664 -280.177748)
		(end 136.760458 -280.190194)
		(stroke
			(width 0.0635)
			(type default)
		)
		(layer "F.Cu")
	)
	(gr_line
		(start 136.915906 -338.486496)
		(end 136.937496 -338.482178)
		(stroke
			(width 0.0635)
			(type default)
		)
		(layer "F.Cu")
	)
	(gr_line
		(start 136.937496 -338.482178)
		(end 136.959086 -338.486496)
		(stroke
			(width 0.0635)
			(type default)
		)
		(layer "F.Cu")
	)
	(gr_line
		(start 137.212832 -336.828892)
		(end 137.231882 -336.825082)
		(stroke
			(width 0.0635)
			(type default)
		)
		(layer "F.Cu")
	)
	(gr_line
		(start 137.231882 -336.825082)
		(end 137.250932 -336.828892)
		(stroke
			(width 0.0635)
			(type default)
		)
		(layer "F.Cu")
	)
	(gr_line
		(start 137.29081 -291.125402)
		(end 137.296652 -291.151818)
		(stroke
			(width 0.0635)
			(type default)
		)
		(layer "F.Cu")
	)
	(gr_line
		(start 137.291064 -291.177472)
		(end 137.296652 -291.151818)
		(stroke
			(width 0.0635)
			(type default)
		)
		(layer "F.Cu")
	)
	(gr_line
		(start 137.454132 -283.316172)
		(end 137.459974 -283.342588)
		(stroke
			(width 0.0635)
			(type default)
		)
		(layer "F.Cu")
	)
	(gr_line
		(start 137.454386 -283.368242)
		(end 137.459974 -283.342588)
		(stroke
			(width 0.0635)
			(type default)
		)
		(layer "F.Cu")
	)
	(gr_line
		(start 138.259312 -303.265332)
		(end 138.270234 -303.215548)
		(stroke
			(width 0.0635)
			(type default)
		)
		(layer "F.Cu")
	)
	(gr_line
		(start 138.259312 -303.265332)
		(end 138.304016 -303.33569)
		(stroke
			(width 0.0635)
			(type default)
		)
		(layer "F.Cu")
	)
	(gr_line
		(start 138.564874 -303.18329)
		(end 138.569446 -303.20361)
		(stroke
			(width 0.0635)
			(type default)
		)
		(layer "F.Cu")
	)
	(gr_line
		(start 139.562078 -198.01967)
		(end 139.564872 -198.032116)
		(stroke
			(width 0.0635)
			(type default)
		)
		(layer "F.Cu")
	)
	(gr_line
		(start 139.564872 -198.032116)
		(end 139.571984 -198.043292)
		(stroke
			(width 0.0635)
			(type default)
		)
		(layer "F.Cu")
	)
	(gr_line
		(start 141.873224 -234.969558)
		(end 141.880844 -234.971082)
		(stroke
			(width 0.0635)
			(type default)
		)
		(layer "F.Cu")
	)
	(gr_line
		(start 141.880844 -234.971082)
		(end 141.88694 -234.974638)
		(stroke
			(width 0.0635)
			(type default)
		)
		(layer "F.Cu")
	)
	(gr_line
		(start 142.168626 -233.093006)
		(end 142.168626 -233.093514)
		(stroke
			(width 0.0635)
			(type default)
		)
		(layer "F.Cu")
	)
	(gr_line
		(start 142.168626 -233.093006)
		(end 142.169388 -233.09326)
		(stroke
			(width 0.0635)
			(type default)
		)
		(layer "F.Cu")
	)
	(gr_line
		(start 142.214346 -232.804462)
		(end 142.23746 -232.809034)
		(stroke
			(width 0.0635)
			(type default)
		)
		(layer "F.Cu")
	)
	(gr_line
		(start 142.2654 -232.814622)
		(end 142.271242 -232.815892)
		(stroke
			(width 0.0635)
			(type default)
		)
		(layer "F.Cu")
	)
	(gr_line
		(start 142.271242 -232.815384)
		(end 142.271242 -232.815892)
		(stroke
			(width 0.0635)
			(type default)
		)
		(layer "F.Cu")
	)
	(gr_line
		(start 142.271242 -232.815384)
		(end 142.27937 -232.819956)
		(stroke
			(width 0.0635)
			(type default)
		)
		(layer "F.Cu")
	)
	(gr_line
		(start 142.303754 -31.776924)
		(end 142.336774 -31.822644)
		(stroke
			(width 0.08255)
			(type default)
		)
		(layer "F.Cu")
	)
	(gr_line
		(start 142.882874 -32.577786)
		(end 142.927578 -32.639762)
		(stroke
			(width 0.08255)
			(type default)
		)
		(layer "F.Cu")
	)
	(gr_line
		(start 142.927578 -32.639762)
		(end 143.00327 -32.654748)
		(stroke
			(width 0.08255)
			(type default)
		)
		(layer "F.Cu")
	)
	(gr_arc
		(start 143.22298 -29.70403)
		(mid 143.312783 -29.666833)
		(end 143.34998 -29.57703)
		(stroke
			(width 0.08255)
			(type default)
		)
		(layer "F.Cu")
	)
	(gr_arc
		(start 143.34998 -30.12313)
		(mid 143.312792 -30.033315)
		(end 143.22298 -29.99613)
		(stroke
			(width 0.08255)
			(type default)
		)
		(layer "F.Cu")
	)
	(gr_line
		(start 143.34998 -30.12313)
		(end 143.34998 -30.550104)
		(stroke
			(width 0.08255)
			(type default)
		)
		(layer "F.Cu")
	)
	(gr_line
		(start 143.34998 -29.150056)
		(end 143.34998 -29.57703)
		(stroke
			(width 0.08255)
			(type default)
		)
		(layer "F.Cu")
	)
	(gr_line
		(start 143.803116 -34.49701)
		(end 143.822928 -34.50082)
		(stroke
			(width 0.08255)
			(type default)
		)
		(layer "F.Cu")
	)
	(gr_line
		(start 143.822928 -34.50082)
		(end 143.842486 -34.496756)
		(stroke
			(width 0.08255)
			(type default)
		)
		(layer "F.Cu")
	)
	(gr_line
		(start 143.859504 -32.823404)
		(end 143.879316 -32.827214)
		(stroke
			(width 0.08255)
			(type default)
		)
		(layer "F.Cu")
	)
	(gr_line
		(start 143.879316 -32.827214)
		(end 143.898874 -32.82315)
		(stroke
			(width 0.08255)
			(type default)
		)
		(layer "F.Cu")
	)
	(gr_line
		(start 144.554956 -231.650286)
		(end 144.562068 -231.65181)
		(stroke
			(width 0.0635)
			(type default)
		)
		(layer "F.Cu")
	)
	(gr_line
		(start 144.562068 -231.65181)
		(end 144.568418 -231.655366)
		(stroke
			(width 0.0635)
			(type default)
		)
		(layer "F.Cu")
	)
	(gr_line
		(start 146.855688 -316.215776)
		(end 146.863562 -316.228222)
		(stroke
			(width 0.0635)
			(type default)
		)
		(layer "F.Cu")
	)
	(gr_line
		(start 146.863562 -316.228222)
		(end 146.866356 -316.241684)
		(stroke
			(width 0.0635)
			(type default)
		)
		(layer "F.Cu")
	)
	(gr_line
		(start 147.454366 -138.12901)
		(end 148.6662 -138.12901)
		(stroke
			(width 0.127)
			(type default)
		)
		(layer "F.Cu")
	)
	(gr_line
		(start 147.454366 -137.629138)
		(end 148.466556 -137.629138)
		(stroke
			(width 0.127)
			(type default)
		)
		(layer "F.Cu")
	)
	(gr_line
		(start 147.454366 -137.129012)
		(end 148.29409 -137.129012)
		(stroke
			(width 0.127)
			(type default)
		)
		(layer "F.Cu")
	)
	(gr_line
		(start 147.454366 -136.62914)
		(end 148.6662 -136.62914)
		(stroke
			(width 0.127)
			(type default)
		)
		(layer "F.Cu")
	)
	(gr_line
		(start 148.29409 -137.129012)
		(end 148.305266 -137.140188)
		(stroke
			(width 0.127)
			(type default)
		)
		(layer "F.Cu")
	)
	(gr_line
		(start 148.6662 -138.12901)
		(end 148.711666 -138.174476)
		(stroke
			(width 0.127)
			(type default)
		)
		(layer "F.Cu")
	)
	(gr_line
		(start 148.6662 -136.62914)
		(end 148.711666 -136.583674)
		(stroke
			(width 0.127)
			(type default)
		)
		(layer "F.Cu")
	)
	(gr_line
		(start 149.99716 -331.710284)
		(end 149.999954 -331.72273)
		(stroke
			(width 0.0635)
			(type default)
		)
		(layer "F.Cu")
	)
	(gr_line
		(start 149.999954 -331.72273)
		(end 150.007066 -331.733906)
		(stroke
			(width 0.0635)
			(type default)
		)
		(layer "F.Cu")
	)
	(gr_line
		(start 150.192486 -137.696194)
		(end 150.311866 -137.815574)
		(stroke
			(width 0.127)
			(type default)
		)
		(layer "F.Cu")
	)
	(gr_line
		(start 150.192486 -137.045954)
		(end 150.311866 -136.926574)
		(stroke
			(width 0.127)
			(type default)
		)
		(layer "F.Cu")
	)
	(gr_line
		(start 150.311866 -137.815574)
		(end 150.431246 -137.696194)
		(stroke
			(width 0.127)
			(type default)
		)
		(layer "F.Cu")
	)
	(gr_line
		(start 150.311866 -136.926574)
		(end 150.431246 -137.045954)
		(stroke
			(width 0.127)
			(type default)
		)
		(layer "F.Cu")
	)
	(gr_line
		(start 151.134826 -338.159598)
		(end 151.159718 -338.178902)
		(stroke
			(width 0.0635)
			(type default)
		)
		(layer "F.Cu")
	)
	(gr_line
		(start 151.159718 -338.178902)
		(end 151.189944 -338.184744)
		(stroke
			(width 0.0635)
			(type default)
		)
		(layer "F.Cu")
	)
	(gr_line
		(start 151.179276 -137.695686)
		(end 151.489156 -138.005566)
		(stroke
			(width 0.127)
			(type default)
		)
		(layer "F.Cu")
	)
	(gr_line
		(start 151.179276 -137.045446)
		(end 151.489156 -136.735566)
		(stroke
			(width 0.127)
			(type default)
		)
		(layer "F.Cu")
	)
	(gr_line
		(start 151.489156 -138.005566)
		(end 151.799036 -137.695686)
		(stroke
			(width 0.127)
			(type default)
		)
		(layer "F.Cu")
	)
	(gr_line
		(start 151.489156 -136.735566)
		(end 151.799036 -137.045446)
		(stroke
			(width 0.127)
			(type default)
		)
		(layer "F.Cu")
	)
	(gr_line
		(start 152.487376 -335.627726)
		(end 152.503378 -335.652872)
		(stroke
			(width 0.0635)
			(type default)
		)
		(layer "F.Cu")
	)
	(gr_line
		(start 152.503378 -335.652872)
		(end 152.528778 -335.668366)
		(stroke
			(width 0.0635)
			(type default)
		)
		(layer "F.Cu")
	)
	(gr_line
		(start 152.605486 -137.696194)
		(end 152.788366 -137.879074)
		(stroke
			(width 0.127)
			(type default)
		)
		(layer "F.Cu")
	)
	(gr_line
		(start 152.605486 -137.045954)
		(end 152.788366 -136.863074)
		(stroke
			(width 0.127)
			(type default)
		)
		(layer "F.Cu")
	)
	(gr_line
		(start 153.677366 -137.879074)
		(end 153.860246 -137.696194)
		(stroke
			(width 0.127)
			(type default)
		)
		(layer "F.Cu")
	)
	(gr_line
		(start 153.677366 -136.863074)
		(end 153.860246 -137.045954)
		(stroke
			(width 0.127)
			(type default)
		)
		(layer "F.Cu")
	)
	(gr_line
		(start 154.094688 -107.827572)
		(end 154.105864 -107.844336)
		(stroke
			(width 0.0635)
			(type default)
		)
		(layer "F.Cu")
	)
	(gr_line
		(start 154.105864 -107.844336)
		(end 154.122374 -107.855766)
		(stroke
			(width 0.0635)
			(type default)
		)
		(layer "F.Cu")
	)
	(gr_line
		(start 154.460956 -137.689844)
		(end 154.770836 -137.999724)
		(stroke
			(width 0.127)
			(type default)
		)
		(layer "F.Cu")
	)
	(gr_line
		(start 154.460956 -137.039604)
		(end 154.770836 -136.729724)
		(stroke
			(width 0.127)
			(type default)
		)
		(layer "F.Cu")
	)
	(gr_line
		(start 155.351734 -337.388962)
		(end 155.362402 -337.395566)
		(stroke
			(width 0.0635)
			(type default)
		)
		(layer "F.Cu")
	)
	(gr_line
		(start 155.362402 -337.395566)
		(end 155.374848 -337.397852)
		(stroke
			(width 0.0635)
			(type default)
		)
		(layer "F.Cu")
	)
	(gr_line
		(start 156.224986 -278.385016)
		(end 157.559502 -278.385016)
		(stroke
			(width 0.0635)
			(type default)
		)
		(layer "F.Cu")
	)
	(gr_line
		(start 156.224986 -277.115016)
		(end 157.559502 -277.115016)
		(stroke
			(width 0.0635)
			(type default)
		)
		(layer "F.Cu")
	)
	(gr_line
		(start 156.224986 -274.575016)
		(end 157.559502 -274.575016)
		(stroke
			(width 0.0635)
			(type default)
		)
		(layer "F.Cu")
	)
	(gr_line
		(start 156.224986 -273.305016)
		(end 157.559502 -273.305016)
		(stroke
			(width 0.0635)
			(type default)
		)
		(layer "F.Cu")
	)
	(gr_line
		(start 156.224986 -163.384992)
		(end 157.559502 -163.384992)
		(stroke
			(width 0.0635)
			(type default)
		)
		(layer "F.Cu")
	)
	(gr_line
		(start 156.224986 -162.114992)
		(end 157.559502 -162.114992)
		(stroke
			(width 0.0635)
			(type default)
		)
		(layer "F.Cu")
	)
	(gr_line
		(start 156.224986 -159.574992)
		(end 157.559502 -159.574992)
		(stroke
			(width 0.0635)
			(type default)
		)
		(layer "F.Cu")
	)
	(gr_line
		(start 156.224986 -158.304992)
		(end 157.559502 -158.304992)
		(stroke
			(width 0.0635)
			(type default)
		)
		(layer "F.Cu")
	)
	(gr_line
		(start 156.224986 -48.384968)
		(end 157.559502 -48.384968)
		(stroke
			(width 0.0635)
			(type default)
		)
		(layer "F.Cu")
	)
	(gr_line
		(start 156.224986 -47.114968)
		(end 157.559502 -47.114968)
		(stroke
			(width 0.0635)
			(type default)
		)
		(layer "F.Cu")
	)
	(gr_line
		(start 156.224986 -44.574968)
		(end 157.559502 -44.574968)
		(stroke
			(width 0.0635)
			(type default)
		)
		(layer "F.Cu")
	)
	(gr_line
		(start 156.224986 -43.304968)
		(end 157.559502 -43.304968)
		(stroke
			(width 0.0635)
			(type default)
		)
		(layer "F.Cu")
	)
	(gr_line
		(start 156.659072 -31.584392)
		(end 156.67863 -31.580328)
		(stroke
			(width 0.08255)
			(type default)
		)
		(layer "F.Cu")
	)
	(gr_line
		(start 156.665676 -29.920946)
		(end 156.685234 -29.916882)
		(stroke
			(width 0.08255)
			(type default)
		)
		(layer "F.Cu")
	)
	(gr_line
		(start 156.67863 -31.580328)
		(end 156.698442 -31.584138)
		(stroke
			(width 0.08255)
			(type default)
		)
		(layer "F.Cu")
	)
	(gr_line
		(start 156.685234 -29.916882)
		(end 156.705046 -29.920692)
		(stroke
			(width 0.08255)
			(type default)
		)
		(layer "F.Cu")
	)
	(gr_line
		(start 156.720032 -137.85723)
		(end 156.902912 -137.67435)
		(stroke
			(width 0.127)
			(type default)
		)
		(layer "F.Cu")
	)
	(gr_line
		(start 156.720032 -136.84123)
		(end 156.902912 -137.02411)
		(stroke
			(width 0.127)
			(type default)
		)
		(layer "F.Cu")
	)
	(gr_line
		(start 157.559502 -278.385016)
		(end 157.686502 -278.258016)
		(stroke
			(width 0.0635)
			(type default)
		)
		(layer "F.Cu")
	)
	(gr_line
		(start 157.559502 -277.115016)
		(end 157.686502 -277.242016)
		(stroke
			(width 0.0635)
			(type default)
		)
		(layer "F.Cu")
	)
	(gr_line
		(start 157.559502 -274.575016)
		(end 157.686502 -274.448016)
		(stroke
			(width 0.0635)
			(type default)
		)
		(layer "F.Cu")
	)
	(gr_line
		(start 157.559502 -273.305016)
		(end 157.686502 -273.432016)
		(stroke
			(width 0.0635)
			(type default)
		)
		(layer "F.Cu")
	)
	(gr_line
		(start 157.559502 -163.384992)
		(end 157.686502 -163.257992)
		(stroke
			(width 0.0635)
			(type default)
		)
		(layer "F.Cu")
	)
	(gr_line
		(start 157.559502 -162.114992)
		(end 157.686502 -162.241992)
		(stroke
			(width 0.0635)
			(type default)
		)
		(layer "F.Cu")
	)
	(gr_line
		(start 157.559502 -159.574992)
		(end 157.686502 -159.447992)
		(stroke
			(width 0.0635)
			(type default)
		)
		(layer "F.Cu")
	)
	(gr_line
		(start 157.559502 -158.304992)
		(end 157.686502 -158.431992)
		(stroke
			(width 0.0635)
			(type default)
		)
		(layer "F.Cu")
	)
	(gr_line
		(start 157.559502 -48.384968)
		(end 157.686502 -48.257968)
		(stroke
			(width 0.0635)
			(type default)
		)
		(layer "F.Cu")
	)
	(gr_line
		(start 157.559502 -47.114968)
		(end 157.686502 -47.241968)
		(stroke
			(width 0.0635)
			(type default)
		)
		(layer "F.Cu")
	)
	(gr_line
		(start 157.559502 -44.574968)
		(end 157.686502 -44.447968)
		(stroke
			(width 0.0635)
			(type default)
		)
		(layer "F.Cu")
	)
	(gr_line
		(start 157.559502 -43.304968)
		(end 157.686502 -43.431968)
		(stroke
			(width 0.0635)
			(type default)
		)
		(layer "F.Cu")
	)
	(gr_line
		(start 157.629352 -137.67435)
		(end 157.748732 -137.79373)
		(stroke
			(width 0.127)
			(type default)
		)
		(layer "F.Cu")
	)
	(gr_line
		(start 157.629352 -137.02411)
		(end 157.748732 -136.90473)
		(stroke
			(width 0.127)
			(type default)
		)
		(layer "F.Cu")
	)
	(gr_line
		(start 157.686502 -278.023066)
		(end 157.686502 -278.258016)
		(stroke
			(width 0.0635)
			(type default)
		)
		(layer "F.Cu")
	)
	(gr_line
		(start 157.686502 -278.023066)
		(end 157.751272 -277.958296)
		(stroke
			(width 0.0635)
			(type default)
		)
		(layer "F.Cu")
	)
	(gr_line
		(start 157.686502 -277.476966)
		(end 157.751272 -277.541736)
		(stroke
			(width 0.0635)
			(type default)
		)
		(layer "F.Cu")
	)
	(gr_line
		(start 157.686502 -277.242016)
		(end 157.686502 -277.476966)
		(stroke
			(width 0.0635)
			(type default)
		)
		(layer "F.Cu")
	)
	(gr_line
		(start 157.686502 -274.213066)
		(end 157.686502 -274.448016)
		(stroke
			(width 0.0635)
			(type default)
		)
		(layer "F.Cu")
	)
	(gr_line
		(start 157.686502 -274.213066)
		(end 157.751272 -274.148296)
		(stroke
			(width 0.0635)
			(type default)
		)
		(layer "F.Cu")
	)
	(gr_line
		(start 157.686502 -273.666966)
		(end 157.751272 -273.731736)
		(stroke
			(width 0.0635)
			(type default)
		)
		(layer "F.Cu")
	)
	(gr_line
		(start 157.686502 -273.432016)
		(end 157.686502 -273.666966)
		(stroke
			(width 0.0635)
			(type default)
		)
		(layer "F.Cu")
	)
	(gr_line
		(start 157.686502 -163.044632)
		(end 157.686502 -163.257992)
		(stroke
			(width 0.0635)
			(type default)
		)
		(layer "F.Cu")
	)
	(gr_line
		(start 157.686502 -163.044632)
		(end 157.76194 -162.969194)
		(stroke
			(width 0.0635)
			(type default)
		)
		(layer "F.Cu")
	)
	(gr_line
		(start 157.686502 -162.476942)
		(end 157.76194 -162.55238)
		(stroke
			(width 0.0635)
			(type default)
		)
		(layer "F.Cu")
	)
	(gr_line
		(start 157.686502 -162.241992)
		(end 157.686502 -162.476942)
		(stroke
			(width 0.0635)
			(type default)
		)
		(layer "F.Cu")
	)
	(gr_line
		(start 157.686502 -159.213042)
		(end 157.686502 -159.447992)
		(stroke
			(width 0.0635)
			(type default)
		)
		(layer "F.Cu")
	)
	(gr_line
		(start 157.686502 -159.213042)
		(end 157.751272 -159.148272)
		(stroke
			(width 0.0635)
			(type default)
		)
		(layer "F.Cu")
	)
	(gr_line
		(start 157.686502 -158.666942)
		(end 157.751272 -158.731712)
		(stroke
			(width 0.0635)
			(type default)
		)
		(layer "F.Cu")
	)
	(gr_line
		(start 157.686502 -158.431992)
		(end 157.686502 -158.666942)
		(stroke
			(width 0.0635)
			(type default)
		)
		(layer "F.Cu")
	)
	(gr_line
		(start 157.686502 -48.040798)
		(end 157.686502 -48.257968)
		(stroke
			(width 0.0635)
			(type default)
		)
		(layer "F.Cu")
	)
	(gr_line
		(start 157.686502 -48.040798)
		(end 157.760162 -47.967138)
		(stroke
			(width 0.0635)
			(type default)
		)
		(layer "F.Cu")
	)
	(gr_line
		(start 157.686502 -47.476918)
		(end 157.760162 -47.550578)
		(stroke
			(width 0.0635)
			(type default)
		)
		(layer "F.Cu")
	)
	(gr_line
		(start 157.686502 -47.241968)
		(end 157.686502 -47.476918)
		(stroke
			(width 0.0635)
			(type default)
		)
		(layer "F.Cu")
	)
	(gr_line
		(start 157.686502 -44.213018)
		(end 157.686502 -44.447968)
		(stroke
			(width 0.0635)
			(type default)
		)
		(layer "F.Cu")
	)
	(gr_line
		(start 157.686502 -44.213018)
		(end 157.751272 -44.148248)
		(stroke
			(width 0.0635)
			(type default)
		)
		(layer "F.Cu")
	)
	(gr_line
		(start 157.686502 -43.666918)
		(end 157.751272 -43.731688)
		(stroke
			(width 0.0635)
			(type default)
		)
		(layer "F.Cu")
	)
	(gr_line
		(start 157.686502 -43.431968)
		(end 157.686502 -43.666918)
		(stroke
			(width 0.0635)
			(type default)
		)
		(layer "F.Cu")
	)
	(gr_line
		(start 157.748732 -137.79373)
		(end 158.271464 -137.79373)
		(stroke
			(width 0.127)
			(type default)
		)
		(layer "F.Cu")
	)
	(gr_line
		(start 157.748732 -136.90473)
		(end 158.271464 -136.90473)
		(stroke
			(width 0.127)
			(type default)
		)
		(layer "F.Cu")
	)
	(gr_line
		(start 157.928818 -274.095464)
		(end 158.05277 -274.219416)
		(stroke
			(width 0.0635)
			(type default)
		)
		(layer "F.Cu")
	)
	(gr_line
		(start 157.928818 -273.784568)
		(end 158.05277 -273.660616)
		(stroke
			(width 0.0635)
			(type default)
		)
		(layer "F.Cu")
	)
	(gr_line
		(start 157.928818 -159.09544)
		(end 158.05277 -159.219392)
		(stroke
			(width 0.0635)
			(type default)
		)
		(layer "F.Cu")
	)
	(gr_line
		(start 157.928818 -158.784544)
		(end 158.05277 -158.660592)
		(stroke
			(width 0.0635)
			(type default)
		)
		(layer "F.Cu")
	)
	(gr_line
		(start 157.928818 -44.095416)
		(end 158.05277 -44.219368)
		(stroke
			(width 0.0635)
			(type default)
		)
		(layer "F.Cu")
	)
	(gr_line
		(start 157.928818 -43.78452)
		(end 158.05277 -43.660568)
		(stroke
			(width 0.0635)
			(type default)
		)
		(layer "F.Cu")
	)
	(gr_line
		(start 158.05277 -274.219416)
		(end 158.383986 -274.219416)
		(stroke
			(width 0.0635)
			(type default)
		)
		(layer "F.Cu")
	)
	(gr_line
		(start 158.05277 -273.660616)
		(end 158.383986 -273.660616)
		(stroke
			(width 0.0635)
			(type default)
		)
		(layer "F.Cu")
	)
	(gr_line
		(start 158.05277 -159.219392)
		(end 158.383986 -159.219392)
		(stroke
			(width 0.0635)
			(type default)
		)
		(layer "F.Cu")
	)
	(gr_line
		(start 158.05277 -158.660592)
		(end 158.383986 -158.660592)
		(stroke
			(width 0.0635)
			(type default)
		)
		(layer "F.Cu")
	)
	(gr_line
		(start 158.05277 -44.219368)
		(end 158.383986 -44.219368)
		(stroke
			(width 0.0635)
			(type default)
		)
		(layer "F.Cu")
	)
	(gr_line
		(start 158.05277 -43.660568)
		(end 158.383986 -43.660568)
		(stroke
			(width 0.0635)
			(type default)
		)
		(layer "F.Cu")
	)
	(gr_line
		(start 158.271464 -137.79373)
		(end 158.390844 -137.67435)
		(stroke
			(width 0.127)
			(type default)
		)
		(layer "F.Cu")
	)
	(gr_line
		(start 158.271464 -136.90473)
		(end 158.390844 -137.02411)
		(stroke
			(width 0.127)
			(type default)
		)
		(layer "F.Cu")
	)
	(gr_line
		(start 158.36519 -343.069164)
		(end 158.38678 -343.073482)
		(stroke
			(width 0.0635)
			(type default)
		)
		(layer "F.Cu")
	)
	(gr_line
		(start 158.38678 -343.073482)
		(end 158.40837 -343.069164)
		(stroke
			(width 0.0635)
			(type default)
		)
		(layer "F.Cu")
	)
	(gr_line
		(start 158.552896 -341.39378)
		(end 158.574486 -341.398098)
		(stroke
			(width 0.0635)
			(type default)
		)
		(layer "F.Cu")
	)
	(gr_line
		(start 158.574486 -341.398098)
		(end 158.596076 -341.39378)
		(stroke
			(width 0.0635)
			(type default)
		)
		(layer "F.Cu")
	)
	(gr_arc
		(start 158.581852 -277.603966)
		(mid 158.671674 -277.566783)
		(end 158.708852 -277.476966)
		(stroke
			(width 0.0635)
			(type default)
		)
		(layer "F.Cu")
	)
	(gr_arc
		(start 158.581852 -162.603942)
		(mid 158.671655 -162.566745)
		(end 158.708852 -162.476942)
		(stroke
			(width 0.0635)
			(type default)
		)
		(layer "F.Cu")
	)
	(gr_arc
		(start 158.581852 -47.603918)
		(mid 158.671692 -47.566739)
		(end 158.708852 -47.476918)
		(stroke
			(width 0.0635)
			(type default)
		)
		(layer "F.Cu")
	)
	(gr_arc
		(start 158.708852 -278.023066)
		(mid 158.671655 -277.933263)
		(end 158.581852 -277.896066)
		(stroke
			(width 0.0635)
			(type default)
		)
		(layer "F.Cu")
	)
	(gr_line
		(start 158.708852 -278.023066)
		(end 158.708852 -278.321516)
		(stroke
			(width 0.0635)
			(type default)
		)
		(layer "F.Cu")
	)
	(gr_line
		(start 158.708852 -277.178516)
		(end 158.708852 -277.476966)
		(stroke
			(width 0.0635)
			(type default)
		)
		(layer "F.Cu")
	)
	(gr_arc
		(start 158.708852 -163.023042)
		(mid 158.671667 -162.933229)
		(end 158.581852 -162.896042)
		(stroke
			(width 0.0635)
			(type default)
		)
		(layer "F.Cu")
	)
	(gr_line
		(start 158.708852 -163.023042)
		(end 158.708852 -163.321492)
		(stroke
			(width 0.0635)
			(type default)
		)
		(layer "F.Cu")
	)
	(gr_line
		(start 158.708852 -162.178492)
		(end 158.708852 -162.476942)
		(stroke
			(width 0.0635)
			(type default)
		)
		(layer "F.Cu")
	)
	(gr_arc
		(start 158.708852 -48.023018)
		(mid 158.671655 -47.933215)
		(end 158.581852 -47.896018)
		(stroke
			(width 0.0635)
			(type default)
		)
		(layer "F.Cu")
	)
	(gr_line
		(start 158.708852 -48.023018)
		(end 158.708852 -48.321468)
		(stroke
			(width 0.0635)
			(type default)
		)
		(layer "F.Cu")
	)
	(gr_line
		(start 158.708852 -47.178468)
		(end 158.708852 -47.476918)
		(stroke
			(width 0.0635)
			(type default)
		)
		(layer "F.Cu")
	)
	(gr_line
		(start 158.942786 -274.219416)
		(end 159.401002 -274.219416)
		(stroke
			(width 0.0635)
			(type default)
		)
		(layer "F.Cu")
	)
	(gr_line
		(start 158.942786 -273.660616)
		(end 159.401002 -273.660616)
		(stroke
			(width 0.0635)
			(type default)
		)
		(layer "F.Cu")
	)
	(gr_line
		(start 158.942786 -159.219392)
		(end 159.451802 -159.219392)
		(stroke
			(width 0.0635)
			(type default)
		)
		(layer "F.Cu")
	)
	(gr_line
		(start 158.942786 -158.660592)
		(end 159.451802 -158.660592)
		(stroke
			(width 0.0635)
			(type default)
		)
		(layer "F.Cu")
	)
	(gr_line
		(start 158.942786 -44.219368)
		(end 159.350202 -44.219368)
		(stroke
			(width 0.0635)
			(type default)
		)
		(layer "F.Cu")
	)
	(gr_line
		(start 158.942786 -43.660568)
		(end 159.350202 -43.660568)
		(stroke
			(width 0.0635)
			(type default)
		)
		(layer "F.Cu")
	)
	(gr_line
		(start 158.944056 -339.736938)
		(end 158.965646 -339.741256)
		(stroke
			(width 0.0635)
			(type default)
		)
		(layer "F.Cu")
	)
	(gr_line
		(start 158.965646 -339.741256)
		(end 158.987236 -339.736938)
		(stroke
			(width 0.0635)
			(type default)
		)
		(layer "F.Cu")
	)
	(gr_line
		(start 159.033464 -137.67435)
		(end 159.258 -137.898886)
		(stroke
			(width 0.127)
			(type default)
		)
		(layer "F.Cu")
	)
	(gr_line
		(start 159.033464 -137.02411)
		(end 159.258 -136.799574)
		(stroke
			(width 0.127)
			(type default)
		)
		(layer "F.Cu")
	)
	(gr_line
		(start 159.057086 -338.135214)
		(end 159.078676 -338.139532)
		(stroke
			(width 0.0635)
			(type default)
		)
		(layer "F.Cu")
	)
	(gr_line
		(start 159.078676 -338.139532)
		(end 159.100266 -338.135214)
		(stroke
			(width 0.0635)
			(type default)
		)
		(layer "F.Cu")
	)
	(gr_line
		(start 159.350202 -44.219368)
		(end 159.421322 -44.148248)
		(stroke
			(width 0.0635)
			(type default)
		)
		(layer "F.Cu")
	)
	(gr_line
		(start 159.350202 -43.660568)
		(end 159.421322 -43.731688)
		(stroke
			(width 0.0635)
			(type default)
		)
		(layer "F.Cu")
	)
	(gr_line
		(start 159.401002 -274.219416)
		(end 159.472122 -274.148296)
		(stroke
			(width 0.0635)
			(type default)
		)
		(layer "F.Cu")
	)
	(gr_line
		(start 159.401002 -273.660616)
		(end 159.472122 -273.731736)
		(stroke
			(width 0.0635)
			(type default)
		)
		(layer "F.Cu")
	)
	(gr_line
		(start 159.451802 -159.219392)
		(end 159.522922 -159.148272)
		(stroke
			(width 0.0635)
			(type default)
		)
		(layer "F.Cu")
	)
	(gr_line
		(start 159.451802 -158.660592)
		(end 159.522922 -158.731712)
		(stroke
			(width 0.0635)
			(type default)
		)
		(layer "F.Cu")
	)
	(gr_line
		(start 160.032446 -43.814492)
		(end 160.071816 -43.839384)
		(stroke
			(width 0.0635)
			(type default)
		)
		(layer "F.Cu")
	)
	(gr_line
		(start 160.297876 -273.839178)
		(end 160.337246 -273.86407)
		(stroke
			(width 0.0635)
			(type default)
		)
		(layer "F.Cu")
	)
	(gr_line
		(start 160.541716 -158.941262)
		(end 160.554162 -158.944056)
		(stroke
			(width 0.0635)
			(type default)
		)
		(layer "F.Cu")
	)
	(gr_line
		(start 160.554162 -158.944056)
		(end 160.565338 -158.951168)
		(stroke
			(width 0.0635)
			(type default)
		)
		(layer "F.Cu")
	)
	(gr_line
		(start 161.445702 -274.565618)
		(end 161.49828 -274.598892)
		(stroke
			(width 0.0635)
			(type default)
		)
		(layer "F.Cu")
	)
	(gr_line
		(start 161.49828 -274.598892)
		(end 161.51987 -274.657312)
		(stroke
			(width 0.0635)
			(type default)
		)
		(layer "F.Cu")
	)
	(gr_line
		(start 161.703512 -44.87291)
		(end 161.755328 -44.905422)
		(stroke
			(width 0.0635)
			(type default)
		)
		(layer "F.Cu")
	)
	(gr_line
		(start 161.755328 -44.905422)
		(end 161.776918 -44.963842)
		(stroke
			(width 0.0635)
			(type default)
		)
		(layer "F.Cu")
	)
	(gr_line
		(start 161.9377 -159.825436)
		(end 161.959798 -159.83966)
		(stroke
			(width 0.0635)
			(type default)
		)
		(layer "F.Cu")
	)
	(gr_line
		(start 161.959798 -159.83966)
		(end 161.974022 -159.861758)
		(stroke
			(width 0.0635)
			(type default)
		)
		(layer "F.Cu")
	)
	(gr_line
		(start 163.18865 -161.768282)
		(end 163.195762 -161.779458)
		(stroke
			(width 0.0635)
			(type default)
		)
		(layer "F.Cu")
	)
	(gr_line
		(start 163.195762 -161.779458)
		(end 163.198556 -161.791904)
		(stroke
			(width 0.0635)
			(type default)
		)
		(layer "F.Cu")
	)
	(gr_line
		(start 165.016434 -172.04563)
		(end 165.09873 -172.417486)
		(stroke
			(width 0.0635)
			(type default)
		)
		(layer "F.Cu")
	)
	(gr_line
		(start 165.016434 -172.04563)
		(end 165.130226 -171.86656)
		(stroke
			(width 0.0635)
			(type default)
		)
		(layer "F.Cu")
	)
	(gr_line
		(start 165.09873 -172.417486)
		(end 165.277546 -172.531532)
		(stroke
			(width 0.0635)
			(type default)
		)
		(layer "F.Cu")
	)
	(gr_line
		(start 165.24732 -173.08703)
		(end 165.329616 -173.45914)
		(stroke
			(width 0.0635)
			(type default)
		)
		(layer "F.Cu")
	)
	(gr_line
		(start 165.24732 -173.08703)
		(end 165.361112 -172.908468)
		(stroke
			(width 0.0635)
			(type default)
		)
		(layer "F.Cu")
	)
	(gr_line
		(start 165.329616 -173.45914)
		(end 165.508432 -173.573186)
		(stroke
			(width 0.0635)
			(type default)
		)
		(layer "F.Cu")
	)
	(gr_line
		(start 165.35019 -172.847)
		(end 165.363144 -172.90542)
		(stroke
			(width 0.0635)
			(type default)
		)
		(layer "F.Cu")
	)
	(gr_line
		(start 165.425374 -171.835826)
		(end 165.557708 -172.43298)
		(stroke
			(width 0.0635)
			(type default)
		)
		(layer "F.Cu")
	)
	(gr_line
		(start 165.478206 -174.128684)
		(end 165.560502 -174.50054)
		(stroke
			(width 0.0635)
			(type default)
		)
		(layer "F.Cu")
	)
	(gr_line
		(start 165.478206 -174.128684)
		(end 165.591998 -173.949868)
		(stroke
			(width 0.0635)
			(type default)
		)
		(layer "F.Cu")
	)
	(gr_line
		(start 165.560502 -174.50054)
		(end 165.739318 -174.614586)
		(stroke
			(width 0.0635)
			(type default)
		)
		(layer "F.Cu")
	)
	(gr_line
		(start 165.577774 -173.873668)
		(end 165.59403 -173.94682)
		(stroke
			(width 0.0635)
			(type default)
		)
		(layer "F.Cu")
	)
	(gr_line
		(start 165.656768 -172.879766)
		(end 165.788594 -173.474888)
		(stroke
			(width 0.0635)
			(type default)
		)
		(layer "F.Cu")
	)
	(gr_line
		(start 165.709092 -175.170084)
		(end 165.791388 -175.542194)
		(stroke
			(width 0.0635)
			(type default)
		)
		(layer "F.Cu")
	)
	(gr_line
		(start 165.709092 -175.170084)
		(end 165.822884 -174.991522)
		(stroke
			(width 0.0635)
			(type default)
		)
		(layer "F.Cu")
	)
	(gr_line
		(start 165.791388 -175.542194)
		(end 165.970458 -175.65624)
		(stroke
			(width 0.0635)
			(type default)
		)
		(layer "F.Cu")
	)
	(gr_line
		(start 165.87851 -173.880272)
		(end 165.880034 -173.88713)
		(stroke
			(width 0.0635)
			(type default)
		)
		(layer "F.Cu")
	)
	(gr_line
		(start 165.887654 -173.921166)
		(end 166.01948 -174.516288)
		(stroke
			(width 0.0635)
			(type default)
		)
		(layer "F.Cu")
	)
	(gr_line
		(start 166.118286 -174.962312)
		(end 166.25062 -175.55845)
		(stroke
			(width 0.0635)
			(type default)
		)
		(layer "F.Cu")
	)
	(gr_line
		(start 166.369238 -177.4444)
		(end 166.374318 -177.467006)
		(stroke
			(width 0.0635)
			(type default)
		)
		(layer "F.Cu")
	)
	(gr_line
		(start 166.374318 -177.467006)
		(end 166.374572 -177.467006)
		(stroke
			(width 0.0635)
			(type default)
		)
		(layer "F.Cu")
	)
	(gr_line
		(start 166.374572 -177.467006)
		(end 166.387272 -177.484532)
		(stroke
			(width 0.0635)
			(type default)
		)
		(layer "F.Cu")
	)
	(gr_line
		(start 167.268652 -126.257558)
		(end 167.299132 -126.265178)
		(stroke
			(width 0.0635)
			(type default)
		)
		(layer "F.Cu")
	)
	(gr_line
		(start 167.299132 -126.265178)
		(end 167.322754 -126.28499)
		(stroke
			(width 0.0635)
			(type default)
		)
		(layer "F.Cu")
	)
	(gr_line
		(start 168.518586 -243.482368)
		(end 168.537382 -243.51234)
		(stroke
			(width 0.0635)
			(type default)
		)
		(layer "F.Cu")
	)
	(gr_line
		(start 168.537382 -243.51234)
		(end 168.56837 -243.529612)
		(stroke
			(width 0.0635)
			(type default)
		)
		(layer "F.Cu")
	)
	(gr_line
		(start 168.962324 -32.629602)
		(end 168.982136 -32.633412)
		(stroke
			(width 0.08255)
			(type default)
		)
		(layer "F.Cu")
	)
	(gr_line
		(start 168.982136 -32.633412)
		(end 169.001694 -32.629348)
		(stroke
			(width 0.08255)
			(type default)
		)
		(layer "F.Cu")
	)
	(gr_line
		(start 169.201338 -34.34207)
		(end 169.22115 -34.34588)
		(stroke
			(width 0.08255)
			(type default)
		)
		(layer "F.Cu")
	)
	(gr_line
		(start 169.22115 -34.34588)
		(end 169.240708 -34.341816)
		(stroke
			(width 0.08255)
			(type default)
		)
		(layer "F.Cu")
	)
	(gr_line
		(start 173.568614 -147.441666)
		(end 173.568614 -148.926296)
		(stroke
			(width 0.127)
			(type default)
		)
		(layer "F.Cu")
	)
	(gr_line
		(start 175.195738 -147.441666)
		(end 175.195738 -148.926296)
		(stroke
			(width 0.127)
			(type default)
		)
		(layer "F.Cu")
	)
	(gr_line
		(start 177.43805 -309.205376)
		(end 177.451258 -309.22595)
		(stroke
			(width 0.0635)
			(type default)
		)
		(layer "F.Cu")
	)
	(gr_line
		(start 177.451258 -309.22595)
		(end 177.471832 -309.239158)
		(stroke
			(width 0.0635)
			(type default)
		)
		(layer "F.Cu")
	)
	(gr_line
		(start 182.176928 -29.64434)
		(end 182.196486 -29.640276)
		(stroke
			(width 0.08255)
			(type default)
		)
		(layer "F.Cu")
	)
	(gr_line
		(start 182.196486 -29.640276)
		(end 182.216298 -29.644086)
		(stroke
			(width 0.08255)
			(type default)
		)
		(layer "F.Cu")
	)
	(gr_line
		(start 182.390034 -31.361888)
		(end 182.409592 -31.357824)
		(stroke
			(width 0.08255)
			(type default)
		)
		(layer "F.Cu")
	)
	(gr_line
		(start 182.409592 -31.357824)
		(end 182.429404 -31.361634)
		(stroke
			(width 0.08255)
			(type default)
		)
		(layer "F.Cu")
	)
	(gr_line
		(start 185.09234 -134.10184)
		(end 185.126884 -134.125462)
		(stroke
			(width 0.0635)
			(type default)
		)
		(layer "F.Cu")
	)
	(gr_line
		(start 185.126884 -134.125462)
		(end 185.145172 -134.163308)
		(stroke
			(width 0.0635)
			(type default)
		)
		(layer "F.Cu")
	)
	(gr_line
		(start 187.52693 -32.365188)
		(end 187.54471 -32.36849)
		(stroke
			(width 0.08255)
			(type default)
		)
		(layer "F.Cu")
	)
	(gr_line
		(start 187.54471 -32.36849)
		(end 187.560458 -32.37865)
		(stroke
			(width 0.08255)
			(type default)
		)
		(layer "F.Cu")
	)
	(gr_line
		(start 187.775088 -278.385016)
		(end 189.109604 -278.385016)
		(stroke
			(width 0.0635)
			(type default)
		)
		(layer "F.Cu")
	)
	(gr_line
		(start 187.775088 -277.115016)
		(end 189.109604 -277.115016)
		(stroke
			(width 0.0635)
			(type default)
		)
		(layer "F.Cu")
	)
	(gr_line
		(start 187.775088 -274.575016)
		(end 189.109604 -274.575016)
		(stroke
			(width 0.0635)
			(type default)
		)
		(layer "F.Cu")
	)
	(gr_line
		(start 187.775088 -273.305016)
		(end 189.109604 -273.305016)
		(stroke
			(width 0.0635)
			(type default)
		)
		(layer "F.Cu")
	)
	(gr_line
		(start 187.775088 -163.384992)
		(end 189.109604 -163.384992)
		(stroke
			(width 0.0635)
			(type default)
		)
		(layer "F.Cu")
	)
	(gr_line
		(start 187.775088 -162.114992)
		(end 189.109604 -162.114992)
		(stroke
			(width 0.0635)
			(type default)
		)
		(layer "F.Cu")
	)
	(gr_line
		(start 187.775088 -159.574992)
		(end 189.109604 -159.574992)
		(stroke
			(width 0.0635)
			(type default)
		)
		(layer "F.Cu")
	)
	(gr_line
		(start 187.775088 -158.304992)
		(end 189.109604 -158.304992)
		(stroke
			(width 0.0635)
			(type default)
		)
		(layer "F.Cu")
	)
	(gr_line
		(start 187.775088 -48.384968)
		(end 189.079124 -48.384968)
		(stroke
			(width 0.0635)
			(type default)
		)
		(layer "F.Cu")
	)
	(gr_line
		(start 187.775088 -47.114968)
		(end 189.109604 -47.114968)
		(stroke
			(width 0.0635)
			(type default)
		)
		(layer "F.Cu")
	)
	(gr_line
		(start 187.775088 -44.574968)
		(end 189.109604 -44.574968)
		(stroke
			(width 0.0635)
			(type default)
		)
		(layer "F.Cu")
	)
	(gr_line
		(start 187.775088 -43.304968)
		(end 189.109604 -43.304968)
		(stroke
			(width 0.0635)
			(type default)
		)
		(layer "F.Cu")
	)
	(gr_line
		(start 187.996576 -30.78226)
		(end 188.014356 -30.785562)
		(stroke
			(width 0.08255)
			(type default)
		)
		(layer "F.Cu")
	)
	(gr_line
		(start 188.014356 -30.785562)
		(end 188.030104 -30.795722)
		(stroke
			(width 0.08255)
			(type default)
		)
		(layer "F.Cu")
	)
	(gr_line
		(start 189.079124 -48.384968)
		(end 189.236604 -48.227488)
		(stroke
			(width 0.0635)
			(type default)
		)
		(layer "F.Cu")
	)
	(gr_line
		(start 189.109604 -278.385016)
		(end 189.236604 -278.258016)
		(stroke
			(width 0.0635)
			(type default)
		)
		(layer "F.Cu")
	)
	(gr_line
		(start 189.109604 -277.115016)
		(end 189.236604 -277.242016)
		(stroke
			(width 0.0635)
			(type default)
		)
		(layer "F.Cu")
	)
	(gr_line
		(start 189.109604 -274.575016)
		(end 189.236604 -274.448016)
		(stroke
			(width 0.0635)
			(type default)
		)
		(layer "F.Cu")
	)
	(gr_line
		(start 189.109604 -273.305016)
		(end 189.236604 -273.432016)
		(stroke
			(width 0.0635)
			(type default)
		)
		(layer "F.Cu")
	)
	(gr_line
		(start 189.109604 -163.384992)
		(end 189.236604 -163.257992)
		(stroke
			(width 0.0635)
			(type default)
		)
		(layer "F.Cu")
	)
	(gr_line
		(start 189.109604 -162.114992)
		(end 189.236604 -162.241992)
		(stroke
			(width 0.0635)
			(type default)
		)
		(layer "F.Cu")
	)
	(gr_line
		(start 189.109604 -159.574992)
		(end 189.236604 -159.447992)
		(stroke
			(width 0.0635)
			(type default)
		)
		(layer "F.Cu")
	)
	(gr_line
		(start 189.109604 -158.304992)
		(end 189.236604 -158.431992)
		(stroke
			(width 0.0635)
			(type default)
		)
		(layer "F.Cu")
	)
	(gr_line
		(start 189.109604 -47.114968)
		(end 189.236604 -47.241968)
		(stroke
			(width 0.0635)
			(type default)
		)
		(layer "F.Cu")
	)
	(gr_line
		(start 189.109604 -44.574968)
		(end 189.236604 -44.447968)
		(stroke
			(width 0.0635)
			(type default)
		)
		(layer "F.Cu")
	)
	(gr_line
		(start 189.109604 -43.304968)
		(end 189.236604 -43.431968)
		(stroke
			(width 0.0635)
			(type default)
		)
		(layer "F.Cu")
	)
	(gr_line
		(start 189.236604 -278.023066)
		(end 189.236604 -278.258016)
		(stroke
			(width 0.0635)
			(type default)
		)
		(layer "F.Cu")
	)
	(gr_line
		(start 189.236604 -278.023066)
		(end 189.301374 -277.958296)
		(stroke
			(width 0.0635)
			(type default)
		)
		(layer "F.Cu")
	)
	(gr_line
		(start 189.236604 -277.476966)
		(end 189.301374 -277.541736)
		(stroke
			(width 0.0635)
			(type default)
		)
		(layer "F.Cu")
	)
	(gr_line
		(start 189.236604 -277.242016)
		(end 189.236604 -277.476966)
		(stroke
			(width 0.0635)
			(type default)
		)
		(layer "F.Cu")
	)
	(gr_line
		(start 189.236604 -274.213066)
		(end 189.236604 -274.448016)
		(stroke
			(width 0.0635)
			(type default)
		)
		(layer "F.Cu")
	)
	(gr_line
		(start 189.236604 -274.213066)
		(end 189.301374 -274.148296)
		(stroke
			(width 0.0635)
			(type default)
		)
		(layer "F.Cu")
	)
	(gr_line
		(start 189.236604 -273.666966)
		(end 189.301374 -273.731736)
		(stroke
			(width 0.0635)
			(type default)
		)
		(layer "F.Cu")
	)
	(gr_line
		(start 189.236604 -273.432016)
		(end 189.236604 -273.666966)
		(stroke
			(width 0.0635)
			(type default)
		)
		(layer "F.Cu")
	)
	(gr_line
		(start 189.236604 -163.023042)
		(end 189.236604 -163.257992)
		(stroke
			(width 0.0635)
			(type default)
		)
		(layer "F.Cu")
	)
	(gr_line
		(start 189.236604 -163.023042)
		(end 189.301374 -162.958272)
		(stroke
			(width 0.0635)
			(type default)
		)
		(layer "F.Cu")
	)
	(gr_line
		(start 189.236604 -162.476942)
		(end 189.301374 -162.541712)
		(stroke
			(width 0.0635)
			(type default)
		)
		(layer "F.Cu")
	)
	(gr_line
		(start 189.236604 -162.241992)
		(end 189.236604 -162.476942)
		(stroke
			(width 0.0635)
			(type default)
		)
		(layer "F.Cu")
	)
	(gr_line
		(start 189.236604 -159.213042)
		(end 189.236604 -159.447992)
		(stroke
			(width 0.0635)
			(type default)
		)
		(layer "F.Cu")
	)
	(gr_line
		(start 189.236604 -159.213042)
		(end 189.301374 -159.148272)
		(stroke
			(width 0.0635)
			(type default)
		)
		(layer "F.Cu")
	)
	(gr_line
		(start 189.236604 -158.666942)
		(end 189.301374 -158.731712)
		(stroke
			(width 0.0635)
			(type default)
		)
		(layer "F.Cu")
	)
	(gr_line
		(start 189.236604 -158.431992)
		(end 189.236604 -158.666942)
		(stroke
			(width 0.0635)
			(type default)
		)
		(layer "F.Cu")
	)
	(gr_line
		(start 189.236604 -48.023018)
		(end 189.236604 -48.227488)
		(stroke
			(width 0.0635)
			(type default)
		)
		(layer "F.Cu")
	)
	(gr_line
		(start 189.236604 -48.023018)
		(end 189.301374 -47.958248)
		(stroke
			(width 0.0635)
			(type default)
		)
		(layer "F.Cu")
	)
	(gr_line
		(start 189.236604 -47.476918)
		(end 189.301374 -47.541688)
		(stroke
			(width 0.0635)
			(type default)
		)
		(layer "F.Cu")
	)
	(gr_line
		(start 189.236604 -47.241968)
		(end 189.236604 -47.476918)
		(stroke
			(width 0.0635)
			(type default)
		)
		(layer "F.Cu")
	)
	(gr_line
		(start 189.236604 -44.213018)
		(end 189.236604 -44.447968)
		(stroke
			(width 0.0635)
			(type default)
		)
		(layer "F.Cu")
	)
	(gr_line
		(start 189.236604 -44.213018)
		(end 189.301374 -44.148248)
		(stroke
			(width 0.0635)
			(type default)
		)
		(layer "F.Cu")
	)
	(gr_line
		(start 189.236604 -43.666918)
		(end 189.301374 -43.731688)
		(stroke
			(width 0.0635)
			(type default)
		)
		(layer "F.Cu")
	)
	(gr_line
		(start 189.236604 -43.431968)
		(end 189.236604 -43.666918)
		(stroke
			(width 0.0635)
			(type default)
		)
		(layer "F.Cu")
	)
	(gr_line
		(start 189.47892 -274.095464)
		(end 189.602872 -274.219416)
		(stroke
			(width 0.0635)
			(type default)
		)
		(layer "F.Cu")
	)
	(gr_line
		(start 189.47892 -273.784568)
		(end 189.602872 -273.660616)
		(stroke
			(width 0.0635)
			(type default)
		)
		(layer "F.Cu")
	)
	(gr_line
		(start 189.47892 -159.09544)
		(end 189.602872 -159.219392)
		(stroke
			(width 0.0635)
			(type default)
		)
		(layer "F.Cu")
	)
	(gr_line
		(start 189.47892 -158.784544)
		(end 189.602872 -158.660592)
		(stroke
			(width 0.0635)
			(type default)
		)
		(layer "F.Cu")
	)
	(gr_line
		(start 189.47892 -44.095416)
		(end 189.602872 -44.219368)
		(stroke
			(width 0.0635)
			(type default)
		)
		(layer "F.Cu")
	)
	(gr_line
		(start 189.47892 -43.78452)
		(end 189.602872 -43.660568)
		(stroke
			(width 0.0635)
			(type default)
		)
		(layer "F.Cu")
	)
	(gr_line
		(start 189.602872 -274.219416)
		(end 189.934088 -274.219416)
		(stroke
			(width 0.0635)
			(type default)
		)
		(layer "F.Cu")
	)
	(gr_line
		(start 189.602872 -273.660616)
		(end 189.934088 -273.660616)
		(stroke
			(width 0.0635)
			(type default)
		)
		(layer "F.Cu")
	)
	(gr_line
		(start 189.602872 -159.219392)
		(end 189.934088 -159.219392)
		(stroke
			(width 0.0635)
			(type default)
		)
		(layer "F.Cu")
	)
	(gr_line
		(start 189.602872 -158.660592)
		(end 189.934088 -158.660592)
		(stroke
			(width 0.0635)
			(type default)
		)
		(layer "F.Cu")
	)
	(gr_line
		(start 189.602872 -44.219368)
		(end 189.934088 -44.219368)
		(stroke
			(width 0.0635)
			(type default)
		)
		(layer "F.Cu")
	)
	(gr_line
		(start 189.602872 -43.660568)
		(end 189.934088 -43.660568)
		(stroke
			(width 0.0635)
			(type default)
		)
		(layer "F.Cu")
	)
	(gr_arc
		(start 190.131954 -277.603966)
		(mid 190.221774 -277.566783)
		(end 190.258954 -277.476966)
		(stroke
			(width 0.0635)
			(type default)
		)
		(layer "F.Cu")
	)
	(gr_arc
		(start 190.131954 -162.603942)
		(mid 190.221801 -162.566763)
		(end 190.258954 -162.476942)
		(stroke
			(width 0.0635)
			(type default)
		)
		(layer "F.Cu")
	)
	(gr_arc
		(start 190.131954 -47.603918)
		(mid 190.221793 -47.566738)
		(end 190.258954 -47.476918)
		(stroke
			(width 0.0635)
			(type default)
		)
		(layer "F.Cu")
	)
	(gr_arc
		(start 190.258954 -278.023066)
		(mid 190.221757 -277.933263)
		(end 190.131954 -277.896066)
		(stroke
			(width 0.0635)
			(type default)
		)
		(layer "F.Cu")
	)
	(gr_line
		(start 190.258954 -278.023066)
		(end 190.258954 -278.321516)
		(stroke
			(width 0.0635)
			(type default)
		)
		(layer "F.Cu")
	)
	(gr_line
		(start 190.258954 -277.178516)
		(end 190.258954 -277.476966)
		(stroke
			(width 0.0635)
			(type default)
		)
		(layer "F.Cu")
	)
	(gr_arc
		(start 190.258954 -163.023042)
		(mid 190.221757 -162.933239)
		(end 190.131954 -162.896042)
		(stroke
			(width 0.0635)
			(type default)
		)
		(layer "F.Cu")
	)
	(gr_line
		(start 190.258954 -163.023042)
		(end 190.258954 -163.321492)
		(stroke
			(width 0.0635)
			(type default)
		)
		(layer "F.Cu")
	)
	(gr_line
		(start 190.258954 -162.178492)
		(end 190.258954 -162.476942)
		(stroke
			(width 0.0635)
			(type default)
		)
		(layer "F.Cu")
	)
	(gr_arc
		(start 190.258954 -48.023018)
		(mid 190.221757 -47.933215)
		(end 190.131954 -47.896018)
		(stroke
			(width 0.0635)
			(type default)
		)
		(layer "F.Cu")
	)
	(gr_line
		(start 190.258954 -48.023018)
		(end 190.258954 -48.321468)
		(stroke
			(width 0.0635)
			(type default)
		)
		(layer "F.Cu")
	)
	(gr_line
		(start 190.258954 -47.178468)
		(end 190.258954 -47.476918)
		(stroke
			(width 0.0635)
			(type default)
		)
		(layer "F.Cu")
	)
	(gr_line
		(start 190.430404 -75.67168)
		(end 190.43904 -75.705462)
		(stroke
			(width 0.0635)
			(type default)
		)
		(layer "F.Cu")
	)
	(gr_line
		(start 190.430404 -75.67168)
		(end 190.43904 -75.637136)
		(stroke
			(width 0.0635)
			(type default)
		)
		(layer "F.Cu")
	)
	(gr_line
		(start 190.443612 -188.368432)
		(end 190.449962 -188.397642)
		(stroke
			(width 0.0635)
			(type default)
		)
		(layer "F.Cu")
	)
	(gr_line
		(start 190.443612 -188.368432)
		(end 190.450978 -188.33846)
		(stroke
			(width 0.0635)
			(type default)
		)
		(layer "F.Cu")
	)
	(gr_line
		(start 190.492888 -274.219416)
		(end 190.925704 -274.219416)
		(stroke
			(width 0.0635)
			(type default)
		)
		(layer "F.Cu")
	)
	(gr_line
		(start 190.492888 -273.660616)
		(end 190.925704 -273.660616)
		(stroke
			(width 0.0635)
			(type default)
		)
		(layer "F.Cu")
	)
	(gr_line
		(start 190.492888 -159.219392)
		(end 190.976504 -159.219392)
		(stroke
			(width 0.0635)
			(type default)
		)
		(layer "F.Cu")
	)
	(gr_line
		(start 190.492888 -158.660592)
		(end 190.976504 -158.660592)
		(stroke
			(width 0.0635)
			(type default)
		)
		(layer "F.Cu")
	)
	(gr_line
		(start 190.492888 -44.219368)
		(end 190.951104 -44.219368)
		(stroke
			(width 0.0635)
			(type default)
		)
		(layer "F.Cu")
	)
	(gr_line
		(start 190.492888 -43.660568)
		(end 190.879984 -43.660568)
		(stroke
			(width 0.0635)
			(type default)
		)
		(layer "F.Cu")
	)
	(gr_line
		(start 190.879984 -43.660568)
		(end 190.986664 -43.767248)
		(stroke
			(width 0.0635)
			(type default)
		)
		(layer "F.Cu")
	)
	(gr_line
		(start 190.925704 -274.219416)
		(end 190.996824 -274.148296)
		(stroke
			(width 0.0635)
			(type default)
		)
		(layer "F.Cu")
	)
	(gr_line
		(start 190.925704 -273.660616)
		(end 190.996824 -273.731736)
		(stroke
			(width 0.0635)
			(type default)
		)
		(layer "F.Cu")
	)
	(gr_line
		(start 190.951104 -44.219368)
		(end 190.986664 -44.183808)
		(stroke
			(width 0.0635)
			(type default)
		)
		(layer "F.Cu")
	)
	(gr_line
		(start 190.976504 -159.219392)
		(end 191.047624 -159.148272)
		(stroke
			(width 0.0635)
			(type default)
		)
		(layer "F.Cu")
	)
	(gr_line
		(start 190.976504 -158.660592)
		(end 191.047624 -158.731712)
		(stroke
			(width 0.0635)
			(type default)
		)
		(layer "F.Cu")
	)
	(gr_line
		(start 191.521842 -158.828232)
		(end 191.561212 -158.853124)
		(stroke
			(width 0.0635)
			(type default)
		)
		(layer "F.Cu")
	)
	(gr_line
		(start 191.636142 -273.834098)
		(end 191.67475 -273.858736)
		(stroke
			(width 0.0635)
			(type default)
		)
		(layer "F.Cu")
	)
	(gr_line
		(start 191.6684 -43.825922)
		(end 191.70777 -43.850814)
		(stroke
			(width 0.0635)
			(type default)
		)
		(layer "F.Cu")
	)
	(gr_line
		(start 191.815466 -159.013906)
		(end 191.887602 -159.059626)
		(stroke
			(width 0.0635)
			(type default)
		)
		(layer "F.Cu")
	)
	(gr_line
		(start 191.854582 -151.678386)
		(end 191.868552 -151.69769)
		(stroke
			(width 0.0635)
			(type default)
		)
		(layer "F.Cu")
	)
	(gr_line
		(start 191.868552 -151.69769)
		(end 191.873632 -151.72055)
		(stroke
			(width 0.0635)
			(type default)
		)
		(layer "F.Cu")
	)
	(gr_line
		(start 191.887602 -159.059626)
		(end 191.905128 -159.142938)
		(stroke
			(width 0.0635)
			(type default)
		)
		(layer "F.Cu")
	)
	(gr_line
		(start 192.481454 -187.199524)
		(end 192.487296 -187.227464)
		(stroke
			(width 0.0635)
			(type default)
		)
		(layer "F.Cu")
	)
	(gr_line
		(start 192.481454 -187.199524)
		(end 192.488566 -187.171076)
		(stroke
			(width 0.0635)
			(type default)
		)
		(layer "F.Cu")
	)
	(gr_line
		(start 192.909444 -44.61129)
		(end 192.931034 -44.625006)
		(stroke
			(width 0.0635)
			(type default)
		)
		(layer "F.Cu")
	)
	(gr_line
		(start 192.931034 -44.625006)
		(end 192.945258 -44.646342)
		(stroke
			(width 0.0635)
			(type default)
		)
		(layer "F.Cu")
	)
	(gr_line
		(start 193.58737 -275.071078)
		(end 193.61023 -275.085556)
		(stroke
			(width 0.0635)
			(type default)
		)
		(layer "F.Cu")
	)
	(gr_line
		(start 193.61023 -275.085556)
		(end 193.6242 -275.107908)
		(stroke
			(width 0.0635)
			(type default)
		)
		(layer "F.Cu")
	)
	(gr_line
		(start 193.653156 -264.02538)
		(end 193.68516 -264.043414)
		(stroke
			(width 0.0635)
			(type default)
		)
		(layer "F.Cu")
	)
	(gr_line
		(start 193.68516 -264.043414)
		(end 193.704718 -264.074148)
		(stroke
			(width 0.0635)
			(type default)
		)
		(layer "F.Cu")
	)
	(gr_line
		(start 194.47637 -135.182864)
		(end 194.498468 -135.198104)
		(stroke
			(width 0.0635)
			(type default)
		)
		(layer "F.Cu")
	)
	(gr_line
		(start 194.498468 -135.198104)
		(end 194.512184 -135.220964)
		(stroke
			(width 0.0635)
			(type default)
		)
		(layer "F.Cu")
	)
	(gr_line
		(start 194.617848 -138.423904)
		(end 194.639946 -138.439144)
		(stroke
			(width 0.0635)
			(type default)
		)
		(layer "F.Cu")
	)
	(gr_line
		(start 194.618864 -262.276844)
		(end 194.648836 -262.293608)
		(stroke
			(width 0.0635)
			(type default)
		)
		(layer "F.Cu")
	)
	(gr_line
		(start 194.639946 -138.439144)
		(end 194.653662 -138.462004)
		(stroke
			(width 0.0635)
			(type default)
		)
		(layer "F.Cu")
	)
	(gr_line
		(start 194.648836 -262.293608)
		(end 194.667886 -262.32358)
		(stroke
			(width 0.0635)
			(type default)
		)
		(layer "F.Cu")
	)
	(gr_line
		(start 194.68084 -172.422058)
		(end 194.687698 -172.394372)
		(stroke
			(width 0.0635)
			(type default)
		)
		(layer "F.Cu")
	)
	(gr_line
		(start 194.681602 -172.366178)
		(end 194.687698 -172.394372)
		(stroke
			(width 0.0635)
			(type default)
		)
		(layer "F.Cu")
	)
	(gr_line
		(start 195.106036 -260.094476)
		(end 195.136008 -260.11124)
		(stroke
			(width 0.0635)
			(type default)
		)
		(layer "F.Cu")
	)
	(gr_line
		(start 195.136008 -260.11124)
		(end 195.155058 -260.141212)
		(stroke
			(width 0.0635)
			(type default)
		)
		(layer "F.Cu")
	)
	(gr_line
		(start 195.302886 -216.77757)
		(end 195.316602 -216.79662)
		(stroke
			(width 0.0635)
			(type default)
		)
		(layer "F.Cu")
	)
	(gr_line
		(start 195.316602 -216.79662)
		(end 195.321682 -216.81948)
		(stroke
			(width 0.0635)
			(type default)
		)
		(layer "F.Cu")
	)
	(gr_line
		(start 195.518278 -48.497998)
		(end 195.528438 -48.513238)
		(stroke
			(width 0.0635)
			(type default)
		)
		(layer "F.Cu")
	)
	(gr_line
		(start 195.528438 -48.513238)
		(end 195.532248 -48.531272)
		(stroke
			(width 0.0635)
			(type default)
		)
		(layer "F.Cu")
	)
	(gr_line
		(start 196.349366 -258.837176)
		(end 196.380354 -258.854702)
		(stroke
			(width 0.0635)
			(type default)
		)
		(layer "F.Cu")
	)
	(gr_line
		(start 196.380354 -258.854702)
		(end 196.399404 -258.884674)
		(stroke
			(width 0.0635)
			(type default)
		)
		(layer "F.Cu")
	)
	(gr_line
		(start 196.398134 -52.713636)
		(end 196.404992 -52.68595)
		(stroke
			(width 0.0635)
			(type default)
		)
		(layer "F.Cu")
	)
	(gr_line
		(start 196.398896 -52.657502)
		(end 196.404992 -52.68595)
		(stroke
			(width 0.0635)
			(type default)
		)
		(layer "F.Cu")
	)
	(gr_line
		(start 196.439028 -172.379386)
		(end 196.446648 -172.348906)
		(stroke
			(width 0.0635)
			(type default)
		)
		(layer "F.Cu")
	)
	(gr_line
		(start 196.43979 -172.318172)
		(end 196.446648 -172.348906)
		(stroke
			(width 0.0635)
			(type default)
		)
		(layer "F.Cu")
	)
	(gr_line
		(start 200.671938 -40.893238)
		(end 200.693782 -40.907462)
		(stroke
			(width 0.08255)
			(type default)
		)
		(layer "F.Cu")
	)
	(gr_line
		(start 200.693782 -40.907462)
		(end 200.707752 -40.929306)
		(stroke
			(width 0.08255)
			(type default)
		)
		(layer "F.Cu")
	)
	(gr_line
		(start 201.80554 -39.742618)
		(end 201.825098 -39.755318)
		(stroke
			(width 0.08255)
			(type default)
		)
		(layer "F.Cu")
	)
	(gr_line
		(start 201.825098 -39.755318)
		(end 201.837798 -39.77513)
		(stroke
			(width 0.08255)
			(type default)
		)
		(layer "F.Cu")
	)
	(gr_line
		(start 202.70343 -333.804514)
		(end 202.72502 -333.800196)
		(stroke
			(width 0.0635)
			(type default)
		)
		(layer "F.Cu")
	)
	(gr_line
		(start 202.72502 -333.800196)
		(end 202.74661 -333.804514)
		(stroke
			(width 0.0635)
			(type default)
		)
		(layer "F.Cu")
	)
	(gr_line
		(start 203.178664 -332.07071)
		(end 203.200254 -332.066392)
		(stroke
			(width 0.0635)
			(type default)
		)
		(layer "F.Cu")
	)
	(gr_line
		(start 203.200254 -332.066392)
		(end 203.221844 -332.07071)
		(stroke
			(width 0.0635)
			(type default)
		)
		(layer "F.Cu")
	)
	(gr_line
		(start 203.6064 -330.405486)
		(end 203.62799 -330.401168)
		(stroke
			(width 0.0635)
			(type default)
		)
		(layer "F.Cu")
	)
	(gr_line
		(start 203.62799 -330.401168)
		(end 203.64958 -330.405486)
		(stroke
			(width 0.0635)
			(type default)
		)
		(layer "F.Cu")
	)
	(gr_line
		(start 204.164438 -332.559914)
		(end 204.28204 -332.736444)
		(stroke
			(width 0.0635)
			(type default)
		)
		(layer "F.Cu")
	)
	(gr_line
		(start 204.25664 -332.277974)
		(end 204.338936 -332.29423)
		(stroke
			(width 0.0635)
			(type default)
		)
		(layer "F.Cu")
	)
	(gr_line
		(start 204.28204 -332.736444)
		(end 204.655674 -332.811374)
		(stroke
			(width 0.0635)
			(type default)
		)
		(layer "F.Cu")
	)
	(gr_line
		(start 204.312266 -328.683366)
		(end 204.333856 -328.679048)
		(stroke
			(width 0.0635)
			(type default)
		)
		(layer "F.Cu")
	)
	(gr_line
		(start 204.333856 -328.679048)
		(end 204.355446 -328.683366)
		(stroke
			(width 0.0635)
			(type default)
		)
		(layer "F.Cu")
	)
	(gr_line
		(start 204.338936 -332.29423)
		(end 204.33919 -332.294484)
		(stroke
			(width 0.0635)
			(type default)
		)
		(layer "F.Cu")
	)
	(gr_line
		(start 204.33919 -332.294484)
		(end 204.854048 -332.397608)
		(stroke
			(width 0.0635)
			(type default)
		)
		(layer "F.Cu")
	)
	(gr_line
		(start 204.655674 -332.811374)
		(end 204.832204 -332.693518)
		(stroke
			(width 0.0635)
			(type default)
		)
		(layer "F.Cu")
	)
	(gr_line
		(start 204.687424 -330.91374)
		(end 204.805026 -331.090524)
		(stroke
			(width 0.0635)
			(type default)
		)
		(layer "F.Cu")
	)
	(gr_line
		(start 204.709522 -329.054714)
		(end 204.827124 -329.231498)
		(stroke
			(width 0.0635)
			(type default)
		)
		(layer "F.Cu")
	)
	(gr_line
		(start 204.778864 -330.6318)
		(end 205.379828 -330.751942)
		(stroke
			(width 0.0635)
			(type default)
		)
		(layer "F.Cu")
	)
	(gr_line
		(start 204.802232 -328.772774)
		(end 205.401926 -328.892916)
		(stroke
			(width 0.0635)
			(type default)
		)
		(layer "F.Cu")
	)
	(gr_line
		(start 204.805026 -331.090524)
		(end 205.17866 -331.165454)
		(stroke
			(width 0.0635)
			(type default)
		)
		(layer "F.Cu")
	)
	(gr_line
		(start 204.827124 -329.231498)
		(end 205.200758 -329.306174)
		(stroke
			(width 0.0635)
			(type default)
		)
		(layer "F.Cu")
	)
	(gr_line
		(start 204.990954 -334.554322)
		(end 205.109064 -334.731106)
		(stroke
			(width 0.0635)
			(type default)
		)
		(layer "F.Cu")
	)
	(gr_line
		(start 205.081886 -334.271874)
		(end 205.682596 -334.39227)
		(stroke
			(width 0.0635)
			(type default)
		)
		(layer "F.Cu")
	)
	(gr_line
		(start 205.109064 -334.731106)
		(end 205.482444 -334.805782)
		(stroke
			(width 0.0635)
			(type default)
		)
		(layer "F.Cu")
	)
	(gr_line
		(start 205.17866 -331.165454)
		(end 205.355444 -331.047598)
		(stroke
			(width 0.0635)
			(type default)
		)
		(layer "F.Cu")
	)
	(gr_line
		(start 205.200758 -329.306174)
		(end 205.377542 -329.188572)
		(stroke
			(width 0.0635)
			(type default)
		)
		(layer "F.Cu")
	)
	(gr_line
		(start 205.210664 -332.769464)
		(end 205.328266 -332.945994)
		(stroke
			(width 0.0635)
			(type default)
		)
		(layer "F.Cu")
	)
	(gr_line
		(start 205.303882 -332.487524)
		(end 205.90002 -332.606904)
		(stroke
			(width 0.0635)
			(type default)
		)
		(layer "F.Cu")
	)
	(gr_line
		(start 205.328266 -332.945994)
		(end 205.701646 -333.02067)
		(stroke
			(width 0.0635)
			(type default)
		)
		(layer "F.Cu")
	)
	(gr_line
		(start 205.482444 -334.805782)
		(end 205.659228 -334.687926)
		(stroke
			(width 0.0635)
			(type default)
		)
		(layer "F.Cu")
	)
	(gr_line
		(start 205.701646 -333.02067)
		(end 205.878176 -332.903068)
		(stroke
			(width 0.0635)
			(type default)
		)
		(layer "F.Cu")
	)
	(gr_line
		(start 205.733142 -331.12329)
		(end 205.851252 -331.300074)
		(stroke
			(width 0.0635)
			(type default)
		)
		(layer "F.Cu")
	)
	(gr_line
		(start 205.755494 -329.264264)
		(end 205.87335 -329.440794)
		(stroke
			(width 0.0635)
			(type default)
		)
		(layer "F.Cu")
	)
	(gr_line
		(start 205.823058 -330.840588)
		(end 206.426562 -330.961492)
		(stroke
			(width 0.0635)
			(type default)
		)
		(layer "F.Cu")
	)
	(gr_line
		(start 205.848458 -328.982578)
		(end 206.445612 -329.101958)
		(stroke
			(width 0.0635)
			(type default)
		)
		(layer "F.Cu")
	)
	(gr_line
		(start 205.851252 -331.300074)
		(end 206.224632 -331.37475)
		(stroke
			(width 0.0635)
			(type default)
		)
		(layer "F.Cu")
	)
	(gr_line
		(start 205.87335 -329.440794)
		(end 206.24673 -329.515724)
		(stroke
			(width 0.0635)
			(type default)
		)
		(layer "F.Cu")
	)
	(gr_line
		(start 205.956154 -266.591288)
		(end 205.958948 -266.603988)
		(stroke
			(width 0.0635)
			(type default)
		)
		(layer "F.Cu")
	)
	(gr_line
		(start 205.958948 -266.603988)
		(end 205.965806 -266.61491)
		(stroke
			(width 0.0635)
			(type default)
		)
		(layer "F.Cu")
	)
	(gr_line
		(start 205.96225 -209.53603)
		(end 205.968092 -209.56397)
		(stroke
			(width 0.0635)
			(type default)
		)
		(layer "F.Cu")
	)
	(gr_line
		(start 205.96225 -209.53603)
		(end 205.969362 -209.507582)
		(stroke
			(width 0.0635)
			(type default)
		)
		(layer "F.Cu")
	)
	(gr_line
		(start 206.03718 -334.763618)
		(end 206.155036 -334.940402)
		(stroke
			(width 0.0635)
			(type default)
		)
		(layer "F.Cu")
	)
	(gr_line
		(start 206.127604 -334.48117)
		(end 206.730346 -334.60182)
		(stroke
			(width 0.0635)
			(type default)
		)
		(layer "F.Cu")
	)
	(gr_line
		(start 206.155036 -334.940402)
		(end 206.52867 -335.015078)
		(stroke
			(width 0.0635)
			(type default)
		)
		(layer "F.Cu")
	)
	(gr_line
		(start 206.224632 -331.37475)
		(end 206.40167 -331.256894)
		(stroke
			(width 0.0635)
			(type default)
		)
		(layer "F.Cu")
	)
	(gr_line
		(start 206.24673 -329.515724)
		(end 206.423514 -329.397868)
		(stroke
			(width 0.0635)
			(type default)
		)
		(layer "F.Cu")
	)
	(gr_line
		(start 206.256382 -332.97876)
		(end 206.374238 -333.15529)
		(stroke
			(width 0.0635)
			(type default)
		)
		(layer "F.Cu")
	)
	(gr_line
		(start 206.34833 -332.696566)
		(end 206.948278 -332.816708)
		(stroke
			(width 0.0635)
			(type default)
		)
		(layer "F.Cu")
	)
	(gr_line
		(start 206.374238 -333.15529)
		(end 206.747872 -333.229966)
		(stroke
			(width 0.0635)
			(type default)
		)
		(layer "F.Cu")
	)
	(gr_line
		(start 206.52867 -335.015078)
		(end 206.705454 -334.897476)
		(stroke
			(width 0.0635)
			(type default)
		)
		(layer "F.Cu")
	)
	(gr_line
		(start 206.747872 -333.229966)
		(end 206.924402 -333.112364)
		(stroke
			(width 0.0635)
			(type default)
		)
		(layer "F.Cu")
	)
	(gr_line
		(start 206.758794 -158.65348)
		(end 206.762096 -158.659068)
		(stroke
			(width 0.0635)
			(type default)
		)
		(layer "F.Cu")
	)
	(gr_line
		(start 206.762096 -158.659068)
		(end 206.76362 -158.66491)
		(stroke
			(width 0.0635)
			(type default)
		)
		(layer "F.Cu")
	)
	(gr_line
		(start 206.779368 -331.332586)
		(end 206.897224 -331.50937)
		(stroke
			(width 0.0635)
			(type default)
		)
		(layer "F.Cu")
	)
	(gr_line
		(start 206.801466 -329.47356)
		(end 206.919322 -329.650344)
		(stroke
			(width 0.0635)
			(type default)
		)
		(layer "F.Cu")
	)
	(gr_line
		(start 206.870554 -331.050392)
		(end 207.471518 -331.170788)
		(stroke
			(width 0.0635)
			(type default)
		)
		(layer "F.Cu")
	)
	(gr_line
		(start 206.894176 -329.191874)
		(end 207.4926 -329.311762)
		(stroke
			(width 0.0635)
			(type default)
		)
		(layer "F.Cu")
	)
	(gr_line
		(start 206.897224 -331.50937)
		(end 207.270858 -331.5843)
		(stroke
			(width 0.0635)
			(type default)
		)
		(layer "F.Cu")
	)
	(gr_line
		(start 206.919322 -329.650344)
		(end 207.292956 -329.72502)
		(stroke
			(width 0.0635)
			(type default)
		)
		(layer "F.Cu")
	)
	(gr_line
		(start 207.083406 -334.972914)
		(end 207.201008 -335.149952)
		(stroke
			(width 0.0635)
			(type default)
		)
		(layer "F.Cu")
	)
	(gr_line
		(start 207.174592 -334.69072)
		(end 207.77581 -334.811116)
		(stroke
			(width 0.0635)
			(type default)
		)
		(layer "F.Cu")
	)
	(gr_line
		(start 207.178656 -264.81024)
		(end 207.18145 -264.823702)
		(stroke
			(width 0.0635)
			(type default)
		)
		(layer "F.Cu")
	)
	(gr_line
		(start 207.18145 -264.823702)
		(end 207.189324 -264.836148)
		(stroke
			(width 0.0635)
			(type default)
		)
		(layer "F.Cu")
	)
	(gr_line
		(start 207.201008 -335.149952)
		(end 207.574642 -335.224628)
		(stroke
			(width 0.0635)
			(type default)
		)
		(layer "F.Cu")
	)
	(gr_line
		(start 207.270858 -331.5843)
		(end 207.447642 -331.466444)
		(stroke
			(width 0.0635)
			(type default)
		)
		(layer "F.Cu")
	)
	(gr_line
		(start 207.292956 -329.72502)
		(end 207.46974 -329.607418)
		(stroke
			(width 0.0635)
			(type default)
		)
		(layer "F.Cu")
	)
	(gr_line
		(start 207.302608 -333.188056)
		(end 207.42021 -333.364586)
		(stroke
			(width 0.0635)
			(type default)
		)
		(layer "F.Cu")
	)
	(gr_line
		(start 207.395318 -332.906116)
		(end 207.9117 -333.009494)
		(stroke
			(width 0.0635)
			(type default)
		)
		(layer "F.Cu")
	)
	(gr_line
		(start 207.42021 -333.364586)
		(end 207.793844 -333.439516)
		(stroke
			(width 0.0635)
			(type default)
		)
		(layer "F.Cu")
	)
	(gr_line
		(start 207.574642 -335.224628)
		(end 207.751426 -335.106772)
		(stroke
			(width 0.0635)
			(type default)
		)
		(layer "F.Cu")
	)
	(gr_line
		(start 207.596994 -209.476848)
		(end 207.602836 -209.504788)
		(stroke
			(width 0.0635)
			(type default)
		)
		(layer "F.Cu")
	)
	(gr_line
		(start 207.596994 -209.476848)
		(end 207.604106 -209.4484)
		(stroke
			(width 0.0635)
			(type default)
		)
		(layer "F.Cu")
	)
	(gr_line
		(start 207.793844 -333.439516)
		(end 207.970374 -333.32166)
		(stroke
			(width 0.0635)
			(type default)
		)
		(layer "F.Cu")
	)
	(gr_line
		(start 207.82534 -331.542136)
		(end 207.943196 -331.71892)
		(stroke
			(width 0.0635)
			(type default)
		)
		(layer "F.Cu")
	)
	(gr_line
		(start 207.847692 -329.68311)
		(end 207.965294 -329.85964)
		(stroke
			(width 0.0635)
			(type default)
		)
		(layer "F.Cu")
	)
	(gr_line
		(start 207.9117 -333.009494)
		(end 207.993742 -333.026004)
		(stroke
			(width 0.0635)
			(type default)
		)
		(layer "F.Cu")
	)
	(gr_line
		(start 207.916018 -331.259688)
		(end 208.518506 -331.380338)
		(stroke
			(width 0.0635)
			(type default)
		)
		(layer "F.Cu")
	)
	(gr_line
		(start 207.941418 -329.401678)
		(end 208.538572 -329.521058)
		(stroke
			(width 0.0635)
			(type default)
		)
		(layer "F.Cu")
	)
	(gr_line
		(start 207.943196 -331.71892)
		(end 208.31683 -331.793596)
		(stroke
			(width 0.0635)
			(type default)
		)
		(layer "F.Cu")
	)
	(gr_line
		(start 207.965294 -329.85964)
		(end 208.338928 -329.93457)
		(stroke
			(width 0.0635)
			(type default)
		)
		(layer "F.Cu")
	)
	(gr_line
		(start 208.129124 -335.18221)
		(end 208.24698 -335.359248)
		(stroke
			(width 0.0635)
			(type default)
		)
		(layer "F.Cu")
	)
	(gr_line
		(start 208.200244 -158.052262)
		(end 208.203546 -158.05785)
		(stroke
			(width 0.0635)
			(type default)
		)
		(layer "F.Cu")
	)
	(gr_line
		(start 208.203546 -158.05785)
		(end 208.20507 -158.063692)
		(stroke
			(width 0.0635)
			(type default)
		)
		(layer "F.Cu")
	)
	(gr_line
		(start 208.220818 -334.900524)
		(end 208.823306 -335.02092)
		(stroke
			(width 0.0635)
			(type default)
		)
		(layer "F.Cu")
	)
	(gr_line
		(start 208.24698 -335.359248)
		(end 208.620614 -335.433924)
		(stroke
			(width 0.0635)
			(type default)
		)
		(layer "F.Cu")
	)
	(gr_line
		(start 208.31683 -331.793596)
		(end 208.493614 -331.67574)
		(stroke
			(width 0.0635)
			(type default)
		)
		(layer "F.Cu")
	)
	(gr_line
		(start 208.338928 -329.93457)
		(end 208.515458 -329.816714)
		(stroke
			(width 0.0635)
			(type default)
		)
		(layer "F.Cu")
	)
	(gr_line
		(start 208.49971 -263.578594)
		(end 208.503266 -263.59485)
		(stroke
			(width 0.0635)
			(type default)
		)
		(layer "F.Cu")
	)
	(gr_line
		(start 208.503266 -263.59485)
		(end 208.512156 -263.609074)
		(stroke
			(width 0.0635)
			(type default)
		)
		(layer "F.Cu")
	)
	(gr_line
		(start 208.620614 -335.433924)
		(end 208.797144 -335.316576)
		(stroke
			(width 0.0635)
			(type default)
		)
		(layer "F.Cu")
	)
	(gr_line
		(start 209.27949 -209.359246)
		(end 209.285332 -209.387186)
		(stroke
			(width 0.0635)
			(type default)
		)
		(layer "F.Cu")
	)
	(gr_line
		(start 209.27949 -209.359246)
		(end 209.286602 -209.330798)
		(stroke
			(width 0.0635)
			(type default)
		)
		(layer "F.Cu")
	)
	(gr_line
		(start 209.649314 -157.473142)
		(end 209.650838 -157.475936)
		(stroke
			(width 0.0635)
			(type default)
		)
		(layer "F.Cu")
	)
	(gr_line
		(start 209.650838 -157.475936)
		(end 209.6516 -157.478984)
		(stroke
			(width 0.0635)
			(type default)
		)
		(layer "F.Cu")
	)
	(gr_line
		(start 210.689698 -180.765704)
		(end 210.697826 -180.777642)
		(stroke
			(width 0.0635)
			(type default)
		)
		(layer "F.Cu")
	)
	(gr_line
		(start 210.697826 -180.777642)
		(end 210.701382 -180.791612)
		(stroke
			(width 0.0635)
			(type default)
		)
		(layer "F.Cu")
	)
	(gr_line
		(start 211.023708 -208.98612)
		(end 211.02955 -209.01406)
		(stroke
			(width 0.0635)
			(type default)
		)
		(layer "F.Cu")
	)
	(gr_line
		(start 211.023708 -208.98612)
		(end 211.03082 -208.957418)
		(stroke
			(width 0.0635)
			(type default)
		)
		(layer "F.Cu")
	)
	(gr_line
		(start 212.031072 -186.096402)
		(end 212.039962 -186.131962)
		(stroke
			(width 0.0635)
			(type default)
		)
		(layer "F.Cu")
	)
	(gr_line
		(start 212.031326 -186.167014)
		(end 212.039962 -186.131962)
		(stroke
			(width 0.0635)
			(type default)
		)
		(layer "F.Cu")
	)
	(gr_line
		(start 212.941154 -208.129378)
		(end 212.946996 -208.157318)
		(stroke
			(width 0.0635)
			(type default)
		)
		(layer "F.Cu")
	)
	(gr_line
		(start 212.941154 -208.129378)
		(end 212.948266 -208.100676)
		(stroke
			(width 0.0635)
			(type default)
		)
		(layer "F.Cu")
	)
	(gr_line
		(start 213.04885 -158.969202)
		(end 213.054438 -158.942278)
		(stroke
			(width 0.08255)
			(type default)
		)
		(layer "F.Cu")
	)
	(gr_line
		(start 213.04885 -158.969202)
		(end 213.055708 -158.996126)
		(stroke
			(width 0.08255)
			(type default)
		)
		(layer "F.Cu")
	)
	(gr_line
		(start 213.642702 -186.127644)
		(end 213.651592 -186.163204)
		(stroke
			(width 0.0635)
			(type default)
		)
		(layer "F.Cu")
	)
	(gr_line
		(start 213.642956 -186.198256)
		(end 213.651592 -186.163204)
		(stroke
			(width 0.0635)
			(type default)
		)
		(layer "F.Cu")
	)
	(gr_line
		(start 215.267032 -186.248548)
		(end 215.275922 -186.284108)
		(stroke
			(width 0.0635)
			(type default)
		)
		(layer "F.Cu")
	)
	(gr_line
		(start 215.267286 -186.31916)
		(end 215.275922 -186.284108)
		(stroke
			(width 0.0635)
			(type default)
		)
		(layer "F.Cu")
	)
	(gr_line
		(start 216.892378 -186.361324)
		(end 216.901268 -186.396884)
		(stroke
			(width 0.0635)
			(type default)
		)
		(layer "F.Cu")
	)
	(gr_line
		(start 216.892632 -186.431428)
		(end 216.901268 -186.396884)
		(stroke
			(width 0.0635)
			(type default)
		)
		(layer "F.Cu")
	)
	(gr_line
		(start 217.440256 -137.390886)
		(end 217.441526 -137.385044)
		(stroke
			(width 0.08255)
			(type default)
		)
		(layer "F.Cu")
	)
	(gr_line
		(start 217.441526 -137.385044)
		(end 217.44432 -137.379964)
		(stroke
			(width 0.08255)
			(type default)
		)
		(layer "F.Cu")
	)
	(gr_line
		(start 218.466162 -180.640736)
		(end 218.467432 -180.645816)
		(stroke
			(width 0.08255)
			(type default)
		)
		(layer "F.Cu")
	)
	(gr_line
		(start 218.467432 -180.645816)
		(end 218.469972 -180.650134)
		(stroke
			(width 0.08255)
			(type default)
		)
		(layer "F.Cu")
	)
	(gr_line
		(start 218.581986 -186.42711)
		(end 218.590876 -186.462162)
		(stroke
			(width 0.0635)
			(type default)
		)
		(layer "F.Cu")
	)
	(gr_line
		(start 218.58224 -186.496452)
		(end 218.590876 -186.462162)
		(stroke
			(width 0.0635)
			(type default)
		)
		(layer "F.Cu")
	)
	(gr_line
		(start 220.722698 -279.872948)
		(end 220.726254 -279.889204)
		(stroke
			(width 0.0635)
			(type default)
		)
		(layer "F.Cu")
	)
	(gr_line
		(start 220.726254 -279.889204)
		(end 220.735144 -279.903428)
		(stroke
			(width 0.0635)
			(type default)
		)
		(layer "F.Cu")
	)
	(gr_line
		(start 222.229172 -279.203912)
		(end 222.232728 -279.220168)
		(stroke
			(width 0.0635)
			(type default)
		)
		(layer "F.Cu")
	)
	(gr_line
		(start 222.232728 -279.220168)
		(end 222.241618 -279.234392)
		(stroke
			(width 0.0635)
			(type default)
		)
		(layer "F.Cu")
	)
	(gr_line
		(start 223.849946 -278.777446)
		(end 223.853502 -278.793702)
		(stroke
			(width 0.0635)
			(type default)
		)
		(layer "F.Cu")
	)
	(gr_line
		(start 223.853502 -278.793702)
		(end 223.862392 -278.807926)
		(stroke
			(width 0.0635)
			(type default)
		)
		(layer "F.Cu")
	)
	(gr_line
		(start 224.553526 -136.293098)
		(end 225.183446 -135.663178)
		(stroke
			(width 0.08255)
			(type default)
		)
		(layer "F.Cu")
	)
	(gr_line
		(start 224.553526 -134.616698)
		(end 225.183446 -135.246618)
		(stroke
			(width 0.08255)
			(type default)
		)
		(layer "F.Cu")
	)
	(gr_line
		(start 225.209862 -325.577708)
		(end 225.231198 -325.611236)
		(stroke
			(width 0.0635)
			(type default)
		)
		(layer "F.Cu")
	)
	(gr_line
		(start 225.231198 -325.611236)
		(end 225.26625 -325.629778)
		(stroke
			(width 0.0635)
			(type default)
		)
		(layer "F.Cu")
	)
	(gr_line
		(start 225.591878 -278.440134)
		(end 225.595434 -278.45639)
		(stroke
			(width 0.0635)
			(type default)
		)
		(layer "F.Cu")
	)
	(gr_line
		(start 225.595434 -278.45639)
		(end 225.604324 -278.470614)
		(stroke
			(width 0.0635)
			(type default)
		)
		(layer "F.Cu")
	)
	(gr_line
		(start 225.71583 -80.92186)
		(end 225.75012 -80.767174)
		(stroke
			(width 0.08255)
			(type default)
		)
		(layer "F.Cu")
	)
	(gr_line
		(start 225.71583 -80.92186)
		(end 225.982022 -81.33969)
		(stroke
			(width 0.08255)
			(type default)
		)
		(layer "F.Cu")
	)
	(gr_line
		(start 225.982022 -81.33969)
		(end 226.136708 -81.373726)
		(stroke
			(width 0.08255)
			(type default)
		)
		(layer "F.Cu")
	)
	(gr_line
		(start 226.016058 -80.635602)
		(end 226.36861 -81.188814)
		(stroke
			(width 0.08255)
			(type default)
		)
		(layer "F.Cu")
	)
	(gr_line
		(start 226.313492 -326.19188)
		(end 226.37496 -326.394826)
		(stroke
			(width 0.0635)
			(type default)
		)
		(layer "F.Cu")
	)
	(gr_line
		(start 226.37115 -81.950052)
		(end 226.40544 -81.795366)
		(stroke
			(width 0.08255)
			(type default)
		)
		(layer "F.Cu")
	)
	(gr_line
		(start 226.37115 -81.950052)
		(end 226.637342 -82.367628)
		(stroke
			(width 0.08255)
			(type default)
		)
		(layer "F.Cu")
	)
	(gr_line
		(start 226.37496 -326.394826)
		(end 226.711002 -326.574404)
		(stroke
			(width 0.0635)
			(type default)
		)
		(layer "F.Cu")
	)
	(gr_line
		(start 226.484434 -325.94931)
		(end 227.02012 -326.235568)
		(stroke
			(width 0.0635)
			(type default)
		)
		(layer "F.Cu")
	)
	(gr_line
		(start 226.564698 -120.573546)
		(end 226.58578 -120.534938)
		(stroke
			(width 0.08255)
			(type default)
		)
		(layer "F.Cu")
	)
	(gr_line
		(start 226.58578 -120.534938)
		(end 226.623626 -120.512332)
		(stroke
			(width 0.08255)
			(type default)
		)
		(layer "F.Cu")
	)
	(gr_line
		(start 226.637342 -82.367628)
		(end 226.792282 -82.401918)
		(stroke
			(width 0.08255)
			(type default)
		)
		(layer "F.Cu")
	)
	(gr_line
		(start 226.671378 -81.663794)
		(end 227.02393 -82.217006)
		(stroke
			(width 0.08255)
			(type default)
		)
		(layer "F.Cu")
	)
	(gr_line
		(start 226.711002 -326.574404)
		(end 226.913948 -326.512682)
		(stroke
			(width 0.0635)
			(type default)
		)
		(layer "F.Cu")
	)
	(gr_line
		(start 227.254308 -326.694292)
		(end 227.31603 -326.897492)
		(stroke
			(width 0.0635)
			(type default)
		)
		(layer "F.Cu")
	)
	(gr_line
		(start 227.31603 -326.897492)
		(end 227.652072 -327.076816)
		(stroke
			(width 0.0635)
			(type default)
		)
		(layer "F.Cu")
	)
	(gr_line
		(start 227.424742 -326.451468)
		(end 227.962206 -326.738742)
		(stroke
			(width 0.0635)
			(type default)
		)
		(layer "F.Cu")
	)
	(gr_line
		(start 227.652072 -327.076816)
		(end 227.855272 -327.015348)
		(stroke
			(width 0.0635)
			(type default)
		)
		(layer "F.Cu")
	)
	(gr_line
		(start 227.804218 -278.957786)
		(end 227.807774 -278.974296)
		(stroke
			(width 0.0635)
			(type default)
		)
		(layer "F.Cu")
	)
	(gr_line
		(start 227.807774 -278.974296)
		(end 227.816664 -278.98852)
		(stroke
			(width 0.0635)
			(type default)
		)
		(layer "F.Cu")
	)
	(gr_line
		(start 228.195378 -327.196958)
		(end 228.2571 -327.399904)
		(stroke
			(width 0.0635)
			(type default)
		)
		(layer "F.Cu")
	)
	(gr_line
		(start 228.2571 -327.399904)
		(end 228.593142 -327.579482)
		(stroke
			(width 0.0635)
			(type default)
		)
		(layer "F.Cu")
	)
	(gr_line
		(start 228.36632 -326.954388)
		(end 228.90226 -327.240646)
		(stroke
			(width 0.0635)
			(type default)
		)
		(layer "F.Cu")
	)
	(gr_line
		(start 228.593142 -327.579482)
		(end 228.796088 -327.51776)
		(stroke
			(width 0.0635)
			(type default)
		)
		(layer "F.Cu")
	)
	(gr_line
		(start 228.81336 -317.149734)
		(end 228.860096 -316.942978)
		(stroke
			(width 0.0635)
			(type default)
		)
		(layer "F.Cu")
	)
	(gr_line
		(start 228.81336 -317.149734)
		(end 229.017068 -317.471806)
		(stroke
			(width 0.0635)
			(type default)
		)
		(layer "F.Cu")
	)
	(gr_line
		(start 229.017068 -317.471806)
		(end 229.223824 -317.518288)
		(stroke
			(width 0.0635)
			(type default)
		)
		(layer "F.Cu")
	)
	(gr_line
		(start 229.127304 -316.813438)
		(end 229.455218 -317.332106)
		(stroke
			(width 0.0635)
			(type default)
		)
		(layer "F.Cu")
	)
	(gr_line
		(start 229.136448 -327.699624)
		(end 229.197916 -327.90257)
		(stroke
			(width 0.0635)
			(type default)
		)
		(layer "F.Cu")
	)
	(gr_line
		(start 229.197916 -327.90257)
		(end 229.534212 -328.082148)
		(stroke
			(width 0.0635)
			(type default)
		)
		(layer "F.Cu")
	)
	(gr_line
		(start 229.30739 -327.457054)
		(end 229.8446 -327.74382)
		(stroke
			(width 0.0635)
			(type default)
		)
		(layer "F.Cu")
	)
	(gr_line
		(start 229.309168 -311.737756)
		(end 229.35565 -311.530746)
		(stroke
			(width 0.0635)
			(type default)
		)
		(layer "F.Cu")
	)
	(gr_line
		(start 229.309168 -311.737756)
		(end 229.512876 -312.059828)
		(stroke
			(width 0.0635)
			(type default)
		)
		(layer "F.Cu")
	)
	(gr_line
		(start 229.38359 -318.051434)
		(end 229.430072 -317.844424)
		(stroke
			(width 0.0635)
			(type default)
		)
		(layer "F.Cu")
	)
	(gr_line
		(start 229.38359 -318.051434)
		(end 229.587298 -318.373252)
		(stroke
			(width 0.0635)
			(type default)
		)
		(layer "F.Cu")
	)
	(gr_line
		(start 229.490778 -86.844378)
		(end 229.524814 -86.689438)
		(stroke
			(width 0.08255)
			(type default)
		)
		(layer "F.Cu")
	)
	(gr_line
		(start 229.490778 -86.844378)
		(end 229.75697 -87.261954)
		(stroke
			(width 0.08255)
			(type default)
		)
		(layer "F.Cu")
	)
	(gr_line
		(start 229.512876 -312.059828)
		(end 229.719886 -312.10631)
		(stroke
			(width 0.0635)
			(type default)
		)
		(layer "F.Cu")
	)
	(gr_line
		(start 229.534212 -328.082148)
		(end 229.737158 -328.020426)
		(stroke
			(width 0.0635)
			(type default)
		)
		(layer "F.Cu")
	)
	(gr_line
		(start 229.587298 -318.373252)
		(end 229.794054 -318.419988)
		(stroke
			(width 0.0635)
			(type default)
		)
		(layer "F.Cu")
	)
	(gr_line
		(start 229.622096 -311.40019)
		(end 229.952296 -311.921906)
		(stroke
			(width 0.0635)
			(type default)
		)
		(layer "F.Cu")
	)
	(gr_line
		(start 229.696518 -317.713868)
		(end 230.025448 -318.233806)
		(stroke
			(width 0.0635)
			(type default)
		)
		(layer "F.Cu")
	)
	(gr_line
		(start 229.75697 -87.261954)
		(end 229.911656 -87.296244)
		(stroke
			(width 0.08255)
			(type default)
		)
		(layer "F.Cu")
	)
	(gr_line
		(start 229.79126 -86.559136)
		(end 230.14305 -87.110824)
		(stroke
			(width 0.08255)
			(type default)
		)
		(layer "F.Cu")
	)
	(gr_line
		(start 229.879398 -312.639456)
		(end 229.92588 -312.432192)
		(stroke
			(width 0.0635)
			(type default)
		)
		(layer "F.Cu")
	)
	(gr_line
		(start 229.879398 -312.639456)
		(end 230.083106 -312.961274)
		(stroke
			(width 0.0635)
			(type default)
		)
		(layer "F.Cu")
	)
	(gr_line
		(start 229.95382 -318.95288)
		(end 230.000302 -318.746124)
		(stroke
			(width 0.0635)
			(type default)
		)
		(layer "F.Cu")
	)
	(gr_line
		(start 229.95382 -318.95288)
		(end 230.157528 -319.274952)
		(stroke
			(width 0.0635)
			(type default)
		)
		(layer "F.Cu")
	)
	(gr_line
		(start 230.083106 -312.961274)
		(end 230.290116 -313.00801)
		(stroke
			(width 0.0635)
			(type default)
		)
		(layer "F.Cu")
	)
	(gr_line
		(start 230.146098 -87.872316)
		(end 230.180134 -87.71763)
		(stroke
			(width 0.08255)
			(type default)
		)
		(layer "F.Cu")
	)
	(gr_line
		(start 230.146098 -87.872316)
		(end 230.41229 -88.290146)
		(stroke
			(width 0.08255)
			(type default)
		)
		(layer "F.Cu")
	)
	(gr_line
		(start 230.157528 -319.274952)
		(end 230.364284 -319.321688)
		(stroke
			(width 0.0635)
			(type default)
		)
		(layer "F.Cu")
	)
	(gr_line
		(start 230.192326 -312.301636)
		(end 230.52151 -312.822082)
		(stroke
			(width 0.0635)
			(type default)
		)
		(layer "F.Cu")
	)
	(gr_line
		(start 230.267256 -318.61633)
		(end 230.596186 -319.136522)
		(stroke
			(width 0.0635)
			(type default)
		)
		(layer "F.Cu")
	)
	(gr_line
		(start 230.41229 -88.290146)
		(end 230.566976 -88.324182)
		(stroke
			(width 0.08255)
			(type default)
		)
		(layer "F.Cu")
	)
	(gr_line
		(start 230.44658 -87.587074)
		(end 230.797354 -88.137492)
		(stroke
			(width 0.08255)
			(type default)
		)
		(layer "F.Cu")
	)
	(gr_line
		(start 230.449882 -313.540902)
		(end 230.496364 -313.333892)
		(stroke
			(width 0.0635)
			(type default)
		)
		(layer "F.Cu")
	)
	(gr_line
		(start 230.449882 -313.540902)
		(end 230.653336 -313.862974)
		(stroke
			(width 0.0635)
			(type default)
		)
		(layer "F.Cu")
	)
	(gr_line
		(start 230.52405 -319.85458)
		(end 230.570532 -319.64757)
		(stroke
			(width 0.0635)
			(type default)
		)
		(layer "F.Cu")
	)
	(gr_line
		(start 230.52405 -319.85458)
		(end 230.727504 -320.176652)
		(stroke
			(width 0.0635)
			(type default)
		)
		(layer "F.Cu")
	)
	(gr_line
		(start 230.653336 -313.862974)
		(end 230.8606 -313.909456)
		(stroke
			(width 0.0635)
			(type default)
		)
		(layer "F.Cu")
	)
	(gr_line
		(start 230.727504 -320.176652)
		(end 230.934514 -320.223134)
		(stroke
			(width 0.0635)
			(type default)
		)
		(layer "F.Cu")
	)
	(gr_line
		(start 230.763572 -313.204606)
		(end 231.09174 -313.723528)
		(stroke
			(width 0.0635)
			(type default)
		)
		(layer "F.Cu")
	)
	(gr_line
		(start 230.801164 -88.900508)
		(end 230.835454 -88.745822)
		(stroke
			(width 0.08255)
			(type default)
		)
		(layer "F.Cu")
	)
	(gr_line
		(start 230.801164 -88.900508)
		(end 231.06761 -89.318084)
		(stroke
			(width 0.08255)
			(type default)
		)
		(layer "F.Cu")
	)
	(gr_line
		(start 230.804212 -323.25818)
		(end 230.838502 -323.312282)
		(stroke
			(width 0.0635)
			(type default)
		)
		(layer "F.Cu")
	)
	(gr_line
		(start 230.837994 -319.519046)
		(end 231.164892 -320.035936)
		(stroke
			(width 0.0635)
			(type default)
		)
		(layer "F.Cu")
	)
	(gr_line
		(start 230.838502 -323.312282)
		(end 230.898954 -323.33311)
		(stroke
			(width 0.0635)
			(type default)
		)
		(layer "F.Cu")
	)
	(gr_line
		(start 231.020112 -314.442348)
		(end 231.066594 -314.235338)
		(stroke
			(width 0.0635)
			(type default)
		)
		(layer "F.Cu")
	)
	(gr_line
		(start 231.020112 -314.442348)
		(end 231.22382 -314.76442)
		(stroke
			(width 0.0635)
			(type default)
		)
		(layer "F.Cu")
	)
	(gr_line
		(start 231.06761 -89.318084)
		(end 231.222296 -89.352374)
		(stroke
			(width 0.08255)
			(type default)
		)
		(layer "F.Cu")
	)
	(gr_line
		(start 231.101646 -88.614758)
		(end 231.45242 -89.165176)
		(stroke
			(width 0.08255)
			(type default)
		)
		(layer "F.Cu")
	)
	(gr_line
		(start 231.22382 -314.76442)
		(end 231.43083 -314.810902)
		(stroke
			(width 0.0635)
			(type default)
		)
		(layer "F.Cu")
	)
	(gr_line
		(start 231.333802 -314.106814)
		(end 231.661462 -314.624466)
		(stroke
			(width 0.0635)
			(type default)
		)
		(layer "F.Cu")
	)
	(gr_line
		(start 231.456484 -89.9287)
		(end 231.490774 -89.774014)
		(stroke
			(width 0.08255)
			(type default)
		)
		(layer "F.Cu")
	)
	(gr_line
		(start 231.456484 -89.9287)
		(end 231.72293 -90.346276)
		(stroke
			(width 0.08255)
			(type default)
		)
		(layer "F.Cu")
	)
	(gr_line
		(start 231.72293 -90.346276)
		(end 231.877616 -90.380566)
		(stroke
			(width 0.08255)
			(type default)
		)
		(layer "F.Cu")
	)
	(gr_line
		(start 231.757728 -89.64422)
		(end 232.107994 -90.193876)
		(stroke
			(width 0.08255)
			(type default)
		)
		(layer "F.Cu")
	)
	(gr_line
		(start 232.047542 -321.979036)
		(end 232.08234 -322.0339)
		(stroke
			(width 0.0635)
			(type default)
		)
		(layer "F.Cu")
	)
	(gr_line
		(start 232.08234 -322.0339)
		(end 232.143808 -322.055236)
		(stroke
			(width 0.0635)
			(type default)
		)
		(layer "F.Cu")
	)
	(gr_line
		(start 232.105962 -117.24513)
		(end 232.144824 -117.091968)
		(stroke
			(width 0.08255)
			(type default)
		)
		(layer "F.Cu")
	)
	(gr_line
		(start 232.115614 -90.749882)
		(end 232.146856 -90.798904)
		(stroke
			(width 0.08255)
			(type default)
		)
		(layer "F.Cu")
	)
	(gr_line
		(start 232.144824 -117.091968)
		(end 232.570528 -116.838476)
		(stroke
			(width 0.08255)
			(type default)
		)
		(layer "F.Cu")
	)
	(gr_line
		(start 232.146856 -90.798904)
		(end 232.20172 -90.820494)
		(stroke
			(width 0.08255)
			(type default)
		)
		(layer "F.Cu")
	)
	(gr_line
		(start 232.28681 -117.480842)
		(end 232.844594 -117.14861)
		(stroke
			(width 0.08255)
			(type default)
		)
		(layer "F.Cu")
	)
	(gr_line
		(start 232.570528 -116.838476)
		(end 232.72369 -116.877592)
		(stroke
			(width 0.08255)
			(type default)
		)
		(layer "F.Cu")
	)
	(gr_line
		(start 232.860596 -332.05547)
		(end 232.946448 -332.249526)
		(stroke
			(width 0.0635)
			(type default)
		)
		(layer "F.Cu")
	)
	(gr_line
		(start 232.871772 -320.293746)
		(end 232.906062 -320.347848)
		(stroke
			(width 0.0635)
			(type default)
		)
		(layer "F.Cu")
	)
	(gr_line
		(start 232.906062 -320.347848)
		(end 232.966768 -320.36893)
		(stroke
			(width 0.0635)
			(type default)
		)
		(layer "F.Cu")
	)
	(gr_line
		(start 232.946448 -332.249526)
		(end 233.301794 -332.387194)
		(stroke
			(width 0.0635)
			(type default)
		)
		(layer "F.Cu")
	)
	(gr_line
		(start 232.997756 -331.792326)
		(end 233.571288 -332.014322)
		(stroke
			(width 0.0635)
			(type default)
		)
		(layer "F.Cu")
	)
	(gr_line
		(start 233.01452 -91.14155)
		(end 233.077766 -91.286584)
		(stroke
			(width 0.08255)
			(type default)
		)
		(layer "F.Cu")
	)
	(gr_line
		(start 233.077766 -91.286584)
		(end 233.53903 -91.467432)
		(stroke
			(width 0.08255)
			(type default)
		)
		(layer "F.Cu")
	)
	(gr_line
		(start 233.147616 -302.544734)
		(end 233.154474 -302.555402)
		(stroke
			(width 0.0635)
			(type default)
		)
		(layer "F.Cu")
	)
	(gr_line
		(start 233.153458 -116.62156)
		(end 233.19232 -116.468144)
		(stroke
			(width 0.08255)
			(type default)
		)
		(layer "F.Cu")
	)
	(gr_line
		(start 233.154474 -302.555402)
		(end 233.164634 -302.56353)
		(stroke
			(width 0.0635)
			(type default)
		)
		(layer "F.Cu")
	)
	(gr_line
		(start 233.154474 -90.87993)
		(end 233.758232 -91.116658)
		(stroke
			(width 0.08255)
			(type default)
		)
		(layer "F.Cu")
	)
	(gr_line
		(start 233.19232 -116.468144)
		(end 233.618024 -116.214906)
		(stroke
			(width 0.08255)
			(type default)
		)
		(layer "F.Cu")
	)
	(gr_line
		(start 233.301794 -332.387194)
		(end 233.496104 -332.301342)
		(stroke
			(width 0.0635)
			(type default)
		)
		(layer "F.Cu")
	)
	(gr_line
		(start 233.333798 -116.857272)
		(end 233.891328 -116.525294)
		(stroke
			(width 0.08255)
			(type default)
		)
		(layer "F.Cu")
	)
	(gr_line
		(start 233.53903 -91.467432)
		(end 233.684064 -91.403932)
		(stroke
			(width 0.08255)
			(type default)
		)
		(layer "F.Cu")
	)
	(gr_line
		(start 233.618024 -116.214906)
		(end 233.77144 -116.253768)
		(stroke
			(width 0.08255)
			(type default)
		)
		(layer "F.Cu")
	)
	(gr_line
		(start 233.772456 -89.647014)
		(end 233.80573 -89.723468)
		(stroke
			(width 0.08255)
			(type default)
		)
		(layer "F.Cu")
	)
	(gr_line
		(start 233.80573 -89.723468)
		(end 233.8832 -89.754202)
		(stroke
			(width 0.08255)
			(type default)
		)
		(layer "F.Cu")
	)
	(gr_line
		(start 233.855514 -332.440534)
		(end 233.941366 -332.63459)
		(stroke
			(width 0.0635)
			(type default)
		)
		(layer "F.Cu")
	)
	(gr_line
		(start 233.941366 -332.63459)
		(end 234.296712 -332.772258)
		(stroke
			(width 0.0635)
			(type default)
		)
		(layer "F.Cu")
	)
	(gr_line
		(start 233.99369 -332.177898)
		(end 234.566714 -332.39964)
		(stroke
			(width 0.0635)
			(type default)
		)
		(layer "F.Cu")
	)
	(gr_line
		(start 234.134914 -319.08115)
		(end 234.169966 -319.136522)
		(stroke
			(width 0.0635)
			(type default)
		)
		(layer "F.Cu")
	)
	(gr_line
		(start 234.149646 -91.586304)
		(end 234.212892 -91.731592)
		(stroke
			(width 0.08255)
			(type default)
		)
		(layer "F.Cu")
	)
	(gr_line
		(start 234.169966 -319.136522)
		(end 234.231434 -319.157858)
		(stroke
			(width 0.0635)
			(type default)
		)
		(layer "F.Cu")
	)
	(gr_line
		(start 234.212892 -91.731592)
		(end 234.674156 -91.91244)
		(stroke
			(width 0.08255)
			(type default)
		)
		(layer "F.Cu")
	)
	(gr_line
		(start 234.290616 -91.325446)
		(end 234.89285 -91.561666)
		(stroke
			(width 0.08255)
			(type default)
		)
		(layer "F.Cu")
	)
	(gr_line
		(start 234.296712 -332.772258)
		(end 234.491022 -332.686406)
		(stroke
			(width 0.0635)
			(type default)
		)
		(layer "F.Cu")
	)
	(gr_line
		(start 234.445302 -301.573692)
		(end 234.45216 -301.58436)
		(stroke
			(width 0.0635)
			(type default)
		)
		(layer "F.Cu")
	)
	(gr_line
		(start 234.45216 -301.58436)
		(end 234.46232 -301.592488)
		(stroke
			(width 0.0635)
			(type default)
		)
		(layer "F.Cu")
	)
	(gr_line
		(start 234.674156 -91.91244)
		(end 234.819444 -91.84894)
		(stroke
			(width 0.08255)
			(type default)
		)
		(layer "F.Cu")
	)
	(gr_line
		(start 234.850432 -332.825598)
		(end 234.936284 -333.019908)
		(stroke
			(width 0.0635)
			(type default)
		)
		(layer "F.Cu")
	)
	(gr_line
		(start 234.936284 -333.019908)
		(end 235.29163 -333.157322)
		(stroke
			(width 0.0635)
			(type default)
		)
		(layer "F.Cu")
	)
	(gr_line
		(start 234.988354 -332.562708)
		(end 235.56214 -332.784958)
		(stroke
			(width 0.0635)
			(type default)
		)
		(layer "F.Cu")
	)
	(gr_line
		(start 235.25099 -115.375436)
		(end 235.287312 -115.353846)
		(stroke
			(width 0.08255)
			(type default)
		)
		(layer "F.Cu")
	)
	(gr_line
		(start 235.284772 -92.031312)
		(end 235.348018 -92.1766)
		(stroke
			(width 0.08255)
			(type default)
		)
		(layer "F.Cu")
	)
	(gr_line
		(start 235.29163 -333.157322)
		(end 235.485686 -333.07147)
		(stroke
			(width 0.0635)
			(type default)
		)
		(layer "F.Cu")
	)
	(gr_line
		(start 235.348018 -92.1766)
		(end 235.809282 -92.357448)
		(stroke
			(width 0.08255)
			(type default)
		)
		(layer "F.Cu")
	)
	(gr_line
		(start 235.425234 -91.7702)
		(end 236.028992 -92.006928)
		(stroke
			(width 0.08255)
			(type default)
		)
		(layer "F.Cu")
	)
	(gr_line
		(start 235.785914 -300.641258)
		(end 235.792772 -300.651926)
		(stroke
			(width 0.0635)
			(type default)
		)
		(layer "F.Cu")
	)
	(gr_line
		(start 235.792772 -300.651926)
		(end 235.802932 -300.660054)
		(stroke
			(width 0.0635)
			(type default)
		)
		(layer "F.Cu")
	)
	(gr_line
		(start 235.809282 -92.357448)
		(end 235.95457 -92.293948)
		(stroke
			(width 0.08255)
			(type default)
		)
		(layer "F.Cu")
	)
	(gr_line
		(start 235.84535 -333.210662)
		(end 235.931202 -333.404972)
		(stroke
			(width 0.0635)
			(type default)
		)
		(layer "F.Cu")
	)
	(gr_line
		(start 235.931202 -333.404972)
		(end 236.286548 -333.542386)
		(stroke
			(width 0.0635)
			(type default)
		)
		(layer "F.Cu")
	)
	(gr_line
		(start 235.982002 -332.947518)
		(end 236.555534 -333.169514)
		(stroke
			(width 0.0635)
			(type default)
		)
		(layer "F.Cu")
	)
	(gr_line
		(start 236.050074 -138.49985)
		(end 236.771434 -138.138916)
		(stroke
			(width 0.08255)
			(type default)
		)
		(layer "F.Cu")
	)
	(gr_line
		(start 236.050074 -114.499898)
		(end 236.771434 -114.138964)
		(stroke
			(width 0.08255)
			(type default)
		)
		(layer "F.Cu")
	)
	(gr_line
		(start 236.050074 -18.200116)
		(end 236.771434 -17.839182)
		(stroke
			(width 0.08255)
			(type default)
		)
		(layer "F.Cu")
	)
	(gr_line
		(start 236.286548 -333.542386)
		(end 236.480604 -333.456534)
		(stroke
			(width 0.0635)
			(type default)
		)
		(layer "F.Cu")
	)
	(gr_line
		(start 236.695996 -115.645946)
		(end 236.754924 -115.587018)
		(stroke
			(width 0.08255)
			(type default)
		)
		(layer "F.Cu")
	)
	(gr_line
		(start 236.962442 -138.177778)
		(end 236.995716 -138.223752)
		(stroke
			(width 0.08255)
			(type default)
		)
		(layer "F.Cu")
	)
	(gr_arc
		(start 236.962442 -138.170412)
		(mid 236.872029 -138.123735)
		(end 236.771434 -138.138916)
		(stroke
			(width 0.08255)
			(type default)
		)
		(layer "F.Cu")
	)
	(gr_line
		(start 236.962442 -114.177826)
		(end 236.995716 -114.2238)
		(stroke
			(width 0.08255)
			(type default)
		)
		(layer "F.Cu")
	)
	(gr_arc
		(start 236.962442 -114.17046)
		(mid 236.872033 -114.123692)
		(end 236.771434 -114.138964)
		(stroke
			(width 0.08255)
			(type default)
		)
		(layer "F.Cu")
	)
	(gr_line
		(start 236.962442 -17.878044)
		(end 236.995716 -17.924018)
		(stroke
			(width 0.08255)
			(type default)
		)
		(layer "F.Cu")
	)
	(gr_arc
		(start 236.962442 -17.870678)
		(mid 236.872028 -17.824011)
		(end 236.771434 -17.839182)
		(stroke
			(width 0.08255)
			(type default)
		)
		(layer "F.Cu")
	)
	(gr_line
		(start 237.010194 -299.58792)
		(end 237.016544 -299.597826)
		(stroke
			(width 0.0635)
			(type default)
		)
		(layer "F.Cu")
	)
	(gr_line
		(start 237.016544 -299.597826)
		(end 237.025434 -299.604684)
		(stroke
			(width 0.0635)
			(type default)
		)
		(layer "F.Cu")
	)
	(gr_arc
		(start 237.328202 -137.86104)
		(mid 237.2455 -137.956529)
		(end 237.254542 -138.082528)
		(stroke
			(width 0.08255)
			(type default)
		)
		(layer "F.Cu")
	)
	(gr_line
		(start 237.328202 -137.86104)
		(end 238.05007 -137.499852)
		(stroke
			(width 0.08255)
			(type default)
		)
		(layer "F.Cu")
	)
	(gr_arc
		(start 237.328202 -113.861088)
		(mid 237.245468 -113.956578)
		(end 237.254542 -114.082576)
		(stroke
			(width 0.08255)
			(type default)
		)
		(layer "F.Cu")
	)
	(gr_line
		(start 237.328202 -113.861088)
		(end 238.05007 -113.4999)
		(stroke
			(width 0.08255)
			(type default)
		)
		(layer "F.Cu")
	)
	(gr_arc
		(start 237.328202 -17.561306)
		(mid 237.2455 -17.656795)
		(end 237.254542 -17.782794)
		(stroke
			(width 0.08255)
			(type default)
		)
		(layer "F.Cu")
	)
	(gr_line
		(start 237.328202 -17.561306)
		(end 238.05007 -17.200118)
		(stroke
			(width 0.08255)
			(type default)
		)
		(layer "F.Cu")
	)
	(gr_line
		(start 237.43285 -335.306416)
		(end 237.437676 -335.307432)
		(stroke
			(width 0.0635)
			(type default)
		)
		(layer "F.Cu")
	)
	(gr_line
		(start 237.437676 -335.307432)
		(end 237.43793 -335.307432)
		(stroke
			(width 0.0635)
			(type default)
		)
		(layer "F.Cu")
	)
	(gr_line
		(start 237.43793 -335.307432)
		(end 237.443264 -335.310226)
		(stroke
			(width 0.0635)
			(type default)
		)
		(layer "F.Cu")
	)
	(gr_line
		(start 237.4519 -340.75243)
		(end 237.456726 -340.753446)
		(stroke
			(width 0.0635)
			(type default)
		)
		(layer "F.Cu")
	)
	(gr_line
		(start 237.456726 -340.753446)
		(end 237.461298 -340.755986)
		(stroke
			(width 0.0635)
			(type default)
		)
		(layer "F.Cu")
	)
	(gr_line
		(start 237.748572 -338.981796)
		(end 237.754668 -338.983066)
		(stroke
			(width 0.0635)
			(type default)
		)
		(layer "F.Cu")
	)
	(gr_line
		(start 237.751366 -337.23326)
		(end 237.757462 -337.23453)
		(stroke
			(width 0.0635)
			(type default)
		)
		(layer "F.Cu")
	)
	(gr_line
		(start 237.754668 -338.983066)
		(end 237.760002 -338.98586)
		(stroke
			(width 0.0635)
			(type default)
		)
		(layer "F.Cu")
	)
	(gr_line
		(start 237.757462 -337.23453)
		(end 237.762796 -337.237324)
		(stroke
			(width 0.0635)
			(type default)
		)
		(layer "F.Cu")
	)
	(gr_line
		(start 238.435134 -298.75099)
		(end 238.441738 -298.761404)
		(stroke
			(width 0.0635)
			(type default)
		)
		(layer "F.Cu")
	)
	(gr_line
		(start 238.441738 -298.761404)
		(end 238.442246 -298.761912)
		(stroke
			(width 0.0635)
			(type default)
		)
		(layer "F.Cu")
	)
	(gr_line
		(start 238.442246 -298.761912)
		(end 238.451136 -298.76877)
		(stroke
			(width 0.0635)
			(type default)
		)
		(layer "F.Cu")
	)
	(gr_line
		(start 239.079786 -318.942212)
		(end 239.114076 -318.996314)
		(stroke
			(width 0.0635)
			(type default)
		)
		(layer "F.Cu")
	)
	(gr_line
		(start 239.114076 -318.996314)
		(end 239.175036 -319.017396)
		(stroke
			(width 0.0635)
			(type default)
		)
		(layer "F.Cu")
	)
	(gr_line
		(start 239.686084 -297.747944)
		(end 239.692942 -297.758612)
		(stroke
			(width 0.0635)
			(type default)
		)
		(layer "F.Cu")
	)
	(gr_line
		(start 239.692942 -297.758612)
		(end 239.703102 -297.76674)
		(stroke
			(width 0.0635)
			(type default)
		)
		(layer "F.Cu")
	)
	(gr_line
		(start 240.40465 -94.03842)
		(end 240.46815 -94.183708)
		(stroke
			(width 0.08255)
			(type default)
		)
		(layer "F.Cu")
	)
	(gr_line
		(start 240.46815 -94.183708)
		(end 240.929414 -94.364556)
		(stroke
			(width 0.08255)
			(type default)
		)
		(layer "F.Cu")
	)
	(gr_line
		(start 240.477548 -317.448184)
		(end 240.513362 -317.504826)
		(stroke
			(width 0.0635)
			(type default)
		)
		(layer "F.Cu")
	)
	(gr_line
		(start 240.513362 -317.504826)
		(end 240.575846 -317.526416)
		(stroke
			(width 0.0635)
			(type default)
		)
		(layer "F.Cu")
	)
	(gr_line
		(start 240.54435 -93.7768)
		(end 241.149378 -94.014036)
		(stroke
			(width 0.08255)
			(type default)
		)
		(layer "F.Cu")
	)
	(gr_line
		(start 240.549938 -135.499856)
		(end 241.271298 -135.86079)
		(stroke
			(width 0.08255)
			(type default)
		)
		(layer "F.Cu")
	)
	(gr_line
		(start 240.549938 -107.499912)
		(end 241.271806 -107.8611)
		(stroke
			(width 0.08255)
			(type default)
		)
		(layer "F.Cu")
	)
	(gr_line
		(start 240.702338 -308.502558)
		(end 240.71072 -308.509416)
		(stroke
			(width 0.0635)
			(type default)
		)
		(layer "F.Cu")
	)
	(gr_line
		(start 240.71072 -308.509416)
		(end 240.721388 -308.513226)
		(stroke
			(width 0.0635)
			(type default)
		)
		(layer "F.Cu")
	)
	(gr_line
		(start 240.875058 -317.63208)
		(end 240.968022 -317.822834)
		(stroke
			(width 0.0635)
			(type default)
		)
		(layer "F.Cu")
	)
	(gr_line
		(start 240.929414 -94.364556)
		(end 241.074702 -94.301056)
		(stroke
			(width 0.08255)
			(type default)
		)
		(layer "F.Cu")
	)
	(gr_line
		(start 240.968022 -317.822834)
		(end 241.328194 -317.94704)
		(stroke
			(width 0.0635)
			(type default)
		)
		(layer "F.Cu")
	)
	(gr_line
		(start 241.004598 -317.365126)
		(end 241.583718 -317.56477)
		(stroke
			(width 0.0635)
			(type default)
		)
		(layer "F.Cu")
	)
	(gr_line
		(start 241.2365 -388.666736)
		(end 242.448334 -388.666736)
		(stroke
			(width 0.127)
			(type default)
		)
		(layer "F.Cu")
	)
	(gr_line
		(start 241.2365 -388.166864)
		(end 241.956336 -388.166864)
		(stroke
			(width 0.127)
			(type default)
		)
		(layer "F.Cu")
	)
	(gr_line
		(start 241.2365 -387.666738)
		(end 241.946938 -387.666738)
		(stroke
			(width 0.127)
			(type default)
		)
		(layer "F.Cu")
	)
	(gr_line
		(start 241.2365 -387.166866)
		(end 242.448334 -387.166866)
		(stroke
			(width 0.127)
			(type default)
		)
		(layer "F.Cu")
	)
	(gr_arc
		(start 241.271298 -135.86079)
		(mid 241.371913 -135.876049)
		(end 241.462306 -135.829294)
		(stroke
			(width 0.08255)
			(type default)
		)
		(layer "F.Cu")
	)
	(gr_line
		(start 241.328194 -317.94704)
		(end 241.518948 -317.854076)
		(stroke
			(width 0.0635)
			(type default)
		)
		(layer "F.Cu")
	)
	(gr_arc
		(start 241.345466 -108.082588)
		(mid 241.354492 -107.956602)
		(end 241.271806 -107.8611)
		(stroke
			(width 0.08255)
			(type default)
		)
		(layer "F.Cu")
	)
	(gr_line
		(start 241.398298 -307.057044)
		(end 241.40668 -307.063902)
		(stroke
			(width 0.0635)
			(type default)
		)
		(layer "F.Cu")
	)
	(gr_line
		(start 241.40668 -307.063902)
		(end 241.417348 -307.067712)
		(stroke
			(width 0.0635)
			(type default)
		)
		(layer "F.Cu")
	)
	(gr_line
		(start 241.462306 -135.821928)
		(end 241.49558 -135.775954)
		(stroke
			(width 0.08255)
			(type default)
		)
		(layer "F.Cu")
	)
	(gr_line
		(start 241.539776 -94.483428)
		(end 241.603276 -94.628716)
		(stroke
			(width 0.08255)
			(type default)
		)
		(layer "F.Cu")
	)
	(gr_line
		(start 241.603276 -94.628716)
		(end 242.064286 -94.80931)
		(stroke
			(width 0.08255)
			(type default)
		)
		(layer "F.Cu")
	)
	(gr_line
		(start 241.60353 -108.224574)
		(end 241.637566 -108.177838)
		(stroke
			(width 0.08255)
			(type default)
		)
		(layer "F.Cu")
	)
	(gr_line
		(start 241.637566 -108.170472)
		(end 241.637566 -108.177838)
		(stroke
			(width 0.08255)
			(type default)
		)
		(layer "F.Cu")
	)
	(gr_line
		(start 241.67846 -94.2213)
		(end 242.284758 -94.459044)
		(stroke
			(width 0.08255)
			(type default)
		)
		(layer "F.Cu")
	)
	(gr_arc
		(start 241.754406 -135.917178)
		(mid 241.745364 -136.043177)
		(end 241.828066 -136.138666)
		(stroke
			(width 0.08255)
			(type default)
		)
		(layer "F.Cu")
	)
	(gr_line
		(start 241.828066 -136.138666)
		(end 242.549934 -136.499854)
		(stroke
			(width 0.08255)
			(type default)
		)
		(layer "F.Cu")
	)
	(gr_arc
		(start 241.828574 -108.138976)
		(mid 241.727995 -108.123825)
		(end 241.637566 -108.170472)
		(stroke
			(width 0.08255)
			(type default)
		)
		(layer "F.Cu")
	)
	(gr_line
		(start 241.828574 -108.138976)
		(end 242.549934 -108.49991)
		(stroke
			(width 0.08255)
			(type default)
		)
		(layer "F.Cu")
	)
	(gr_line
		(start 241.883184 -317.979806)
		(end 241.976402 -318.170814)
		(stroke
			(width 0.0635)
			(type default)
		)
		(layer "F.Cu")
	)
	(gr_line
		(start 241.976402 -318.170814)
		(end 242.336574 -318.29502)
		(stroke
			(width 0.0635)
			(type default)
		)
		(layer "F.Cu")
	)
	(gr_line
		(start 242.0112 -317.712344)
		(end 242.590574 -317.911988)
		(stroke
			(width 0.0635)
			(type default)
		)
		(layer "F.Cu")
	)
	(gr_line
		(start 242.064286 -94.80931)
		(end 242.209828 -94.746064)
		(stroke
			(width 0.08255)
			(type default)
		)
		(layer "F.Cu")
	)
	(gr_line
		(start 242.09883 -305.620928)
		(end 242.108228 -305.628294)
		(stroke
			(width 0.0635)
			(type default)
		)
		(layer "F.Cu")
	)
	(gr_line
		(start 242.108228 -305.628294)
		(end 242.119912 -305.632358)
		(stroke
			(width 0.0635)
			(type default)
		)
		(layer "F.Cu")
	)
	(gr_line
		(start 242.336574 -318.29502)
		(end 242.527328 -318.202056)
		(stroke
			(width 0.0635)
			(type default)
		)
		(layer "F.Cu")
	)
	(gr_line
		(start 242.448334 -388.666736)
		(end 242.4938 -388.712202)
		(stroke
			(width 0.127)
			(type default)
		)
		(layer "F.Cu")
	)
	(gr_line
		(start 242.448334 -387.166866)
		(end 242.4938 -387.1214)
		(stroke
			(width 0.127)
			(type default)
		)
		(layer "F.Cu")
	)
	(gr_line
		(start 242.674902 -94.928436)
		(end 242.738402 -95.073724)
		(stroke
			(width 0.08255)
			(type default)
		)
		(layer "F.Cu")
	)
	(gr_line
		(start 242.738402 -95.073724)
		(end 243.199412 -95.254318)
		(stroke
			(width 0.08255)
			(type default)
		)
		(layer "F.Cu")
	)
	(gr_line
		(start 242.815364 -94.66707)
		(end 243.421154 -94.90456)
		(stroke
			(width 0.08255)
			(type default)
		)
		(layer "F.Cu")
	)
	(gr_line
		(start 242.838224 -109.866176)
		(end 242.879118 -109.838998)
		(stroke
			(width 0.08255)
			(type default)
		)
		(layer "F.Cu")
	)
	(gr_line
		(start 242.892072 -318.327786)
		(end 242.984782 -318.51854)
		(stroke
			(width 0.0635)
			(type default)
		)
		(layer "F.Cu")
	)
	(gr_line
		(start 242.967764 -304.287428)
		(end 242.976146 -304.294286)
		(stroke
			(width 0.0635)
			(type default)
		)
		(layer "F.Cu")
	)
	(gr_line
		(start 242.976146 -304.294286)
		(end 242.986814 -304.298096)
		(stroke
			(width 0.0635)
			(type default)
		)
		(layer "F.Cu")
	)
	(gr_line
		(start 242.984782 -318.51854)
		(end 243.344954 -318.642746)
		(stroke
			(width 0.0635)
			(type default)
		)
		(layer "F.Cu")
	)
	(gr_line
		(start 243.02085 -318.060324)
		(end 243.600732 -318.260476)
		(stroke
			(width 0.0635)
			(type default)
		)
		(layer "F.Cu")
	)
	(gr_line
		(start 243.199412 -95.254318)
		(end 243.344954 -95.191072)
		(stroke
			(width 0.08255)
			(type default)
		)
		(layer "F.Cu")
	)
	(gr_line
		(start 243.344954 -318.642746)
		(end 243.535962 -318.549782)
		(stroke
			(width 0.0635)
			(type default)
		)
		(layer "F.Cu")
	)
	(gr_line
		(start 243.530374 -109.408976)
		(end 243.596922 -109.365034)
		(stroke
			(width 0.08255)
			(type default)
		)
		(layer "F.Cu")
	)
	(gr_line
		(start 243.596922 -109.365034)
		(end 243.614702 -109.287056)
		(stroke
			(width 0.08255)
			(type default)
		)
		(layer "F.Cu")
	)
	(gr_line
		(start 243.665502 -302.877474)
		(end 243.673884 -302.884332)
		(stroke
			(width 0.0635)
			(type default)
		)
		(layer "F.Cu")
	)
	(gr_line
		(start 243.673884 -302.884332)
		(end 243.684552 -302.888142)
		(stroke
			(width 0.0635)
			(type default)
		)
		(layer "F.Cu")
	)
	(gr_line
		(start 243.810028 -95.373444)
		(end 243.873528 -95.518478)
		(stroke
			(width 0.08255)
			(type default)
		)
		(layer "F.Cu")
	)
	(gr_line
		(start 243.873528 -95.518478)
		(end 244.334538 -95.699326)
		(stroke
			(width 0.08255)
			(type default)
		)
		(layer "F.Cu")
	)
	(gr_line
		(start 243.900198 -318.675512)
		(end 243.993416 -318.86652)
		(stroke
			(width 0.0635)
			(type default)
		)
		(layer "F.Cu")
	)
	(gr_line
		(start 243.949474 -95.11157)
		(end 244.55501 -95.348806)
		(stroke
			(width 0.08255)
			(type default)
		)
		(layer "F.Cu")
	)
	(gr_line
		(start 243.97462 -388.23392)
		(end 244.094 -388.3533)
		(stroke
			(width 0.127)
			(type default)
		)
		(layer "F.Cu")
	)
	(gr_line
		(start 243.97462 -387.58368)
		(end 244.094 -387.4643)
		(stroke
			(width 0.127)
			(type default)
		)
		(layer "F.Cu")
	)
	(gr_line
		(start 243.993416 -318.86652)
		(end 244.353588 -318.990726)
		(stroke
			(width 0.0635)
			(type default)
		)
		(layer "F.Cu")
	)
	(gr_line
		(start 244.027706 -318.407542)
		(end 244.607588 -318.607694)
		(stroke
			(width 0.0635)
			(type default)
		)
		(layer "F.Cu")
	)
	(gr_line
		(start 244.094 -388.3533)
		(end 244.21338 -388.23392)
		(stroke
			(width 0.127)
			(type default)
		)
		(layer "F.Cu")
	)
	(gr_line
		(start 244.094 -387.4643)
		(end 244.21338 -387.58368)
		(stroke
			(width 0.127)
			(type default)
		)
		(layer "F.Cu")
	)
	(gr_line
		(start 244.133116 -136.898888)
		(end 244.14353 -136.853676)
		(stroke
			(width 0.08255)
			(type default)
		)
		(layer "F.Cu")
	)
	(gr_line
		(start 244.334538 -95.699326)
		(end 244.479826 -95.635826)
		(stroke
			(width 0.08255)
			(type default)
		)
		(layer "F.Cu")
	)
	(gr_line
		(start 244.353588 -318.990726)
		(end 244.544342 -318.897762)
		(stroke
			(width 0.0635)
			(type default)
		)
		(layer "F.Cu")
	)
	(gr_line
		(start 244.383306 -301.454566)
		(end 244.39245 -301.461678)
		(stroke
			(width 0.0635)
			(type default)
		)
		(layer "F.Cu")
	)
	(gr_line
		(start 244.39245 -301.461678)
		(end 244.403118 -301.465488)
		(stroke
			(width 0.0635)
			(type default)
		)
		(layer "F.Cu")
	)
	(gr_line
		(start 244.607842 -132.936488)
		(end 244.69979 -133.082538)
		(stroke
			(width 0.08255)
			(type default)
		)
		(layer "F.Cu")
	)
	(gr_line
		(start 244.607842 -132.936488)
		(end 244.717824 -132.45338)
		(stroke
			(width 0.08255)
			(type default)
		)
		(layer "F.Cu")
	)
	(gr_line
		(start 244.705632 -102.632002)
		(end 244.78996 -102.76586)
		(stroke
			(width 0.08255)
			(type default)
		)
		(layer "F.Cu")
	)
	(gr_line
		(start 244.705632 -102.632002)
		(end 244.815106 -102.148894)
		(stroke
			(width 0.08255)
			(type default)
		)
		(layer "F.Cu")
	)
	(gr_line
		(start 244.717824 -132.45338)
		(end 244.863874 -132.361686)
		(stroke
			(width 0.08255)
			(type default)
		)
		(layer "F.Cu")
	)
	(gr_line
		(start 244.815106 -102.148894)
		(end 244.948964 -102.064566)
		(stroke
			(width 0.08255)
			(type default)
		)
		(layer "F.Cu")
	)
	(gr_line
		(start 244.866922 -132.359654)
		(end 244.884956 -132.280152)
		(stroke
			(width 0.08255)
			(type default)
		)
		(layer "F.Cu")
	)
	(gr_line
		(start 244.882924 -131.727702)
		(end 244.974872 -131.874006)
		(stroke
			(width 0.08255)
			(type default)
		)
		(layer "F.Cu")
	)
	(gr_line
		(start 244.882924 -131.727702)
		(end 244.992906 -131.244848)
		(stroke
			(width 0.08255)
			(type default)
		)
		(layer "F.Cu")
	)
	(gr_line
		(start 244.974872 -101.443028)
		(end 245.059454 -101.576886)
		(stroke
			(width 0.08255)
			(type default)
		)
		(layer "F.Cu")
	)
	(gr_line
		(start 244.974872 -101.443028)
		(end 245.084346 -100.95992)
		(stroke
			(width 0.08255)
			(type default)
		)
		(layer "F.Cu")
	)
	(gr_line
		(start 244.992906 -131.244848)
		(end 245.138956 -131.153154)
		(stroke
			(width 0.08255)
			(type default)
		)
		(layer "F.Cu")
	)
	(gr_line
		(start 244.994938 -133.11378)
		(end 245.143528 -132.461254)
		(stroke
			(width 0.08255)
			(type default)
		)
		(layer "F.Cu")
	)
	(gr_line
		(start 245.084346 -100.95992)
		(end 245.218458 -100.875338)
		(stroke
			(width 0.08255)
			(type default)
		)
		(layer "F.Cu")
	)
	(gr_line
		(start 245.084346 -95.556324)
		(end 245.093236 -95.55988)
		(stroke
			(width 0.08255)
			(type default)
		)
		(layer "F.Cu")
	)
	(gr_line
		(start 245.085108 -102.797356)
		(end 245.228872 -102.163118)
		(stroke
			(width 0.08255)
			(type default)
		)
		(layer "F.Cu")
	)
	(gr_line
		(start 245.093236 -95.55988)
		(end 245.100348 -95.565722)
		(stroke
			(width 0.08255)
			(type default)
		)
		(layer "F.Cu")
	)
	(gr_line
		(start 245.149624 -132.432806)
		(end 245.153942 -132.41528)
		(stroke
			(width 0.08255)
			(type default)
		)
		(layer "F.Cu")
	)
	(gr_line
		(start 245.15318 -131.1021)
		(end 245.251986 -130.668268)
		(stroke
			(width 0.08255)
			(type default)
		)
		(layer "F.Cu")
	)
	(gr_line
		(start 245.15826 -130.51917)
		(end 245.249954 -130.66522)
		(stroke
			(width 0.08255)
			(type default)
		)
		(layer "F.Cu")
	)
	(gr_line
		(start 245.15826 -130.51917)
		(end 245.267988 -130.036316)
		(stroke
			(width 0.08255)
			(type default)
		)
		(layer "F.Cu")
	)
	(gr_line
		(start 245.244366 -100.2538)
		(end 245.328948 -100.387912)
		(stroke
			(width 0.08255)
			(type default)
		)
		(layer "F.Cu")
	)
	(gr_line
		(start 245.244366 -100.2538)
		(end 245.35384 -99.770946)
		(stroke
			(width 0.08255)
			(type default)
		)
		(layer "F.Cu")
	)
	(gr_line
		(start 245.267988 -130.036316)
		(end 245.414038 -129.944368)
		(stroke
			(width 0.08255)
			(type default)
		)
		(layer "F.Cu")
	)
	(gr_line
		(start 245.269766 -131.906772)
		(end 245.418864 -131.252214)
		(stroke
			(width 0.08255)
			(type default)
		)
		(layer "F.Cu")
	)
	(gr_line
		(start 245.35384 -99.770946)
		(end 245.487952 -99.68611)
		(stroke
			(width 0.08255)
			(type default)
		)
		(layer "F.Cu")
	)
	(gr_line
		(start 245.354602 -101.607366)
		(end 245.498366 -100.97389)
		(stroke
			(width 0.08255)
			(type default)
		)
		(layer "F.Cu")
	)
	(gr_line
		(start 245.51386 -99.064826)
		(end 245.598442 -99.199192)
		(stroke
			(width 0.08255)
			(type default)
		)
		(layer "F.Cu")
	)
	(gr_line
		(start 245.51386 -99.064826)
		(end 245.623334 -98.581718)
		(stroke
			(width 0.08255)
			(type default)
		)
		(layer "F.Cu")
	)
	(gr_line
		(start 245.545356 -130.695446)
		(end 245.693184 -130.045206)
		(stroke
			(width 0.08255)
			(type default)
		)
		(layer "F.Cu")
	)
	(gr_line
		(start 245.55323 -95.935038)
		(end 245.593362 -95.967804)
		(stroke
			(width 0.08255)
			(type default)
		)
		(layer "F.Cu")
	)
	(gr_line
		(start 245.593362 -95.967804)
		(end 245.608094 -96.017334)
		(stroke
			(width 0.08255)
			(type default)
		)
		(layer "F.Cu")
	)
	(gr_line
		(start 245.623334 -98.581718)
		(end 245.757192 -98.49739)
		(stroke
			(width 0.08255)
			(type default)
		)
		(layer "F.Cu")
	)
	(gr_line
		(start 245.624096 -100.418392)
		(end 245.76786 -99.7839)
		(stroke
			(width 0.08255)
			(type default)
		)
		(layer "F.Cu")
	)
	(gr_line
		(start 245.62562 -388.23392)
		(end 245.8085 -388.4168)
		(stroke
			(width 0.127)
			(type default)
		)
		(layer "F.Cu")
	)
	(gr_line
		(start 245.62562 -387.58368)
		(end 245.8085 -387.4008)
		(stroke
			(width 0.127)
			(type default)
		)
		(layer "F.Cu")
	)
	(gr_line
		(start 245.893082 -99.231958)
		(end 246.018558 -98.678238)
		(stroke
			(width 0.08255)
			(type default)
		)
		(layer "F.Cu")
	)
	(gr_line
		(start 246.018304 -98.678238)
		(end 246.018558 -98.678238)
		(stroke
			(width 0.08255)
			(type default)
		)
		(layer "F.Cu")
	)
	(gr_line
		(start 246.018304 -98.678238)
		(end 246.036846 -98.596704)
		(stroke
			(width 0.08255)
			(type default)
		)
		(layer "F.Cu")
	)
	(gr_line
		(start 246.01932 -94.23019)
		(end 246.026686 -94.233238)
		(stroke
			(width 0.08255)
			(type default)
		)
		(layer "F.Cu")
	)
	(gr_line
		(start 246.026686 -94.233238)
		(end 246.032274 -94.23781)
		(stroke
			(width 0.08255)
			(type default)
		)
		(layer "F.Cu")
	)
	(gr_line
		(start 246.170958 -97.918016)
		(end 246.18188 -97.9551)
		(stroke
			(width 0.08255)
			(type default)
		)
		(layer "F.Cu")
	)
	(gr_line
		(start 246.173498 -97.992184)
		(end 246.18188 -97.9551)
		(stroke
			(width 0.08255)
			(type default)
		)
		(layer "F.Cu")
	)
	(gr_line
		(start 247.012206 -325.216012)
		(end 247.10517 -325.40702)
		(stroke
			(width 0.0635)
			(type default)
		)
		(layer "F.Cu")
	)
	(gr_line
		(start 247.10517 -325.40702)
		(end 247.465342 -325.531226)
		(stroke
			(width 0.0635)
			(type default)
		)
		(layer "F.Cu")
	)
	(gr_line
		(start 247.141492 -324.949058)
		(end 247.720358 -325.148702)
		(stroke
			(width 0.0635)
			(type default)
		)
		(layer "F.Cu")
	)
	(gr_line
		(start 247.465342 -325.531226)
		(end 247.656604 -325.438262)
		(stroke
			(width 0.0635)
			(type default)
		)
		(layer "F.Cu")
	)
	(gr_line
		(start 247.543574 -95.468186)
		(end 247.585738 -95.502476)
		(stroke
			(width 0.08255)
			(type default)
		)
		(layer "F.Cu")
	)
	(gr_line
		(start 247.585738 -95.502476)
		(end 247.600724 -95.554038)
		(stroke
			(width 0.08255)
			(type default)
		)
		(layer "F.Cu")
	)
	(gr_line
		(start 247.595898 -388.4422)
		(end 247.804178 -388.23392)
		(stroke
			(width 0.127)
			(type default)
		)
		(layer "F.Cu")
	)
	(gr_line
		(start 247.595898 -387.3754)
		(end 247.804178 -387.58368)
		(stroke
			(width 0.127)
			(type default)
		)
		(layer "F.Cu")
	)
	(gr_line
		(start 248.020586 -325.563992)
		(end 248.113804 -325.755)
		(stroke
			(width 0.0635)
			(type default)
		)
		(layer "F.Cu")
	)
	(gr_line
		(start 248.113804 -325.755)
		(end 248.473976 -325.879206)
		(stroke
			(width 0.0635)
			(type default)
		)
		(layer "F.Cu")
	)
	(gr_line
		(start 248.148348 -325.296276)
		(end 248.729754 -325.496936)
		(stroke
			(width 0.0635)
			(type default)
		)
		(layer "F.Cu")
	)
	(gr_line
		(start 248.473976 -325.879206)
		(end 248.665238 -325.786242)
		(stroke
			(width 0.0635)
			(type default)
		)
		(layer "F.Cu")
	)
	(gr_line
		(start 249.02922 -325.911718)
		(end 249.122184 -326.10298)
		(stroke
			(width 0.0635)
			(type default)
		)
		(layer "F.Cu")
	)
	(gr_line
		(start 249.122184 -326.10298)
		(end 249.482356 -326.227186)
		(stroke
			(width 0.0635)
			(type default)
		)
		(layer "F.Cu")
	)
	(gr_line
		(start 249.15622 -325.644002)
		(end 249.737372 -325.844408)
		(stroke
			(width 0.0635)
			(type default)
		)
		(layer "F.Cu")
	)
	(gr_line
		(start 249.482356 -326.227186)
		(end 249.673618 -326.133968)
		(stroke
			(width 0.0635)
			(type default)
		)
		(layer "F.Cu")
	)
	(gr_line
		(start 250.0376 -326.259698)
		(end 250.130818 -326.450706)
		(stroke
			(width 0.0635)
			(type default)
		)
		(layer "F.Cu")
	)
	(gr_line
		(start 250.130818 -326.450706)
		(end 250.49099 -326.574912)
		(stroke
			(width 0.0635)
			(type default)
		)
		(layer "F.Cu")
	)
	(gr_line
		(start 250.165616 -325.992236)
		(end 250.748038 -326.192896)
		(stroke
			(width 0.0635)
			(type default)
		)
		(layer "F.Cu")
	)
	(gr_line
		(start 250.49099 -326.574912)
		(end 250.68149 -326.482202)
		(stroke
			(width 0.0635)
			(type default)
		)
		(layer "F.Cu")
	)
	(gr_line
		(start 250.937014 -106.927142)
		(end 250.947682 -106.964226)
		(stroke
			(width 0.08255)
			(type default)
		)
		(layer "F.Cu")
	)
	(gr_line
		(start 250.9393 -107.001056)
		(end 250.947682 -106.964226)
		(stroke
			(width 0.08255)
			(type default)
		)
		(layer "F.Cu")
	)
	(gr_line
		(start 251.483876 -328.7268)
		(end 251.485146 -328.727308)
		(stroke
			(width 0.0635)
			(type default)
		)
		(layer "F.Cu")
	)
	(gr_line
		(start 251.578618 -328.450194)
		(end 251.579888 -328.450702)
		(stroke
			(width 0.0635)
			(type default)
		)
		(layer "F.Cu")
	)
	(gr_line
		(start 254.868172 -19.465036)
		(end 255.498092 -20.094956)
		(stroke
			(width 0.08255)
			(type default)
		)
		(layer "F.Cu")
	)
	(gr_line
		(start 254.868172 -19.048476)
		(end 255.498092 -18.418556)
		(stroke
			(width 0.08255)
			(type default)
		)
		(layer "F.Cu")
	)
	(gr_line
		(start 255.62306 -390.862058)
		(end 255.78054 -391.019538)
		(stroke
			(width 0.127)
			(type default)
		)
		(layer "F.Cu")
	)
	(gr_line
		(start 255.62306 -390.211818)
		(end 255.78054 -390.054338)
		(stroke
			(width 0.127)
			(type default)
		)
		(layer "F.Cu")
	)
	(gr_line
		(start 255.78054 -391.019538)
		(end 255.78054 -394.651992)
		(stroke
			(width 0.127)
			(type default)
		)
		(layer "F.Cu")
	)
	(gr_line
		(start 255.78054 -386.421884)
		(end 255.78054 -390.054338)
		(stroke
			(width 0.127)
			(type default)
		)
		(layer "F.Cu")
	)
	(gr_line
		(start 259.316728 -306.610512)
		(end 259.326634 -306.613814)
		(stroke
			(width 0.0635)
			(type default)
		)
		(layer "F.Cu")
	)
	(gr_line
		(start 259.694426 -308.41061)
		(end 259.704332 -308.413912)
		(stroke
			(width 0.0635)
			(type default)
		)
		(layer "F.Cu")
	)
	(gr_line
		(start 260.125718 -310.210454)
		(end 260.135624 -310.213756)
		(stroke
			(width 0.0635)
			(type default)
		)
		(layer "F.Cu")
	)
	(gr_line
		(start 260.608318 -312.010552)
		(end 260.618224 -312.013854)
		(stroke
			(width 0.0635)
			(type default)
		)
		(layer "F.Cu")
	)
	(gr_line
		(start 260.962648 -313.81065)
		(end 260.972554 -313.813952)
		(stroke
			(width 0.0635)
			(type default)
		)
		(layer "F.Cu")
	)
	(gr_line
		(start 261.295642 -315.610494)
		(end 261.305548 -315.613796)
		(stroke
			(width 0.0635)
			(type default)
		)
		(layer "F.Cu")
	)
	(gr_line
		(start 262.668512 -254.104648)
		(end 262.683244 -254.129032)
		(stroke
			(width 0.08255)
			(type default)
		)
		(layer "F.Cu")
	)
	(gr_line
		(start 262.683244 -254.129032)
		(end 262.70712 -254.14478)
		(stroke
			(width 0.08255)
			(type default)
		)
		(layer "F.Cu")
	)
	(gr_line
		(start 266.018264 -308.416452)
		(end 266.168124 -308.566312)
		(stroke
			(width 0.0635)
			(type default)
		)
		(layer "F.Cu")
	)
	(gr_line
		(start 266.045188 -310.216296)
		(end 266.195048 -310.366156)
		(stroke
			(width 0.0635)
			(type default)
		)
		(layer "F.Cu")
	)
	(gr_line
		(start 266.045442 -312.016394)
		(end 266.195302 -312.166254)
		(stroke
			(width 0.0635)
			(type default)
		)
		(layer "F.Cu")
	)
	(gr_line
		(start 266.045696 -315.616336)
		(end 266.195556 -315.766196)
		(stroke
			(width 0.0635)
			(type default)
		)
		(layer "F.Cu")
	)
	(gr_line
		(start 266.045696 -313.816492)
		(end 266.195556 -313.966352)
		(stroke
			(width 0.0635)
			(type default)
		)
		(layer "F.Cu")
	)
	(gr_line
		(start 266.168124 -308.566312)
		(end 266.549124 -308.566312)
		(stroke
			(width 0.0635)
			(type default)
		)
		(layer "F.Cu")
	)
	(gr_line
		(start 266.195048 -310.366156)
		(end 266.576048 -310.366156)
		(stroke
			(width 0.0635)
			(type default)
		)
		(layer "F.Cu")
	)
	(gr_line
		(start 266.195302 -312.166254)
		(end 266.576302 -312.166254)
		(stroke
			(width 0.0635)
			(type default)
		)
		(layer "F.Cu")
	)
	(gr_line
		(start 266.195556 -315.766196)
		(end 266.576556 -315.766196)
		(stroke
			(width 0.0635)
			(type default)
		)
		(layer "F.Cu")
	)
	(gr_line
		(start 266.195556 -313.966352)
		(end 266.576556 -313.966352)
		(stroke
			(width 0.0635)
			(type default)
		)
		(layer "F.Cu")
	)
	(gr_line
		(start 266.211812 -306.616354)
		(end 266.361672 -306.766214)
		(stroke
			(width 0.0635)
			(type default)
		)
		(layer "F.Cu")
	)
	(gr_line
		(start 266.310364 -308.121812)
		(end 266.406884 -308.121812)
		(stroke
			(width 0.0635)
			(type default)
		)
		(layer "F.Cu")
	)
	(gr_line
		(start 266.337288 -309.921656)
		(end 266.433808 -309.921656)
		(stroke
			(width 0.0635)
			(type default)
		)
		(layer "F.Cu")
	)
	(gr_line
		(start 266.337542 -311.721754)
		(end 266.434062 -311.721754)
		(stroke
			(width 0.0635)
			(type default)
		)
		(layer "F.Cu")
	)
	(gr_line
		(start 266.337796 -315.321696)
		(end 266.434316 -315.321696)
		(stroke
			(width 0.0635)
			(type default)
		)
		(layer "F.Cu")
	)
	(gr_line
		(start 266.337796 -313.521852)
		(end 266.434316 -313.521852)
		(stroke
			(width 0.0635)
			(type default)
		)
		(layer "F.Cu")
	)
	(gr_line
		(start 266.361672 -306.766214)
		(end 266.742672 -306.766214)
		(stroke
			(width 0.0635)
			(type default)
		)
		(layer "F.Cu")
	)
	(gr_line
		(start 266.503912 -306.321714)
		(end 266.600432 -306.321714)
		(stroke
			(width 0.0635)
			(type default)
		)
		(layer "F.Cu")
	)
	(gr_line
		(start 266.549124 -308.566312)
		(end 266.698984 -308.416452)
		(stroke
			(width 0.0635)
			(type default)
		)
		(layer "F.Cu")
	)
	(gr_line
		(start 266.576048 -310.366156)
		(end 266.725908 -310.216296)
		(stroke
			(width 0.0635)
			(type default)
		)
		(layer "F.Cu")
	)
	(gr_line
		(start 266.576302 -312.166254)
		(end 266.726162 -312.016394)
		(stroke
			(width 0.0635)
			(type default)
		)
		(layer "F.Cu")
	)
	(gr_line
		(start 266.576556 -315.766196)
		(end 266.726416 -315.616336)
		(stroke
			(width 0.0635)
			(type default)
		)
		(layer "F.Cu")
	)
	(gr_line
		(start 266.576556 -313.966352)
		(end 266.726416 -313.816492)
		(stroke
			(width 0.0635)
			(type default)
		)
		(layer "F.Cu")
	)
	(gr_line
		(start 266.727178 -335.671414)
		(end 266.820142 -335.861914)
		(stroke
			(width 0.0635)
			(type default)
		)
		(layer "F.Cu")
	)
	(gr_line
		(start 266.742672 -306.766214)
		(end 266.892532 -306.616354)
		(stroke
			(width 0.0635)
			(type default)
		)
		(layer "F.Cu")
	)
	(gr_line
		(start 266.820142 -335.861914)
		(end 267.180314 -335.98612)
		(stroke
			(width 0.0635)
			(type default)
		)
		(layer "F.Cu")
	)
	(gr_line
		(start 266.85621 -335.404206)
		(end 267.433044 -335.602834)
		(stroke
			(width 0.0635)
			(type default)
		)
		(layer "F.Cu")
	)
	(gr_line
		(start 267.085064 -308.416452)
		(end 267.234924 -308.566312)
		(stroke
			(width 0.0635)
			(type default)
		)
		(layer "F.Cu")
	)
	(gr_line
		(start 267.111988 -310.216296)
		(end 267.261848 -310.366156)
		(stroke
			(width 0.0635)
			(type default)
		)
		(layer "F.Cu")
	)
	(gr_line
		(start 267.112242 -312.016394)
		(end 267.262102 -312.166254)
		(stroke
			(width 0.0635)
			(type default)
		)
		(layer "F.Cu")
	)
	(gr_line
		(start 267.112496 -315.616336)
		(end 267.262356 -315.766196)
		(stroke
			(width 0.0635)
			(type default)
		)
		(layer "F.Cu")
	)
	(gr_line
		(start 267.112496 -313.816492)
		(end 267.262356 -313.966352)
		(stroke
			(width 0.0635)
			(type default)
		)
		(layer "F.Cu")
	)
	(gr_line
		(start 267.174726 -136.672066)
		(end 267.804646 -136.042146)
		(stroke
			(width 0.08255)
			(type default)
		)
		(layer "F.Cu")
	)
	(gr_line
		(start 267.174726 -134.995666)
		(end 267.804646 -135.625586)
		(stroke
			(width 0.08255)
			(type default)
		)
		(layer "F.Cu")
	)
	(gr_line
		(start 267.180314 -335.98612)
		(end 267.371068 -335.893156)
		(stroke
			(width 0.0635)
			(type default)
		)
		(layer "F.Cu")
	)
	(gr_line
		(start 267.234924 -308.566312)
		(end 267.615924 -308.566312)
		(stroke
			(width 0.0635)
			(type default)
		)
		(layer "F.Cu")
	)
	(gr_line
		(start 267.261848 -310.366156)
		(end 267.642848 -310.366156)
		(stroke
			(width 0.0635)
			(type default)
		)
		(layer "F.Cu")
	)
	(gr_line
		(start 267.262102 -312.166254)
		(end 267.643102 -312.166254)
		(stroke
			(width 0.0635)
			(type default)
		)
		(layer "F.Cu")
	)
	(gr_line
		(start 267.262356 -315.766196)
		(end 267.643356 -315.766196)
		(stroke
			(width 0.0635)
			(type default)
		)
		(layer "F.Cu")
	)
	(gr_line
		(start 267.262356 -313.966352)
		(end 267.643356 -313.966352)
		(stroke
			(width 0.0635)
			(type default)
		)
		(layer "F.Cu")
	)
	(gr_line
		(start 267.278612 -306.616354)
		(end 267.428472 -306.766214)
		(stroke
			(width 0.0635)
			(type default)
		)
		(layer "F.Cu")
	)
	(gr_line
		(start 267.377164 -308.121812)
		(end 267.473684 -308.121812)
		(stroke
			(width 0.0635)
			(type default)
		)
		(layer "F.Cu")
	)
	(gr_line
		(start 267.404088 -309.921656)
		(end 267.500608 -309.921656)
		(stroke
			(width 0.0635)
			(type default)
		)
		(layer "F.Cu")
	)
	(gr_line
		(start 267.404342 -311.721754)
		(end 267.500862 -311.721754)
		(stroke
			(width 0.0635)
			(type default)
		)
		(layer "F.Cu")
	)
	(gr_line
		(start 267.404596 -315.321696)
		(end 267.501116 -315.321696)
		(stroke
			(width 0.0635)
			(type default)
		)
		(layer "F.Cu")
	)
	(gr_line
		(start 267.404596 -313.521852)
		(end 267.501116 -313.521852)
		(stroke
			(width 0.0635)
			(type default)
		)
		(layer "F.Cu")
	)
	(gr_line
		(start 267.428472 -306.766214)
		(end 267.809472 -306.766214)
		(stroke
			(width 0.0635)
			(type default)
		)
		(layer "F.Cu")
	)
	(gr_line
		(start 267.570712 -306.321714)
		(end 267.667232 -306.321714)
		(stroke
			(width 0.0635)
			(type default)
		)
		(layer "F.Cu")
	)
	(gr_line
		(start 267.615924 -308.566312)
		(end 267.765784 -308.416452)
		(stroke
			(width 0.0635)
			(type default)
		)
		(layer "F.Cu")
	)
	(gr_line
		(start 267.642848 -310.366156)
		(end 267.792708 -310.216296)
		(stroke
			(width 0.0635)
			(type default)
		)
		(layer "F.Cu")
	)
	(gr_line
		(start 267.643102 -312.166254)
		(end 267.792962 -312.016394)
		(stroke
			(width 0.0635)
			(type default)
		)
		(layer "F.Cu")
	)
	(gr_line
		(start 267.643356 -315.766196)
		(end 267.793216 -315.616336)
		(stroke
			(width 0.0635)
			(type default)
		)
		(layer "F.Cu")
	)
	(gr_line
		(start 267.643356 -313.966352)
		(end 267.793216 -313.816492)
		(stroke
			(width 0.0635)
			(type default)
		)
		(layer "F.Cu")
	)
	(gr_line
		(start 267.678662 -335.687416)
		(end 267.837412 -335.74228)
		(stroke
			(width 0.0635)
			(type default)
		)
		(layer "F.Cu")
	)
	(gr_line
		(start 267.735812 -336.018886)
		(end 267.828776 -336.209386)
		(stroke
			(width 0.0635)
			(type default)
		)
		(layer "F.Cu")
	)
	(gr_line
		(start 267.809472 -306.766214)
		(end 267.959332 -306.616354)
		(stroke
			(width 0.0635)
			(type default)
		)
		(layer "F.Cu")
	)
	(gr_line
		(start 267.828776 -336.209386)
		(end 268.188948 -336.333338)
		(stroke
			(width 0.0635)
			(type default)
		)
		(layer "F.Cu")
	)
	(gr_line
		(start 267.866114 -335.751932)
		(end 268.440408 -335.949798)
		(stroke
			(width 0.0635)
			(type default)
		)
		(layer "F.Cu")
	)
	(gr_line
		(start 268.151864 -308.416452)
		(end 268.301724 -308.566312)
		(stroke
			(width 0.0635)
			(type default)
		)
		(layer "F.Cu")
	)
	(gr_line
		(start 268.178788 -310.216296)
		(end 268.328648 -310.366156)
		(stroke
			(width 0.0635)
			(type default)
		)
		(layer "F.Cu")
	)
	(gr_line
		(start 268.179042 -312.016394)
		(end 268.328902 -312.166254)
		(stroke
			(width 0.0635)
			(type default)
		)
		(layer "F.Cu")
	)
	(gr_line
		(start 268.179296 -315.616336)
		(end 268.329156 -315.766196)
		(stroke
			(width 0.0635)
			(type default)
		)
		(layer "F.Cu")
	)
	(gr_line
		(start 268.179296 -313.816492)
		(end 268.329156 -313.966352)
		(stroke
			(width 0.0635)
			(type default)
		)
		(layer "F.Cu")
	)
	(gr_line
		(start 268.188948 -336.333338)
		(end 268.379448 -336.240374)
		(stroke
			(width 0.0635)
			(type default)
		)
		(layer "F.Cu")
	)
	(gr_line
		(start 268.301724 -308.566312)
		(end 268.682724 -308.566312)
		(stroke
			(width 0.0635)
			(type default)
		)
		(layer "F.Cu")
	)
	(gr_line
		(start 268.328648 -310.366156)
		(end 268.709648 -310.366156)
		(stroke
			(width 0.0635)
			(type default)
		)
		(layer "F.Cu")
	)
	(gr_line
		(start 268.328902 -312.166254)
		(end 268.709902 -312.166254)
		(stroke
			(width 0.0635)
			(type default)
		)
		(layer "F.Cu")
	)
	(gr_line
		(start 268.329156 -315.766196)
		(end 268.710156 -315.766196)
		(stroke
			(width 0.0635)
			(type default)
		)
		(layer "F.Cu")
	)
	(gr_line
		(start 268.329156 -313.966352)
		(end 268.710156 -313.966352)
		(stroke
			(width 0.0635)
			(type default)
		)
		(layer "F.Cu")
	)
	(gr_line
		(start 268.345412 -306.616354)
		(end 268.495272 -306.766214)
		(stroke
			(width 0.0635)
			(type default)
		)
		(layer "F.Cu")
	)
	(gr_line
		(start 268.443964 -308.121812)
		(end 268.540484 -308.121812)
		(stroke
			(width 0.0635)
			(type default)
		)
		(layer "F.Cu")
	)
	(gr_line
		(start 268.470888 -309.921656)
		(end 268.567408 -309.921656)
		(stroke
			(width 0.0635)
			(type default)
		)
		(layer "F.Cu")
	)
	(gr_line
		(start 268.471142 -311.721754)
		(end 268.567662 -311.721754)
		(stroke
			(width 0.0635)
			(type default)
		)
		(layer "F.Cu")
	)
	(gr_line
		(start 268.471396 -315.321696)
		(end 268.567916 -315.321696)
		(stroke
			(width 0.0635)
			(type default)
		)
		(layer "F.Cu")
	)
	(gr_line
		(start 268.471396 -313.521852)
		(end 268.567916 -313.521852)
		(stroke
			(width 0.0635)
			(type default)
		)
		(layer "F.Cu")
	)
	(gr_line
		(start 268.473428 -335.961228)
		(end 268.482064 -335.964276)
		(stroke
			(width 0.0635)
			(type default)
		)
		(layer "F.Cu")
	)
	(gr_line
		(start 268.495272 -306.766214)
		(end 268.876272 -306.766214)
		(stroke
			(width 0.0635)
			(type default)
		)
		(layer "F.Cu")
	)
	(gr_line
		(start 268.632178 -336.015838)
		(end 268.848332 -336.09026)
		(stroke
			(width 0.0635)
			(type default)
		)
		(layer "F.Cu")
	)
	(gr_line
		(start 268.637512 -306.321714)
		(end 268.734032 -306.321714)
		(stroke
			(width 0.0635)
			(type default)
		)
		(layer "F.Cu")
	)
	(gr_line
		(start 268.64056 -336.327496)
		(end 268.742922 -336.362802)
		(stroke
			(width 0.0635)
			(type default)
		)
		(layer "F.Cu")
	)
	(gr_line
		(start 268.682724 -308.566312)
		(end 268.832584 -308.416452)
		(stroke
			(width 0.0635)
			(type default)
		)
		(layer "F.Cu")
	)
	(gr_line
		(start 268.709648 -310.366156)
		(end 268.859508 -310.216296)
		(stroke
			(width 0.0635)
			(type default)
		)
		(layer "F.Cu")
	)
	(gr_line
		(start 268.709902 -312.166254)
		(end 268.859762 -312.016394)
		(stroke
			(width 0.0635)
			(type default)
		)
		(layer "F.Cu")
	)
	(gr_line
		(start 268.710156 -315.766196)
		(end 268.860016 -315.616336)
		(stroke
			(width 0.0635)
			(type default)
		)
		(layer "F.Cu")
	)
	(gr_line
		(start 268.710156 -313.966352)
		(end 268.860016 -313.816492)
		(stroke
			(width 0.0635)
			(type default)
		)
		(layer "F.Cu")
	)
	(gr_line
		(start 268.744446 -336.366104)
		(end 268.83741 -336.556604)
		(stroke
			(width 0.0635)
			(type default)
		)
		(layer "F.Cu")
	)
	(gr_line
		(start 268.83741 -336.556604)
		(end 269.197582 -336.680556)
		(stroke
			(width 0.0635)
			(type default)
		)
		(layer "F.Cu")
	)
	(gr_line
		(start 268.876272 -306.766214)
		(end 269.026132 -306.616354)
		(stroke
			(width 0.0635)
			(type default)
		)
		(layer "F.Cu")
	)
	(gr_line
		(start 268.876526 -336.100166)
		(end 269.448534 -336.297016)
		(stroke
			(width 0.0635)
			(type default)
		)
		(layer "F.Cu")
	)
	(gr_line
		(start 269.197582 -336.680556)
		(end 269.388082 -336.587592)
		(stroke
			(width 0.0635)
			(type default)
		)
		(layer "F.Cu")
	)
	(gr_line
		(start 269.218664 -308.416452)
		(end 269.368524 -308.566312)
		(stroke
			(width 0.0635)
			(type default)
		)
		(layer "F.Cu")
	)
	(gr_line
		(start 269.245588 -310.216296)
		(end 269.395448 -310.366156)
		(stroke
			(width 0.0635)
			(type default)
		)
		(layer "F.Cu")
	)
	(gr_line
		(start 269.245842 -312.016394)
		(end 269.395702 -312.166254)
		(stroke
			(width 0.0635)
			(type default)
		)
		(layer "F.Cu")
	)
	(gr_line
		(start 269.246096 -315.616336)
		(end 269.395956 -315.766196)
		(stroke
			(width 0.0635)
			(type default)
		)
		(layer "F.Cu")
	)
	(gr_line
		(start 269.246096 -313.816492)
		(end 269.395956 -313.966352)
		(stroke
			(width 0.0635)
			(type default)
		)
		(layer "F.Cu")
	)
	(gr_line
		(start 269.368524 -308.566312)
		(end 269.749524 -308.566312)
		(stroke
			(width 0.0635)
			(type default)
		)
		(layer "F.Cu")
	)
	(gr_line
		(start 269.391384 -336.586068)
		(end 269.420848 -336.596228)
		(stroke
			(width 0.0635)
			(type default)
		)
		(layer "F.Cu")
	)
	(gr_line
		(start 269.395448 -310.366156)
		(end 269.776448 -310.366156)
		(stroke
			(width 0.0635)
			(type default)
		)
		(layer "F.Cu")
	)
	(gr_line
		(start 269.395702 -312.166254)
		(end 269.776702 -312.166254)
		(stroke
			(width 0.0635)
			(type default)
		)
		(layer "F.Cu")
	)
	(gr_line
		(start 269.395956 -315.766196)
		(end 269.776956 -315.766196)
		(stroke
			(width 0.0635)
			(type default)
		)
		(layer "F.Cu")
	)
	(gr_line
		(start 269.395956 -313.966352)
		(end 269.776956 -313.966352)
		(stroke
			(width 0.0635)
			(type default)
		)
		(layer "F.Cu")
	)
	(gr_line
		(start 269.412212 -306.616354)
		(end 269.562072 -306.766214)
		(stroke
			(width 0.0635)
			(type default)
		)
		(layer "F.Cu")
	)
	(gr_line
		(start 269.480538 -336.307938)
		(end 269.516098 -336.32013)
		(stroke
			(width 0.0635)
			(type default)
		)
		(layer "F.Cu")
	)
	(gr_line
		(start 269.510764 -308.121812)
		(end 269.607284 -308.121812)
		(stroke
			(width 0.0635)
			(type default)
		)
		(layer "F.Cu")
	)
	(gr_line
		(start 269.537688 -309.921656)
		(end 269.634208 -309.921656)
		(stroke
			(width 0.0635)
			(type default)
		)
		(layer "F.Cu")
	)
	(gr_line
		(start 269.537942 -311.721754)
		(end 269.634462 -311.721754)
		(stroke
			(width 0.0635)
			(type default)
		)
		(layer "F.Cu")
	)
	(gr_line
		(start 269.538196 -315.321696)
		(end 269.634716 -315.321696)
		(stroke
			(width 0.0635)
			(type default)
		)
		(layer "F.Cu")
	)
	(gr_line
		(start 269.538196 -313.521852)
		(end 269.634716 -313.521852)
		(stroke
			(width 0.0635)
			(type default)
		)
		(layer "F.Cu")
	)
	(gr_line
		(start 269.562072 -306.766214)
		(end 269.943072 -306.766214)
		(stroke
			(width 0.0635)
			(type default)
		)
		(layer "F.Cu")
	)
	(gr_line
		(start 269.704312 -306.321714)
		(end 269.800832 -306.321714)
		(stroke
			(width 0.0635)
			(type default)
		)
		(layer "F.Cu")
	)
	(gr_line
		(start 269.749524 -308.566312)
		(end 269.899384 -308.416452)
		(stroke
			(width 0.0635)
			(type default)
		)
		(layer "F.Cu")
	)
	(gr_line
		(start 269.75308 -336.713322)
		(end 269.846044 -336.903822)
		(stroke
			(width 0.0635)
			(type default)
		)
		(layer "F.Cu")
	)
	(gr_line
		(start 269.776448 -310.366156)
		(end 269.926308 -310.216296)
		(stroke
			(width 0.0635)
			(type default)
		)
		(layer "F.Cu")
	)
	(gr_line
		(start 269.776702 -312.166254)
		(end 269.926562 -312.016394)
		(stroke
			(width 0.0635)
			(type default)
		)
		(layer "F.Cu")
	)
	(gr_line
		(start 269.776956 -315.766196)
		(end 269.926816 -315.616336)
		(stroke
			(width 0.0635)
			(type default)
		)
		(layer "F.Cu")
	)
	(gr_line
		(start 269.776956 -313.966352)
		(end 269.926816 -313.816492)
		(stroke
			(width 0.0635)
			(type default)
		)
		(layer "F.Cu")
	)
	(gr_line
		(start 269.846044 -336.903822)
		(end 270.20647 -337.028028)
		(stroke
			(width 0.0635)
			(type default)
		)
		(layer "F.Cu")
	)
	(gr_line
		(start 269.88262 -336.446368)
		(end 270.458692 -336.644742)
		(stroke
			(width 0.0635)
			(type default)
		)
		(layer "F.Cu")
	)
	(gr_line
		(start 269.943072 -306.766214)
		(end 270.092932 -306.616354)
		(stroke
			(width 0.0635)
			(type default)
		)
		(layer "F.Cu")
	)
	(gr_line
		(start 270.20647 -337.028028)
		(end 270.39697 -336.935064)
		(stroke
			(width 0.0635)
			(type default)
		)
		(layer "F.Cu")
	)
	(gr_line
		(start 270.336264 -358.646476)
		(end 270.366744 -358.662732)
		(stroke
			(width 0.0635)
			(type default)
		)
		(layer "F.Cu")
	)
	(gr_line
		(start 270.459708 -351.533714)
		(end 270.490188 -351.54997)
		(stroke
			(width 0.0635)
			(type default)
		)
		(layer "F.Cu")
	)
	(gr_line
		(start 270.519398 -349.797624)
		(end 270.549878 -349.81388)
		(stroke
			(width 0.0635)
			(type default)
		)
		(layer "F.Cu")
	)
	(gr_line
		(start 270.683736 -353.397566)
		(end 270.714216 -353.413822)
		(stroke
			(width 0.0635)
			(type default)
		)
		(layer "F.Cu")
	)
	(gr_line
		(start 270.709136 -329.902566)
		(end 270.719042 -329.905868)
		(stroke
			(width 0.0635)
			(type default)
		)
		(layer "F.Cu")
	)
	(gr_line
		(start 270.759936 -355.197664)
		(end 270.790416 -355.21392)
		(stroke
			(width 0.0635)
			(type default)
		)
		(layer "F.Cu")
	)
	(gr_line
		(start 270.847566 -356.994714)
		(end 270.878046 -357.01097)
		(stroke
			(width 0.0635)
			(type default)
		)
		(layer "F.Cu")
	)
	(gr_line
		(start 270.860266 -335.410556)
		(end 270.870172 -335.413858)
		(stroke
			(width 0.0635)
			(type default)
		)
		(layer "F.Cu")
	)
	(gr_line
		(start 270.914368 -331.810614)
		(end 270.924274 -331.813916)
		(stroke
			(width 0.0635)
			(type default)
		)
		(layer "F.Cu")
	)
	(gr_line
		(start 271.204944 -337.210654)
		(end 271.21485 -337.213956)
		(stroke
			(width 0.0635)
			(type default)
		)
		(layer "F.Cu")
	)
	(gr_line
		(start 271.354296 -333.610458)
		(end 271.364202 -333.61376)
		(stroke
			(width 0.0635)
			(type default)
		)
		(layer "F.Cu")
	)
	(gr_line
		(start 271.55775 -328.212958)
		(end 271.567656 -328.21626)
		(stroke
			(width 0.0635)
			(type default)
		)
		(layer "F.Cu")
	)
	(gr_line
		(start 271.9705 -359.504996)
		(end 272.26895 -359.504996)
		(stroke
			(width 0.0635)
			(type default)
		)
		(layer "F.Cu")
	)
	(gr_line
		(start 271.9705 -357.704898)
		(end 272.26895 -357.704898)
		(stroke
			(width 0.0635)
			(type default)
		)
		(layer "F.Cu")
	)
	(gr_line
		(start 271.9705 -355.905054)
		(end 272.26895 -355.905054)
		(stroke
			(width 0.0635)
			(type default)
		)
		(layer "F.Cu")
	)
	(gr_line
		(start 271.9705 -354.104956)
		(end 272.26895 -354.104956)
		(stroke
			(width 0.0635)
			(type default)
		)
		(layer "F.Cu")
	)
	(gr_line
		(start 271.9705 -352.305112)
		(end 272.26895 -352.305112)
		(stroke
			(width 0.0635)
			(type default)
		)
		(layer "F.Cu")
	)
	(gr_line
		(start 271.9705 -350.505014)
		(end 272.26895 -350.505014)
		(stroke
			(width 0.0635)
			(type default)
		)
		(layer "F.Cu")
	)
	(gr_line
		(start 271.9705 -337.90509)
		(end 272.26895 -337.90509)
		(stroke
			(width 0.0635)
			(type default)
		)
		(layer "F.Cu")
	)
	(gr_line
		(start 271.9705 -336.104992)
		(end 272.26895 -336.104992)
		(stroke
			(width 0.0635)
			(type default)
		)
		(layer "F.Cu")
	)
	(gr_line
		(start 271.9705 -334.304894)
		(end 272.26895 -334.304894)
		(stroke
			(width 0.0635)
			(type default)
		)
		(layer "F.Cu")
	)
	(gr_line
		(start 271.9705 -332.50505)
		(end 272.26895 -332.50505)
		(stroke
			(width 0.0635)
			(type default)
		)
		(layer "F.Cu")
	)
	(gr_line
		(start 271.9705 -330.704952)
		(end 272.26895 -330.704952)
		(stroke
			(width 0.0635)
			(type default)
		)
		(layer "F.Cu")
	)
	(gr_line
		(start 271.9705 -328.905108)
		(end 272.26895 -328.905108)
		(stroke
			(width 0.0635)
			(type default)
		)
		(layer "F.Cu")
	)
	(gr_line
		(start 271.9705 -316.30493)
		(end 272.26895 -316.30493)
		(stroke
			(width 0.0635)
			(type default)
		)
		(layer "F.Cu")
	)
	(gr_line
		(start 271.9705 -314.505086)
		(end 272.26895 -314.505086)
		(stroke
			(width 0.0635)
			(type default)
		)
		(layer "F.Cu")
	)
	(gr_line
		(start 271.9705 -312.704988)
		(end 272.26895 -312.704988)
		(stroke
			(width 0.0635)
			(type default)
		)
		(layer "F.Cu")
	)
	(gr_line
		(start 271.9705 -310.90489)
		(end 272.26895 -310.90489)
		(stroke
			(width 0.0635)
			(type default)
		)
		(layer "F.Cu")
	)
	(gr_line
		(start 271.9705 -309.105046)
		(end 272.26895 -309.105046)
		(stroke
			(width 0.0635)
			(type default)
		)
		(layer "F.Cu")
	)
	(gr_line
		(start 271.9705 -307.304948)
		(end 272.26895 -307.304948)
		(stroke
			(width 0.0635)
			(type default)
		)
		(layer "F.Cu")
	)
	(gr_arc
		(start 272.26895 -359.504996)
		(mid 272.358783 -359.467816)
		(end 272.39595 -359.377996)
		(stroke
			(width 0.0635)
			(type default)
		)
		(layer "F.Cu")
	)
	(gr_arc
		(start 272.26895 -357.704898)
		(mid 272.358784 -357.667718)
		(end 272.39595 -357.577898)
		(stroke
			(width 0.0635)
			(type default)
		)
		(layer "F.Cu")
	)
	(gr_arc
		(start 272.26895 -355.905054)
		(mid 272.358769 -355.867871)
		(end 272.39595 -355.778054)
		(stroke
			(width 0.0635)
			(type default)
		)
		(layer "F.Cu")
	)
	(gr_arc
		(start 272.26895 -354.104956)
		(mid 272.358769 -354.067774)
		(end 272.39595 -353.977956)
		(stroke
			(width 0.0635)
			(type default)
		)
		(layer "F.Cu")
	)
	(gr_arc
		(start 272.26895 -352.305112)
		(mid 272.358789 -352.267933)
		(end 272.39595 -352.178112)
		(stroke
			(width 0.0635)
			(type default)
		)
		(layer "F.Cu")
	)
	(gr_arc
		(start 272.26895 -350.505014)
		(mid 272.35879 -350.467835)
		(end 272.39595 -350.378014)
		(stroke
			(width 0.0635)
			(type default)
		)
		(layer "F.Cu")
	)
	(gr_arc
		(start 272.26895 -337.90509)
		(mid 272.358781 -337.86791)
		(end 272.39595 -337.77809)
		(stroke
			(width 0.0635)
			(type default)
		)
		(layer "F.Cu")
	)
	(gr_arc
		(start 272.26895 -336.104992)
		(mid 272.358782 -336.067812)
		(end 272.39595 -335.977992)
		(stroke
			(width 0.0635)
			(type default)
		)
		(layer "F.Cu")
	)
	(gr_arc
		(start 272.26895 -334.304894)
		(mid 272.358753 -334.267697)
		(end 272.39595 -334.177894)
		(stroke
			(width 0.0635)
			(type default)
		)
		(layer "F.Cu")
	)
	(gr_arc
		(start 272.26895 -332.50505)
		(mid 272.358767 -332.467867)
		(end 272.39595 -332.37805)
		(stroke
			(width 0.0635)
			(type default)
		)
		(layer "F.Cu")
	)
	(gr_arc
		(start 272.26895 -330.704952)
		(mid 272.358768 -330.667769)
		(end 272.39595 -330.577952)
		(stroke
			(width 0.0635)
			(type default)
		)
		(layer "F.Cu")
	)
	(gr_arc
		(start 272.26895 -328.905108)
		(mid 272.358788 -328.867929)
		(end 272.39595 -328.778108)
		(stroke
			(width 0.0635)
			(type default)
		)
		(layer "F.Cu")
	)
	(gr_arc
		(start 272.26895 -316.30493)
		(mid 272.358795 -316.267752)
		(end 272.39595 -316.17793)
		(stroke
			(width 0.0635)
			(type default)
		)
		(layer "F.Cu")
	)
	(gr_arc
		(start 272.26895 -314.505086)
		(mid 272.358753 -314.467889)
		(end 272.39595 -314.378086)
		(stroke
			(width 0.0635)
			(type default)
		)
		(layer "F.Cu")
	)
	(gr_arc
		(start 272.26895 -312.704988)
		(mid 272.358753 -312.667791)
		(end 272.39595 -312.577988)
		(stroke
			(width 0.0635)
			(type default)
		)
		(layer "F.Cu")
	)
	(gr_arc
		(start 272.26895 -310.90489)
		(mid 272.358753 -310.867693)
		(end 272.39595 -310.77789)
		(stroke
			(width 0.0635)
			(type default)
		)
		(layer "F.Cu")
	)
	(gr_arc
		(start 272.26895 -309.105046)
		(mid 272.358753 -309.067849)
		(end 272.39595 -308.978046)
		(stroke
			(width 0.0635)
			(type default)
		)
		(layer "F.Cu")
	)
	(gr_arc
		(start 272.26895 -307.304948)
		(mid 272.358753 -307.267751)
		(end 272.39595 -307.177948)
		(stroke
			(width 0.0635)
			(type default)
		)
		(layer "F.Cu")
	)
	(gr_line
		(start 272.321528 -17.873472)
		(end 272.837148 -17.357852)
		(stroke
			(width 0.08255)
			(type default)
		)
		(layer "F.Cu")
	)
	(gr_line
		(start 272.321528 -16.425672)
		(end 272.837148 -16.941292)
		(stroke
			(width 0.08255)
			(type default)
		)
		(layer "F.Cu")
	)
	(gr_arc
		(start 272.68805 -359.377996)
		(mid 272.725247 -359.467799)
		(end 272.81505 -359.504996)
		(stroke
			(width 0.0635)
			(type default)
		)
		(layer "F.Cu")
	)
	(gr_arc
		(start 272.68805 -357.577898)
		(mid 272.725247 -357.667701)
		(end 272.81505 -357.704898)
		(stroke
			(width 0.0635)
			(type default)
		)
		(layer "F.Cu")
	)
	(gr_arc
		(start 272.68805 -355.778054)
		(mid 272.725247 -355.867857)
		(end 272.81505 -355.905054)
		(stroke
			(width 0.0635)
			(type default)
		)
		(layer "F.Cu")
	)
	(gr_arc
		(start 272.68805 -353.977956)
		(mid 272.725247 -354.067759)
		(end 272.81505 -354.104956)
		(stroke
			(width 0.0635)
			(type default)
		)
		(layer "F.Cu")
	)
	(gr_arc
		(start 272.68805 -352.178112)
		(mid 272.725247 -352.267915)
		(end 272.81505 -352.305112)
		(stroke
			(width 0.0635)
			(type default)
		)
		(layer "F.Cu")
	)
	(gr_arc
		(start 272.68805 -350.378014)
		(mid 272.725247 -350.467817)
		(end 272.81505 -350.505014)
		(stroke
			(width 0.0635)
			(type default)
		)
		(layer "F.Cu")
	)
	(gr_arc
		(start 272.68805 -337.77809)
		(mid 272.725247 -337.867893)
		(end 272.81505 -337.90509)
		(stroke
			(width 0.0635)
			(type default)
		)
		(layer "F.Cu")
	)
	(gr_arc
		(start 272.68805 -335.977992)
		(mid 272.725247 -336.067795)
		(end 272.81505 -336.104992)
		(stroke
			(width 0.0635)
			(type default)
		)
		(layer "F.Cu")
	)
	(gr_arc
		(start 272.68805 -334.177894)
		(mid 272.725248 -334.267683)
		(end 272.81505 -334.304894)
		(stroke
			(width 0.0635)
			(type default)
		)
		(layer "F.Cu")
	)
	(gr_arc
		(start 272.68805 -332.37805)
		(mid 272.725247 -332.467853)
		(end 272.81505 -332.50505)
		(stroke
			(width 0.0635)
			(type default)
		)
		(layer "F.Cu")
	)
	(gr_arc
		(start 272.68805 -330.577952)
		(mid 272.725247 -330.667755)
		(end 272.81505 -330.704952)
		(stroke
			(width 0.0635)
			(type default)
		)
		(layer "F.Cu")
	)
	(gr_arc
		(start 272.68805 -328.778108)
		(mid 272.725247 -328.867911)
		(end 272.81505 -328.905108)
		(stroke
			(width 0.0635)
			(type default)
		)
		(layer "F.Cu")
	)
	(gr_arc
		(start 272.68805 -316.17793)
		(mid 272.725247 -316.267733)
		(end 272.81505 -316.30493)
		(stroke
			(width 0.0635)
			(type default)
		)
		(layer "F.Cu")
	)
	(gr_arc
		(start 272.68805 -314.378086)
		(mid 272.725246 -314.46788)
		(end 272.81505 -314.505086)
		(stroke
			(width 0.0635)
			(type default)
		)
		(layer "F.Cu")
	)
	(gr_arc
		(start 272.68805 -312.577988)
		(mid 272.725246 -312.667781)
		(end 272.81505 -312.704988)
		(stroke
			(width 0.0635)
			(type default)
		)
		(layer "F.Cu")
	)
	(gr_arc
		(start 272.68805 -310.77789)
		(mid 272.725247 -310.867681)
		(end 272.81505 -310.90489)
		(stroke
			(width 0.0635)
			(type default)
		)
		(layer "F.Cu")
	)
	(gr_arc
		(start 272.68805 -308.978046)
		(mid 272.725267 -309.067801)
		(end 272.81505 -309.105046)
		(stroke
			(width 0.0635)
			(type default)
		)
		(layer "F.Cu")
	)
	(gr_arc
		(start 272.68805 -307.177948)
		(mid 272.725267 -307.267702)
		(end 272.81505 -307.304948)
		(stroke
			(width 0.0635)
			(type default)
		)
		(layer "F.Cu")
	)
	(gr_line
		(start 272.81505 -359.504996)
		(end 273.1135 -359.504996)
		(stroke
			(width 0.0635)
			(type default)
		)
		(layer "F.Cu")
	)
	(gr_line
		(start 272.81505 -357.704898)
		(end 273.1135 -357.704898)
		(stroke
			(width 0.0635)
			(type default)
		)
		(layer "F.Cu")
	)
	(gr_line
		(start 272.81505 -355.905054)
		(end 273.1135 -355.905054)
		(stroke
			(width 0.0635)
			(type default)
		)
		(layer "F.Cu")
	)
	(gr_line
		(start 272.81505 -354.104956)
		(end 273.1135 -354.104956)
		(stroke
			(width 0.0635)
			(type default)
		)
		(layer "F.Cu")
	)
	(gr_line
		(start 272.81505 -352.305112)
		(end 273.1135 -352.305112)
		(stroke
			(width 0.0635)
			(type default)
		)
		(layer "F.Cu")
	)
	(gr_line
		(start 272.81505 -350.505014)
		(end 273.1135 -350.505014)
		(stroke
			(width 0.0635)
			(type default)
		)
		(layer "F.Cu")
	)
	(gr_line
		(start 272.81505 -337.90509)
		(end 273.1135 -337.90509)
		(stroke
			(width 0.0635)
			(type default)
		)
		(layer "F.Cu")
	)
	(gr_line
		(start 272.81505 -336.104992)
		(end 273.1135 -336.104992)
		(stroke
			(width 0.0635)
			(type default)
		)
		(layer "F.Cu")
	)
	(gr_line
		(start 272.81505 -334.304894)
		(end 273.1135 -334.304894)
		(stroke
			(width 0.0635)
			(type default)
		)
		(layer "F.Cu")
	)
	(gr_line
		(start 272.81505 -332.50505)
		(end 273.1135 -332.50505)
		(stroke
			(width 0.0635)
			(type default)
		)
		(layer "F.Cu")
	)
	(gr_line
		(start 272.81505 -330.704952)
		(end 273.1135 -330.704952)
		(stroke
			(width 0.0635)
			(type default)
		)
		(layer "F.Cu")
	)
	(gr_line
		(start 272.81505 -328.905108)
		(end 273.1135 -328.905108)
		(stroke
			(width 0.0635)
			(type default)
		)
		(layer "F.Cu")
	)
	(gr_line
		(start 272.81505 -316.30493)
		(end 273.1135 -316.30493)
		(stroke
			(width 0.0635)
			(type default)
		)
		(layer "F.Cu")
	)
	(gr_line
		(start 272.81505 -314.505086)
		(end 273.1135 -314.505086)
		(stroke
			(width 0.0635)
			(type default)
		)
		(layer "F.Cu")
	)
	(gr_line
		(start 272.81505 -312.704988)
		(end 273.1135 -312.704988)
		(stroke
			(width 0.0635)
			(type default)
		)
		(layer "F.Cu")
	)
	(gr_line
		(start 272.81505 -310.90489)
		(end 273.1135 -310.90489)
		(stroke
			(width 0.0635)
			(type default)
		)
		(layer "F.Cu")
	)
	(gr_line
		(start 272.81505 -309.105046)
		(end 273.1135 -309.105046)
		(stroke
			(width 0.0635)
			(type default)
		)
		(layer "F.Cu")
	)
	(gr_line
		(start 272.81505 -307.304948)
		(end 273.1135 -307.304948)
		(stroke
			(width 0.0635)
			(type default)
		)
		(layer "F.Cu")
	)
	(gr_line
		(start 276.037294 -262.921242)
		(end 276.077934 -262.948166)
		(stroke
			(width 0.08255)
			(type default)
		)
		(layer "F.Cu")
	)
	(gr_line
		(start 278.750014 -138.49985)
		(end 279.471374 -138.138916)
		(stroke
			(width 0.08255)
			(type default)
		)
		(layer "F.Cu")
	)
	(gr_line
		(start 278.750014 -18.200116)
		(end 279.471882 -17.838928)
		(stroke
			(width 0.08255)
			(type default)
		)
		(layer "F.Cu")
	)
	(gr_arc
		(start 279.471882 -17.838928)
		(mid 279.554571 -17.743445)
		(end 279.545542 -17.61744)
		(stroke
			(width 0.08255)
			(type default)
		)
		(layer "F.Cu")
	)
	(gr_line
		(start 279.662382 -138.177778)
		(end 279.695148 -138.22299)
		(stroke
			(width 0.08255)
			(type default)
		)
		(layer "F.Cu")
	)
	(gr_arc
		(start 279.662382 -138.170412)
		(mid 279.571973 -138.123644)
		(end 279.471374 -138.138916)
		(stroke
			(width 0.08255)
			(type default)
		)
		(layer "F.Cu")
	)
	(gr_line
		(start 279.804368 -17.476216)
		(end 279.837642 -17.52219)
		(stroke
			(width 0.08255)
			(type default)
		)
		(layer "F.Cu")
	)
	(gr_arc
		(start 279.837642 -17.529556)
		(mid 279.928051 -17.576324)
		(end 280.02865 -17.561052)
		(stroke
			(width 0.08255)
			(type default)
		)
		(layer "F.Cu")
	)
	(gr_arc
		(start 280.028142 -137.86104)
		(mid 279.945471 -137.95653)
		(end 279.954482 -138.082528)
		(stroke
			(width 0.08255)
			(type default)
		)
		(layer "F.Cu")
	)
	(gr_line
		(start 280.028142 -137.86104)
		(end 280.75001 -137.499852)
		(stroke
			(width 0.08255)
			(type default)
		)
		(layer "F.Cu")
	)
	(gr_line
		(start 280.02865 -17.561052)
		(end 280.75001 -17.200118)
		(stroke
			(width 0.08255)
			(type default)
		)
		(layer "F.Cu")
	)
	(gr_line
		(start 282.83662 -263.702292)
		(end 283.263594 -263.702292)
		(stroke
			(width 0.08255)
			(type default)
		)
		(layer "F.Cu")
	)
	(gr_line
		(start 283.249878 -135.499856)
		(end 283.971238 -135.86079)
		(stroke
			(width 0.08255)
			(type default)
		)
		(layer "F.Cu")
	)
	(gr_line
		(start 283.249878 -107.499912)
		(end 283.971238 -107.860846)
		(stroke
			(width 0.08255)
			(type default)
		)
		(layer "F.Cu")
	)
	(gr_arc
		(start 283.263594 -263.702292)
		(mid 283.353397 -263.665095)
		(end 283.390594 -263.575292)
		(stroke
			(width 0.08255)
			(type default)
		)
		(layer "F.Cu")
	)
	(gr_arc
		(start 283.682694 -263.575292)
		(mid 283.719888 -263.665102)
		(end 283.809694 -263.702292)
		(stroke
			(width 0.08255)
			(type default)
		)
		(layer "F.Cu")
	)
	(gr_line
		(start 283.809694 -263.702292)
		(end 284.236668 -263.702292)
		(stroke
			(width 0.08255)
			(type default)
		)
		(layer "F.Cu")
	)
	(gr_arc
		(start 283.971238 -135.86079)
		(mid 284.071817 -135.875941)
		(end 284.162246 -135.829294)
		(stroke
			(width 0.08255)
			(type default)
		)
		(layer "F.Cu")
	)
	(gr_arc
		(start 283.971238 -107.860846)
		(mid 284.071869 -107.876144)
		(end 284.162246 -107.82935)
		(stroke
			(width 0.08255)
			(type default)
		)
		(layer "F.Cu")
	)
	(gr_line
		(start 284.162246 -135.821928)
		(end 284.195266 -135.776462)
		(stroke
			(width 0.08255)
			(type default)
		)
		(layer "F.Cu")
	)
	(gr_line
		(start 284.162246 -107.821984)
		(end 284.19552 -107.77601)
		(stroke
			(width 0.08255)
			(type default)
		)
		(layer "F.Cu")
	)
	(gr_arc
		(start 284.454346 -135.917178)
		(mid 284.445298 -136.04318)
		(end 284.528006 -136.138666)
		(stroke
			(width 0.08255)
			(type default)
		)
		(layer "F.Cu")
	)
	(gr_arc
		(start 284.454346 -107.917234)
		(mid 284.445304 -108.043233)
		(end 284.528006 -108.138722)
		(stroke
			(width 0.08255)
			(type default)
		)
		(layer "F.Cu")
	)
	(gr_line
		(start 284.528006 -136.138666)
		(end 285.249874 -136.499854)
		(stroke
			(width 0.08255)
			(type default)
		)
		(layer "F.Cu")
	)
	(gr_line
		(start 284.528006 -108.138722)
		(end 285.249874 -108.49991)
		(stroke
			(width 0.08255)
			(type default)
		)
		(layer "F.Cu")
	)
	(gr_line
		(start 285.803848 -107.645962)
		(end 285.847536 -107.615736)
		(stroke
			(width 0.08255)
			(type default)
		)
		(layer "F.Cu")
	)
	(gr_line
		(start 286.295338 -137.645902)
		(end 286.339026 -137.615676)
		(stroke
			(width 0.08255)
			(type default)
		)
		(layer "F.Cu")
	)
	(gr_line
		(start 288.008568 -136.458452)
		(end 288.018982 -136.451086)
		(stroke
			(width 0.08255)
			(type default)
		)
		(layer "F.Cu")
	)
	(gr_line
		(start 288.018982 -136.451086)
		(end 288.026602 -136.440672)
		(stroke
			(width 0.08255)
			(type default)
		)
		(layer "F.Cu")
	)
	(gr_line
		(start 288.078672 -135.692642)
		(end 288.101532 -135.834882)
		(stroke
			(width 0.08255)
			(type default)
		)
		(layer "F.Cu")
	)
	(gr_line
		(start 288.078672 -135.692642)
		(end 288.369248 -135.291576)
		(stroke
			(width 0.08255)
			(type default)
		)
		(layer "F.Cu")
	)
	(gr_line
		(start 288.361374 -135.978138)
		(end 288.729674 -135.46963)
		(stroke
			(width 0.08255)
			(type default)
		)
		(layer "F.Cu")
	)
	(gr_line
		(start 288.369248 -135.291576)
		(end 288.511234 -135.268716)
		(stroke
			(width 0.08255)
			(type default)
		)
		(layer "F.Cu")
	)
	(gr_line
		(start 288.781744 -134.7216)
		(end 288.804604 -134.86384)
		(stroke
			(width 0.08255)
			(type default)
		)
		(layer "F.Cu")
	)
	(gr_line
		(start 288.781744 -134.7216)
		(end 289.07232 -134.320534)
		(stroke
			(width 0.08255)
			(type default)
		)
		(layer "F.Cu")
	)
	(gr_line
		(start 289.064446 -135.007096)
		(end 289.431984 -134.499604)
		(stroke
			(width 0.08255)
			(type default)
		)
		(layer "F.Cu")
	)
	(gr_line
		(start 289.07232 -134.320534)
		(end 289.21456 -134.297674)
		(stroke
			(width 0.08255)
			(type default)
		)
		(layer "F.Cu")
	)
	(gr_line
		(start 289.370516 -105.17378)
		(end 289.37966 -105.16743)
		(stroke
			(width 0.08255)
			(type default)
		)
		(layer "F.Cu")
	)
	(gr_line
		(start 289.37966 -105.16743)
		(end 289.386518 -105.158032)
		(stroke
			(width 0.08255)
			(type default)
		)
		(layer "F.Cu")
	)
	(gr_line
		(start 289.48507 -133.750558)
		(end 289.507676 -133.892798)
		(stroke
			(width 0.08255)
			(type default)
		)
		(layer "F.Cu")
	)
	(gr_line
		(start 289.48507 -133.750558)
		(end 289.775392 -133.349492)
		(stroke
			(width 0.08255)
			(type default)
		)
		(layer "F.Cu")
	)
	(gr_line
		(start 289.767264 -134.036562)
		(end 290.134802 -133.528816)
		(stroke
			(width 0.08255)
			(type default)
		)
		(layer "F.Cu")
	)
	(gr_line
		(start 289.775392 -133.349492)
		(end 289.917632 -133.326632)
		(stroke
			(width 0.08255)
			(type default)
		)
		(layer "F.Cu")
	)
	(gr_line
		(start 290.188142 -132.779516)
		(end 290.211002 -132.921502)
		(stroke
			(width 0.08255)
			(type default)
		)
		(layer "F.Cu")
	)
	(gr_line
		(start 290.188142 -132.779516)
		(end 290.478718 -132.37845)
		(stroke
			(width 0.08255)
			(type default)
		)
		(layer "F.Cu")
	)
	(gr_line
		(start 290.471098 -133.06425)
		(end 290.837874 -132.557774)
		(stroke
			(width 0.08255)
			(type default)
		)
		(layer "F.Cu")
	)
	(gr_line
		(start 290.478718 -132.37845)
		(end 290.620704 -132.35559)
		(stroke
			(width 0.08255)
			(type default)
		)
		(layer "F.Cu")
	)
	(gr_line
		(start 291.648388 -101.535738)
		(end 292.029642 -101.009196)
		(stroke
			(width 0.08255)
			(type default)
		)
		(layer "F.Cu")
	)
	(gr_line
		(start 291.866574 -101.736906)
		(end 292.023038 -101.71176)
		(stroke
			(width 0.08255)
			(type default)
		)
		(layer "F.Cu")
	)
	(gr_line
		(start 292.023038 -101.71176)
		(end 292.31336 -101.310694)
		(stroke
			(width 0.08255)
			(type default)
		)
		(layer "F.Cu")
	)
	(gr_line
		(start 292.288468 -101.15423)
		(end 292.31336 -101.310694)
		(stroke
			(width 0.08255)
			(type default)
		)
		(layer "F.Cu")
	)
	(gr_line
		(start 292.363398 -100.54844)
		(end 292.74389 -100.022914)
		(stroke
			(width 0.08255)
			(type default)
		)
		(layer "F.Cu")
	)
	(gr_line
		(start 292.581838 -100.749354)
		(end 292.738048 -100.724208)
		(stroke
			(width 0.08255)
			(type default)
		)
		(layer "F.Cu")
	)
	(gr_line
		(start 292.738048 -100.724208)
		(end 293.02837 -100.323142)
		(stroke
			(width 0.08255)
			(type default)
		)
		(layer "F.Cu")
	)
	(gr_line
		(start 293.003478 -100.166678)
		(end 293.02837 -100.323142)
		(stroke
			(width 0.08255)
			(type default)
		)
		(layer "F.Cu")
	)
	(gr_line
		(start 293.078662 -99.56038)
		(end 293.459408 -99.034346)
		(stroke
			(width 0.08255)
			(type default)
		)
		(layer "F.Cu")
	)
	(gr_line
		(start 293.296848 -99.761802)
		(end 293.453058 -99.736656)
		(stroke
			(width 0.08255)
			(type default)
		)
		(layer "F.Cu")
	)
	(gr_line
		(start 293.453058 -99.736656)
		(end 293.74338 -99.33559)
		(stroke
			(width 0.08255)
			(type default)
		)
		(layer "F.Cu")
	)
	(gr_line
		(start 293.718488 -99.179126)
		(end 293.74338 -99.33559)
		(stroke
			(width 0.08255)
			(type default)
		)
		(layer "F.Cu")
	)
	(gr_line
		(start 293.793164 -98.573336)
		(end 294.175434 -98.04527)
		(stroke
			(width 0.08255)
			(type default)
		)
		(layer "F.Cu")
	)
	(gr_line
		(start 294.011858 -98.77425)
		(end 294.168068 -98.749104)
		(stroke
			(width 0.08255)
			(type default)
		)
		(layer "F.Cu")
	)
	(gr_line
		(start 294.168068 -98.749104)
		(end 294.45839 -98.348038)
		(stroke
			(width 0.08255)
			(type default)
		)
		(layer "F.Cu")
	)
	(gr_line
		(start 294.433498 -98.191828)
		(end 294.45839 -98.348038)
		(stroke
			(width 0.08255)
			(type default)
		)
		(layer "F.Cu")
	)
	(gr_line
		(start 297.843956 -122.88266)
		(end 297.85691 -122.864626)
		(stroke
			(width 0.08255)
			(type default)
		)
		(layer "F.Cu")
	)
	(gr_line
		(start 297.85691 -122.864626)
		(end 297.857418 -122.863356)
		(stroke
			(width 0.08255)
			(type default)
		)
		(layer "F.Cu")
	)
	(gr_line
		(start 297.857164 -122.863102)
		(end 297.857672 -122.863356)
		(stroke
			(width 0.08255)
			(type default)
		)
		(layer "F.Cu")
	)
	(gr_line
		(start 297.857164 -122.863102)
		(end 297.861228 -122.844306)
		(stroke
			(width 0.08255)
			(type default)
		)
		(layer "F.Cu")
	)
	(gr_line
		(start 297.857418 -122.863356)
		(end 297.857672 -122.863356)
		(stroke
			(width 0.08255)
			(type default)
		)
		(layer "F.Cu")
	)
	(gr_line
		(start 304.25009 -63.721234)
		(end 304.254408 -63.74384)
		(stroke
			(width 0.08255)
			(type default)
		)
		(layer "F.Cu")
	)
	(gr_line
		(start 304.25009 -63.721234)
		(end 304.25517 -63.698628)
		(stroke
			(width 0.08255)
			(type default)
		)
		(layer "F.Cu")
	)
	(gr_line
		(start 304.25517 -63.698374)
		(end 304.25517 -63.698628)
		(stroke
			(width 0.08255)
			(type default)
		)
		(layer "F.Cu")
	)
	(gr_line
		(start 305.14163 -83.398614)
		(end 305.154584 -83.38058)
		(stroke
			(width 0.08255)
			(type default)
		)
		(layer "F.Cu")
	)
	(gr_line
		(start 305.154584 -83.38058)
		(end 305.15941 -83.359498)
		(stroke
			(width 0.08255)
			(type default)
		)
		(layer "F.Cu")
	)
	(gr_line
		(start 305.916838 -64.007746)
		(end 305.921156 -64.030352)
		(stroke
			(width 0.08255)
			(type default)
		)
		(layer "F.Cu")
	)
	(gr_line
		(start 305.916838 -64.007746)
		(end 305.921918 -63.98514)
		(stroke
			(width 0.08255)
			(type default)
		)
		(layer "F.Cu")
	)
	(gr_line
		(start 305.921918 -63.984886)
		(end 305.921918 -63.98514)
		(stroke
			(width 0.08255)
			(type default)
		)
		(layer "F.Cu")
	)
	(gr_line
		(start 306.853336 -52.233576)
		(end 306.856384 -52.220622)
		(stroke
			(width 0.08255)
			(type default)
		)
		(layer "F.Cu")
	)
	(gr_line
		(start 306.856384 -52.220622)
		(end 306.863496 -52.209446)
		(stroke
			(width 0.08255)
			(type default)
		)
		(layer "F.Cu")
	)
	(gr_line
		(start 306.859432 -75.855576)
		(end 306.864512 -75.83297)
		(stroke
			(width 0.08255)
			(type default)
		)
		(layer "F.Cu")
	)
	(gr_line
		(start 306.860194 -75.81011)
		(end 306.864512 -75.83297)
		(stroke
			(width 0.08255)
			(type default)
		)
		(layer "F.Cu")
	)
	(gr_line
		(start 308.459124 -52.791106)
		(end 308.462172 -52.777644)
		(stroke
			(width 0.08255)
			(type default)
		)
		(layer "F.Cu")
	)
	(gr_line
		(start 308.462172 -52.777644)
		(end 308.469538 -52.76596)
		(stroke
			(width 0.08255)
			(type default)
		)
		(layer "F.Cu")
	)
	(gr_line
		(start 308.48808 -75.942698)
		(end 308.49316 -75.920092)
		(stroke
			(width 0.08255)
			(type default)
		)
		(layer "F.Cu")
	)
	(gr_line
		(start 308.488842 -75.897232)
		(end 308.49316 -75.920092)
		(stroke
			(width 0.08255)
			(type default)
		)
		(layer "F.Cu")
	)
	(gr_line
		(start 318.514984 -33.909254)
		(end 318.532256 -33.88233)
		(stroke
			(width 0.08255)
			(type default)
		)
		(layer "F.Cu")
	)
	(gr_line
		(start 318.532256 -33.88233)
		(end 318.559942 -33.866074)
		(stroke
			(width 0.08255)
			(type default)
		)
		(layer "F.Cu")
	)
	(gr_line
		(start 319.2145 -42.627042)
		(end 319.41516 -42.627042)
		(stroke
			(width 0.0635)
			(type default)
		)
		(layer "F.Cu")
	)
	(gr_line
		(start 319.61836 -35.265614)
		(end 319.6336 -35.241738)
		(stroke
			(width 0.08255)
			(type default)
		)
		(layer "F.Cu")
	)
	(gr_line
		(start 319.6336 -35.241738)
		(end 319.65773 -35.226498)
		(stroke
			(width 0.08255)
			(type default)
		)
		(layer "F.Cu")
	)
	(gr_arc
		(start 319.63995 -42.851832)
		(mid 319.574111 -42.692881)
		(end 319.41516 -42.627042)
		(stroke
			(width 0.0635)
			(type default)
		)
		(layer "F.Cu")
	)
	(gr_line
		(start 319.9892 -274.230338)
		(end 319.9892 -274.511516)
		(stroke
			(width 0.0635)
			(type default)
		)
		(layer "F.Cu")
	)
	(gr_arc
		(start 319.9892 -273.649948)
		(mid 319.998833 -273.698466)
		(end 320.026284 -273.73961)
		(stroke
			(width 0.0635)
			(type default)
		)
		(layer "F.Cu")
	)
	(gr_line
		(start 319.9892 -273.368516)
		(end 319.9892 -273.649948)
		(stroke
			(width 0.0635)
			(type default)
		)
		(layer "F.Cu")
	)
	(gr_line
		(start 319.9892 -159.213296)
		(end 319.9892 -159.511492)
		(stroke
			(width 0.0635)
			(type default)
		)
		(layer "F.Cu")
	)
	(gr_line
		(start 319.9892 -159.213296)
		(end 320.054224 -159.148272)
		(stroke
			(width 0.0635)
			(type default)
		)
		(layer "F.Cu")
	)
	(gr_line
		(start 319.9892 -158.666688)
		(end 320.054224 -158.731712)
		(stroke
			(width 0.0635)
			(type default)
		)
		(layer "F.Cu")
	)
	(gr_line
		(start 319.9892 -158.368492)
		(end 319.9892 -158.666688)
		(stroke
			(width 0.0635)
			(type default)
		)
		(layer "F.Cu")
	)
	(gr_arc
		(start 320.026284 -274.140676)
		(mid 319.998842 -274.181824)
		(end 319.9892 -274.230338)
		(stroke
			(width 0.0635)
			(type default)
		)
		(layer "F.Cu")
	)
	(gr_line
		(start 320.026284 -274.140676)
		(end 320.04381 -274.12315)
		(stroke
			(width 0.0635)
			(type default)
		)
		(layer "F.Cu")
	)
	(gr_line
		(start 320.026284 -273.73961)
		(end 320.043556 -273.756882)
		(stroke
			(width 0.0635)
			(type default)
		)
		(layer "F.Cu")
	)
	(gr_arc
		(start 320.043556 -273.756882)
		(mid 320.084707 -273.784315)
		(end 320.133218 -273.793966)
		(stroke
			(width 0.0635)
			(type default)
		)
		(layer "F.Cu")
	)
	(gr_arc
		(start 320.133472 -274.086066)
		(mid 320.084953 -274.0957)
		(end 320.04381 -274.12315)
		(stroke
			(width 0.0635)
			(type default)
		)
		(layer "F.Cu")
	)
	(gr_arc
		(start 320.15684 -42.627042)
		(mid 319.997875 -42.692869)
		(end 319.93205 -42.851832)
		(stroke
			(width 0.0635)
			(type default)
		)
		(layer "F.Cu")
	)
	(gr_line
		(start 320.15684 -42.627042)
		(end 320.3575 -42.627042)
		(stroke
			(width 0.0635)
			(type default)
		)
		(layer "F.Cu")
	)
	(gr_line
		(start 320.952876 -274.148296)
		(end 321.023996 -274.219416)
		(stroke
			(width 0.0635)
			(type default)
		)
		(layer "F.Cu")
	)
	(gr_line
		(start 320.952876 -273.731736)
		(end 321.023996 -273.660616)
		(stroke
			(width 0.0635)
			(type default)
		)
		(layer "F.Cu")
	)
	(gr_line
		(start 320.952876 -159.148272)
		(end 321.023996 -159.219392)
		(stroke
			(width 0.0635)
			(type default)
		)
		(layer "F.Cu")
	)
	(gr_line
		(start 320.952876 -158.731712)
		(end 321.023996 -158.660592)
		(stroke
			(width 0.0635)
			(type default)
		)
		(layer "F.Cu")
	)
	(gr_line
		(start 321.023996 -274.219416)
		(end 321.355212 -274.219416)
		(stroke
			(width 0.0635)
			(type default)
		)
		(layer "F.Cu")
	)
	(gr_line
		(start 321.023996 -273.660616)
		(end 321.355212 -273.660616)
		(stroke
			(width 0.0635)
			(type default)
		)
		(layer "F.Cu")
	)
	(gr_line
		(start 321.023996 -159.219392)
		(end 321.355212 -159.219392)
		(stroke
			(width 0.0635)
			(type default)
		)
		(layer "F.Cu")
	)
	(gr_line
		(start 321.023996 -158.660592)
		(end 321.355212 -158.660592)
		(stroke
			(width 0.0635)
			(type default)
		)
		(layer "F.Cu")
	)
	(gr_line
		(start 321.089528 -44.115736)
		(end 321.19316 -44.219368)
		(stroke
			(width 0.0635)
			(type default)
		)
		(layer "F.Cu")
	)
	(gr_line
		(start 321.089528 -43.698922)
		(end 321.127882 -43.660568)
		(stroke
			(width 0.0635)
			(type default)
		)
		(layer "F.Cu")
	)
	(gr_line
		(start 321.127882 -43.660568)
		(end 321.355212 -43.660568)
		(stroke
			(width 0.0635)
			(type default)
		)
		(layer "F.Cu")
	)
	(gr_line
		(start 321.19316 -44.219368)
		(end 321.355212 -44.219368)
		(stroke
			(width 0.0635)
			(type default)
		)
		(layer "F.Cu")
	)
	(gr_line
		(start 321.618864 -32.074866)
		(end 321.653662 -32.054546)
		(stroke
			(width 0.08255)
			(type default)
		)
		(layer "F.Cu")
	)
	(gr_line
		(start 321.914012 -274.219416)
		(end 322.448428 -274.219416)
		(stroke
			(width 0.0635)
			(type default)
		)
		(layer "F.Cu")
	)
	(gr_line
		(start 321.914012 -273.660616)
		(end 322.448428 -273.660616)
		(stroke
			(width 0.0635)
			(type default)
		)
		(layer "F.Cu")
	)
	(gr_line
		(start 321.914012 -159.219392)
		(end 322.372228 -159.219392)
		(stroke
			(width 0.0635)
			(type default)
		)
		(layer "F.Cu")
	)
	(gr_line
		(start 321.914012 -158.660592)
		(end 322.372228 -158.660592)
		(stroke
			(width 0.0635)
			(type default)
		)
		(layer "F.Cu")
	)
	(gr_line
		(start 321.914012 -44.219368)
		(end 322.397628 -44.219368)
		(stroke
			(width 0.0635)
			(type default)
		)
		(layer "F.Cu")
	)
	(gr_line
		(start 321.914012 -43.660568)
		(end 322.397628 -43.660568)
		(stroke
			(width 0.0635)
			(type default)
		)
		(layer "F.Cu")
	)
	(gr_line
		(start 322.117974 -33.683448)
		(end 322.156582 -33.659318)
		(stroke
			(width 0.08255)
			(type default)
		)
		(layer "F.Cu")
	)
	(gr_line
		(start 322.372228 -159.219392)
		(end 322.443348 -159.148272)
		(stroke
			(width 0.0635)
			(type default)
		)
		(layer "F.Cu")
	)
	(gr_line
		(start 322.372228 -158.660592)
		(end 322.443348 -158.731712)
		(stroke
			(width 0.0635)
			(type default)
		)
		(layer "F.Cu")
	)
	(gr_line
		(start 322.397628 -44.219368)
		(end 322.468748 -44.148248)
		(stroke
			(width 0.0635)
			(type default)
		)
		(layer "F.Cu")
	)
	(gr_line
		(start 322.397628 -43.660568)
		(end 322.468748 -43.731688)
		(stroke
			(width 0.0635)
			(type default)
		)
		(layer "F.Cu")
	)
	(gr_line
		(start 322.448428 -274.219416)
		(end 322.519548 -274.148296)
		(stroke
			(width 0.0635)
			(type default)
		)
		(layer "F.Cu")
	)
	(gr_line
		(start 322.448428 -273.660616)
		(end 322.519548 -273.731736)
		(stroke
			(width 0.0635)
			(type default)
		)
		(layer "F.Cu")
	)
	(gr_line
		(start 322.6816 -46.437042)
		(end 322.860924 -46.437042)
		(stroke
			(width 0.0635)
			(type default)
		)
		(layer "F.Cu")
	)
	(gr_arc
		(start 323.10705 -46.683168)
		(mid 323.034952 -46.509143)
		(end 322.860924 -46.437042)
		(stroke
			(width 0.0635)
			(type default)
		)
		(layer "F.Cu")
	)
	(gr_arc
		(start 323.645276 -46.437042)
		(mid 323.471239 -46.509131)
		(end 323.39915 -46.683168)
		(stroke
			(width 0.0635)
			(type default)
		)
		(layer "F.Cu")
	)
	(gr_line
		(start 323.645276 -46.437042)
		(end 323.8246 -46.437042)
		(stroke
			(width 0.0635)
			(type default)
		)
		(layer "F.Cu")
	)
	(gr_line
		(start 324.739 -278.02332)
		(end 324.739 -278.321516)
		(stroke
			(width 0.0635)
			(type default)
		)
		(layer "F.Cu")
	)
	(gr_arc
		(start 324.739 -277.476712)
		(mid 324.776272 -277.566694)
		(end 324.866254 -277.603966)
		(stroke
			(width 0.0635)
			(type default)
		)
		(layer "F.Cu")
	)
	(gr_line
		(start 324.739 -277.178516)
		(end 324.739 -277.476712)
		(stroke
			(width 0.0635)
			(type default)
		)
		(layer "F.Cu")
	)
	(gr_line
		(start 324.739 -163.023296)
		(end 324.739 -163.321492)
		(stroke
			(width 0.0635)
			(type default)
		)
		(layer "F.Cu")
	)
	(gr_arc
		(start 324.739 -162.476688)
		(mid 324.776272 -162.56667)
		(end 324.866254 -162.603942)
		(stroke
			(width 0.0635)
			(type default)
		)
		(layer "F.Cu")
	)
	(gr_line
		(start 324.739 -162.178492)
		(end 324.739 -162.476688)
		(stroke
			(width 0.0635)
			(type default)
		)
		(layer "F.Cu")
	)
	(gr_arc
		(start 324.866254 -277.896066)
		(mid 324.776309 -277.933355)
		(end 324.739 -278.02332)
		(stroke
			(width 0.0635)
			(type default)
		)
		(layer "F.Cu")
	)
	(gr_arc
		(start 324.866254 -162.896042)
		(mid 324.7763 -162.93333)
		(end 324.739 -163.023296)
		(stroke
			(width 0.0635)
			(type default)
		)
		(layer "F.Cu")
	)
	(gr_line
		(start 325.819008 -47.92853)
		(end 325.913496 -48.023018)
		(stroke
			(width 0.0635)
			(type default)
		)
		(layer "F.Cu")
	)
	(gr_line
		(start 325.819008 -47.51197)
		(end 325.913496 -47.417482)
		(stroke
			(width 0.0635)
			(type default)
		)
		(layer "F.Cu")
	)
	(gr_line
		(start 325.83501 -162.971988)
		(end 325.913496 -163.050474)
		(stroke
			(width 0.0635)
			(type default)
		)
		(layer "F.Cu")
	)
	(gr_line
		(start 325.83501 -162.555428)
		(end 325.913496 -162.476942)
		(stroke
			(width 0.0635)
			(type default)
		)
		(layer "F.Cu")
	)
	(gr_line
		(start 325.840598 -277.966424)
		(end 325.913496 -278.039322)
		(stroke
			(width 0.0635)
			(type default)
		)
		(layer "F.Cu")
	)
	(gr_line
		(start 325.840598 -277.549864)
		(end 325.913496 -277.476966)
		(stroke
			(width 0.0635)
			(type default)
		)
		(layer "F.Cu")
	)
	(gr_line
		(start 325.848726 -274.148296)
		(end 325.913496 -274.213066)
		(stroke
			(width 0.0635)
			(type default)
		)
		(layer "F.Cu")
	)
	(gr_line
		(start 325.848726 -273.731736)
		(end 325.913496 -273.666966)
		(stroke
			(width 0.0635)
			(type default)
		)
		(layer "F.Cu")
	)
	(gr_line
		(start 325.848726 -159.148272)
		(end 325.913496 -159.213042)
		(stroke
			(width 0.0635)
			(type default)
		)
		(layer "F.Cu")
	)
	(gr_line
		(start 325.848726 -158.731712)
		(end 325.913496 -158.666942)
		(stroke
			(width 0.0635)
			(type default)
		)
		(layer "F.Cu")
	)
	(gr_line
		(start 325.848726 -44.148248)
		(end 325.913496 -44.213018)
		(stroke
			(width 0.0635)
			(type default)
		)
		(layer "F.Cu")
	)
	(gr_line
		(start 325.848726 -43.731688)
		(end 325.913496 -43.666918)
		(stroke
			(width 0.0635)
			(type default)
		)
		(layer "F.Cu")
	)
	(gr_line
		(start 325.913496 -278.2062)
		(end 326.092312 -278.385016)
		(stroke
			(width 0.0635)
			(type default)
		)
		(layer "F.Cu")
	)
	(gr_line
		(start 325.913496 -278.039322)
		(end 325.913496 -278.2062)
		(stroke
			(width 0.0635)
			(type default)
		)
		(layer "F.Cu")
	)
	(gr_line
		(start 325.913496 -277.242016)
		(end 325.913496 -277.476966)
		(stroke
			(width 0.0635)
			(type default)
		)
		(layer "F.Cu")
	)
	(gr_line
		(start 325.913496 -277.242016)
		(end 326.040496 -277.115016)
		(stroke
			(width 0.0635)
			(type default)
		)
		(layer "F.Cu")
	)
	(gr_line
		(start 325.913496 -274.448016)
		(end 326.040496 -274.575016)
		(stroke
			(width 0.0635)
			(type default)
		)
		(layer "F.Cu")
	)
	(gr_line
		(start 325.913496 -274.213066)
		(end 325.913496 -274.448016)
		(stroke
			(width 0.0635)
			(type default)
		)
		(layer "F.Cu")
	)
	(gr_line
		(start 325.913496 -273.432016)
		(end 325.913496 -273.666966)
		(stroke
			(width 0.0635)
			(type default)
		)
		(layer "F.Cu")
	)
	(gr_line
		(start 325.913496 -273.432016)
		(end 326.040496 -273.305016)
		(stroke
			(width 0.0635)
			(type default)
		)
		(layer "F.Cu")
	)
	(gr_line
		(start 325.913496 -163.201604)
		(end 326.096884 -163.384992)
		(stroke
			(width 0.0635)
			(type default)
		)
		(layer "F.Cu")
	)
	(gr_line
		(start 325.913496 -163.050474)
		(end 325.913496 -163.201604)
		(stroke
			(width 0.0635)
			(type default)
		)
		(layer "F.Cu")
	)
	(gr_line
		(start 325.913496 -162.241992)
		(end 325.913496 -162.476942)
		(stroke
			(width 0.0635)
			(type default)
		)
		(layer "F.Cu")
	)
	(gr_line
		(start 325.913496 -162.241992)
		(end 326.040496 -162.114992)
		(stroke
			(width 0.0635)
			(type default)
		)
		(layer "F.Cu")
	)
	(gr_line
		(start 325.913496 -159.447992)
		(end 326.040496 -159.574992)
		(stroke
			(width 0.0635)
			(type default)
		)
		(layer "F.Cu")
	)
	(gr_line
		(start 325.913496 -159.213042)
		(end 325.913496 -159.447992)
		(stroke
			(width 0.0635)
			(type default)
		)
		(layer "F.Cu")
	)
	(gr_line
		(start 325.913496 -158.431992)
		(end 325.913496 -158.666942)
		(stroke
			(width 0.0635)
			(type default)
		)
		(layer "F.Cu")
	)
	(gr_line
		(start 325.913496 -158.431992)
		(end 326.040496 -158.304992)
		(stroke
			(width 0.0635)
			(type default)
		)
		(layer "F.Cu")
	)
	(gr_line
		(start 325.913496 -48.257968)
		(end 326.040496 -48.384968)
		(stroke
			(width 0.0635)
			(type default)
		)
		(layer "F.Cu")
	)
	(gr_line
		(start 325.913496 -48.023018)
		(end 325.913496 -48.257968)
		(stroke
			(width 0.0635)
			(type default)
		)
		(layer "F.Cu")
	)
	(gr_line
		(start 325.913496 -47.251112)
		(end 325.913496 -47.417482)
		(stroke
			(width 0.0635)
			(type default)
		)
		(layer "F.Cu")
	)
	(gr_line
		(start 325.913496 -47.251112)
		(end 326.04964 -47.114968)
		(stroke
			(width 0.0635)
			(type default)
		)
		(layer "F.Cu")
	)
	(gr_line
		(start 325.913496 -44.447968)
		(end 326.040496 -44.574968)
		(stroke
			(width 0.0635)
			(type default)
		)
		(layer "F.Cu")
	)
	(gr_line
		(start 325.913496 -44.213018)
		(end 325.913496 -44.447968)
		(stroke
			(width 0.0635)
			(type default)
		)
		(layer "F.Cu")
	)
	(gr_line
		(start 325.913496 -43.431968)
		(end 325.913496 -43.666918)
		(stroke
			(width 0.0635)
			(type default)
		)
		(layer "F.Cu")
	)
	(gr_line
		(start 325.913496 -43.431968)
		(end 326.040496 -43.304968)
		(stroke
			(width 0.0635)
			(type default)
		)
		(layer "F.Cu")
	)
	(gr_line
		(start 326.040496 -277.115016)
		(end 327.375012 -277.115016)
		(stroke
			(width 0.0635)
			(type default)
		)
		(layer "F.Cu")
	)
	(gr_line
		(start 326.040496 -274.575016)
		(end 327.375012 -274.575016)
		(stroke
			(width 0.0635)
			(type default)
		)
		(layer "F.Cu")
	)
	(gr_line
		(start 326.040496 -273.305016)
		(end 327.375012 -273.305016)
		(stroke
			(width 0.0635)
			(type default)
		)
		(layer "F.Cu")
	)
	(gr_line
		(start 326.040496 -162.114992)
		(end 327.375012 -162.114992)
		(stroke
			(width 0.0635)
			(type default)
		)
		(layer "F.Cu")
	)
	(gr_line
		(start 326.040496 -159.574992)
		(end 327.375012 -159.574992)
		(stroke
			(width 0.0635)
			(type default)
		)
		(layer "F.Cu")
	)
	(gr_line
		(start 326.040496 -158.304992)
		(end 327.375012 -158.304992)
		(stroke
			(width 0.0635)
			(type default)
		)
		(layer "F.Cu")
	)
	(gr_line
		(start 326.040496 -48.384968)
		(end 327.375012 -48.384968)
		(stroke
			(width 0.0635)
			(type default)
		)
		(layer "F.Cu")
	)
	(gr_line
		(start 326.040496 -44.574968)
		(end 327.375012 -44.574968)
		(stroke
			(width 0.0635)
			(type default)
		)
		(layer "F.Cu")
	)
	(gr_line
		(start 326.040496 -43.304968)
		(end 327.375012 -43.304968)
		(stroke
			(width 0.0635)
			(type default)
		)
		(layer "F.Cu")
	)
	(gr_line
		(start 326.04964 -47.114968)
		(end 327.375012 -47.114968)
		(stroke
			(width 0.0635)
			(type default)
		)
		(layer "F.Cu")
	)
	(gr_line
		(start 326.092312 -278.385016)
		(end 327.375012 -278.385016)
		(stroke
			(width 0.0635)
			(type default)
		)
		(layer "F.Cu")
	)
	(gr_line
		(start 326.096884 -163.384992)
		(end 327.375012 -163.384992)
		(stroke
			(width 0.0635)
			(type default)
		)
		(layer "F.Cu")
	)
	(gr_line
		(start 329.262486 -33.659318)
		(end 329.326494 -33.743138)
		(stroke
			(width 0.08255)
			(type default)
		)
		(layer "F.Cu")
	)
	(gr_line
		(start 330.114402 -32.054546)
		(end 330.179426 -32.139382)
		(stroke
			(width 0.08255)
			(type default)
		)
		(layer "F.Cu")
	)
	(gr_line
		(start 331.883766 -37.56025)
		(end 331.908658 -37.593016)
		(stroke
			(width 0.08255)
			(type default)
		)
		(layer "F.Cu")
	)
	(gr_line
		(start 331.908658 -37.593016)
		(end 331.946758 -37.608256)
		(stroke
			(width 0.08255)
			(type default)
		)
		(layer "F.Cu")
	)
	(gr_line
		(start 332.86319 -36.12769)
		(end 332.886812 -36.158424)
		(stroke
			(width 0.08255)
			(type default)
		)
		(layer "F.Cu")
	)
	(gr_line
		(start 332.886812 -36.158424)
		(end 332.922626 -36.173664)
		(stroke
			(width 0.08255)
			(type default)
		)
		(layer "F.Cu")
	)
	(gr_line
		(start 336.460338 -37.668708)
		(end 336.500724 -37.685726)
		(stroke
			(width 0.08255)
			(type default)
		)
		(layer "F.Cu")
	)
	(gr_line
		(start 336.500724 -37.685726)
		(end 336.544158 -37.679376)
		(stroke
			(width 0.08255)
			(type default)
		)
		(layer "F.Cu")
	)
	(gr_line
		(start 336.594704 -39.473378)
		(end 336.637376 -39.49065)
		(stroke
			(width 0.08255)
			(type default)
		)
		(layer "F.Cu")
	)
	(gr_line
		(start 336.637376 -39.49065)
		(end 336.682842 -39.482522)
		(stroke
			(width 0.08255)
			(type default)
		)
		(layer "F.Cu")
	)
	(gr_line
		(start 350.764602 -42.627042)
		(end 351.089722 -42.627042)
		(stroke
			(width 0.0635)
			(type default)
		)
		(layer "F.Cu")
	)
	(gr_arc
		(start 351.216722 -42.754042)
		(mid 351.179525 -42.664239)
		(end 351.089722 -42.627042)
		(stroke
			(width 0.0635)
			(type default)
		)
		(layer "F.Cu")
	)
	(gr_line
		(start 351.539302 -274.230592)
		(end 351.539302 -274.511516)
		(stroke
			(width 0.0635)
			(type default)
		)
		(layer "F.Cu")
	)
	(gr_arc
		(start 351.539302 -273.649186)
		(mid 351.548935 -273.697704)
		(end 351.576386 -273.738848)
		(stroke
			(width 0.0635)
			(type default)
		)
		(layer "F.Cu")
	)
	(gr_line
		(start 351.539302 -273.368516)
		(end 351.539302 -273.649186)
		(stroke
			(width 0.0635)
			(type default)
		)
		(layer "F.Cu")
	)
	(gr_line
		(start 351.539302 -159.223456)
		(end 351.539302 -159.511492)
		(stroke
			(width 0.0635)
			(type default)
		)
		(layer "F.Cu")
	)
	(gr_arc
		(start 351.539302 -158.653734)
		(mid 351.548935 -158.702252)
		(end 351.576386 -158.743396)
		(stroke
			(width 0.0635)
			(type default)
		)
		(layer "F.Cu")
	)
	(gr_line
		(start 351.539302 -158.368492)
		(end 351.539302 -158.653734)
		(stroke
			(width 0.0635)
			(type default)
		)
		(layer "F.Cu")
	)
	(gr_arc
		(start 351.576386 -274.14093)
		(mid 351.548928 -274.182075)
		(end 351.539302 -274.230592)
		(stroke
			(width 0.0635)
			(type default)
		)
		(layer "F.Cu")
	)
	(gr_line
		(start 351.576386 -274.14093)
		(end 351.594166 -274.12315)
		(stroke
			(width 0.0635)
			(type default)
		)
		(layer "F.Cu")
	)
	(gr_line
		(start 351.576386 -273.738848)
		(end 351.59442 -273.756882)
		(stroke
			(width 0.0635)
			(type default)
		)
		(layer "F.Cu")
	)
	(gr_arc
		(start 351.576386 -159.133794)
		(mid 351.548949 -159.174943)
		(end 351.539302 -159.223456)
		(stroke
			(width 0.0635)
			(type default)
		)
		(layer "F.Cu")
	)
	(gr_line
		(start 351.576386 -159.133794)
		(end 351.587054 -159.123126)
		(stroke
			(width 0.0635)
			(type default)
		)
		(layer "F.Cu")
	)
	(gr_line
		(start 351.576386 -158.743396)
		(end 351.589848 -158.756858)
		(stroke
			(width 0.0635)
			(type default)
		)
		(layer "F.Cu")
	)
	(gr_arc
		(start 351.589848 -158.756858)
		(mid 351.630999 -158.784291)
		(end 351.67951 -158.793942)
		(stroke
			(width 0.0635)
			(type default)
		)
		(layer "F.Cu")
	)
	(gr_arc
		(start 351.59442 -273.756882)
		(mid 351.635571 -273.784315)
		(end 351.684082 -273.793966)
		(stroke
			(width 0.0635)
			(type default)
		)
		(layer "F.Cu")
	)
	(gr_arc
		(start 351.635822 -42.627042)
		(mid 351.54602 -42.664234)
		(end 351.508822 -42.754042)
		(stroke
			(width 0.0635)
			(type default)
		)
		(layer "F.Cu")
	)
	(gr_line
		(start 351.635822 -42.627042)
		(end 351.907602 -42.627042)
		(stroke
			(width 0.0635)
			(type default)
		)
		(layer "F.Cu")
	)
	(gr_arc
		(start 351.676716 -159.086042)
		(mid 351.628207 -159.095693)
		(end 351.587054 -159.123126)
		(stroke
			(width 0.0635)
			(type default)
		)
		(layer "F.Cu")
	)
	(gr_arc
		(start 351.683828 -274.086066)
		(mid 351.635318 -274.095715)
		(end 351.594166 -274.12315)
		(stroke
			(width 0.0635)
			(type default)
		)
		(layer "F.Cu")
	)
	(gr_line
		(start 352.350578 -44.148248)
		(end 352.421698 -44.219368)
		(stroke
			(width 0.0635)
			(type default)
		)
		(layer "F.Cu")
	)
	(gr_line
		(start 352.350578 -43.731688)
		(end 352.421698 -43.660568)
		(stroke
			(width 0.0635)
			(type default)
		)
		(layer "F.Cu")
	)
	(gr_line
		(start 352.421698 -44.219368)
		(end 352.905314 -44.219368)
		(stroke
			(width 0.0635)
			(type default)
		)
		(layer "F.Cu")
	)
	(gr_line
		(start 352.421698 -43.660568)
		(end 352.905314 -43.660568)
		(stroke
			(width 0.0635)
			(type default)
		)
		(layer "F.Cu")
	)
	(gr_line
		(start 352.502978 -274.148296)
		(end 352.574098 -274.219416)
		(stroke
			(width 0.0635)
			(type default)
		)
		(layer "F.Cu")
	)
	(gr_line
		(start 352.502978 -273.731736)
		(end 352.574098 -273.660616)
		(stroke
			(width 0.0635)
			(type default)
		)
		(layer "F.Cu")
	)
	(gr_line
		(start 352.502978 -159.148272)
		(end 352.574098 -159.219392)
		(stroke
			(width 0.0635)
			(type default)
		)
		(layer "F.Cu")
	)
	(gr_line
		(start 352.502978 -158.731712)
		(end 352.574098 -158.660592)
		(stroke
			(width 0.0635)
			(type default)
		)
		(layer "F.Cu")
	)
	(gr_line
		(start 352.574098 -274.219416)
		(end 352.905314 -274.219416)
		(stroke
			(width 0.0635)
			(type default)
		)
		(layer "F.Cu")
	)
	(gr_line
		(start 352.574098 -273.660616)
		(end 352.905314 -273.660616)
		(stroke
			(width 0.0635)
			(type default)
		)
		(layer "F.Cu")
	)
	(gr_line
		(start 352.574098 -159.219392)
		(end 352.905314 -159.219392)
		(stroke
			(width 0.0635)
			(type default)
		)
		(layer "F.Cu")
	)
	(gr_line
		(start 352.574098 -158.660592)
		(end 352.905314 -158.660592)
		(stroke
			(width 0.0635)
			(type default)
		)
		(layer "F.Cu")
	)
	(gr_line
		(start 353.263454 -31.792672)
		(end 353.27971 -31.786322)
		(stroke
			(width 0.08255)
			(type default)
		)
		(layer "F.Cu")
	)
	(gr_line
		(start 353.464114 -274.219416)
		(end 354.02393 -274.219416)
		(stroke
			(width 0.0635)
			(type default)
		)
		(layer "F.Cu")
	)
	(gr_line
		(start 353.464114 -273.660616)
		(end 354.02393 -273.660616)
		(stroke
			(width 0.0635)
			(type default)
		)
		(layer "F.Cu")
	)
	(gr_line
		(start 353.464114 -159.219392)
		(end 353.99853 -159.219392)
		(stroke
			(width 0.0635)
			(type default)
		)
		(layer "F.Cu")
	)
	(gr_line
		(start 353.464114 -158.660592)
		(end 353.99853 -158.660592)
		(stroke
			(width 0.0635)
			(type default)
		)
		(layer "F.Cu")
	)
	(gr_line
		(start 353.464114 -44.219368)
		(end 353.87153 -44.219368)
		(stroke
			(width 0.0635)
			(type default)
		)
		(layer "F.Cu")
	)
	(gr_line
		(start 353.464114 -43.660568)
		(end 353.87153 -43.660568)
		(stroke
			(width 0.0635)
			(type default)
		)
		(layer "F.Cu")
	)
	(gr_line
		(start 353.682808 -147.269962)
		(end 354.659438 -147.269962)
		(stroke
			(width 0.127)
			(type default)
		)
		(layer "F.Cu")
	)
	(gr_line
		(start 353.682808 -145.642838)
		(end 354.659438 -145.642838)
		(stroke
			(width 0.127)
			(type default)
		)
		(layer "F.Cu")
	)
	(gr_line
		(start 353.87153 -44.219368)
		(end 353.94265 -44.148248)
		(stroke
			(width 0.0635)
			(type default)
		)
		(layer "F.Cu")
	)
	(gr_line
		(start 353.87153 -43.660568)
		(end 353.94265 -43.731688)
		(stroke
			(width 0.0635)
			(type default)
		)
		(layer "F.Cu")
	)
	(gr_line
		(start 353.93249 -33.37052)
		(end 353.948746 -33.36417)
		(stroke
			(width 0.08255)
			(type default)
		)
		(layer "F.Cu")
	)
	(gr_line
		(start 353.99853 -159.219392)
		(end 354.06965 -159.148272)
		(stroke
			(width 0.0635)
			(type default)
		)
		(layer "F.Cu")
	)
	(gr_line
		(start 353.99853 -158.660592)
		(end 354.06965 -158.731712)
		(stroke
			(width 0.0635)
			(type default)
		)
		(layer "F.Cu")
	)
	(gr_line
		(start 354.02393 -274.219416)
		(end 354.09505 -274.148296)
		(stroke
			(width 0.0635)
			(type default)
		)
		(layer "F.Cu")
	)
	(gr_line
		(start 354.02393 -273.660616)
		(end 354.09505 -273.731736)
		(stroke
			(width 0.0635)
			(type default)
		)
		(layer "F.Cu")
	)
	(gr_line
		(start 356.289102 -278.02332)
		(end 356.289102 -278.321516)
		(stroke
			(width 0.0635)
			(type default)
		)
		(layer "F.Cu")
	)
	(gr_arc
		(start 356.289102 -277.476712)
		(mid 356.326374 -277.566694)
		(end 356.416356 -277.603966)
		(stroke
			(width 0.0635)
			(type default)
		)
		(layer "F.Cu")
	)
	(gr_line
		(start 356.289102 -277.178516)
		(end 356.289102 -277.476712)
		(stroke
			(width 0.0635)
			(type default)
		)
		(layer "F.Cu")
	)
	(gr_line
		(start 356.289102 -163.023296)
		(end 356.289102 -163.321492)
		(stroke
			(width 0.0635)
			(type default)
		)
		(layer "F.Cu")
	)
	(gr_arc
		(start 356.289102 -162.476688)
		(mid 356.326374 -162.56667)
		(end 356.416356 -162.603942)
		(stroke
			(width 0.0635)
			(type default)
		)
		(layer "F.Cu")
	)
	(gr_line
		(start 356.289102 -162.178492)
		(end 356.289102 -162.476688)
		(stroke
			(width 0.0635)
			(type default)
		)
		(layer "F.Cu")
	)
	(gr_line
		(start 356.289102 -48.023018)
		(end 356.289102 -48.321468)
		(stroke
			(width 0.0635)
			(type default)
		)
		(layer "F.Cu")
	)
	(gr_arc
		(start 356.289102 -47.476918)
		(mid 356.326299 -47.566721)
		(end 356.416102 -47.603918)
		(stroke
			(width 0.0635)
			(type default)
		)
		(layer "F.Cu")
	)
	(gr_line
		(start 356.289102 -47.178468)
		(end 356.289102 -47.476918)
		(stroke
			(width 0.0635)
			(type default)
		)
		(layer "F.Cu")
	)
	(gr_arc
		(start 356.416102 -47.896018)
		(mid 356.326305 -47.933216)
		(end 356.289102 -48.023018)
		(stroke
			(width 0.0635)
			(type default)
		)
		(layer "F.Cu")
	)
	(gr_arc
		(start 356.416356 -277.896066)
		(mid 356.326409 -277.933355)
		(end 356.289102 -278.02332)
		(stroke
			(width 0.0635)
			(type default)
		)
		(layer "F.Cu")
	)
	(gr_arc
		(start 356.416356 -162.896042)
		(mid 356.326401 -162.933329)
		(end 356.289102 -163.023296)
		(stroke
			(width 0.0635)
			(type default)
		)
		(layer "F.Cu")
	)
	(gr_line
		(start 357.389938 -162.967162)
		(end 357.463598 -163.040822)
		(stroke
			(width 0.0635)
			(type default)
		)
		(layer "F.Cu")
	)
	(gr_line
		(start 357.389938 -162.550602)
		(end 357.463598 -162.476942)
		(stroke
			(width 0.0635)
			(type default)
		)
		(layer "F.Cu")
	)
	(gr_line
		(start 357.392478 -277.964646)
		(end 357.463598 -278.035766)
		(stroke
			(width 0.0635)
			(type default)
		)
		(layer "F.Cu")
	)
	(gr_line
		(start 357.392478 -277.548086)
		(end 357.463598 -277.476966)
		(stroke
			(width 0.0635)
			(type default)
		)
		(layer "F.Cu")
	)
	(gr_line
		(start 357.398828 -274.148296)
		(end 357.463598 -274.213066)
		(stroke
			(width 0.0635)
			(type default)
		)
		(layer "F.Cu")
	)
	(gr_line
		(start 357.398828 -273.731736)
		(end 357.463598 -273.666966)
		(stroke
			(width 0.0635)
			(type default)
		)
		(layer "F.Cu")
	)
	(gr_line
		(start 357.398828 -159.148272)
		(end 357.463598 -159.213042)
		(stroke
			(width 0.0635)
			(type default)
		)
		(layer "F.Cu")
	)
	(gr_line
		(start 357.398828 -158.731712)
		(end 357.463598 -158.666942)
		(stroke
			(width 0.0635)
			(type default)
		)
		(layer "F.Cu")
	)
	(gr_line
		(start 357.398828 -47.958248)
		(end 357.463598 -48.023018)
		(stroke
			(width 0.0635)
			(type default)
		)
		(layer "F.Cu")
	)
	(gr_line
		(start 357.398828 -47.541688)
		(end 357.463598 -47.476918)
		(stroke
			(width 0.0635)
			(type default)
		)
		(layer "F.Cu")
	)
	(gr_line
		(start 357.398828 -44.148248)
		(end 357.463598 -44.213018)
		(stroke
			(width 0.0635)
			(type default)
		)
		(layer "F.Cu")
	)
	(gr_line
		(start 357.398828 -43.731688)
		(end 357.463598 -43.666918)
		(stroke
			(width 0.0635)
			(type default)
		)
		(layer "F.Cu")
	)
	(gr_line
		(start 357.463598 -278.202644)
		(end 357.64597 -278.385016)
		(stroke
			(width 0.0635)
			(type default)
		)
		(layer "F.Cu")
	)
	(gr_line
		(start 357.463598 -278.035766)
		(end 357.463598 -278.202644)
		(stroke
			(width 0.0635)
			(type default)
		)
		(layer "F.Cu")
	)
	(gr_line
		(start 357.463598 -277.242016)
		(end 357.463598 -277.476966)
		(stroke
			(width 0.0635)
			(type default)
		)
		(layer "F.Cu")
	)
	(gr_line
		(start 357.463598 -277.242016)
		(end 357.590598 -277.115016)
		(stroke
			(width 0.0635)
			(type default)
		)
		(layer "F.Cu")
	)
	(gr_line
		(start 357.463598 -274.448016)
		(end 357.590598 -274.575016)
		(stroke
			(width 0.0635)
			(type default)
		)
		(layer "F.Cu")
	)
	(gr_line
		(start 357.463598 -274.213066)
		(end 357.463598 -274.448016)
		(stroke
			(width 0.0635)
			(type default)
		)
		(layer "F.Cu")
	)
	(gr_line
		(start 357.463598 -273.432016)
		(end 357.463598 -273.666966)
		(stroke
			(width 0.0635)
			(type default)
		)
		(layer "F.Cu")
	)
	(gr_line
		(start 357.463598 -273.432016)
		(end 357.590598 -273.305016)
		(stroke
			(width 0.0635)
			(type default)
		)
		(layer "F.Cu")
	)
	(gr_line
		(start 357.463598 -163.211764)
		(end 357.636826 -163.384992)
		(stroke
			(width 0.0635)
			(type default)
		)
		(layer "F.Cu")
	)
	(gr_line
		(start 357.463598 -163.040822)
		(end 357.463598 -163.211764)
		(stroke
			(width 0.0635)
			(type default)
		)
		(layer "F.Cu")
	)
	(gr_line
		(start 357.463598 -162.241992)
		(end 357.463598 -162.476942)
		(stroke
			(width 0.0635)
			(type default)
		)
		(layer "F.Cu")
	)
	(gr_line
		(start 357.463598 -162.241992)
		(end 357.590598 -162.114992)
		(stroke
			(width 0.0635)
			(type default)
		)
		(layer "F.Cu")
	)
	(gr_line
		(start 357.463598 -159.447992)
		(end 357.590598 -159.574992)
		(stroke
			(width 0.0635)
			(type default)
		)
		(layer "F.Cu")
	)
	(gr_line
		(start 357.463598 -159.213042)
		(end 357.463598 -159.447992)
		(stroke
			(width 0.0635)
			(type default)
		)
		(layer "F.Cu")
	)
	(gr_line
		(start 357.463598 -158.431992)
		(end 357.463598 -158.666942)
		(stroke
			(width 0.0635)
			(type default)
		)
		(layer "F.Cu")
	)
	(gr_line
		(start 357.463598 -158.431992)
		(end 357.590598 -158.304992)
		(stroke
			(width 0.0635)
			(type default)
		)
		(layer "F.Cu")
	)
	(gr_line
		(start 357.463598 -48.257968)
		(end 357.590598 -48.384968)
		(stroke
			(width 0.0635)
			(type default)
		)
		(layer "F.Cu")
	)
	(gr_line
		(start 357.463598 -48.023018)
		(end 357.463598 -48.257968)
		(stroke
			(width 0.0635)
			(type default)
		)
		(layer "F.Cu")
	)
	(gr_line
		(start 357.463598 -47.241968)
		(end 357.463598 -47.476918)
		(stroke
			(width 0.0635)
			(type default)
		)
		(layer "F.Cu")
	)
	(gr_line
		(start 357.463598 -47.241968)
		(end 357.590598 -47.114968)
		(stroke
			(width 0.0635)
			(type default)
		)
		(layer "F.Cu")
	)
	(gr_line
		(start 357.463598 -44.447968)
		(end 357.590598 -44.574968)
		(stroke
			(width 0.0635)
			(type default)
		)
		(layer "F.Cu")
	)
	(gr_line
		(start 357.463598 -44.213018)
		(end 357.463598 -44.447968)
		(stroke
			(width 0.0635)
			(type default)
		)
		(layer "F.Cu")
	)
	(gr_line
		(start 357.463598 -43.431968)
		(end 357.463598 -43.666918)
		(stroke
			(width 0.0635)
			(type default)
		)
		(layer "F.Cu")
	)
	(gr_line
		(start 357.463598 -43.431968)
		(end 357.590598 -43.304968)
		(stroke
			(width 0.0635)
			(type default)
		)
		(layer "F.Cu")
	)
	(gr_line
		(start 357.590598 -277.115016)
		(end 358.925114 -277.115016)
		(stroke
			(width 0.0635)
			(type default)
		)
		(layer "F.Cu")
	)
	(gr_line
		(start 357.590598 -274.575016)
		(end 358.925114 -274.575016)
		(stroke
			(width 0.0635)
			(type default)
		)
		(layer "F.Cu")
	)
	(gr_line
		(start 357.590598 -273.305016)
		(end 358.925114 -273.305016)
		(stroke
			(width 0.0635)
			(type default)
		)
		(layer "F.Cu")
	)
	(gr_line
		(start 357.590598 -162.114992)
		(end 358.925114 -162.114992)
		(stroke
			(width 0.0635)
			(type default)
		)
		(layer "F.Cu")
	)
	(gr_line
		(start 357.590598 -159.574992)
		(end 358.925114 -159.574992)
		(stroke
			(width 0.0635)
			(type default)
		)
		(layer "F.Cu")
	)
	(gr_line
		(start 357.590598 -158.304992)
		(end 358.925114 -158.304992)
		(stroke
			(width 0.0635)
			(type default)
		)
		(layer "F.Cu")
	)
	(gr_line
		(start 357.590598 -48.384968)
		(end 358.925114 -48.384968)
		(stroke
			(width 0.0635)
			(type default)
		)
		(layer "F.Cu")
	)
	(gr_line
		(start 357.590598 -47.114968)
		(end 358.925114 -47.114968)
		(stroke
			(width 0.0635)
			(type default)
		)
		(layer "F.Cu")
	)
	(gr_line
		(start 357.590598 -44.574968)
		(end 358.925114 -44.574968)
		(stroke
			(width 0.0635)
			(type default)
		)
		(layer "F.Cu")
	)
	(gr_line
		(start 357.590598 -43.304968)
		(end 358.925114 -43.304968)
		(stroke
			(width 0.0635)
			(type default)
		)
		(layer "F.Cu")
	)
	(gr_line
		(start 357.636826 -163.384992)
		(end 358.925114 -163.384992)
		(stroke
			(width 0.0635)
			(type default)
		)
		(layer "F.Cu")
	)
	(gr_line
		(start 357.64597 -278.385016)
		(end 358.925114 -278.385016)
		(stroke
			(width 0.0635)
			(type default)
		)
		(layer "F.Cu")
	)
	(gr_line
		(start 360.786426 -142.597886)
		(end 360.994706 -142.806166)
		(stroke
			(width 0.127)
			(type default)
		)
		(layer "F.Cu")
	)
	(gr_line
		(start 360.786426 -141.947646)
		(end 360.994706 -141.739366)
		(stroke
			(width 0.127)
			(type default)
		)
		(layer "F.Cu")
	)
	(gr_line
		(start 360.99242 -140.43152)
		(end 361.1753 -140.6144)
		(stroke
			(width 0.127)
			(type default)
		)
		(layer "F.Cu")
	)
	(gr_line
		(start 360.99242 -139.78128)
		(end 361.1753 -139.5984)
		(stroke
			(width 0.127)
			(type default)
		)
		(layer "F.Cu")
	)
	(gr_line
		(start 362.0643 -140.6144)
		(end 362.24718 -140.43152)
		(stroke
			(width 0.127)
			(type default)
		)
		(layer "F.Cu")
	)
	(gr_line
		(start 362.0643 -139.5984)
		(end 362.24718 -139.78128)
		(stroke
			(width 0.127)
			(type default)
		)
		(layer "F.Cu")
	)
	(gr_arc
		(start 362.22305 -28.704032)
		(mid 362.312896 -28.666854)
		(end 362.35005 -28.577032)
		(stroke
			(width 0.08255)
			(type default)
		)
		(layer "F.Cu")
	)
	(gr_arc
		(start 362.35005 -29.123132)
		(mid 362.312853 -29.033329)
		(end 362.22305 -28.996132)
		(stroke
			(width 0.08255)
			(type default)
		)
		(layer "F.Cu")
	)
	(gr_line
		(start 362.35005 -29.123132)
		(end 362.35005 -29.550106)
		(stroke
			(width 0.08255)
			(type default)
		)
		(layer "F.Cu")
	)
	(gr_line
		(start 362.35005 -28.150058)
		(end 362.35005 -28.577032)
		(stroke
			(width 0.08255)
			(type default)
		)
		(layer "F.Cu")
	)
	(gr_line
		(start 363.019594 -140.43914)
		(end 363.329474 -140.74902)
		(stroke
			(width 0.127)
			(type default)
		)
		(layer "F.Cu")
	)
	(gr_line
		(start 363.019594 -139.7889)
		(end 363.329474 -139.47902)
		(stroke
			(width 0.127)
			(type default)
		)
		(layer "F.Cu")
	)
	(gr_line
		(start 363.329474 -140.74902)
		(end 363.639354 -140.43914)
		(stroke
			(width 0.127)
			(type default)
		)
		(layer "F.Cu")
	)
	(gr_line
		(start 363.329474 -139.47902)
		(end 363.639354 -139.7889)
		(stroke
			(width 0.127)
			(type default)
		)
		(layer "F.Cu")
	)
	(gr_line
		(start 364.152688 -140.43152)
		(end 364.272068 -140.5509)
		(stroke
			(width 0.127)
			(type default)
		)
		(layer "F.Cu")
	)
	(gr_line
		(start 364.152688 -139.78128)
		(end 364.272068 -139.6619)
		(stroke
			(width 0.127)
			(type default)
		)
		(layer "F.Cu")
	)
	(gr_line
		(start 364.272068 -140.5509)
		(end 364.7948 -140.5509)
		(stroke
			(width 0.127)
			(type default)
		)
		(layer "F.Cu")
	)
	(gr_line
		(start 364.272068 -139.6619)
		(end 364.7948 -139.6619)
		(stroke
			(width 0.127)
			(type default)
		)
		(layer "F.Cu")
	)
	(gr_line
		(start 364.7948 -140.5509)
		(end 364.91418 -140.43152)
		(stroke
			(width 0.127)
			(type default)
		)
		(layer "F.Cu")
	)
	(gr_line
		(start 364.7948 -139.6619)
		(end 364.91418 -139.78128)
		(stroke
			(width 0.127)
			(type default)
		)
		(layer "F.Cu")
	)
	(gr_line
		(start 366.395 -140.8938)
		(end 366.440466 -140.848334)
		(stroke
			(width 0.127)
			(type default)
		)
		(layer "F.Cu")
	)
	(gr_line
		(start 366.395 -139.2936)
		(end 366.449864 -139.348464)
		(stroke
			(width 0.127)
			(type default)
		)
		(layer "F.Cu")
	)
	(gr_line
		(start 366.440466 -140.848334)
		(end 367.6523 -140.848334)
		(stroke
			(width 0.127)
			(type default)
		)
		(layer "F.Cu")
	)
	(gr_line
		(start 366.449864 -139.348464)
		(end 367.6523 -139.348464)
		(stroke
			(width 0.127)
			(type default)
		)
		(layer "F.Cu")
	)
	(gr_line
		(start 366.805464 -139.848336)
		(end 367.6523 -139.848336)
		(stroke
			(width 0.127)
			(type default)
		)
		(layer "F.Cu")
	)
	(gr_line
		(start 366.814862 -140.348462)
		(end 367.6523 -140.348462)
		(stroke
			(width 0.127)
			(type default)
		)
		(layer "F.Cu")
	)
	(gr_line
		(start 382.7653 -46.1518)
		(end 383.054098 -46.1518)
		(stroke
			(width 0.0635)
			(type default)
		)
		(layer "F.Cu")
	)
	(gr_arc
		(start 383.054098 -46.1518)
		(mid 383.102616 -46.142167)
		(end 383.14376 -46.114716)
		(stroke
			(width 0.0635)
			(type default)
		)
		(layer "F.Cu")
	)
	(gr_line
		(start 383.08915 -274.227544)
		(end 383.08915 -274.511516)
		(stroke
			(width 0.0635)
			(type default)
		)
		(layer "F.Cu")
	)
	(gr_arc
		(start 383.08915 -273.657314)
		(mid 383.098783 -273.705832)
		(end 383.126234 -273.746976)
		(stroke
			(width 0.0635)
			(type default)
		)
		(layer "F.Cu")
	)
	(gr_line
		(start 383.08915 -273.368516)
		(end 383.08915 -273.657314)
		(stroke
			(width 0.0635)
			(type default)
		)
		(layer "F.Cu")
	)
	(gr_line
		(start 383.08915 -159.229298)
		(end 383.08915 -159.511492)
		(stroke
			(width 0.0635)
			(type default)
		)
		(layer "F.Cu")
	)
	(gr_arc
		(start 383.08915 -158.650432)
		(mid 383.098783 -158.69895)
		(end 383.126234 -158.740094)
		(stroke
			(width 0.0635)
			(type default)
		)
		(layer "F.Cu")
	)
	(gr_line
		(start 383.08915 -158.368492)
		(end 383.08915 -158.650432)
		(stroke
			(width 0.0635)
			(type default)
		)
		(layer "F.Cu")
	)
	(gr_arc
		(start 383.126234 -274.137882)
		(mid 383.098783 -274.179028)
		(end 383.08915 -274.227544)
		(stroke
			(width 0.0635)
			(type default)
		)
		(layer "F.Cu")
	)
	(gr_line
		(start 383.126234 -274.137882)
		(end 383.140966 -274.12315)
		(stroke
			(width 0.0635)
			(type default)
		)
		(layer "F.Cu")
	)
	(gr_line
		(start 383.126234 -273.746976)
		(end 383.13614 -273.756882)
		(stroke
			(width 0.0635)
			(type default)
		)
		(layer "F.Cu")
	)
	(gr_arc
		(start 383.126234 -159.139636)
		(mid 383.098768 -159.180779)
		(end 383.08915 -159.229298)
		(stroke
			(width 0.0635)
			(type default)
		)
		(layer "F.Cu")
	)
	(gr_line
		(start 383.126234 -159.139636)
		(end 383.142744 -159.123126)
		(stroke
			(width 0.0635)
			(type default)
		)
		(layer "F.Cu")
	)
	(gr_line
		(start 383.126234 -158.740094)
		(end 383.142998 -158.756858)
		(stroke
			(width 0.0635)
			(type default)
		)
		(layer "F.Cu")
	)
	(gr_arc
		(start 383.13614 -273.756882)
		(mid 383.177291 -273.784315)
		(end 383.225802 -273.793966)
		(stroke
			(width 0.0635)
			(type default)
		)
		(layer "F.Cu")
	)
	(gr_arc
		(start 383.142998 -158.756858)
		(mid 383.184149 -158.784291)
		(end 383.23266 -158.793942)
		(stroke
			(width 0.0635)
			(type default)
		)
		(layer "F.Cu")
	)
	(gr_line
		(start 383.14376 -46.114716)
		(end 383.153666 -46.10481)
		(stroke
			(width 0.0635)
			(type default)
		)
		(layer "F.Cu")
	)
	(gr_arc
		(start 383.153666 -46.10481)
		(mid 383.181099 -46.063659)
		(end 383.19075 -46.015148)
		(stroke
			(width 0.0635)
			(type default)
		)
		(layer "F.Cu")
	)
	(gr_arc
		(start 383.230628 -274.086066)
		(mid 383.182118 -274.095715)
		(end 383.140966 -274.12315)
		(stroke
			(width 0.0635)
			(type default)
		)
		(layer "F.Cu")
	)
	(gr_arc
		(start 383.232406 -159.086042)
		(mid 383.183899 -159.095696)
		(end 383.142744 -159.123126)
		(stroke
			(width 0.0635)
			(type default)
		)
		(layer "F.Cu")
	)
	(gr_arc
		(start 383.48285 -46.022768)
		(mid 383.492496 -46.07128)
		(end 383.519934 -46.11243)
		(stroke
			(width 0.0635)
			(type default)
		)
		(layer "F.Cu")
	)
	(gr_line
		(start 383.519934 -46.11243)
		(end 383.52222 -46.114716)
		(stroke
			(width 0.0635)
			(type default)
		)
		(layer "F.Cu")
	)
	(gr_arc
		(start 383.52222 -46.114716)
		(mid 383.563365 -46.142176)
		(end 383.611882 -46.1518)
		(stroke
			(width 0.0635)
			(type default)
		)
		(layer "F.Cu")
	)
	(gr_line
		(start 383.611882 -46.1518)
		(end 383.9083 -46.1518)
		(stroke
			(width 0.0635)
			(type default)
		)
		(layer "F.Cu")
	)
	(gr_line
		(start 384.052826 -274.148296)
		(end 384.123946 -274.219416)
		(stroke
			(width 0.0635)
			(type default)
		)
		(layer "F.Cu")
	)
	(gr_line
		(start 384.052826 -273.731736)
		(end 384.123946 -273.660616)
		(stroke
			(width 0.0635)
			(type default)
		)
		(layer "F.Cu")
	)
	(gr_line
		(start 384.052826 -159.148272)
		(end 384.123946 -159.219392)
		(stroke
			(width 0.0635)
			(type default)
		)
		(layer "F.Cu")
	)
	(gr_line
		(start 384.052826 -158.731712)
		(end 384.123946 -158.660592)
		(stroke
			(width 0.0635)
			(type default)
		)
		(layer "F.Cu")
	)
	(gr_line
		(start 384.052826 -44.148248)
		(end 384.123946 -44.219368)
		(stroke
			(width 0.0635)
			(type default)
		)
		(layer "F.Cu")
	)
	(gr_line
		(start 384.052826 -43.731688)
		(end 384.123946 -43.660568)
		(stroke
			(width 0.0635)
			(type default)
		)
		(layer "F.Cu")
	)
	(gr_line
		(start 384.123946 -274.219416)
		(end 384.455162 -274.219416)
		(stroke
			(width 0.0635)
			(type default)
		)
		(layer "F.Cu")
	)
	(gr_line
		(start 384.123946 -273.660616)
		(end 384.455162 -273.660616)
		(stroke
			(width 0.0635)
			(type default)
		)
		(layer "F.Cu")
	)
	(gr_line
		(start 384.123946 -159.219392)
		(end 384.455162 -159.219392)
		(stroke
			(width 0.0635)
			(type default)
		)
		(layer "F.Cu")
	)
	(gr_line
		(start 384.123946 -158.660592)
		(end 384.455162 -158.660592)
		(stroke
			(width 0.0635)
			(type default)
		)
		(layer "F.Cu")
	)
	(gr_line
		(start 384.123946 -44.219368)
		(end 384.455162 -44.219368)
		(stroke
			(width 0.0635)
			(type default)
		)
		(layer "F.Cu")
	)
	(gr_line
		(start 384.123946 -43.660568)
		(end 384.455162 -43.660568)
		(stroke
			(width 0.0635)
			(type default)
		)
		(layer "F.Cu")
	)
	(gr_line
		(start 385.013962 -274.219416)
		(end 385.497578 -274.219416)
		(stroke
			(width 0.0635)
			(type default)
		)
		(layer "F.Cu")
	)
	(gr_line
		(start 385.013962 -273.660616)
		(end 385.497578 -273.660616)
		(stroke
			(width 0.0635)
			(type default)
		)
		(layer "F.Cu")
	)
	(gr_line
		(start 385.013962 -159.219392)
		(end 385.421378 -159.219392)
		(stroke
			(width 0.0635)
			(type default)
		)
		(layer "F.Cu")
	)
	(gr_line
		(start 385.013962 -158.660592)
		(end 385.421378 -158.660592)
		(stroke
			(width 0.0635)
			(type default)
		)
		(layer "F.Cu")
	)
	(gr_line
		(start 385.013962 -44.219368)
		(end 385.472178 -44.219368)
		(stroke
			(width 0.0635)
			(type default)
		)
		(layer "F.Cu")
	)
	(gr_line
		(start 385.013962 -43.660568)
		(end 385.472178 -43.660568)
		(stroke
			(width 0.0635)
			(type default)
		)
		(layer "F.Cu")
	)
	(gr_line
		(start 385.421378 -159.219392)
		(end 385.492498 -159.148272)
		(stroke
			(width 0.0635)
			(type default)
		)
		(layer "F.Cu")
	)
	(gr_line
		(start 385.421378 -158.660592)
		(end 385.492498 -158.731712)
		(stroke
			(width 0.0635)
			(type default)
		)
		(layer "F.Cu")
	)
	(gr_line
		(start 385.472178 -44.219368)
		(end 385.543298 -44.148248)
		(stroke
			(width 0.0635)
			(type default)
		)
		(layer "F.Cu")
	)
	(gr_line
		(start 385.472178 -43.660568)
		(end 385.543298 -43.731688)
		(stroke
			(width 0.0635)
			(type default)
		)
		(layer "F.Cu")
	)
	(gr_line
		(start 385.497578 -274.219416)
		(end 385.568698 -274.148296)
		(stroke
			(width 0.0635)
			(type default)
		)
		(layer "F.Cu")
	)
	(gr_line
		(start 385.497578 -273.660616)
		(end 385.568698 -273.731736)
		(stroke
			(width 0.0635)
			(type default)
		)
		(layer "F.Cu")
	)
	(gr_line
		(start 387.83895 -278.02332)
		(end 387.83895 -278.321516)
		(stroke
			(width 0.0635)
			(type default)
		)
		(layer "F.Cu")
	)
	(gr_arc
		(start 387.83895 -277.476712)
		(mid 387.876222 -277.566694)
		(end 387.966204 -277.603966)
		(stroke
			(width 0.0635)
			(type default)
		)
		(layer "F.Cu")
	)
	(gr_line
		(start 387.83895 -277.178516)
		(end 387.83895 -277.476712)
		(stroke
			(width 0.0635)
			(type default)
		)
		(layer "F.Cu")
	)
	(gr_line
		(start 387.83895 -163.023296)
		(end 387.83895 -163.321492)
		(stroke
			(width 0.0635)
			(type default)
		)
		(layer "F.Cu")
	)
	(gr_arc
		(start 387.83895 -162.476688)
		(mid 387.876222 -162.56667)
		(end 387.966204 -162.603942)
		(stroke
			(width 0.0635)
			(type default)
		)
		(layer "F.Cu")
	)
	(gr_line
		(start 387.83895 -162.178492)
		(end 387.83895 -162.476688)
		(stroke
			(width 0.0635)
			(type default)
		)
		(layer "F.Cu")
	)
	(gr_line
		(start 387.83895 -48.023272)
		(end 387.83895 -48.321468)
		(stroke
			(width 0.0635)
			(type default)
		)
		(layer "F.Cu")
	)
	(gr_arc
		(start 387.83895 -47.476664)
		(mid 387.876222 -47.566646)
		(end 387.966204 -47.603918)
		(stroke
			(width 0.0635)
			(type default)
		)
		(layer "F.Cu")
	)
	(gr_line
		(start 387.83895 -47.178468)
		(end 387.83895 -47.476664)
		(stroke
			(width 0.0635)
			(type default)
		)
		(layer "F.Cu")
	)
	(gr_arc
		(start 387.966204 -277.896066)
		(mid 387.876226 -277.933338)
		(end 387.83895 -278.02332)
		(stroke
			(width 0.0635)
			(type default)
		)
		(layer "F.Cu")
	)
	(gr_arc
		(start 387.966204 -162.896042)
		(mid 387.876218 -162.933312)
		(end 387.83895 -163.023296)
		(stroke
			(width 0.0635)
			(type default)
		)
		(layer "F.Cu")
	)
	(gr_arc
		(start 387.966204 -47.896018)
		(mid 387.876209 -47.933287)
		(end 387.83895 -48.023272)
		(stroke
			(width 0.0635)
			(type default)
		)
		(layer "F.Cu")
	)
	(gr_line
		(start 388.935468 -162.97148)
		(end 389.013446 -163.049458)
		(stroke
			(width 0.0635)
			(type default)
		)
		(layer "F.Cu")
	)
	(gr_line
		(start 388.935468 -162.55492)
		(end 389.013446 -162.476942)
		(stroke
			(width 0.0635)
			(type default)
		)
		(layer "F.Cu")
	)
	(gr_line
		(start 388.94131 -277.965662)
		(end 389.013446 -278.037798)
		(stroke
			(width 0.0635)
			(type default)
		)
		(layer "F.Cu")
	)
	(gr_line
		(start 388.94131 -277.549102)
		(end 389.013446 -277.476966)
		(stroke
			(width 0.0635)
			(type default)
		)
		(layer "F.Cu")
	)
	(gr_line
		(start 388.948676 -274.148296)
		(end 389.013446 -274.213066)
		(stroke
			(width 0.0635)
			(type default)
		)
		(layer "F.Cu")
	)
	(gr_line
		(start 388.948676 -273.731736)
		(end 389.013446 -273.666966)
		(stroke
			(width 0.0635)
			(type default)
		)
		(layer "F.Cu")
	)
	(gr_line
		(start 388.948676 -159.148272)
		(end 389.013446 -159.213042)
		(stroke
			(width 0.0635)
			(type default)
		)
		(layer "F.Cu")
	)
	(gr_line
		(start 388.948676 -158.731712)
		(end 389.013446 -158.666942)
		(stroke
			(width 0.0635)
			(type default)
		)
		(layer "F.Cu")
	)
	(gr_line
		(start 388.948676 -47.958248)
		(end 389.013446 -48.023018)
		(stroke
			(width 0.0635)
			(type default)
		)
		(layer "F.Cu")
	)
	(gr_line
		(start 388.948676 -47.541688)
		(end 389.013446 -47.476918)
		(stroke
			(width 0.0635)
			(type default)
		)
		(layer "F.Cu")
	)
	(gr_line
		(start 388.948676 -44.148248)
		(end 389.013446 -44.213018)
		(stroke
			(width 0.0635)
			(type default)
		)
		(layer "F.Cu")
	)
	(gr_line
		(start 388.948676 -43.731688)
		(end 389.013446 -43.666918)
		(stroke
			(width 0.0635)
			(type default)
		)
		(layer "F.Cu")
	)
	(gr_line
		(start 389.013446 -278.209756)
		(end 389.188706 -278.385016)
		(stroke
			(width 0.0635)
			(type default)
		)
		(layer "F.Cu")
	)
	(gr_line
		(start 389.013446 -278.037798)
		(end 389.013446 -278.209756)
		(stroke
			(width 0.0635)
			(type default)
		)
		(layer "F.Cu")
	)
	(gr_line
		(start 389.013446 -277.242016)
		(end 389.013446 -277.476966)
		(stroke
			(width 0.0635)
			(type default)
		)
		(layer "F.Cu")
	)
	(gr_line
		(start 389.013446 -277.242016)
		(end 389.140446 -277.115016)
		(stroke
			(width 0.0635)
			(type default)
		)
		(layer "F.Cu")
	)
	(gr_line
		(start 389.013446 -274.448016)
		(end 389.140446 -274.575016)
		(stroke
			(width 0.0635)
			(type default)
		)
		(layer "F.Cu")
	)
	(gr_line
		(start 389.013446 -274.213066)
		(end 389.013446 -274.448016)
		(stroke
			(width 0.0635)
			(type default)
		)
		(layer "F.Cu")
	)
	(gr_line
		(start 389.013446 -273.432016)
		(end 389.013446 -273.666966)
		(stroke
			(width 0.0635)
			(type default)
		)
		(layer "F.Cu")
	)
	(gr_line
		(start 389.013446 -273.432016)
		(end 389.140446 -273.305016)
		(stroke
			(width 0.0635)
			(type default)
		)
		(layer "F.Cu")
	)
	(gr_line
		(start 389.013446 -163.212272)
		(end 389.186166 -163.384992)
		(stroke
			(width 0.0635)
			(type default)
		)
		(layer "F.Cu")
	)
	(gr_line
		(start 389.013446 -163.049458)
		(end 389.013446 -163.212272)
		(stroke
			(width 0.0635)
			(type default)
		)
		(layer "F.Cu")
	)
	(gr_line
		(start 389.013446 -162.241992)
		(end 389.013446 -162.476942)
		(stroke
			(width 0.0635)
			(type default)
		)
		(layer "F.Cu")
	)
	(gr_line
		(start 389.013446 -162.241992)
		(end 389.140446 -162.114992)
		(stroke
			(width 0.0635)
			(type default)
		)
		(layer "F.Cu")
	)
	(gr_line
		(start 389.013446 -159.447992)
		(end 389.140446 -159.574992)
		(stroke
			(width 0.0635)
			(type default)
		)
		(layer "F.Cu")
	)
	(gr_line
		(start 389.013446 -159.213042)
		(end 389.013446 -159.447992)
		(stroke
			(width 0.0635)
			(type default)
		)
		(layer "F.Cu")
	)
	(gr_line
		(start 389.013446 -158.431992)
		(end 389.013446 -158.666942)
		(stroke
			(width 0.0635)
			(type default)
		)
		(layer "F.Cu")
	)
	(gr_line
		(start 389.013446 -158.431992)
		(end 389.140446 -158.304992)
		(stroke
			(width 0.0635)
			(type default)
		)
		(layer "F.Cu")
	)
	(gr_line
		(start 389.013446 -48.213264)
		(end 389.18515 -48.384968)
		(stroke
			(width 0.0635)
			(type default)
		)
		(layer "F.Cu")
	)
	(gr_line
		(start 389.013446 -48.023018)
		(end 389.013446 -48.213264)
		(stroke
			(width 0.0635)
			(type default)
		)
		(layer "F.Cu")
	)
	(gr_line
		(start 389.013446 -47.241968)
		(end 389.013446 -47.476918)
		(stroke
			(width 0.0635)
			(type default)
		)
		(layer "F.Cu")
	)
	(gr_line
		(start 389.013446 -47.241968)
		(end 389.140446 -47.114968)
		(stroke
			(width 0.0635)
			(type default)
		)
		(layer "F.Cu")
	)
	(gr_line
		(start 389.013446 -44.447968)
		(end 389.140446 -44.574968)
		(stroke
			(width 0.0635)
			(type default)
		)
		(layer "F.Cu")
	)
	(gr_line
		(start 389.013446 -44.213018)
		(end 389.013446 -44.447968)
		(stroke
			(width 0.0635)
			(type default)
		)
		(layer "F.Cu")
	)
	(gr_line
		(start 389.013446 -43.431968)
		(end 389.013446 -43.666918)
		(stroke
			(width 0.0635)
			(type default)
		)
		(layer "F.Cu")
	)
	(gr_line
		(start 389.013446 -43.431968)
		(end 389.140446 -43.304968)
		(stroke
			(width 0.0635)
			(type default)
		)
		(layer "F.Cu")
	)
	(gr_line
		(start 389.140446 -277.115016)
		(end 390.474962 -277.115016)
		(stroke
			(width 0.0635)
			(type default)
		)
		(layer "F.Cu")
	)
	(gr_line
		(start 389.140446 -274.575016)
		(end 390.474962 -274.575016)
		(stroke
			(width 0.0635)
			(type default)
		)
		(layer "F.Cu")
	)
	(gr_line
		(start 389.140446 -273.305016)
		(end 390.474962 -273.305016)
		(stroke
			(width 0.0635)
			(type default)
		)
		(layer "F.Cu")
	)
	(gr_line
		(start 389.140446 -162.114992)
		(end 390.474962 -162.114992)
		(stroke
			(width 0.0635)
			(type default)
		)
		(layer "F.Cu")
	)
	(gr_line
		(start 389.140446 -159.574992)
		(end 390.474962 -159.574992)
		(stroke
			(width 0.0635)
			(type default)
		)
		(layer "F.Cu")
	)
	(gr_line
		(start 389.140446 -158.304992)
		(end 390.474962 -158.304992)
		(stroke
			(width 0.0635)
			(type default)
		)
		(layer "F.Cu")
	)
	(gr_line
		(start 389.140446 -47.114968)
		(end 390.474962 -47.114968)
		(stroke
			(width 0.0635)
			(type default)
		)
		(layer "F.Cu")
	)
	(gr_line
		(start 389.140446 -44.574968)
		(end 390.474962 -44.574968)
		(stroke
			(width 0.0635)
			(type default)
		)
		(layer "F.Cu")
	)
	(gr_line
		(start 389.140446 -43.304968)
		(end 390.474962 -43.304968)
		(stroke
			(width 0.0635)
			(type default)
		)
		(layer "F.Cu")
	)
	(gr_line
		(start 389.18515 -48.384968)
		(end 390.474962 -48.384968)
		(stroke
			(width 0.0635)
			(type default)
		)
		(layer "F.Cu")
	)
	(gr_line
		(start 389.186166 -163.384992)
		(end 390.474962 -163.384992)
		(stroke
			(width 0.0635)
			(type default)
		)
		(layer "F.Cu")
	)
	(gr_line
		(start 389.188706 -278.385016)
		(end 390.474962 -278.385016)
		(stroke
			(width 0.0635)
			(type default)
		)
		(layer "F.Cu")
	)
	(gr_arc
		(start 389.222996 -29.70403)
		(mid 389.312812 -29.666836)
		(end 389.349996 -29.57703)
		(stroke
			(width 0.08255)
			(type default)
		)
		(layer "F.Cu")
	)
	(gr_arc
		(start 389.349996 -30.12313)
		(mid 389.312799 -30.033327)
		(end 389.222996 -29.99613)
		(stroke
			(width 0.08255)
			(type default)
		)
		(layer "F.Cu")
	)
	(gr_line
		(start 389.349996 -30.12313)
		(end 389.349996 -30.550104)
		(stroke
			(width 0.08255)
			(type default)
		)
		(layer "F.Cu")
	)
	(gr_line
		(start 389.349996 -29.150056)
		(end 389.349996 -29.57703)
		(stroke
			(width 0.08255)
			(type default)
		)
		(layer "F.Cu")
	)
	(gr_line
		(start 414.639252 -274.237958)
		(end 414.639252 -274.511516)
		(stroke
			(width 0.0635)
			(type default)
		)
		(layer "F.Cu")
	)
	(gr_arc
		(start 414.639252 -273.656298)
		(mid 414.648885 -273.704816)
		(end 414.676336 -273.74596)
		(stroke
			(width 0.0635)
			(type default)
		)
		(layer "F.Cu")
	)
	(gr_line
		(start 414.639252 -273.368516)
		(end 414.639252 -273.656298)
		(stroke
			(width 0.0635)
			(type default)
		)
		(layer "F.Cu")
	)
	(gr_line
		(start 414.639252 -159.239204)
		(end 414.639252 -159.511492)
		(stroke
			(width 0.0635)
			(type default)
		)
		(layer "F.Cu")
	)
	(gr_arc
		(start 414.639252 -158.65856)
		(mid 414.648885 -158.707078)
		(end 414.676336 -158.748222)
		(stroke
			(width 0.0635)
			(type default)
		)
		(layer "F.Cu")
	)
	(gr_line
		(start 414.639252 -158.368492)
		(end 414.639252 -158.65856)
		(stroke
			(width 0.0635)
			(type default)
		)
		(layer "F.Cu")
	)
	(gr_line
		(start 414.639252 -44.250102)
		(end 414.639252 -44.511468)
		(stroke
			(width 0.0635)
			(type default)
		)
		(layer "F.Cu")
	)
	(gr_arc
		(start 414.639252 -43.652694)
		(mid 414.648885 -43.701212)
		(end 414.676336 -43.742356)
		(stroke
			(width 0.0635)
			(type default)
		)
		(layer "F.Cu")
	)
	(gr_line
		(start 414.639252 -43.368468)
		(end 414.639252 -43.652694)
		(stroke
			(width 0.0635)
			(type default)
		)
		(layer "F.Cu")
	)
	(gr_arc
		(start 414.676336 -274.148296)
		(mid 414.648889 -274.189442)
		(end 414.639252 -274.237958)
		(stroke
			(width 0.0635)
			(type default)
		)
		(layer "F.Cu")
	)
	(gr_line
		(start 414.676336 -274.148296)
		(end 414.701482 -274.12315)
		(stroke
			(width 0.0635)
			(type default)
		)
		(layer "F.Cu")
	)
	(gr_line
		(start 414.676336 -273.74596)
		(end 414.687258 -273.756882)
		(stroke
			(width 0.0635)
			(type default)
		)
		(layer "F.Cu")
	)
	(gr_arc
		(start 414.676336 -159.149542)
		(mid 414.648872 -159.190685)
		(end 414.639252 -159.239204)
		(stroke
			(width 0.0635)
			(type default)
		)
		(layer "F.Cu")
	)
	(gr_line
		(start 414.676336 -159.149542)
		(end 414.702752 -159.123126)
		(stroke
			(width 0.0635)
			(type default)
		)
		(layer "F.Cu")
	)
	(gr_line
		(start 414.676336 -158.748222)
		(end 414.684972 -158.756858)
		(stroke
			(width 0.0635)
			(type default)
		)
		(layer "F.Cu")
	)
	(gr_arc
		(start 414.676336 -44.16044)
		(mid 414.648871 -44.201583)
		(end 414.639252 -44.250102)
		(stroke
			(width 0.0635)
			(type default)
		)
		(layer "F.Cu")
	)
	(gr_line
		(start 414.676336 -44.16044)
		(end 414.713674 -44.123102)
		(stroke
			(width 0.0635)
			(type default)
		)
		(layer "F.Cu")
	)
	(gr_line
		(start 414.676336 -43.742356)
		(end 414.690814 -43.756834)
		(stroke
			(width 0.0635)
			(type default)
		)
		(layer "F.Cu")
	)
	(gr_arc
		(start 414.684972 -158.756858)
		(mid 414.726123 -158.784291)
		(end 414.774634 -158.793942)
		(stroke
			(width 0.0635)
			(type default)
		)
		(layer "F.Cu")
	)
	(gr_arc
		(start 414.687258 -273.756882)
		(mid 414.728409 -273.784315)
		(end 414.77692 -273.793966)
		(stroke
			(width 0.0635)
			(type default)
		)
		(layer "F.Cu")
	)
	(gr_arc
		(start 414.690814 -43.756834)
		(mid 414.731965 -43.784267)
		(end 414.780476 -43.793918)
		(stroke
			(width 0.0635)
			(type default)
		)
		(layer "F.Cu")
	)
	(gr_arc
		(start 414.791144 -274.086066)
		(mid 414.742631 -274.095709)
		(end 414.701482 -274.12315)
		(stroke
			(width 0.0635)
			(type default)
		)
		(layer "F.Cu")
	)
	(gr_arc
		(start 414.792414 -159.086042)
		(mid 414.743905 -159.095694)
		(end 414.702752 -159.123126)
		(stroke
			(width 0.0635)
			(type default)
		)
		(layer "F.Cu")
	)
	(gr_arc
		(start 414.803336 -44.086018)
		(mid 414.754827 -44.095667)
		(end 414.713674 -44.123102)
		(stroke
			(width 0.0635)
			(type default)
		)
		(layer "F.Cu")
	)
	(gr_line
		(start 415.602928 -274.148296)
		(end 415.674048 -274.219416)
		(stroke
			(width 0.0635)
			(type default)
		)
		(layer "F.Cu")
	)
	(gr_line
		(start 415.602928 -273.731736)
		(end 415.674048 -273.660616)
		(stroke
			(width 0.0635)
			(type default)
		)
		(layer "F.Cu")
	)
	(gr_line
		(start 415.602928 -159.148272)
		(end 415.674048 -159.219392)
		(stroke
			(width 0.0635)
			(type default)
		)
		(layer "F.Cu")
	)
	(gr_line
		(start 415.602928 -158.731712)
		(end 415.674048 -158.660592)
		(stroke
			(width 0.0635)
			(type default)
		)
		(layer "F.Cu")
	)
	(gr_line
		(start 415.602928 -44.148248)
		(end 415.674048 -44.219368)
		(stroke
			(width 0.0635)
			(type default)
		)
		(layer "F.Cu")
	)
	(gr_line
		(start 415.602928 -43.731688)
		(end 415.674048 -43.660568)
		(stroke
			(width 0.0635)
			(type default)
		)
		(layer "F.Cu")
	)
	(gr_line
		(start 415.674048 -274.219416)
		(end 416.005264 -274.219416)
		(stroke
			(width 0.0635)
			(type default)
		)
		(layer "F.Cu")
	)
	(gr_line
		(start 415.674048 -273.660616)
		(end 416.005264 -273.660616)
		(stroke
			(width 0.0635)
			(type default)
		)
		(layer "F.Cu")
	)
	(gr_line
		(start 415.674048 -159.219392)
		(end 416.005264 -159.219392)
		(stroke
			(width 0.0635)
			(type default)
		)
		(layer "F.Cu")
	)
	(gr_line
		(start 415.674048 -158.660592)
		(end 416.005264 -158.660592)
		(stroke
			(width 0.0635)
			(type default)
		)
		(layer "F.Cu")
	)
	(gr_line
		(start 415.674048 -44.219368)
		(end 416.005264 -44.219368)
		(stroke
			(width 0.0635)
			(type default)
		)
		(layer "F.Cu")
	)
	(gr_line
		(start 415.674048 -43.660568)
		(end 416.005264 -43.660568)
		(stroke
			(width 0.0635)
			(type default)
		)
		(layer "F.Cu")
	)
	(gr_line
		(start 416.564064 -274.219416)
		(end 417.12388 -274.219416)
		(stroke
			(width 0.0635)
			(type default)
		)
		(layer "F.Cu")
	)
	(gr_line
		(start 416.564064 -273.660616)
		(end 417.12388 -273.660616)
		(stroke
			(width 0.0635)
			(type default)
		)
		(layer "F.Cu")
	)
	(gr_line
		(start 416.564064 -159.219392)
		(end 416.99688 -159.219392)
		(stroke
			(width 0.0635)
			(type default)
		)
		(layer "F.Cu")
	)
	(gr_line
		(start 416.564064 -158.660592)
		(end 416.99688 -158.660592)
		(stroke
			(width 0.0635)
			(type default)
		)
		(layer "F.Cu")
	)
	(gr_line
		(start 416.564064 -44.219368)
		(end 417.07308 -44.219368)
		(stroke
			(width 0.0635)
			(type default)
		)
		(layer "F.Cu")
	)
	(gr_line
		(start 416.564064 -43.660568)
		(end 417.07308 -43.660568)
		(stroke
			(width 0.0635)
			(type default)
		)
		(layer "F.Cu")
	)
	(gr_line
		(start 416.99688 -159.219392)
		(end 417.068 -159.148272)
		(stroke
			(width 0.0635)
			(type default)
		)
		(layer "F.Cu")
	)
	(gr_line
		(start 416.99688 -158.660592)
		(end 417.068 -158.731712)
		(stroke
			(width 0.0635)
			(type default)
		)
		(layer "F.Cu")
	)
	(gr_line
		(start 417.07308 -44.219368)
		(end 417.1442 -44.148248)
		(stroke
			(width 0.0635)
			(type default)
		)
		(layer "F.Cu")
	)
	(gr_line
		(start 417.07308 -43.660568)
		(end 417.1442 -43.731688)
		(stroke
			(width 0.0635)
			(type default)
		)
		(layer "F.Cu")
	)
	(gr_line
		(start 417.12388 -274.219416)
		(end 417.195 -274.148296)
		(stroke
			(width 0.0635)
			(type default)
		)
		(layer "F.Cu")
	)
	(gr_line
		(start 417.12388 -273.660616)
		(end 417.195 -273.731736)
		(stroke
			(width 0.0635)
			(type default)
		)
		(layer "F.Cu")
	)
	(gr_line
		(start 419.389052 -278.02332)
		(end 419.389052 -278.321516)
		(stroke
			(width 0.0635)
			(type default)
		)
		(layer "F.Cu")
	)
	(gr_arc
		(start 419.389052 -277.476712)
		(mid 419.426324 -277.566694)
		(end 419.516306 -277.603966)
		(stroke
			(width 0.0635)
			(type default)
		)
		(layer "F.Cu")
	)
	(gr_line
		(start 419.389052 -277.178516)
		(end 419.389052 -277.476712)
		(stroke
			(width 0.0635)
			(type default)
		)
		(layer "F.Cu")
	)
	(gr_line
		(start 419.389052 -163.023296)
		(end 419.389052 -163.321492)
		(stroke
			(width 0.0635)
			(type default)
		)
		(layer "F.Cu")
	)
	(gr_arc
		(start 419.389052 -162.476688)
		(mid 419.426324 -162.56667)
		(end 419.516306 -162.603942)
		(stroke
			(width 0.0635)
			(type default)
		)
		(layer "F.Cu")
	)
	(gr_line
		(start 419.389052 -162.178492)
		(end 419.389052 -162.476688)
		(stroke
			(width 0.0635)
			(type default)
		)
		(layer "F.Cu")
	)
	(gr_line
		(start 419.389052 -48.023272)
		(end 419.389052 -48.321468)
		(stroke
			(width 0.0635)
			(type default)
		)
		(layer "F.Cu")
	)
	(gr_arc
		(start 419.389052 -47.476664)
		(mid 419.426324 -47.566646)
		(end 419.516306 -47.603918)
		(stroke
			(width 0.0635)
			(type default)
		)
		(layer "F.Cu")
	)
	(gr_line
		(start 419.389052 -47.178468)
		(end 419.389052 -47.476664)
		(stroke
			(width 0.0635)
			(type default)
		)
		(layer "F.Cu")
	)
	(gr_arc
		(start 419.516306 -277.896066)
		(mid 419.426327 -277.933337)
		(end 419.389052 -278.02332)
		(stroke
			(width 0.0635)
			(type default)
		)
		(layer "F.Cu")
	)
	(gr_arc
		(start 419.516306 -162.896042)
		(mid 419.426319 -162.933311)
		(end 419.389052 -163.023296)
		(stroke
			(width 0.0635)
			(type default)
		)
		(layer "F.Cu")
	)
	(gr_arc
		(start 419.516306 -47.896018)
		(mid 419.42631 -47.933286)
		(end 419.389052 -48.023272)
		(stroke
			(width 0.0635)
			(type default)
		)
		(layer "F.Cu")
	)
	(gr_line
		(start 420.478458 -162.978592)
		(end 420.563548 -163.063682)
		(stroke
			(width 0.0635)
			(type default)
		)
		(layer "F.Cu")
	)
	(gr_line
		(start 420.478458 -162.562032)
		(end 420.563548 -162.476942)
		(stroke
			(width 0.0635)
			(type default)
		)
		(layer "F.Cu")
	)
	(gr_line
		(start 420.482268 -277.974806)
		(end 420.563548 -278.056086)
		(stroke
			(width 0.0635)
			(type default)
		)
		(layer "F.Cu")
	)
	(gr_line
		(start 420.482268 -277.558246)
		(end 420.563548 -277.476966)
		(stroke
			(width 0.0635)
			(type default)
		)
		(layer "F.Cu")
	)
	(gr_line
		(start 420.489634 -47.967392)
		(end 420.563548 -48.041306)
		(stroke
			(width 0.0635)
			(type default)
		)
		(layer "F.Cu")
	)
	(gr_line
		(start 420.489634 -47.550832)
		(end 420.563548 -47.476918)
		(stroke
			(width 0.0635)
			(type default)
		)
		(layer "F.Cu")
	)
	(gr_line
		(start 420.498778 -274.148296)
		(end 420.563548 -274.213066)
		(stroke
			(width 0.0635)
			(type default)
		)
		(layer "F.Cu")
	)
	(gr_line
		(start 420.498778 -273.731736)
		(end 420.563548 -273.666966)
		(stroke
			(width 0.0635)
			(type default)
		)
		(layer "F.Cu")
	)
	(gr_line
		(start 420.498778 -159.148272)
		(end 420.563548 -159.213042)
		(stroke
			(width 0.0635)
			(type default)
		)
		(layer "F.Cu")
	)
	(gr_line
		(start 420.498778 -158.731712)
		(end 420.563548 -158.666942)
		(stroke
			(width 0.0635)
			(type default)
		)
		(layer "F.Cu")
	)
	(gr_line
		(start 420.498778 -44.148248)
		(end 420.563548 -44.213018)
		(stroke
			(width 0.0635)
			(type default)
		)
		(layer "F.Cu")
	)
	(gr_line
		(start 420.498778 -43.731688)
		(end 420.563548 -43.666918)
		(stroke
			(width 0.0635)
			(type default)
		)
		(layer "F.Cu")
	)
	(gr_line
		(start 420.563548 -278.186896)
		(end 420.761668 -278.385016)
		(stroke
			(width 0.0635)
			(type default)
		)
		(layer "F.Cu")
	)
	(gr_line
		(start 420.563548 -278.056086)
		(end 420.563548 -278.186896)
		(stroke
			(width 0.0635)
			(type default)
		)
		(layer "F.Cu")
	)
	(gr_line
		(start 420.563548 -277.242016)
		(end 420.563548 -277.476966)
		(stroke
			(width 0.0635)
			(type default)
		)
		(layer "F.Cu")
	)
	(gr_line
		(start 420.563548 -277.242016)
		(end 420.690548 -277.115016)
		(stroke
			(width 0.0635)
			(type default)
		)
		(layer "F.Cu")
	)
	(gr_line
		(start 420.563548 -274.448016)
		(end 420.690548 -274.575016)
		(stroke
			(width 0.0635)
			(type default)
		)
		(layer "F.Cu")
	)
	(gr_line
		(start 420.563548 -274.213066)
		(end 420.563548 -274.448016)
		(stroke
			(width 0.0635)
			(type default)
		)
		(layer "F.Cu")
	)
	(gr_line
		(start 420.563548 -273.432016)
		(end 420.563548 -273.666966)
		(stroke
			(width 0.0635)
			(type default)
		)
		(layer "F.Cu")
	)
	(gr_line
		(start 420.563548 -273.432016)
		(end 420.690548 -273.305016)
		(stroke
			(width 0.0635)
			(type default)
		)
		(layer "F.Cu")
	)
	(gr_line
		(start 420.563548 -163.242244)
		(end 420.706296 -163.384992)
		(stroke
			(width 0.0635)
			(type default)
		)
		(layer "F.Cu")
	)
	(gr_line
		(start 420.563548 -163.063682)
		(end 420.563548 -163.242244)
		(stroke
			(width 0.0635)
			(type default)
		)
		(layer "F.Cu")
	)
	(gr_line
		(start 420.563548 -162.241992)
		(end 420.563548 -162.476942)
		(stroke
			(width 0.0635)
			(type default)
		)
		(layer "F.Cu")
	)
	(gr_line
		(start 420.563548 -162.241992)
		(end 420.690548 -162.114992)
		(stroke
			(width 0.0635)
			(type default)
		)
		(layer "F.Cu")
	)
	(gr_line
		(start 420.563548 -159.447992)
		(end 420.690548 -159.574992)
		(stroke
			(width 0.0635)
			(type default)
		)
		(layer "F.Cu")
	)
	(gr_line
		(start 420.563548 -159.213042)
		(end 420.563548 -159.447992)
		(stroke
			(width 0.0635)
			(type default)
		)
		(layer "F.Cu")
	)
	(gr_line
		(start 420.563548 -158.431992)
		(end 420.563548 -158.666942)
		(stroke
			(width 0.0635)
			(type default)
		)
		(layer "F.Cu")
	)
	(gr_line
		(start 420.563548 -158.431992)
		(end 420.690548 -158.304992)
		(stroke
			(width 0.0635)
			(type default)
		)
		(layer "F.Cu")
	)
	(gr_line
		(start 420.563548 -48.22952)
		(end 420.718996 -48.384968)
		(stroke
			(width 0.0635)
			(type default)
		)
		(layer "F.Cu")
	)
	(gr_line
		(start 420.563548 -48.041306)
		(end 420.563548 -48.22952)
		(stroke
			(width 0.0635)
			(type default)
		)
		(layer "F.Cu")
	)
	(gr_line
		(start 420.563548 -47.241968)
		(end 420.563548 -47.476918)
		(stroke
			(width 0.0635)
			(type default)
		)
		(layer "F.Cu")
	)
	(gr_line
		(start 420.563548 -47.241968)
		(end 420.690548 -47.114968)
		(stroke
			(width 0.0635)
			(type default)
		)
		(layer "F.Cu")
	)
	(gr_line
		(start 420.563548 -44.447968)
		(end 420.690548 -44.574968)
		(stroke
			(width 0.0635)
			(type default)
		)
		(layer "F.Cu")
	)
	(gr_line
		(start 420.563548 -44.213018)
		(end 420.563548 -44.447968)
		(stroke
			(width 0.0635)
			(type default)
		)
		(layer "F.Cu")
	)
	(gr_line
		(start 420.563548 -43.431968)
		(end 420.563548 -43.666918)
		(stroke
			(width 0.0635)
			(type default)
		)
		(layer "F.Cu")
	)
	(gr_line
		(start 420.563548 -43.431968)
		(end 420.690548 -43.304968)
		(stroke
			(width 0.0635)
			(type default)
		)
		(layer "F.Cu")
	)
	(gr_line
		(start 420.690548 -277.115016)
		(end 422.025064 -277.115016)
		(stroke
			(width 0.0635)
			(type default)
		)
		(layer "F.Cu")
	)
	(gr_line
		(start 420.690548 -274.575016)
		(end 422.025064 -274.575016)
		(stroke
			(width 0.0635)
			(type default)
		)
		(layer "F.Cu")
	)
	(gr_line
		(start 420.690548 -273.305016)
		(end 422.025064 -273.305016)
		(stroke
			(width 0.0635)
			(type default)
		)
		(layer "F.Cu")
	)
	(gr_line
		(start 420.690548 -162.114992)
		(end 422.025064 -162.114992)
		(stroke
			(width 0.0635)
			(type default)
		)
		(layer "F.Cu")
	)
	(gr_line
		(start 420.690548 -159.574992)
		(end 422.025064 -159.574992)
		(stroke
			(width 0.0635)
			(type default)
		)
		(layer "F.Cu")
	)
	(gr_line
		(start 420.690548 -158.304992)
		(end 422.025064 -158.304992)
		(stroke
			(width 0.0635)
			(type default)
		)
		(layer "F.Cu")
	)
	(gr_line
		(start 420.690548 -47.114968)
		(end 422.025064 -47.114968)
		(stroke
			(width 0.0635)
			(type default)
		)
		(layer "F.Cu")
	)
	(gr_line
		(start 420.690548 -44.574968)
		(end 422.025064 -44.574968)
		(stroke
			(width 0.0635)
			(type default)
		)
		(layer "F.Cu")
	)
	(gr_line
		(start 420.690548 -43.304968)
		(end 422.025064 -43.304968)
		(stroke
			(width 0.0635)
			(type default)
		)
		(layer "F.Cu")
	)
	(gr_line
		(start 420.706296 -163.384992)
		(end 422.025064 -163.384992)
		(stroke
			(width 0.0635)
			(type default)
		)
		(layer "F.Cu")
	)
	(gr_line
		(start 420.718996 -48.384968)
		(end 422.025064 -48.384968)
		(stroke
			(width 0.0635)
			(type default)
		)
		(layer "F.Cu")
	)
	(gr_line
		(start 420.761668 -278.385016)
		(end 422.025064 -278.385016)
		(stroke
			(width 0.0635)
			(type default)
		)
		(layer "F.Cu")
	)
	(gr_line
		(start 438.2389 -163.044378)
		(end 438.2389 -163.321492)
		(stroke
			(width 0.0635)
			(type default)
		)
		(layer "F.Cu")
	)
	(gr_arc
		(start 438.2389 -162.455606)
		(mid 438.282351 -162.560479)
		(end 438.387236 -162.603942)
		(stroke
			(width 0.0635)
			(type default)
		)
		(layer "F.Cu")
	)
	(gr_line
		(start 438.2389 -162.178492)
		(end 438.2389 -162.455606)
		(stroke
			(width 0.0635)
			(type default)
		)
		(layer "F.Cu")
	)
	(gr_arc
		(start 438.387236 -162.896042)
		(mid 438.282347 -162.939489)
		(end 438.2389 -163.044378)
		(stroke
			(width 0.0635)
			(type default)
		)
		(layer "F.Cu")
	)
	(gr_line
		(start 439.8391 -159.236918)
		(end 439.8391 -159.511492)
		(stroke
			(width 0.0635)
			(type default)
		)
		(layer "F.Cu")
	)
	(gr_arc
		(start 439.8391 -158.653226)
		(mid 439.848736 -158.701744)
		(end 439.876184 -158.742888)
		(stroke
			(width 0.0635)
			(type default)
		)
		(layer "F.Cu")
	)
	(gr_line
		(start 439.8391 -158.368492)
		(end 439.8391 -158.653226)
		(stroke
			(width 0.0635)
			(type default)
		)
		(layer "F.Cu")
	)
	(gr_arc
		(start 439.876184 -159.147256)
		(mid 439.848751 -159.188407)
		(end 439.8391 -159.236918)
		(stroke
			(width 0.0635)
			(type default)
		)
		(layer "F.Cu")
	)
	(gr_line
		(start 439.876184 -159.147256)
		(end 439.900314 -159.123126)
		(stroke
			(width 0.0635)
			(type default)
		)
		(layer "F.Cu")
	)
	(gr_line
		(start 439.876184 -158.742888)
		(end 439.890154 -158.756858)
		(stroke
			(width 0.0635)
			(type default)
		)
		(layer "F.Cu")
	)
	(gr_arc
		(start 439.890154 -158.756858)
		(mid 439.931298 -158.78432)
		(end 439.979816 -158.793942)
		(stroke
			(width 0.0635)
			(type default)
		)
		(layer "F.Cu")
	)
	(gr_arc
		(start 439.989976 -159.086042)
		(mid 439.941458 -159.095675)
		(end 439.900314 -159.123126)
		(stroke
			(width 0.0635)
			(type default)
		)
		(layer "F.Cu")
	)
	(gr_line
		(start 440.802776 -159.148272)
		(end 440.873896 -159.219392)
		(stroke
			(width 0.0635)
			(type default)
		)
		(layer "F.Cu")
	)
	(gr_line
		(start 440.802776 -158.731712)
		(end 440.873896 -158.660592)
		(stroke
			(width 0.0635)
			(type default)
		)
		(layer "F.Cu")
	)
	(gr_line
		(start 440.873896 -159.219392)
		(end 441.205112 -159.219392)
		(stroke
			(width 0.0635)
			(type default)
		)
		(layer "F.Cu")
	)
	(gr_line
		(start 440.873896 -158.660592)
		(end 441.205112 -158.660592)
		(stroke
			(width 0.0635)
			(type default)
		)
		(layer "F.Cu")
	)
	(gr_line
		(start 441.763912 -159.219392)
		(end 442.222128 -159.219392)
		(stroke
			(width 0.0635)
			(type default)
		)
		(layer "F.Cu")
	)
	(gr_line
		(start 441.763912 -158.660592)
		(end 442.222128 -158.660592)
		(stroke
			(width 0.0635)
			(type default)
		)
		(layer "F.Cu")
	)
	(gr_line
		(start 442.222128 -159.219392)
		(end 442.293248 -159.148272)
		(stroke
			(width 0.0635)
			(type default)
		)
		(layer "F.Cu")
	)
	(gr_line
		(start 442.222128 -158.660592)
		(end 442.293248 -158.731712)
		(stroke
			(width 0.0635)
			(type default)
		)
		(layer "F.Cu")
	)
	(gr_line
		(start 446.1891 -274.237958)
		(end 446.1891 -274.511516)
		(stroke
			(width 0.0635)
			(type default)
		)
		(layer "F.Cu")
	)
	(gr_arc
		(start 446.1891 -273.628104)
		(mid 446.198733 -273.676622)
		(end 446.226184 -273.717766)
		(stroke
			(width 0.0635)
			(type default)
		)
		(layer "F.Cu")
	)
	(gr_line
		(start 446.1891 -273.368516)
		(end 446.1891 -273.628104)
		(stroke
			(width 0.0635)
			(type default)
		)
		(layer "F.Cu")
	)
	(gr_line
		(start 446.1891 -44.254166)
		(end 446.1891 -44.511468)
		(stroke
			(width 0.0635)
			(type default)
		)
		(layer "F.Cu")
	)
	(gr_arc
		(start 446.1891 -43.654472)
		(mid 446.198733 -43.70299)
		(end 446.226184 -43.744134)
		(stroke
			(width 0.0635)
			(type default)
		)
		(layer "F.Cu")
	)
	(gr_line
		(start 446.1891 -43.368468)
		(end 446.1891 -43.654472)
		(stroke
			(width 0.0635)
			(type default)
		)
		(layer "F.Cu")
	)
	(gr_arc
		(start 446.226184 -274.148296)
		(mid 446.198748 -274.189445)
		(end 446.1891 -274.237958)
		(stroke
			(width 0.0635)
			(type default)
		)
		(layer "F.Cu")
	)
	(gr_line
		(start 446.226184 -274.148296)
		(end 446.25133 -274.12315)
		(stroke
			(width 0.0635)
			(type default)
		)
		(layer "F.Cu")
	)
	(gr_line
		(start 446.226184 -273.717766)
		(end 446.2653 -273.756882)
		(stroke
			(width 0.0635)
			(type default)
		)
		(layer "F.Cu")
	)
	(gr_arc
		(start 446.226184 -44.164504)
		(mid 446.198751 -44.205654)
		(end 446.1891 -44.254166)
		(stroke
			(width 0.0635)
			(type default)
		)
		(layer "F.Cu")
	)
	(gr_line
		(start 446.226184 -44.164504)
		(end 446.267586 -44.123102)
		(stroke
			(width 0.0635)
			(type default)
		)
		(layer "F.Cu")
	)
	(gr_line
		(start 446.226184 -43.744134)
		(end 446.238884 -43.756834)
		(stroke
			(width 0.0635)
			(type default)
		)
		(layer "F.Cu")
	)
	(gr_arc
		(start 446.238884 -43.756834)
		(mid 446.280035 -43.784267)
		(end 446.328546 -43.793918)
		(stroke
			(width 0.0635)
			(type default)
		)
		(layer "F.Cu")
	)
	(gr_arc
		(start 446.2653 -273.756882)
		(mid 446.306451 -273.784315)
		(end 446.354962 -273.793966)
		(stroke
			(width 0.0635)
			(type default)
		)
		(layer "F.Cu")
	)
	(gr_arc
		(start 446.340992 -274.086066)
		(mid 446.292489 -274.095726)
		(end 446.25133 -274.12315)
		(stroke
			(width 0.0635)
			(type default)
		)
		(layer "F.Cu")
	)
	(gr_arc
		(start 446.357248 -44.086018)
		(mid 446.308737 -44.095663)
		(end 446.267586 -44.123102)
		(stroke
			(width 0.0635)
			(type default)
		)
		(layer "F.Cu")
	)
	(gr_line
		(start 447.152776 -274.148296)
		(end 447.223896 -274.219416)
		(stroke
			(width 0.0635)
			(type default)
		)
		(layer "F.Cu")
	)
	(gr_line
		(start 447.152776 -273.731736)
		(end 447.223896 -273.660616)
		(stroke
			(width 0.0635)
			(type default)
		)
		(layer "F.Cu")
	)
	(gr_line
		(start 447.152776 -44.148248)
		(end 447.223896 -44.219368)
		(stroke
			(width 0.0635)
			(type default)
		)
		(layer "F.Cu")
	)
	(gr_line
		(start 447.152776 -43.731688)
		(end 447.223896 -43.660568)
		(stroke
			(width 0.0635)
			(type default)
		)
		(layer "F.Cu")
	)
	(gr_line
		(start 447.223896 -274.219416)
		(end 447.555112 -274.219416)
		(stroke
			(width 0.0635)
			(type default)
		)
		(layer "F.Cu")
	)
	(gr_line
		(start 447.223896 -273.660616)
		(end 447.555112 -273.660616)
		(stroke
			(width 0.0635)
			(type default)
		)
		(layer "F.Cu")
	)
	(gr_line
		(start 447.223896 -44.219368)
		(end 447.555112 -44.219368)
		(stroke
			(width 0.0635)
			(type default)
		)
		(layer "F.Cu")
	)
	(gr_line
		(start 447.223896 -43.660568)
		(end 447.555112 -43.660568)
		(stroke
			(width 0.0635)
			(type default)
		)
		(layer "F.Cu")
	)
	(gr_line
		(start 448.113912 -274.219416)
		(end 448.597528 -274.219416)
		(stroke
			(width 0.0635)
			(type default)
		)
		(layer "F.Cu")
	)
	(gr_line
		(start 448.113912 -273.660616)
		(end 448.597528 -273.660616)
		(stroke
			(width 0.0635)
			(type default)
		)
		(layer "F.Cu")
	)
	(gr_line
		(start 448.113912 -44.219368)
		(end 448.622928 -44.219368)
		(stroke
			(width 0.0635)
			(type default)
		)
		(layer "F.Cu")
	)
	(gr_line
		(start 448.113912 -43.660568)
		(end 448.622928 -43.660568)
		(stroke
			(width 0.0635)
			(type default)
		)
		(layer "F.Cu")
	)
	(gr_line
		(start 448.597528 -274.219416)
		(end 448.668648 -274.148296)
		(stroke
			(width 0.0635)
			(type default)
		)
		(layer "F.Cu")
	)
	(gr_line
		(start 448.597528 -273.660616)
		(end 448.668648 -273.731736)
		(stroke
			(width 0.0635)
			(type default)
		)
		(layer "F.Cu")
	)
	(gr_line
		(start 448.622928 -44.219368)
		(end 448.694048 -44.148248)
		(stroke
			(width 0.0635)
			(type default)
		)
		(layer "F.Cu")
	)
	(gr_line
		(start 448.622928 -43.660568)
		(end 448.694048 -43.731688)
		(stroke
			(width 0.0635)
			(type default)
		)
		(layer "F.Cu")
	)
	(gr_line
		(start 450.9389 -278.05634)
		(end 450.9389 -278.321516)
		(stroke
			(width 0.0635)
			(type default)
		)
		(layer "F.Cu")
	)
	(gr_arc
		(start 450.9389 -277.443692)
		(mid 450.985843 -277.557023)
		(end 451.099174 -277.603966)
		(stroke
			(width 0.0635)
			(type default)
		)
		(layer "F.Cu")
	)
	(gr_line
		(start 450.9389 -277.178516)
		(end 450.9389 -277.443692)
		(stroke
			(width 0.0635)
			(type default)
		)
		(layer "F.Cu")
	)
	(gr_line
		(start 450.9389 -48.056038)
		(end 450.9389 -48.321468)
		(stroke
			(width 0.0635)
			(type default)
		)
		(layer "F.Cu")
	)
	(gr_arc
		(start 450.9389 -47.443898)
		(mid 450.985769 -47.557049)
		(end 451.09892 -47.603918)
		(stroke
			(width 0.0635)
			(type default)
		)
		(layer "F.Cu")
	)
	(gr_line
		(start 450.9389 -47.178468)
		(end 450.9389 -47.443898)
		(stroke
			(width 0.0635)
			(type default)
		)
		(layer "F.Cu")
	)
	(gr_arc
		(start 451.09892 -47.896018)
		(mid 450.985769 -47.942882)
		(end 450.9389 -48.056038)
		(stroke
			(width 0.0635)
			(type default)
		)
		(layer "F.Cu")
	)
	(gr_arc
		(start 451.099174 -277.896066)
		(mid 450.985874 -277.943021)
		(end 450.9389 -278.05634)
		(stroke
			(width 0.0635)
			(type default)
		)
		(layer "F.Cu")
	)
	(gr_line
		(start 452.0311 -277.975822)
		(end 452.113396 -278.058118)
		(stroke
			(width 0.0635)
			(type default)
		)
		(layer "F.Cu")
	)
	(gr_line
		(start 452.0311 -277.559262)
		(end 452.113396 -277.476966)
		(stroke
			(width 0.0635)
			(type default)
		)
		(layer "F.Cu")
	)
	(gr_line
		(start 452.03999 -162.966908)
		(end 452.113396 -163.040314)
		(stroke
			(width 0.0635)
			(type default)
		)
		(layer "F.Cu")
	)
	(gr_line
		(start 452.03999 -162.550348)
		(end 452.113396 -162.476942)
		(stroke
			(width 0.0635)
			(type default)
		)
		(layer "F.Cu")
	)
	(gr_line
		(start 452.041514 -47.96536)
		(end 452.113396 -48.037242)
		(stroke
			(width 0.0635)
			(type default)
		)
		(layer "F.Cu")
	)
	(gr_line
		(start 452.041514 -47.5488)
		(end 452.113396 -47.476918)
		(stroke
			(width 0.0635)
			(type default)
		)
		(layer "F.Cu")
	)
	(gr_line
		(start 452.048626 -274.148296)
		(end 452.113396 -274.213066)
		(stroke
			(width 0.0635)
			(type default)
		)
		(layer "F.Cu")
	)
	(gr_line
		(start 452.048626 -273.731736)
		(end 452.113396 -273.666966)
		(stroke
			(width 0.0635)
			(type default)
		)
		(layer "F.Cu")
	)
	(gr_line
		(start 452.048626 -159.148272)
		(end 452.113396 -159.213042)
		(stroke
			(width 0.0635)
			(type default)
		)
		(layer "F.Cu")
	)
	(gr_line
		(start 452.048626 -158.731712)
		(end 452.113396 -158.666942)
		(stroke
			(width 0.0635)
			(type default)
		)
		(layer "F.Cu")
	)
	(gr_line
		(start 452.048626 -44.148248)
		(end 452.113396 -44.213018)
		(stroke
			(width 0.0635)
			(type default)
		)
		(layer "F.Cu")
	)
	(gr_line
		(start 452.048626 -43.731688)
		(end 452.113396 -43.666918)
		(stroke
			(width 0.0635)
			(type default)
		)
		(layer "F.Cu")
	)
	(gr_line
		(start 452.113396 -278.189436)
		(end 452.308976 -278.385016)
		(stroke
			(width 0.0635)
			(type default)
		)
		(layer "F.Cu")
	)
	(gr_line
		(start 452.113396 -278.058118)
		(end 452.113396 -278.189436)
		(stroke
			(width 0.0635)
			(type default)
		)
		(layer "F.Cu")
	)
	(gr_line
		(start 452.113396 -277.242016)
		(end 452.113396 -277.476966)
		(stroke
			(width 0.0635)
			(type default)
		)
		(layer "F.Cu")
	)
	(gr_line
		(start 452.113396 -277.242016)
		(end 452.240396 -277.115016)
		(stroke
			(width 0.0635)
			(type default)
		)
		(layer "F.Cu")
	)
	(gr_line
		(start 452.113396 -274.448016)
		(end 452.240396 -274.575016)
		(stroke
			(width 0.0635)
			(type default)
		)
		(layer "F.Cu")
	)
	(gr_line
		(start 452.113396 -274.213066)
		(end 452.113396 -274.448016)
		(stroke
			(width 0.0635)
			(type default)
		)
		(layer "F.Cu")
	)
	(gr_line
		(start 452.113396 -273.432016)
		(end 452.113396 -273.666966)
		(stroke
			(width 0.0635)
			(type default)
		)
		(layer "F.Cu")
	)
	(gr_line
		(start 452.113396 -273.432016)
		(end 452.240396 -273.305016)
		(stroke
			(width 0.0635)
			(type default)
		)
		(layer "F.Cu")
	)
	(gr_line
		(start 452.113396 -163.227004)
		(end 452.271384 -163.384992)
		(stroke
			(width 0.0635)
			(type default)
		)
		(layer "F.Cu")
	)
	(gr_line
		(start 452.113396 -163.040314)
		(end 452.113396 -163.227004)
		(stroke
			(width 0.0635)
			(type default)
		)
		(layer "F.Cu")
	)
	(gr_line
		(start 452.113396 -162.241992)
		(end 452.113396 -162.476942)
		(stroke
			(width 0.0635)
			(type default)
		)
		(layer "F.Cu")
	)
	(gr_line
		(start 452.113396 -162.241992)
		(end 452.240396 -162.114992)
		(stroke
			(width 0.0635)
			(type default)
		)
		(layer "F.Cu")
	)
	(gr_line
		(start 452.113396 -159.447992)
		(end 452.240396 -159.574992)
		(stroke
			(width 0.0635)
			(type default)
		)
		(layer "F.Cu")
	)
	(gr_line
		(start 452.113396 -159.213042)
		(end 452.113396 -159.447992)
		(stroke
			(width 0.0635)
			(type default)
		)
		(layer "F.Cu")
	)
	(gr_line
		(start 452.113396 -158.431992)
		(end 452.113396 -158.666942)
		(stroke
			(width 0.0635)
			(type default)
		)
		(layer "F.Cu")
	)
	(gr_line
		(start 452.113396 -158.431992)
		(end 452.240396 -158.304992)
		(stroke
			(width 0.0635)
			(type default)
		)
		(layer "F.Cu")
	)
	(gr_line
		(start 452.113396 -48.202088)
		(end 452.296276 -48.384968)
		(stroke
			(width 0.0635)
			(type default)
		)
		(layer "F.Cu")
	)
	(gr_line
		(start 452.113396 -48.037242)
		(end 452.113396 -48.202088)
		(stroke
			(width 0.0635)
			(type default)
		)
		(layer "F.Cu")
	)
	(gr_line
		(start 452.113396 -47.241968)
		(end 452.113396 -47.476918)
		(stroke
			(width 0.0635)
			(type default)
		)
		(layer "F.Cu")
	)
	(gr_line
		(start 452.113396 -47.241968)
		(end 452.240396 -47.114968)
		(stroke
			(width 0.0635)
			(type default)
		)
		(layer "F.Cu")
	)
	(gr_line
		(start 452.113396 -44.447968)
		(end 452.240396 -44.574968)
		(stroke
			(width 0.0635)
			(type default)
		)
		(layer "F.Cu")
	)
	(gr_line
		(start 452.113396 -44.213018)
		(end 452.113396 -44.447968)
		(stroke
			(width 0.0635)
			(type default)
		)
		(layer "F.Cu")
	)
	(gr_line
		(start 452.113396 -43.431968)
		(end 452.113396 -43.666918)
		(stroke
			(width 0.0635)
			(type default)
		)
		(layer "F.Cu")
	)
	(gr_line
		(start 452.113396 -43.431968)
		(end 452.240396 -43.304968)
		(stroke
			(width 0.0635)
			(type default)
		)
		(layer "F.Cu")
	)
	(gr_line
		(start 452.240396 -277.115016)
		(end 453.574912 -277.115016)
		(stroke
			(width 0.0635)
			(type default)
		)
		(layer "F.Cu")
	)
	(gr_line
		(start 452.240396 -274.575016)
		(end 453.574912 -274.575016)
		(stroke
			(width 0.0635)
			(type default)
		)
		(layer "F.Cu")
	)
	(gr_line
		(start 452.240396 -273.305016)
		(end 453.574912 -273.305016)
		(stroke
			(width 0.0635)
			(type default)
		)
		(layer "F.Cu")
	)
	(gr_line
		(start 452.240396 -162.114992)
		(end 453.574912 -162.114992)
		(stroke
			(width 0.0635)
			(type default)
		)
		(layer "F.Cu")
	)
	(gr_line
		(start 452.240396 -159.574992)
		(end 453.574912 -159.574992)
		(stroke
			(width 0.0635)
			(type default)
		)
		(layer "F.Cu")
	)
	(gr_line
		(start 452.240396 -158.304992)
		(end 453.574912 -158.304992)
		(stroke
			(width 0.0635)
			(type default)
		)
		(layer "F.Cu")
	)
	(gr_line
		(start 452.240396 -47.114968)
		(end 453.574912 -47.114968)
		(stroke
			(width 0.0635)
			(type default)
		)
		(layer "F.Cu")
	)
	(gr_line
		(start 452.240396 -44.574968)
		(end 453.574912 -44.574968)
		(stroke
			(width 0.0635)
			(type default)
		)
		(layer "F.Cu")
	)
	(gr_line
		(start 452.240396 -43.304968)
		(end 453.574912 -43.304968)
		(stroke
			(width 0.0635)
			(type default)
		)
		(layer "F.Cu")
	)
	(gr_line
		(start 452.271384 -163.384992)
		(end 453.574912 -163.384992)
		(stroke
			(width 0.0635)
			(type default)
		)
		(layer "F.Cu")
	)
	(gr_line
		(start 452.296276 -48.384968)
		(end 453.574912 -48.384968)
		(stroke
			(width 0.0635)
			(type default)
		)
		(layer "F.Cu")
	)
	(gr_line
		(start 452.308976 -278.385016)
		(end 453.574912 -278.385016)
		(stroke
			(width 0.0635)
			(type default)
		)
		(layer "F.Cu")
	)
	(gr_line
		(start 477.739202 -274.234656)
		(end 477.739202 -274.511516)
		(stroke
			(width 0.0635)
			(type default)
		)
		(layer "F.Cu")
	)
	(gr_arc
		(start 477.739202 -273.654774)
		(mid 477.748835 -273.703292)
		(end 477.776286 -273.744436)
		(stroke
			(width 0.0635)
			(type default)
		)
		(layer "F.Cu")
	)
	(gr_line
		(start 477.739202 -273.368516)
		(end 477.739202 -273.654774)
		(stroke
			(width 0.0635)
			(type default)
		)
		(layer "F.Cu")
	)
	(gr_line
		(start 477.739202 -159.222948)
		(end 477.739202 -159.511492)
		(stroke
			(width 0.0635)
			(type default)
		)
		(layer "F.Cu")
	)
	(gr_arc
		(start 477.739202 -158.638748)
		(mid 477.748835 -158.687266)
		(end 477.776286 -158.72841)
		(stroke
			(width 0.0635)
			(type default)
		)
		(layer "F.Cu")
	)
	(gr_line
		(start 477.739202 -158.368492)
		(end 477.739202 -158.638748)
		(stroke
			(width 0.0635)
			(type default)
		)
		(layer "F.Cu")
	)
	(gr_line
		(start 477.739202 -44.240196)
		(end 477.739202 -44.511468)
		(stroke
			(width 0.0635)
			(type default)
		)
		(layer "F.Cu")
	)
	(gr_arc
		(start 477.739202 -43.655234)
		(mid 477.748835 -43.703752)
		(end 477.776286 -43.744896)
		(stroke
			(width 0.0635)
			(type default)
		)
		(layer "F.Cu")
	)
	(gr_line
		(start 477.739202 -43.368468)
		(end 477.739202 -43.655234)
		(stroke
			(width 0.0635)
			(type default)
		)
		(layer "F.Cu")
	)
	(gr_arc
		(start 477.776286 -274.144994)
		(mid 477.748849 -274.186143)
		(end 477.739202 -274.234656)
		(stroke
			(width 0.0635)
			(type default)
		)
		(layer "F.Cu")
	)
	(gr_line
		(start 477.776286 -274.144994)
		(end 477.79813 -274.12315)
		(stroke
			(width 0.0635)
			(type default)
		)
		(layer "F.Cu")
	)
	(gr_line
		(start 477.776286 -273.744436)
		(end 477.788732 -273.756882)
		(stroke
			(width 0.0635)
			(type default)
		)
		(layer "F.Cu")
	)
	(gr_arc
		(start 477.776286 -159.133286)
		(mid 477.748847 -159.174435)
		(end 477.739202 -159.222948)
		(stroke
			(width 0.0635)
			(type default)
		)
		(layer "F.Cu")
	)
	(gr_line
		(start 477.776286 -159.133286)
		(end 477.786446 -159.123126)
		(stroke
			(width 0.0635)
			(type default)
		)
		(layer "F.Cu")
	)
	(gr_line
		(start 477.776286 -158.72841)
		(end 477.804734 -158.756858)
		(stroke
			(width 0.0635)
			(type default)
		)
		(layer "F.Cu")
	)
	(gr_arc
		(start 477.776286 -44.150534)
		(mid 477.74883 -44.19168)
		(end 477.739202 -44.240196)
		(stroke
			(width 0.0635)
			(type default)
		)
		(layer "F.Cu")
	)
	(gr_line
		(start 477.776286 -44.150534)
		(end 477.803718 -44.123102)
		(stroke
			(width 0.0635)
			(type default)
		)
		(layer "F.Cu")
	)
	(gr_line
		(start 477.776286 -43.744896)
		(end 477.788224 -43.756834)
		(stroke
			(width 0.0635)
			(type default)
		)
		(layer "F.Cu")
	)
	(gr_arc
		(start 477.788224 -43.756834)
		(mid 477.829375 -43.784267)
		(end 477.877886 -43.793918)
		(stroke
			(width 0.0635)
			(type default)
		)
		(layer "F.Cu")
	)
	(gr_arc
		(start 477.788732 -273.756882)
		(mid 477.829883 -273.784315)
		(end 477.878394 -273.793966)
		(stroke
			(width 0.0635)
			(type default)
		)
		(layer "F.Cu")
	)
	(gr_arc
		(start 477.804734 -158.756858)
		(mid 477.845885 -158.784291)
		(end 477.894396 -158.793942)
		(stroke
			(width 0.0635)
			(type default)
		)
		(layer "F.Cu")
	)
	(gr_arc
		(start 477.876108 -159.086042)
		(mid 477.827601 -159.095696)
		(end 477.786446 -159.123126)
		(stroke
			(width 0.0635)
			(type default)
		)
		(layer "F.Cu")
	)
	(gr_arc
		(start 477.887792 -274.086066)
		(mid 477.839289 -274.095726)
		(end 477.79813 -274.12315)
		(stroke
			(width 0.0635)
			(type default)
		)
		(layer "F.Cu")
	)
	(gr_arc
		(start 477.89338 -44.086018)
		(mid 477.844883 -44.095685)
		(end 477.803718 -44.123102)
		(stroke
			(width 0.0635)
			(type default)
		)
		(layer "F.Cu")
	)
	(gr_line
		(start 478.702878 -274.148296)
		(end 478.773998 -274.219416)
		(stroke
			(width 0.0635)
			(type default)
		)
		(layer "F.Cu")
	)
	(gr_line
		(start 478.702878 -273.731736)
		(end 478.773998 -273.660616)
		(stroke
			(width 0.0635)
			(type default)
		)
		(layer "F.Cu")
	)
	(gr_line
		(start 478.702878 -159.148272)
		(end 478.773998 -159.219392)
		(stroke
			(width 0.0635)
			(type default)
		)
		(layer "F.Cu")
	)
	(gr_line
		(start 478.702878 -158.731712)
		(end 478.773998 -158.660592)
		(stroke
			(width 0.0635)
			(type default)
		)
		(layer "F.Cu")
	)
	(gr_line
		(start 478.702878 -44.148248)
		(end 478.773998 -44.219368)
		(stroke
			(width 0.0635)
			(type default)
		)
		(layer "F.Cu")
	)
	(gr_line
		(start 478.702878 -43.731688)
		(end 478.773998 -43.660568)
		(stroke
			(width 0.0635)
			(type default)
		)
		(layer "F.Cu")
	)
	(gr_line
		(start 478.773998 -274.219416)
		(end 479.105214 -274.219416)
		(stroke
			(width 0.0635)
			(type default)
		)
		(layer "F.Cu")
	)
	(gr_line
		(start 478.773998 -273.660616)
		(end 479.105214 -273.660616)
		(stroke
			(width 0.0635)
			(type default)
		)
		(layer "F.Cu")
	)
	(gr_line
		(start 478.773998 -159.219392)
		(end 479.105214 -159.219392)
		(stroke
			(width 0.0635)
			(type default)
		)
		(layer "F.Cu")
	)
	(gr_line
		(start 478.773998 -158.660592)
		(end 479.105214 -158.660592)
		(stroke
			(width 0.0635)
			(type default)
		)
		(layer "F.Cu")
	)
	(gr_line
		(start 478.773998 -44.219368)
		(end 479.105214 -44.219368)
		(stroke
			(width 0.0635)
			(type default)
		)
		(layer "F.Cu")
	)
	(gr_line
		(start 478.773998 -43.660568)
		(end 479.105214 -43.660568)
		(stroke
			(width 0.0635)
			(type default)
		)
		(layer "F.Cu")
	)
	(gr_line
		(start 479.664014 -274.219416)
		(end 480.19843 -274.219416)
		(stroke
			(width 0.0635)
			(type default)
		)
		(layer "F.Cu")
	)
	(gr_line
		(start 479.664014 -273.660616)
		(end 480.19843 -273.660616)
		(stroke
			(width 0.0635)
			(type default)
		)
		(layer "F.Cu")
	)
	(gr_line
		(start 479.664014 -159.219392)
		(end 480.24923 -159.219392)
		(stroke
			(width 0.0635)
			(type default)
		)
		(layer "F.Cu")
	)
	(gr_line
		(start 479.664014 -158.660592)
		(end 480.24923 -158.660592)
		(stroke
			(width 0.0635)
			(type default)
		)
		(layer "F.Cu")
	)
	(gr_line
		(start 479.664014 -44.219368)
		(end 480.17303 -44.219368)
		(stroke
			(width 0.0635)
			(type default)
		)
		(layer "F.Cu")
	)
	(gr_line
		(start 479.664014 -43.660568)
		(end 480.17303 -43.660568)
		(stroke
			(width 0.0635)
			(type default)
		)
		(layer "F.Cu")
	)
	(gr_line
		(start 480.17303 -44.219368)
		(end 480.24415 -44.148248)
		(stroke
			(width 0.0635)
			(type default)
		)
		(layer "F.Cu")
	)
	(gr_line
		(start 480.17303 -43.660568)
		(end 480.24415 -43.731688)
		(stroke
			(width 0.0635)
			(type default)
		)
		(layer "F.Cu")
	)
	(gr_line
		(start 480.19843 -274.219416)
		(end 480.26955 -274.148296)
		(stroke
			(width 0.0635)
			(type default)
		)
		(layer "F.Cu")
	)
	(gr_line
		(start 480.19843 -273.660616)
		(end 480.26955 -273.731736)
		(stroke
			(width 0.0635)
			(type default)
		)
		(layer "F.Cu")
	)
	(gr_line
		(start 480.24923 -159.219392)
		(end 480.32035 -159.148272)
		(stroke
			(width 0.0635)
			(type default)
		)
		(layer "F.Cu")
	)
	(gr_line
		(start 480.24923 -158.660592)
		(end 480.32035 -158.731712)
		(stroke
			(width 0.0635)
			(type default)
		)
		(layer "F.Cu")
	)
	(gr_line
		(start 482.489002 -278.02332)
		(end 482.489002 -278.321516)
		(stroke
			(width 0.0635)
			(type default)
		)
		(layer "F.Cu")
	)
	(gr_arc
		(start 482.489002 -277.476712)
		(mid 482.526274 -277.566694)
		(end 482.616256 -277.603966)
		(stroke
			(width 0.0635)
			(type default)
		)
		(layer "F.Cu")
	)
	(gr_line
		(start 482.489002 -277.178516)
		(end 482.489002 -277.476712)
		(stroke
			(width 0.0635)
			(type default)
		)
		(layer "F.Cu")
	)
	(gr_line
		(start 482.489002 -163.065714)
		(end 482.489002 -163.321492)
		(stroke
			(width 0.0635)
			(type default)
		)
		(layer "F.Cu")
	)
	(gr_arc
		(start 482.489002 -162.43427)
		(mid 482.538698 -162.554246)
		(end 482.658674 -162.603942)
		(stroke
			(width 0.0635)
			(type default)
		)
		(layer "F.Cu")
	)
	(gr_line
		(start 482.489002 -162.178492)
		(end 482.489002 -162.43427)
		(stroke
			(width 0.0635)
			(type default)
		)
		(layer "F.Cu")
	)
	(gr_line
		(start 482.489002 -48.05172)
		(end 482.489002 -48.321468)
		(stroke
			(width 0.0635)
			(type default)
		)
		(layer "F.Cu")
	)
	(gr_arc
		(start 482.489002 -47.448216)
		(mid 482.534606 -47.558314)
		(end 482.644704 -47.603918)
		(stroke
			(width 0.0635)
			(type default)
		)
		(layer "F.Cu")
	)
	(gr_line
		(start 482.489002 -47.178468)
		(end 482.489002 -47.448216)
		(stroke
			(width 0.0635)
			(type default)
		)
		(layer "F.Cu")
	)
	(gr_arc
		(start 482.616256 -277.896066)
		(mid 482.526309 -277.933355)
		(end 482.489002 -278.02332)
		(stroke
			(width 0.0635)
			(type default)
		)
		(layer "F.Cu")
	)
	(gr_arc
		(start 482.644704 -47.896018)
		(mid 482.534606 -47.941622)
		(end 482.489002 -48.05172)
		(stroke
			(width 0.0635)
			(type default)
		)
		(layer "F.Cu")
	)
	(gr_arc
		(start 482.658674 -162.896042)
		(mid 482.53872 -162.945748)
		(end 482.489002 -163.065714)
		(stroke
			(width 0.0635)
			(type default)
		)
		(layer "F.Cu")
	)
	(gr_line
		(start 483.581202 -162.975798)
		(end 483.663498 -163.058094)
		(stroke
			(width 0.0635)
			(type default)
		)
		(layer "F.Cu")
	)
	(gr_line
		(start 483.581202 -162.559238)
		(end 483.663498 -162.476942)
		(stroke
			(width 0.0635)
			(type default)
		)
		(layer "F.Cu")
	)
	(gr_line
		(start 483.587044 -277.96998)
		(end 483.663498 -278.046434)
		(stroke
			(width 0.0635)
			(type default)
		)
		(layer "F.Cu")
	)
	(gr_line
		(start 483.587044 -277.55342)
		(end 483.663498 -277.476966)
		(stroke
			(width 0.0635)
			(type default)
		)
		(layer "F.Cu")
	)
	(gr_line
		(start 483.594664 -47.962312)
		(end 483.663498 -48.031146)
		(stroke
			(width 0.0635)
			(type default)
		)
		(layer "F.Cu")
	)
	(gr_line
		(start 483.594664 -47.545752)
		(end 483.663498 -47.476918)
		(stroke
			(width 0.0635)
			(type default)
		)
		(layer "F.Cu")
	)
	(gr_line
		(start 483.598728 -274.148296)
		(end 483.663498 -274.213066)
		(stroke
			(width 0.0635)
			(type default)
		)
		(layer "F.Cu")
	)
	(gr_line
		(start 483.598728 -273.731736)
		(end 483.663498 -273.666966)
		(stroke
			(width 0.0635)
			(type default)
		)
		(layer "F.Cu")
	)
	(gr_line
		(start 483.598728 -159.148272)
		(end 483.663498 -159.213042)
		(stroke
			(width 0.0635)
			(type default)
		)
		(layer "F.Cu")
	)
	(gr_line
		(start 483.598728 -158.731712)
		(end 483.663498 -158.666942)
		(stroke
			(width 0.0635)
			(type default)
		)
		(layer "F.Cu")
	)
	(gr_line
		(start 483.598728 -44.148248)
		(end 483.663498 -44.213018)
		(stroke
			(width 0.0635)
			(type default)
		)
		(layer "F.Cu")
	)
	(gr_line
		(start 483.598728 -43.731688)
		(end 483.663498 -43.666918)
		(stroke
			(width 0.0635)
			(type default)
		)
		(layer "F.Cu")
	)
	(gr_line
		(start 483.663498 -278.20112)
		(end 483.847394 -278.385016)
		(stroke
			(width 0.0635)
			(type default)
		)
		(layer "F.Cu")
	)
	(gr_line
		(start 483.663498 -278.046434)
		(end 483.663498 -278.20112)
		(stroke
			(width 0.0635)
			(type default)
		)
		(layer "F.Cu")
	)
	(gr_line
		(start 483.663498 -277.242016)
		(end 483.663498 -277.476966)
		(stroke
			(width 0.0635)
			(type default)
		)
		(layer "F.Cu")
	)
	(gr_line
		(start 483.663498 -277.242016)
		(end 483.790498 -277.115016)
		(stroke
			(width 0.0635)
			(type default)
		)
		(layer "F.Cu")
	)
	(gr_line
		(start 483.663498 -274.448016)
		(end 483.790498 -274.575016)
		(stroke
			(width 0.0635)
			(type default)
		)
		(layer "F.Cu")
	)
	(gr_line
		(start 483.663498 -274.213066)
		(end 483.663498 -274.448016)
		(stroke
			(width 0.0635)
			(type default)
		)
		(layer "F.Cu")
	)
	(gr_line
		(start 483.663498 -273.432016)
		(end 483.663498 -273.666966)
		(stroke
			(width 0.0635)
			(type default)
		)
		(layer "F.Cu")
	)
	(gr_line
		(start 483.663498 -273.432016)
		(end 483.790498 -273.305016)
		(stroke
			(width 0.0635)
			(type default)
		)
		(layer "F.Cu")
	)
	(gr_line
		(start 483.663498 -163.224972)
		(end 483.823518 -163.384992)
		(stroke
			(width 0.0635)
			(type default)
		)
		(layer "F.Cu")
	)
	(gr_line
		(start 483.663498 -163.058094)
		(end 483.663498 -163.224972)
		(stroke
			(width 0.0635)
			(type default)
		)
		(layer "F.Cu")
	)
	(gr_line
		(start 483.663498 -162.241992)
		(end 483.663498 -162.476942)
		(stroke
			(width 0.0635)
			(type default)
		)
		(layer "F.Cu")
	)
	(gr_line
		(start 483.663498 -162.241992)
		(end 483.790498 -162.114992)
		(stroke
			(width 0.0635)
			(type default)
		)
		(layer "F.Cu")
	)
	(gr_line
		(start 483.663498 -159.447992)
		(end 483.790498 -159.574992)
		(stroke
			(width 0.0635)
			(type default)
		)
		(layer "F.Cu")
	)
	(gr_line
		(start 483.663498 -159.213042)
		(end 483.663498 -159.447992)
		(stroke
			(width 0.0635)
			(type default)
		)
		(layer "F.Cu")
	)
	(gr_line
		(start 483.663498 -158.431992)
		(end 483.663498 -158.666942)
		(stroke
			(width 0.0635)
			(type default)
		)
		(layer "F.Cu")
	)
	(gr_line
		(start 483.663498 -158.431992)
		(end 483.790498 -158.304992)
		(stroke
			(width 0.0635)
			(type default)
		)
		(layer "F.Cu")
	)
	(gr_line
		(start 483.663498 -48.198532)
		(end 483.849934 -48.384968)
		(stroke
			(width 0.0635)
			(type default)
		)
		(layer "F.Cu")
	)
	(gr_line
		(start 483.663498 -48.031146)
		(end 483.663498 -48.198532)
		(stroke
			(width 0.0635)
			(type default)
		)
		(layer "F.Cu")
	)
	(gr_line
		(start 483.663498 -47.241968)
		(end 483.663498 -47.476918)
		(stroke
			(width 0.0635)
			(type default)
		)
		(layer "F.Cu")
	)
	(gr_line
		(start 483.663498 -47.241968)
		(end 483.790498 -47.114968)
		(stroke
			(width 0.0635)
			(type default)
		)
		(layer "F.Cu")
	)
	(gr_line
		(start 483.663498 -44.447968)
		(end 483.790498 -44.574968)
		(stroke
			(width 0.0635)
			(type default)
		)
		(layer "F.Cu")
	)
	(gr_line
		(start 483.663498 -44.213018)
		(end 483.663498 -44.447968)
		(stroke
			(width 0.0635)
			(type default)
		)
		(layer "F.Cu")
	)
	(gr_line
		(start 483.663498 -43.431968)
		(end 483.663498 -43.666918)
		(stroke
			(width 0.0635)
			(type default)
		)
		(layer "F.Cu")
	)
	(gr_line
		(start 483.663498 -43.431968)
		(end 483.790498 -43.304968)
		(stroke
			(width 0.0635)
			(type default)
		)
		(layer "F.Cu")
	)
	(gr_line
		(start 483.790498 -277.115016)
		(end 485.125014 -277.115016)
		(stroke
			(width 0.0635)
			(type default)
		)
		(layer "F.Cu")
	)
	(gr_line
		(start 483.790498 -274.575016)
		(end 485.125014 -274.575016)
		(stroke
			(width 0.0635)
			(type default)
		)
		(layer "F.Cu")
	)
	(gr_line
		(start 483.790498 -273.305016)
		(end 485.125014 -273.305016)
		(stroke
			(width 0.0635)
			(type default)
		)
		(layer "F.Cu")
	)
	(gr_line
		(start 483.790498 -162.114992)
		(end 485.125014 -162.114992)
		(stroke
			(width 0.0635)
			(type default)
		)
		(layer "F.Cu")
	)
	(gr_line
		(start 483.790498 -159.574992)
		(end 485.125014 -159.574992)
		(stroke
			(width 0.0635)
			(type default)
		)
		(layer "F.Cu")
	)
	(gr_line
		(start 483.790498 -158.304992)
		(end 485.125014 -158.304992)
		(stroke
			(width 0.0635)
			(type default)
		)
		(layer "F.Cu")
	)
	(gr_line
		(start 483.790498 -47.114968)
		(end 485.125014 -47.114968)
		(stroke
			(width 0.0635)
			(type default)
		)
		(layer "F.Cu")
	)
	(gr_line
		(start 483.790498 -44.574968)
		(end 485.125014 -44.574968)
		(stroke
			(width 0.0635)
			(type default)
		)
		(layer "F.Cu")
	)
	(gr_line
		(start 483.790498 -43.304968)
		(end 485.125014 -43.304968)
		(stroke
			(width 0.0635)
			(type default)
		)
		(layer "F.Cu")
	)
	(gr_line
		(start 483.823518 -163.384992)
		(end 485.125014 -163.384992)
		(stroke
			(width 0.0635)
			(type default)
		)
		(layer "F.Cu")
	)
	(gr_line
		(start 483.847394 -278.385016)
		(end 485.125014 -278.385016)
		(stroke
			(width 0.0635)
			(type default)
		)
		(layer "F.Cu")
	)
	(gr_line
		(start 483.849934 -48.384968)
		(end 485.125014 -48.384968)
		(stroke
			(width 0.0635)
			(type default)
		)
		(layer "F.Cu")
	)
	(gr_arc
		(start 108.983526 -21.504148)
		(mid 109.101143 -21.455409)
		(end 109.149896 -21.337778)
		(stroke
			(width 0.08255)
			(type default)
		)
		(layer "B.Cu")
	)
	(gr_line
		(start 109.081062 -36.22294)
		(end 109.084872 -36.240974)
		(stroke
			(width 0.08255)
			(type default)
		)
		(layer "B.Cu")
	)
	(gr_line
		(start 109.084872 -36.24072)
		(end 109.084872 -36.240974)
		(stroke
			(width 0.08255)
			(type default)
		)
		(layer "B.Cu")
	)
	(gr_line
		(start 109.084872 -36.24072)
		(end 109.094778 -36.255706)
		(stroke
			(width 0.08255)
			(type default)
		)
		(layer "B.Cu")
	)
	(gr_arc
		(start 109.149896 -21.962618)
		(mid 109.101167 -21.844977)
		(end 108.983526 -21.796248)
		(stroke
			(width 0.08255)
			(type default)
		)
		(layer "B.Cu")
	)
	(gr_line
		(start 109.149896 -21.962618)
		(end 109.149896 -22.350222)
		(stroke
			(width 0.08255)
			(type default)
		)
		(layer "B.Cu")
	)
	(gr_line
		(start 109.149896 -20.950174)
		(end 109.149896 -21.337778)
		(stroke
			(width 0.08255)
			(type default)
		)
		(layer "B.Cu")
	)
	(gr_arc
		(start 110.783624 -22.504146)
		(mid 110.901241 -22.455407)
		(end 110.949994 -22.337776)
		(stroke
			(width 0.08255)
			(type default)
		)
		(layer "B.Cu")
	)
	(gr_line
		(start 110.820962 -35.985196)
		(end 110.824772 -36.00323)
		(stroke
			(width 0.08255)
			(type default)
		)
		(layer "B.Cu")
	)
	(gr_line
		(start 110.824772 -36.00323)
		(end 110.835186 -36.018978)
		(stroke
			(width 0.08255)
			(type default)
		)
		(layer "B.Cu")
	)
	(gr_arc
		(start 110.949994 -22.962616)
		(mid 110.901265 -22.844975)
		(end 110.783624 -22.796246)
		(stroke
			(width 0.08255)
			(type default)
		)
		(layer "B.Cu")
	)
	(gr_line
		(start 110.949994 -22.962616)
		(end 110.949994 -23.35022)
		(stroke
			(width 0.08255)
			(type default)
		)
		(layer "B.Cu")
	)
	(gr_line
		(start 110.949994 -21.950172)
		(end 110.949994 -22.337776)
		(stroke
			(width 0.08255)
			(type default)
		)
		(layer "B.Cu")
	)
	(gr_arc
		(start 112.583722 -21.504148)
		(mid 112.701341 -21.45541)
		(end 112.750092 -21.337778)
		(stroke
			(width 0.08255)
			(type default)
		)
		(layer "B.Cu")
	)
	(gr_line
		(start 112.60201 -35.19678)
		(end 112.60582 -35.21456)
		(stroke
			(width 0.08255)
			(type default)
		)
		(layer "B.Cu")
	)
	(gr_line
		(start 112.60582 -35.21456)
		(end 112.615726 -35.229292)
		(stroke
			(width 0.08255)
			(type default)
		)
		(layer "B.Cu")
	)
	(gr_arc
		(start 112.750092 -21.962618)
		(mid 112.701363 -21.844977)
		(end 112.583722 -21.796248)
		(stroke
			(width 0.08255)
			(type default)
		)
		(layer "B.Cu")
	)
	(gr_line
		(start 112.750092 -21.962618)
		(end 112.750092 -22.350222)
		(stroke
			(width 0.08255)
			(type default)
		)
		(layer "B.Cu")
	)
	(gr_line
		(start 112.750092 -20.950174)
		(end 112.750092 -21.337778)
		(stroke
			(width 0.08255)
			(type default)
		)
		(layer "B.Cu")
	)
	(gr_line
		(start 114.27333 -34.713672)
		(end 114.276886 -34.730436)
		(stroke
			(width 0.08255)
			(type default)
		)
		(layer "B.Cu")
	)
	(gr_line
		(start 114.276886 -34.730436)
		(end 114.286538 -34.745168)
		(stroke
			(width 0.08255)
			(type default)
		)
		(layer "B.Cu")
	)
	(gr_arc
		(start 114.383566 -22.504146)
		(mid 114.501221 -22.455428)
		(end 114.549936 -22.337776)
		(stroke
			(width 0.08255)
			(type default)
		)
		(layer "B.Cu")
	)
	(gr_arc
		(start 114.549936 -22.962616)
		(mid 114.501207 -22.844975)
		(end 114.383566 -22.796246)
		(stroke
			(width 0.08255)
			(type default)
		)
		(layer "B.Cu")
	)
	(gr_line
		(start 114.549936 -22.962616)
		(end 114.549936 -23.35022)
		(stroke
			(width 0.08255)
			(type default)
		)
		(layer "B.Cu")
	)
	(gr_line
		(start 114.549936 -21.950172)
		(end 114.549936 -22.337776)
		(stroke
			(width 0.08255)
			(type default)
		)
		(layer "B.Cu")
	)
	(gr_line
		(start 116.063522 -34.535618)
		(end 116.067078 -34.552382)
		(stroke
			(width 0.08255)
			(type default)
		)
		(layer "B.Cu")
	)
	(gr_line
		(start 116.067078 -34.552382)
		(end 116.07673 -34.567114)
		(stroke
			(width 0.08255)
			(type default)
		)
		(layer "B.Cu")
	)
	(gr_arc
		(start 116.183664 -21.504148)
		(mid 116.301321 -21.455431)
		(end 116.350034 -21.337778)
		(stroke
			(width 0.08255)
			(type default)
		)
		(layer "B.Cu")
	)
	(gr_arc
		(start 116.350034 -21.962618)
		(mid 116.301305 -21.844977)
		(end 116.183664 -21.796248)
		(stroke
			(width 0.08255)
			(type default)
		)
		(layer "B.Cu")
	)
	(gr_line
		(start 116.350034 -21.962618)
		(end 116.350034 -22.350222)
		(stroke
			(width 0.08255)
			(type default)
		)
		(layer "B.Cu")
	)
	(gr_line
		(start 116.350034 -20.950174)
		(end 116.350034 -21.337778)
		(stroke
			(width 0.08255)
			(type default)
		)
		(layer "B.Cu")
	)
	(gr_line
		(start 117.780308 -34.266378)
		(end 117.783864 -34.283142)
		(stroke
			(width 0.08255)
			(type default)
		)
		(layer "B.Cu")
	)
	(gr_line
		(start 117.783864 -34.283142)
		(end 117.793516 -34.297874)
		(stroke
			(width 0.08255)
			(type default)
		)
		(layer "B.Cu")
	)
	(gr_arc
		(start 117.983508 -22.504146)
		(mid 118.101136 -22.455413)
		(end 118.149878 -22.337776)
		(stroke
			(width 0.08255)
			(type default)
		)
		(layer "B.Cu")
	)
	(gr_arc
		(start 118.149878 -22.962616)
		(mid 118.101149 -22.844975)
		(end 117.983508 -22.796246)
		(stroke
			(width 0.08255)
			(type default)
		)
		(layer "B.Cu")
	)
	(gr_line
		(start 118.149878 -22.962616)
		(end 118.149878 -23.35022)
		(stroke
			(width 0.08255)
			(type default)
		)
		(layer "B.Cu")
	)
	(gr_line
		(start 118.149878 -21.950172)
		(end 118.149878 -22.337776)
		(stroke
			(width 0.08255)
			(type default)
		)
		(layer "B.Cu")
	)
	(gr_line
		(start 118.904004 -32.045402)
		(end 118.930928 -32.086042)
		(stroke
			(width 0.08255)
			(type default)
		)
		(layer "B.Cu")
	)
	(gr_arc
		(start 119.783606 -21.504148)
		(mid 119.901236 -21.455416)
		(end 119.949976 -21.337778)
		(stroke
			(width 0.08255)
			(type default)
		)
		(layer "B.Cu")
	)
	(gr_arc
		(start 119.949976 -21.962618)
		(mid 119.901247 -21.844977)
		(end 119.783606 -21.796248)
		(stroke
			(width 0.08255)
			(type default)
		)
		(layer "B.Cu")
	)
	(gr_line
		(start 119.949976 -21.962618)
		(end 119.949976 -22.350222)
		(stroke
			(width 0.08255)
			(type default)
		)
		(layer "B.Cu")
	)
	(gr_line
		(start 119.949976 -20.950174)
		(end 119.949976 -21.337778)
		(stroke
			(width 0.08255)
			(type default)
		)
		(layer "B.Cu")
	)
	(gr_line
		(start 120.703086 -41.593262)
		(end 120.716294 -41.613328)
		(stroke
			(width 0.08255)
			(type default)
		)
		(layer "B.Cu")
	)
	(gr_line
		(start 120.704102 -31.924244)
		(end 120.744234 -31.964376)
		(stroke
			(width 0.08255)
			(type default)
		)
		(layer "B.Cu")
	)
	(gr_line
		(start 120.716294 -41.613328)
		(end 120.736106 -41.626536)
		(stroke
			(width 0.08255)
			(type default)
		)
		(layer "B.Cu")
	)
	(gr_line
		(start 121.581672 -36.111688)
		(end 121.592848 -36.128706)
		(stroke
			(width 0.08255)
			(type default)
		)
		(layer "B.Cu")
	)
	(gr_arc
		(start 121.583704 -22.504146)
		(mid 121.701334 -22.455414)
		(end 121.750074 -22.337776)
		(stroke
			(width 0.08255)
			(type default)
		)
		(layer "B.Cu")
	)
	(gr_line
		(start 121.592848 -36.128706)
		(end 121.609612 -36.139882)
		(stroke
			(width 0.08255)
			(type default)
		)
		(layer "B.Cu")
	)
	(gr_line
		(start 121.670064 -40.180768)
		(end 121.682764 -40.199818)
		(stroke
			(width 0.08255)
			(type default)
		)
		(layer "B.Cu")
	)
	(gr_line
		(start 121.682764 -40.199818)
		(end 121.701814 -40.212518)
		(stroke
			(width 0.08255)
			(type default)
		)
		(layer "B.Cu")
	)
	(gr_arc
		(start 121.750074 -22.962616)
		(mid 121.701345 -22.844975)
		(end 121.583704 -22.796246)
		(stroke
			(width 0.08255)
			(type default)
		)
		(layer "B.Cu")
	)
	(gr_line
		(start 121.750074 -22.962616)
		(end 121.750074 -23.35022)
		(stroke
			(width 0.08255)
			(type default)
		)
		(layer "B.Cu")
	)
	(gr_line
		(start 121.750074 -21.950172)
		(end 121.750074 -22.337776)
		(stroke
			(width 0.08255)
			(type default)
		)
		(layer "B.Cu")
	)
	(gr_line
		(start 122.254518 -42.280586)
		(end 122.277378 -42.295826)
		(stroke
			(width 0.08255)
			(type default)
		)
		(layer "B.Cu")
	)
	(gr_line
		(start 122.277378 -42.295826)
		(end 122.291602 -42.319194)
		(stroke
			(width 0.08255)
			(type default)
		)
		(layer "B.Cu")
	)
	(gr_line
		(start 122.49785 -34.620962)
		(end 122.509026 -34.63798)
		(stroke
			(width 0.08255)
			(type default)
		)
		(layer "B.Cu")
	)
	(gr_line
		(start 122.509026 -34.63798)
		(end 122.52579 -34.649156)
		(stroke
			(width 0.08255)
			(type default)
		)
		(layer "B.Cu")
	)
	(gr_line
		(start 123.325128 -57.754012)
		(end 123.336558 -57.771284)
		(stroke
			(width 0.08255)
			(type default)
		)
		(layer "B.Cu")
	)
	(gr_line
		(start 123.336558 -57.771284)
		(end 123.35383 -57.782714)
		(stroke
			(width 0.08255)
			(type default)
		)
		(layer "B.Cu")
	)
	(gr_line
		(start 123.461526 -55.095394)
		(end 123.472956 -55.112666)
		(stroke
			(width 0.08255)
			(type default)
		)
		(layer "B.Cu")
	)
	(gr_line
		(start 123.472956 -55.112666)
		(end 123.490228 -55.124096)
		(stroke
			(width 0.08255)
			(type default)
		)
		(layer "B.Cu")
	)
	(gr_line
		(start 125.0823 -54.129178)
		(end 125.093984 -54.146958)
		(stroke
			(width 0.08255)
			(type default)
		)
		(layer "B.Cu")
	)
	(gr_line
		(start 125.093984 -54.146958)
		(end 125.111764 -54.158896)
		(stroke
			(width 0.08255)
			(type default)
		)
		(layer "B.Cu")
	)
	(gr_line
		(start 126.298452 -52.986432)
		(end 126.31166 -53.006498)
		(stroke
			(width 0.08255)
			(type default)
		)
		(layer "B.Cu")
	)
	(gr_line
		(start 126.31166 -53.006498)
		(end 126.331218 -53.019452)
		(stroke
			(width 0.08255)
			(type default)
		)
		(layer "B.Cu")
	)
	(gr_line
		(start 126.614682 -50.047144)
		(end 126.654052 -50.112168)
		(stroke
			(width 0.08255)
			(type default)
		)
		(layer "B.Cu")
	)
	(gr_line
		(start 126.654052 -50.112168)
		(end 126.72695 -50.13325)
		(stroke
			(width 0.08255)
			(type default)
		)
		(layer "B.Cu")
	)
	(gr_line
		(start 130.750056 -21.962618)
		(end 130.750056 -22.350222)
		(stroke
			(width 0.08255)
			(type default)
		)
		(layer "B.Cu")
	)
	(gr_arc
		(start 130.750056 -21.337778)
		(mid 130.798785 -21.455419)
		(end 130.916426 -21.504148)
		(stroke
			(width 0.08255)
			(type default)
		)
		(layer "B.Cu")
	)
	(gr_line
		(start 130.750056 -20.950174)
		(end 130.750056 -21.337778)
		(stroke
			(width 0.08255)
			(type default)
		)
		(layer "B.Cu")
	)
	(gr_arc
		(start 130.916426 -21.796248)
		(mid 130.798774 -21.844969)
		(end 130.750056 -21.962618)
		(stroke
			(width 0.08255)
			(type default)
		)
		(layer "B.Cu")
	)
	(gr_line
		(start 131.503928 -33.079182)
		(end 131.530852 -33.119822)
		(stroke
			(width 0.08255)
			(type default)
		)
		(layer "B.Cu")
	)
	(gr_line
		(start 132.5499 -22.962616)
		(end 132.5499 -23.35022)
		(stroke
			(width 0.08255)
			(type default)
		)
		(layer "B.Cu")
	)
	(gr_arc
		(start 132.5499 -22.337776)
		(mid 132.598629 -22.455417)
		(end 132.71627 -22.504146)
		(stroke
			(width 0.08255)
			(type default)
		)
		(layer "B.Cu")
	)
	(gr_line
		(start 132.5499 -21.950172)
		(end 132.5499 -22.337776)
		(stroke
			(width 0.08255)
			(type default)
		)
		(layer "B.Cu")
	)
	(gr_arc
		(start 132.71627 -22.796246)
		(mid 132.598654 -22.844986)
		(end 132.5499 -22.962616)
		(stroke
			(width 0.08255)
			(type default)
		)
		(layer "B.Cu")
	)
	(gr_line
		(start 133.303772 -32.856932)
		(end 133.330696 -32.897572)
		(stroke
			(width 0.08255)
			(type default)
		)
		(layer "B.Cu")
	)
	(gr_line
		(start 134.349998 -21.962618)
		(end 134.349998 -22.350222)
		(stroke
			(width 0.08255)
			(type default)
		)
		(layer "B.Cu")
	)
	(gr_arc
		(start 134.349998 -21.337778)
		(mid 134.398727 -21.455419)
		(end 134.516368 -21.504148)
		(stroke
			(width 0.08255)
			(type default)
		)
		(layer "B.Cu")
	)
	(gr_line
		(start 134.349998 -20.950174)
		(end 134.349998 -21.337778)
		(stroke
			(width 0.08255)
			(type default)
		)
		(layer "B.Cu")
	)
	(gr_arc
		(start 134.516368 -21.796248)
		(mid 134.398754 -21.844989)
		(end 134.349998 -21.962618)
		(stroke
			(width 0.08255)
			(type default)
		)
		(layer "B.Cu")
	)
	(gr_line
		(start 135.08101 -45.226732)
		(end 135.098028 -45.238162)
		(stroke
			(width 0.08255)
			(type default)
		)
		(layer "B.Cu")
	)
	(gr_line
		(start 135.098028 -45.238162)
		(end 135.118856 -45.24248)
		(stroke
			(width 0.08255)
			(type default)
		)
		(layer "B.Cu")
	)
	(gr_line
		(start 135.10387 -32.55772)
		(end 135.130794 -32.59836)
		(stroke
			(width 0.08255)
			(type default)
		)
		(layer "B.Cu")
	)
	(gr_line
		(start 135.11657 -65.556892)
		(end 135.654288 -65.912238)
		(stroke
			(width 0.08255)
			(type default)
		)
		(layer "B.Cu")
	)
	(gr_line
		(start 135.248904 -65.291208)
		(end 135.403844 -65.259712)
		(stroke
			(width 0.08255)
			(type default)
		)
		(layer "B.Cu")
	)
	(gr_line
		(start 135.403844 -65.259712)
		(end 135.817102 -65.532762)
		(stroke
			(width 0.08255)
			(type default)
		)
		(layer "B.Cu")
	)
	(gr_line
		(start 135.633206 -39.351204)
		(end 135.644382 -39.368222)
		(stroke
			(width 0.08255)
			(type default)
		)
		(layer "B.Cu")
	)
	(gr_line
		(start 135.644382 -39.368222)
		(end 135.661146 -39.379398)
		(stroke
			(width 0.08255)
			(type default)
		)
		(layer "B.Cu")
	)
	(gr_line
		(start 135.685022 -65.932812)
		(end 135.690864 -65.936622)
		(stroke
			(width 0.08255)
			(type default)
		)
		(layer "B.Cu")
	)
	(gr_line
		(start 135.817102 -65.532762)
		(end 135.848598 -65.687702)
		(stroke
			(width 0.08255)
			(type default)
		)
		(layer "B.Cu")
	)
	(gr_line
		(start 135.885428 -43.658028)
		(end 135.903208 -43.669966)
		(stroke
			(width 0.08255)
			(type default)
		)
		(layer "B.Cu")
	)
	(gr_line
		(start 135.903208 -43.669966)
		(end 135.925052 -43.674284)
		(stroke
			(width 0.08255)
			(type default)
		)
		(layer "B.Cu")
	)
	(gr_line
		(start 136.134602 -66.229738)
		(end 136.671558 -66.584576)
		(stroke
			(width 0.08255)
			(type default)
		)
		(layer "B.Cu")
	)
	(gr_line
		(start 136.150096 -22.962616)
		(end 136.150096 -23.35022)
		(stroke
			(width 0.08255)
			(type default)
		)
		(layer "B.Cu")
	)
	(gr_arc
		(start 136.150096 -22.337776)
		(mid 136.198825 -22.455417)
		(end 136.316466 -22.504146)
		(stroke
			(width 0.08255)
			(type default)
		)
		(layer "B.Cu")
	)
	(gr_line
		(start 136.150096 -21.950172)
		(end 136.150096 -22.337776)
		(stroke
			(width 0.08255)
			(type default)
		)
		(layer "B.Cu")
	)
	(gr_line
		(start 136.26592 -65.963546)
		(end 136.421114 -65.93205)
		(stroke
			(width 0.08255)
			(type default)
		)
		(layer "B.Cu")
	)
	(gr_arc
		(start 136.316466 -22.796246)
		(mid 136.198852 -22.844988)
		(end 136.150096 -22.962616)
		(stroke
			(width 0.08255)
			(type default)
		)
		(layer "B.Cu")
	)
	(gr_line
		(start 136.421114 -65.93205)
		(end 136.834372 -66.2051)
		(stroke
			(width 0.08255)
			(type default)
		)
		(layer "B.Cu")
	)
	(gr_line
		(start 136.834372 -66.2051)
		(end 136.865868 -66.36004)
		(stroke
			(width 0.08255)
			(type default)
		)
		(layer "B.Cu")
	)
	(gr_line
		(start 136.86155 -38.259766)
		(end 136.873488 -38.2778)
		(stroke
			(width 0.08255)
			(type default)
		)
		(layer "B.Cu")
	)
	(gr_line
		(start 136.873488 -38.2778)
		(end 136.891014 -38.289484)
		(stroke
			(width 0.08255)
			(type default)
		)
		(layer "B.Cu")
	)
	(gr_line
		(start 136.903968 -31.806896)
		(end 136.9314 -31.848806)
		(stroke
			(width 0.08255)
			(type default)
		)
		(layer "B.Cu")
	)
	(gr_line
		(start 137.151872 -66.902076)
		(end 137.690352 -67.25793)
		(stroke
			(width 0.08255)
			(type default)
		)
		(layer "B.Cu")
	)
	(gr_line
		(start 137.28319 -66.635884)
		(end 137.43813 -66.604388)
		(stroke
			(width 0.08255)
			(type default)
		)
		(layer "B.Cu")
	)
	(gr_line
		(start 137.43813 -66.604388)
		(end 137.851388 -66.877438)
		(stroke
			(width 0.08255)
			(type default)
		)
		(layer "B.Cu")
	)
	(gr_line
		(start 137.7442 -36.567364)
		(end 137.751312 -36.578032)
		(stroke
			(width 0.08255)
			(type default)
		)
		(layer "B.Cu")
	)
	(gr_line
		(start 137.751312 -36.578032)
		(end 137.760964 -36.585398)
		(stroke
			(width 0.08255)
			(type default)
		)
		(layer "B.Cu")
	)
	(gr_line
		(start 137.851388 -66.877438)
		(end 137.883138 -67.032632)
		(stroke
			(width 0.08255)
			(type default)
		)
		(layer "B.Cu")
	)
	(gr_line
		(start 137.94994 -21.962618)
		(end 137.94994 -22.350222)
		(stroke
			(width 0.08255)
			(type default)
		)
		(layer "B.Cu")
	)
	(gr_arc
		(start 137.94994 -21.337778)
		(mid 137.998669 -21.455419)
		(end 138.11631 -21.504148)
		(stroke
			(width 0.08255)
			(type default)
		)
		(layer "B.Cu")
	)
	(gr_line
		(start 137.94994 -20.950174)
		(end 137.94994 -21.337778)
		(stroke
			(width 0.08255)
			(type default)
		)
		(layer "B.Cu")
	)
	(gr_line
		(start 138.085068 -67.519042)
		(end 138.1379 -67.554094)
		(stroke
			(width 0.08255)
			(type default)
		)
		(layer "B.Cu")
	)
	(gr_arc
		(start 138.11631 -21.796248)
		(mid 137.998669 -21.844974)
		(end 137.94994 -21.962618)
		(stroke
			(width 0.08255)
			(type default)
		)
		(layer "B.Cu")
	)
	(gr_line
		(start 138.168888 -67.574414)
		(end 138.707368 -67.930268)
		(stroke
			(width 0.08255)
			(type default)
		)
		(layer "B.Cu")
	)
	(gr_line
		(start 138.282426 -67.299586)
		(end 138.296904 -67.308984)
		(stroke
			(width 0.08255)
			(type default)
		)
		(layer "B.Cu")
	)
	(gr_line
		(start 138.30046 -67.308222)
		(end 138.4554 -67.276472)
		(stroke
			(width 0.08255)
			(type default)
		)
		(layer "B.Cu")
	)
	(gr_line
		(start 138.4554 -67.276472)
		(end 138.868658 -67.549776)
		(stroke
			(width 0.08255)
			(type default)
		)
		(layer "B.Cu")
	)
	(gr_arc
		(start 138.704066 -31.572962)
		(mid 138.714771 -31.645887)
		(end 138.745976 -31.712662)
		(stroke
			(width 0.08255)
			(type default)
		)
		(layer "B.Cu")
	)
	(gr_line
		(start 138.745976 -31.712662)
		(end 138.758168 -31.731458)
		(stroke
			(width 0.08255)
			(type default)
		)
		(layer "B.Cu")
	)
	(gr_line
		(start 138.868658 -67.549776)
		(end 138.900154 -67.704716)
		(stroke
			(width 0.08255)
			(type default)
		)
		(layer "B.Cu")
	)
	(gr_arc
		(start 138.996166 -31.511748)
		(mid 139.003061 -31.559218)
		(end 139.023344 -31.60268)
		(stroke
			(width 0.08255)
			(type default)
		)
		(layer "B.Cu")
	)
	(gr_line
		(start 139.18565 -68.246244)
		(end 139.72413 -68.602098)
		(stroke
			(width 0.08255)
			(type default)
		)
		(layer "B.Cu")
	)
	(gr_line
		(start 139.317476 -67.980306)
		(end 139.472416 -67.94881)
		(stroke
			(width 0.08255)
			(type default)
		)
		(layer "B.Cu")
	)
	(gr_line
		(start 139.472416 -67.94881)
		(end 139.885674 -68.22186)
		(stroke
			(width 0.08255)
			(type default)
		)
		(layer "B.Cu")
	)
	(gr_line
		(start 139.601956 -52.164742)
		(end 139.61872 -52.175918)
		(stroke
			(width 0.08255)
			(type default)
		)
		(layer "B.Cu")
	)
	(gr_line
		(start 139.61872 -52.175918)
		(end 139.638024 -52.179474)
		(stroke
			(width 0.08255)
			(type default)
		)
		(layer "B.Cu")
	)
	(gr_line
		(start 139.702286 -36.057586)
		(end 139.713462 -36.074604)
		(stroke
			(width 0.08255)
			(type default)
		)
		(layer "B.Cu")
	)
	(gr_line
		(start 139.713462 -36.074604)
		(end 139.730226 -36.08578)
		(stroke
			(width 0.08255)
			(type default)
		)
		(layer "B.Cu")
	)
	(gr_line
		(start 139.750038 -22.962616)
		(end 139.750038 -23.35022)
		(stroke
			(width 0.08255)
			(type default)
		)
		(layer "B.Cu")
	)
	(gr_arc
		(start 139.750038 -22.337776)
		(mid 139.798767 -22.455417)
		(end 139.916408 -22.504146)
		(stroke
			(width 0.08255)
			(type default)
		)
		(layer "B.Cu")
	)
	(gr_line
		(start 139.750038 -21.950172)
		(end 139.750038 -22.337776)
		(stroke
			(width 0.08255)
			(type default)
		)
		(layer "B.Cu")
	)
	(gr_line
		(start 139.885674 -68.22186)
		(end 139.91717 -68.3768)
		(stroke
			(width 0.08255)
			(type default)
		)
		(layer "B.Cu")
	)
	(gr_arc
		(start 139.916408 -22.796246)
		(mid 139.798767 -22.844973)
		(end 139.750038 -22.962616)
		(stroke
			(width 0.08255)
			(type default)
		)
		(layer "B.Cu")
	)
	(gr_line
		(start 140.50391 -31.363666)
		(end 140.530834 -31.404306)
		(stroke
			(width 0.08255)
			(type default)
		)
		(layer "B.Cu")
	)
	(gr_line
		(start 140.69314 -34.66973)
		(end 140.72235 -34.71418)
		(stroke
			(width 0.08255)
			(type default)
		)
		(layer "B.Cu")
	)
	(gr_line
		(start 140.72235 -34.71418)
		(end 140.766546 -34.744152)
		(stroke
			(width 0.08255)
			(type default)
		)
		(layer "B.Cu")
	)
	(gr_arc
		(start 140.915898 -34.476944)
		(mid 140.936459 -34.502332)
		(end 140.961618 -34.523172)
		(stroke
			(width 0.08255)
			(type default)
		)
		(layer "B.Cu")
	)
	(gr_line
		(start 141.101064 -43.050206)
		(end 141.119606 -43.062652)
		(stroke
			(width 0.08255)
			(type default)
		)
		(layer "B.Cu")
	)
	(gr_line
		(start 141.119606 -43.062652)
		(end 141.141704 -43.06697)
		(stroke
			(width 0.08255)
			(type default)
		)
		(layer "B.Cu")
	)
	(gr_line
		(start 141.549882 -21.962618)
		(end 141.549882 -22.350222)
		(stroke
			(width 0.08255)
			(type default)
		)
		(layer "B.Cu")
	)
	(gr_arc
		(start 141.549882 -21.337778)
		(mid 141.598611 -21.455419)
		(end 141.716252 -21.504148)
		(stroke
			(width 0.08255)
			(type default)
		)
		(layer "B.Cu")
	)
	(gr_line
		(start 141.549882 -20.950174)
		(end 141.549882 -21.337778)
		(stroke
			(width 0.08255)
			(type default)
		)
		(layer "B.Cu")
	)
	(gr_line
		(start 141.608048 -41.472104)
		(end 141.62659 -41.48455)
		(stroke
			(width 0.08255)
			(type default)
		)
		(layer "B.Cu")
	)
	(gr_line
		(start 141.62659 -41.48455)
		(end 141.648688 -41.488868)
		(stroke
			(width 0.08255)
			(type default)
		)
		(layer "B.Cu")
	)
	(gr_arc
		(start 141.716252 -21.796248)
		(mid 141.598648 -21.844995)
		(end 141.549882 -21.962618)
		(stroke
			(width 0.08255)
			(type default)
		)
		(layer "B.Cu")
	)
	(gr_line
		(start 142.01902 -33.664144)
		(end 142.030196 -33.681162)
		(stroke
			(width 0.08255)
			(type default)
		)
		(layer "B.Cu")
	)
	(gr_line
		(start 142.030196 -33.681162)
		(end 142.04696 -33.692338)
		(stroke
			(width 0.08255)
			(type default)
		)
		(layer "B.Cu")
	)
	(gr_line
		(start 142.20825 -39.965122)
		(end 142.23238 -39.98341)
		(stroke
			(width 0.08255)
			(type default)
		)
		(layer "B.Cu")
	)
	(gr_line
		(start 142.23238 -39.98341)
		(end 142.262098 -39.989252)
		(stroke
			(width 0.08255)
			(type default)
		)
		(layer "B.Cu")
	)
	(gr_line
		(start 142.303754 -31.684214)
		(end 142.330678 -31.724854)
		(stroke
			(width 0.08255)
			(type default)
		)
		(layer "B.Cu")
	)
	(gr_line
		(start 142.653258 -32.215074)
		(end 142.664434 -32.232092)
		(stroke
			(width 0.08255)
			(type default)
		)
		(layer "B.Cu")
	)
	(gr_line
		(start 142.664434 -32.232092)
		(end 142.681198 -32.243268)
		(stroke
			(width 0.08255)
			(type default)
		)
		(layer "B.Cu")
	)
	(gr_line
		(start 142.888462 -34.259774)
		(end 142.906242 -34.271712)
		(stroke
			(width 0.08255)
			(type default)
		)
		(layer "B.Cu")
	)
	(gr_line
		(start 142.906242 -34.271712)
		(end 142.928086 -34.27603)
		(stroke
			(width 0.08255)
			(type default)
		)
		(layer "B.Cu")
	)
	(gr_line
		(start 142.996412 -36.249102)
		(end 143.014954 -36.261548)
		(stroke
			(width 0.08255)
			(type default)
		)
		(layer "B.Cu")
	)
	(gr_line
		(start 143.014954 -36.261548)
		(end 143.037052 -36.265866)
		(stroke
			(width 0.08255)
			(type default)
		)
		(layer "B.Cu")
	)
	(gr_line
		(start 143.340582 -32.688276)
		(end 143.358362 -32.700214)
		(stroke
			(width 0.08255)
			(type default)
		)
		(layer "B.Cu")
	)
	(gr_line
		(start 143.34998 -22.962616)
		(end 143.34998 -23.35022)
		(stroke
			(width 0.08255)
			(type default)
		)
		(layer "B.Cu")
	)
	(gr_arc
		(start 143.34998 -22.337776)
		(mid 143.398709 -22.455417)
		(end 143.51635 -22.504146)
		(stroke
			(width 0.08255)
			(type default)
		)
		(layer "B.Cu")
	)
	(gr_line
		(start 143.34998 -21.950172)
		(end 143.34998 -22.337776)
		(stroke
			(width 0.08255)
			(type default)
		)
		(layer "B.Cu")
	)
	(gr_line
		(start 143.358362 -32.700214)
		(end 143.380206 -32.704532)
		(stroke
			(width 0.08255)
			(type default)
		)
		(layer "B.Cu")
	)
	(gr_line
		(start 143.368014 -38.539928)
		(end 143.386556 -38.552374)
		(stroke
			(width 0.08255)
			(type default)
		)
		(layer "B.Cu")
	)
	(gr_line
		(start 143.386556 -38.552374)
		(end 143.38681 -38.552628)
		(stroke
			(width 0.08255)
			(type default)
		)
		(layer "B.Cu")
	)
	(gr_line
		(start 143.38681 -38.552374)
		(end 143.38681 -38.552628)
		(stroke
			(width 0.08255)
			(type default)
		)
		(layer "B.Cu")
	)
	(gr_line
		(start 143.38681 -38.552374)
		(end 143.408654 -38.556692)
		(stroke
			(width 0.08255)
			(type default)
		)
		(layer "B.Cu")
	)
	(gr_arc
		(start 143.51635 -22.796246)
		(mid 143.398747 -22.844993)
		(end 143.34998 -22.962616)
		(stroke
			(width 0.08255)
			(type default)
		)
		(layer "B.Cu")
	)
	(gr_line
		(start 146.583654 -47.276766)
		(end 146.603212 -47.28083)
		(stroke
			(width 0.08255)
			(type default)
		)
		(layer "B.Cu")
	)
	(gr_line
		(start 146.603212 -47.28083)
		(end 146.619722 -47.291752)
		(stroke
			(width 0.08255)
			(type default)
		)
		(layer "B.Cu")
	)
	(gr_line
		(start 147.776438 -45.679868)
		(end 147.798536 -45.684186)
		(stroke
			(width 0.08255)
			(type default)
		)
		(layer "B.Cu")
	)
	(gr_line
		(start 147.798536 -45.684186)
		(end 147.817078 -45.696632)
		(stroke
			(width 0.08255)
			(type default)
		)
		(layer "B.Cu")
	)
	(gr_line
		(start 148.095208 -74.13498)
		(end 148.110702 -74.145394)
		(stroke
			(width 0.08255)
			(type default)
		)
		(layer "B.Cu")
	)
	(gr_line
		(start 148.110702 -74.145394)
		(end 148.129498 -74.149204)
		(stroke
			(width 0.08255)
			(type default)
		)
		(layer "B.Cu")
	)
	(gr_line
		(start 148.278596 -67.546728)
		(end 148.294598 -67.557142)
		(stroke
			(width 0.08255)
			(type default)
		)
		(layer "B.Cu")
	)
	(gr_line
		(start 148.294598 -67.557142)
		(end 148.313394 -67.560952)
		(stroke
			(width 0.08255)
			(type default)
		)
		(layer "B.Cu")
	)
	(gr_line
		(start 148.711666 -138.174476)
		(end 149.182074 -137.704068)
		(stroke
			(width 0.127)
			(type default)
		)
		(layer "B.Cu")
	)
	(gr_line
		(start 148.711666 -136.583674)
		(end 149.182074 -137.054082)
		(stroke
			(width 0.127)
			(type default)
		)
		(layer "B.Cu")
	)
	(gr_line
		(start 150.520908 -73.015856)
		(end 150.53691 -73.02627)
		(stroke
			(width 0.08255)
			(type default)
		)
		(layer "B.Cu")
	)
	(gr_line
		(start 150.53691 -73.02627)
		(end 150.555706 -73.03008)
		(stroke
			(width 0.08255)
			(type default)
		)
		(layer "B.Cu")
	)
	(gr_line
		(start 150.599902 -50.277268)
		(end 150.61565 -50.287682)
		(stroke
			(width 0.08255)
			(type default)
		)
		(layer "B.Cu")
	)
	(gr_line
		(start 150.61565 -50.287682)
		(end 150.634192 -50.291492)
		(stroke
			(width 0.08255)
			(type default)
		)
		(layer "B.Cu")
	)
	(gr_line
		(start 151.148796 -71.517002)
		(end 151.165814 -71.528178)
		(stroke
			(width 0.08255)
			(type default)
		)
		(layer "B.Cu")
	)
	(gr_line
		(start 151.165814 -71.528178)
		(end 151.18588 -71.532242)
		(stroke
			(width 0.08255)
			(type default)
		)
		(layer "B.Cu")
	)
	(gr_line
		(start 151.332438 -37.878512)
		(end 151.351234 -37.882068)
		(stroke
			(width 0.08255)
			(type default)
		)
		(layer "B.Cu")
	)
	(gr_line
		(start 151.351234 -37.882068)
		(end 151.37003 -37.878512)
		(stroke
			(width 0.08255)
			(type default)
		)
		(layer "B.Cu")
	)
	(gr_line
		(start 151.73706 -48.693832)
		(end 151.754078 -48.705262)
		(stroke
			(width 0.08255)
			(type default)
		)
		(layer "B.Cu")
	)
	(gr_line
		(start 151.754078 -48.705262)
		(end 151.774906 -48.70958)
		(stroke
			(width 0.08255)
			(type default)
		)
		(layer "B.Cu")
	)
	(gr_line
		(start 152.032716 -36.045902)
		(end 152.051512 -36.049458)
		(stroke
			(width 0.08255)
			(type default)
		)
		(layer "B.Cu")
	)
	(gr_line
		(start 152.051512 -36.049458)
		(end 152.070308 -36.045902)
		(stroke
			(width 0.08255)
			(type default)
		)
		(layer "B.Cu")
	)
	(gr_line
		(start 152.144984 -34.408364)
		(end 152.16378 -34.41192)
		(stroke
			(width 0.08255)
			(type default)
		)
		(layer "B.Cu")
	)
	(gr_line
		(start 152.16378 -34.41192)
		(end 152.182576 -34.408364)
		(stroke
			(width 0.08255)
			(type default)
		)
		(layer "B.Cu")
	)
	(gr_line
		(start 154.264106 -42.322242)
		(end 154.284426 -42.326052)
		(stroke
			(width 0.08255)
			(type default)
		)
		(layer "B.Cu")
	)
	(gr_line
		(start 154.284426 -42.326052)
		(end 154.304746 -42.321988)
		(stroke
			(width 0.08255)
			(type default)
		)
		(layer "B.Cu")
	)
	(gr_line
		(start 154.363674 -40.686482)
		(end 154.384502 -40.690546)
		(stroke
			(width 0.08255)
			(type default)
		)
		(layer "B.Cu")
	)
	(gr_line
		(start 154.384502 -40.690546)
		(end 154.406092 -40.685974)
		(stroke
			(width 0.08255)
			(type default)
		)
		(layer "B.Cu")
	)
	(gr_line
		(start 154.460956 -137.689844)
		(end 154.770836 -137.999724)
		(stroke
			(width 0.127)
			(type default)
		)
		(layer "B.Cu")
	)
	(gr_line
		(start 154.460956 -137.039604)
		(end 154.770836 -136.729724)
		(stroke
			(width 0.127)
			(type default)
		)
		(layer "B.Cu")
	)
	(gr_line
		(start 155.109418 -20.355306)
		(end 155.128722 -20.351242)
		(stroke
			(width 0.08255)
			(type default)
		)
		(layer "B.Cu")
	)
	(gr_line
		(start 155.128722 -20.351242)
		(end 155.147772 -20.355052)
		(stroke
			(width 0.08255)
			(type default)
		)
		(layer "B.Cu")
	)
	(gr_line
		(start 155.142438 -44.111926)
		(end 155.163266 -44.11599)
		(stroke
			(width 0.08255)
			(type default)
		)
		(layer "B.Cu")
	)
	(gr_line
		(start 155.163266 -44.11599)
		(end 155.18384 -44.111672)
		(stroke
			(width 0.08255)
			(type default)
		)
		(layer "B.Cu")
	)
	(gr_line
		(start 155.83281 -45.922692)
		(end 155.8544 -45.926756)
		(stroke
			(width 0.08255)
			(type default)
		)
		(layer "B.Cu")
	)
	(gr_line
		(start 155.8544 -45.926756)
		(end 155.875736 -45.922184)
		(stroke
			(width 0.08255)
			(type default)
		)
		(layer "B.Cu")
	)
	(gr_line
		(start 157.512258 -51.684174)
		(end 158.168594 -51.817016)
		(stroke
			(width 0.08255)
			(type default)
		)
		(layer "B.Cu")
	)
	(gr_line
		(start 157.53715 -51.388518)
		(end 157.681168 -51.293014)
		(stroke
			(width 0.08255)
			(type default)
		)
		(layer "B.Cu")
	)
	(gr_line
		(start 157.681168 -51.293014)
		(end 158.166562 -51.391312)
		(stroke
			(width 0.08255)
			(type default)
		)
		(layer "B.Cu")
	)
	(gr_line
		(start 158.166562 -51.391312)
		(end 158.261812 -51.535076)
		(stroke
			(width 0.08255)
			(type default)
		)
		(layer "B.Cu")
	)
	(gr_line
		(start 158.72968 -51.9303)
		(end 159.38373 -52.062888)
		(stroke
			(width 0.08255)
			(type default)
		)
		(layer "B.Cu")
	)
	(gr_line
		(start 158.752286 -51.63439)
		(end 158.89605 -51.53914)
		(stroke
			(width 0.08255)
			(type default)
		)
		(layer "B.Cu")
	)
	(gr_line
		(start 158.89605 -51.53914)
		(end 159.381444 -51.637438)
		(stroke
			(width 0.08255)
			(type default)
		)
		(layer "B.Cu")
	)
	(gr_line
		(start 159.033464 -137.67435)
		(end 159.258 -137.898886)
		(stroke
			(width 0.127)
			(type default)
		)
		(layer "B.Cu")
	)
	(gr_line
		(start 159.033464 -137.02411)
		(end 159.258 -136.799574)
		(stroke
			(width 0.127)
			(type default)
		)
		(layer "B.Cu")
	)
	(gr_line
		(start 159.381444 -51.637438)
		(end 159.476948 -51.781202)
		(stroke
			(width 0.08255)
			(type default)
		)
		(layer "B.Cu")
	)
	(gr_line
		(start 159.943038 -52.176172)
		(end 160.59785 -52.30876)
		(stroke
			(width 0.08255)
			(type default)
		)
		(layer "B.Cu")
	)
	(gr_line
		(start 159.966914 -51.880516)
		(end 160.110932 -51.785012)
		(stroke
			(width 0.08255)
			(type default)
		)
		(layer "B.Cu")
	)
	(gr_line
		(start 160.110932 -51.785012)
		(end 160.596326 -51.88331)
		(stroke
			(width 0.08255)
			(type default)
		)
		(layer "B.Cu")
	)
	(gr_line
		(start 160.596326 -51.88331)
		(end 160.691576 -52.027074)
		(stroke
			(width 0.08255)
			(type default)
		)
		(layer "B.Cu")
	)
	(gr_line
		(start 173.568614 -147.441666)
		(end 174.057056 -146.953224)
		(stroke
			(width 0.127)
			(type default)
		)
		(layer "B.Cu")
	)
	(gr_line
		(start 174.390558 -61.07684)
		(end 174.413418 -61.081412)
		(stroke
			(width 0.08255)
			(type default)
		)
		(layer "B.Cu")
	)
	(gr_line
		(start 174.413418 -61.081412)
		(end 174.435262 -61.07684)
		(stroke
			(width 0.08255)
			(type default)
		)
		(layer "B.Cu")
	)
	(gr_line
		(start 174.707296 -146.953224)
		(end 175.195738 -147.441666)
		(stroke
			(width 0.127)
			(type default)
		)
		(layer "B.Cu")
	)
	(gr_line
		(start 175.63592 -59.178444)
		(end 175.656748 -59.182508)
		(stroke
			(width 0.08255)
			(type default)
		)
		(layer "B.Cu")
	)
	(gr_line
		(start 175.656748 -59.182508)
		(end 175.677322 -59.17819)
		(stroke
			(width 0.08255)
			(type default)
		)
		(layer "B.Cu")
	)
	(gr_line
		(start 176.40808 -55.509922)
		(end 176.43094 -55.514494)
		(stroke
			(width 0.08255)
			(type default)
		)
		(layer "B.Cu")
	)
	(gr_line
		(start 176.43094 -55.514494)
		(end 176.453546 -55.509668)
		(stroke
			(width 0.08255)
			(type default)
		)
		(layer "B.Cu")
	)
	(gr_line
		(start 176.533048 -53.745892)
		(end 176.554384 -53.75021)
		(stroke
			(width 0.08255)
			(type default)
		)
		(layer "B.Cu")
	)
	(gr_line
		(start 176.554384 -53.75021)
		(end 176.57572 -53.745892)
		(stroke
			(width 0.08255)
			(type default)
		)
		(layer "B.Cu")
	)
	(gr_line
		(start 182.85714 -39.972488)
		(end 182.878222 -39.96817)
		(stroke
			(width 0.08255)
			(type default)
		)
		(layer "B.Cu")
	)
	(gr_line
		(start 182.878222 -39.96817)
		(end 182.898542 -39.972234)
		(stroke
			(width 0.08255)
			(type default)
		)
		(layer "B.Cu")
	)
	(gr_line
		(start 184.526428 -26.491438)
		(end 184.546748 -26.495502)
		(stroke
			(width 0.08255)
			(type default)
		)
		(layer "B.Cu")
	)
	(gr_line
		(start 184.546748 -26.495502)
		(end 184.56783 -26.491184)
		(stroke
			(width 0.08255)
			(type default)
		)
		(layer "B.Cu")
	)
	(gr_line
		(start 189.451742 -79.13243)
		(end 190.110364 -79.26324)
		(stroke
			(width 0.08255)
			(type default)
		)
		(layer "B.Cu")
	)
	(gr_line
		(start 189.475364 -78.836774)
		(end 189.619128 -78.740762)
		(stroke
			(width 0.08255)
			(type default)
		)
		(layer "B.Cu")
	)
	(gr_line
		(start 189.619128 -78.740762)
		(end 190.10503 -78.837282)
		(stroke
			(width 0.08255)
			(type default)
		)
		(layer "B.Cu")
	)
	(gr_line
		(start 190.10503 -78.837282)
		(end 190.201042 -78.980792)
		(stroke
			(width 0.08255)
			(type default)
		)
		(layer "B.Cu")
	)
	(gr_line
		(start 190.666878 -79.373984)
		(end 191.325754 -79.504794)
		(stroke
			(width 0.08255)
			(type default)
		)
		(layer "B.Cu")
	)
	(gr_line
		(start 190.691516 -79.078328)
		(end 190.835026 -78.982316)
		(stroke
			(width 0.08255)
			(type default)
		)
		(layer "B.Cu")
	)
	(gr_line
		(start 190.835026 -78.982316)
		(end 191.320674 -79.078836)
		(stroke
			(width 0.08255)
			(type default)
		)
		(layer "B.Cu")
	)
	(gr_line
		(start 191.045846 -36.301934)
		(end 191.066928 -36.297616)
		(stroke
			(width 0.08255)
			(type default)
		)
		(layer "B.Cu")
	)
	(gr_line
		(start 191.066928 -36.297616)
		(end 191.087248 -36.30168)
		(stroke
			(width 0.08255)
			(type default)
		)
		(layer "B.Cu")
	)
	(gr_line
		(start 191.320674 -79.078836)
		(end 191.41694 -79.222346)
		(stroke
			(width 0.08255)
			(type default)
		)
		(layer "B.Cu")
	)
	(gr_line
		(start 191.884808 -79.615538)
		(end 192.539874 -79.74584)
		(stroke
			(width 0.08255)
			(type default)
		)
		(layer "B.Cu")
	)
	(gr_line
		(start 191.90716 -79.319882)
		(end 192.05067 -79.22387)
		(stroke
			(width 0.08255)
			(type default)
		)
		(layer "B.Cu")
	)
	(gr_line
		(start 192.05067 -79.22387)
		(end 192.536572 -79.32039)
		(stroke
			(width 0.08255)
			(type default)
		)
		(layer "B.Cu")
	)
	(gr_line
		(start 192.536572 -79.32039)
		(end 192.63233 -79.4639)
		(stroke
			(width 0.08255)
			(type default)
		)
		(layer "B.Cu")
	)
	(gr_line
		(start 195.281296 -80.290162)
		(end 195.9356 -80.42021)
		(stroke
			(width 0.08255)
			(type default)
		)
		(layer "B.Cu")
	)
	(gr_line
		(start 195.302378 -79.993998)
		(end 195.445888 -79.89824)
		(stroke
			(width 0.08255)
			(type default)
		)
		(layer "B.Cu")
	)
	(gr_line
		(start 195.445888 -79.89824)
		(end 195.93179 -79.99476)
		(stroke
			(width 0.08255)
			(type default)
		)
		(layer "B.Cu")
	)
	(gr_line
		(start 195.93179 -79.99476)
		(end 196.027548 -80.13827)
		(stroke
			(width 0.08255)
			(type default)
		)
		(layer "B.Cu")
	)
	(gr_line
		(start 196.47535 -33.539684)
		(end 196.49567 -33.53562)
		(stroke
			(width 0.08255)
			(type default)
		)
		(layer "B.Cu")
	)
	(gr_line
		(start 196.494146 -80.531462)
		(end 197.151498 -80.662018)
		(stroke
			(width 0.08255)
			(type default)
		)
		(layer "B.Cu")
	)
	(gr_line
		(start 196.49567 -33.53562)
		(end 196.51599 -33.53943)
		(stroke
			(width 0.08255)
			(type default)
		)
		(layer "B.Cu")
	)
	(gr_line
		(start 196.51853 -80.235552)
		(end 196.661786 -80.139794)
		(stroke
			(width 0.08255)
			(type default)
		)
		(layer "B.Cu")
	)
	(gr_line
		(start 196.661786 -80.139794)
		(end 197.147434 -80.236314)
		(stroke
			(width 0.08255)
			(type default)
		)
		(layer "B.Cu")
	)
	(gr_line
		(start 197.147434 -80.236314)
		(end 197.243446 -80.37957)
		(stroke
			(width 0.08255)
			(type default)
		)
		(layer "B.Cu")
	)
	(gr_line
		(start 197.361302 -54.33568)
		(end 197.45579 -54.191154)
		(stroke
			(width 0.08255)
			(type default)
		)
		(layer "B.Cu")
	)
	(gr_line
		(start 197.45579 -54.616858)
		(end 198.110348 -54.479952)
		(stroke
			(width 0.08255)
			(type default)
		)
		(layer "B.Cu")
	)
	(gr_line
		(start 197.45579 -54.191154)
		(end 197.940422 -54.089808)
		(stroke
			(width 0.08255)
			(type default)
		)
		(layer "B.Cu")
	)
	(gr_line
		(start 197.70471 -49.146968)
		(end 197.79996 -49.00295)
		(stroke
			(width 0.08255)
			(type default)
		)
		(layer "B.Cu")
	)
	(gr_line
		(start 197.709028 -80.772762)
		(end 198.367904 -80.903572)
		(stroke
			(width 0.08255)
			(type default)
		)
		(layer "B.Cu")
	)
	(gr_line
		(start 197.73392 -80.477106)
		(end 197.87743 -80.381094)
		(stroke
			(width 0.08255)
			(type default)
		)
		(layer "B.Cu")
	)
	(gr_line
		(start 197.79742 -49.428908)
		(end 198.45528 -49.29505)
		(stroke
			(width 0.08255)
			(type default)
		)
		(layer "B.Cu")
	)
	(gr_line
		(start 197.79996 -49.00295)
		(end 198.285354 -48.904398)
		(stroke
			(width 0.08255)
			(type default)
		)
		(layer "B.Cu")
	)
	(gr_line
		(start 197.87743 -80.381094)
		(end 198.363332 -80.477614)
		(stroke
			(width 0.08255)
			(type default)
		)
		(layer "B.Cu")
	)
	(gr_line
		(start 197.940422 -54.089808)
		(end 198.084694 -54.184042)
		(stroke
			(width 0.08255)
			(type default)
		)
		(layer "B.Cu")
	)
	(gr_line
		(start 198.142606 -50.679096)
		(end 198.163942 -50.674778)
		(stroke
			(width 0.08255)
			(type default)
		)
		(layer "B.Cu")
	)
	(gr_line
		(start 198.163942 -50.674778)
		(end 198.184516 -50.678842)
		(stroke
			(width 0.08255)
			(type default)
		)
		(layer "B.Cu")
	)
	(gr_line
		(start 198.285354 -48.904398)
		(end 198.429372 -48.999648)
		(stroke
			(width 0.08255)
			(type default)
		)
		(layer "B.Cu")
	)
	(gr_line
		(start 198.363332 -80.477614)
		(end 198.459344 -80.621124)
		(stroke
			(width 0.08255)
			(type default)
		)
		(layer "B.Cu")
	)
	(gr_line
		(start 198.574406 -54.08168)
		(end 198.668894 -53.937154)
		(stroke
			(width 0.08255)
			(type default)
		)
		(layer "B.Cu")
	)
	(gr_line
		(start 198.668894 -53.937154)
		(end 199.15378 -53.835554)
		(stroke
			(width 0.08255)
			(type default)
		)
		(layer "B.Cu")
	)
	(gr_line
		(start 198.670164 -54.362604)
		(end 199.323706 -54.225698)
		(stroke
			(width 0.08255)
			(type default)
		)
		(layer "B.Cu")
	)
	(gr_line
		(start 198.919592 -48.90008)
		(end 199.014588 -48.756062)
		(stroke
			(width 0.08255)
			(type default)
		)
		(layer "B.Cu")
	)
	(gr_line
		(start 199.013064 -49.181512)
		(end 199.668384 -49.048416)
		(stroke
			(width 0.08255)
			(type default)
		)
		(layer "B.Cu")
	)
	(gr_line
		(start 199.014588 -48.756062)
		(end 199.499982 -48.657256)
		(stroke
			(width 0.08255)
			(type default)
		)
		(layer "B.Cu")
	)
	(gr_line
		(start 199.15378 -53.835554)
		(end 199.298306 -53.930042)
		(stroke
			(width 0.08255)
			(type default)
		)
		(layer "B.Cu")
	)
	(gr_line
		(start 199.499982 -48.657256)
		(end 199.644 -48.752506)
		(stroke
			(width 0.08255)
			(type default)
		)
		(layer "B.Cu")
	)
	(gr_line
		(start 199.587358 -77.744574)
		(end 200.22947 -77.872082)
		(stroke
			(width 0.08255)
			(type default)
		)
		(layer "B.Cu")
	)
	(gr_line
		(start 199.612758 -77.448918)
		(end 199.74433 -77.36078)
		(stroke
			(width 0.08255)
			(type default)
		)
		(layer "B.Cu")
	)
	(gr_line
		(start 199.74433 -77.36078)
		(end 200.230232 -77.4573)
		(stroke
			(width 0.08255)
			(type default)
		)
		(layer "B.Cu")
	)
	(gr_line
		(start 199.787764 -53.827426)
		(end 199.881998 -53.683154)
		(stroke
			(width 0.08255)
			(type default)
		)
		(layer "B.Cu")
	)
	(gr_line
		(start 199.881998 -53.683154)
		(end 200.366884 -53.581554)
		(stroke
			(width 0.08255)
			(type default)
		)
		(layer "B.Cu")
	)
	(gr_line
		(start 199.882506 -54.108858)
		(end 200.537064 -53.971698)
		(stroke
			(width 0.08255)
			(type default)
		)
		(layer "B.Cu")
	)
	(gr_line
		(start 200.230232 -77.4573)
		(end 200.318116 -77.588872)
		(stroke
			(width 0.08255)
			(type default)
		)
		(layer "B.Cu")
	)
	(gr_line
		(start 200.366884 -53.581554)
		(end 200.51141 -53.676042)
		(stroke
			(width 0.08255)
			(type default)
		)
		(layer "B.Cu")
	)
	(gr_line
		(start 200.4441 -81.31556)
		(end 200.459848 -81.318862)
		(stroke
			(width 0.08255)
			(type default)
		)
		(layer "B.Cu")
	)
	(gr_line
		(start 200.459848 -81.318862)
		(end 200.476104 -81.316068)
		(stroke
			(width 0.08255)
			(type default)
		)
		(layer "B.Cu")
	)
	(gr_line
		(start 200.782682 -77.98181)
		(end 201.425048 -78.109572)
		(stroke
			(width 0.08255)
			(type default)
		)
		(layer "B.Cu")
	)
	(gr_line
		(start 200.80859 -77.686408)
		(end 200.940162 -77.59827)
		(stroke
			(width 0.08255)
			(type default)
		)
		(layer "B.Cu")
	)
	(gr_line
		(start 200.940162 -77.59827)
		(end 201.426064 -77.69479)
		(stroke
			(width 0.08255)
			(type default)
		)
		(layer "B.Cu")
	)
	(gr_line
		(start 200.953878 -80.93456)
		(end 201.04481 -80.805274)
		(stroke
			(width 0.08255)
			(type default)
		)
		(layer "B.Cu")
	)
	(gr_line
		(start 201.039476 -81.218786)
		(end 201.676508 -81.10855)
		(stroke
			(width 0.08255)
			(type default)
		)
		(layer "B.Cu")
	)
	(gr_line
		(start 201.04481 -80.805274)
		(end 201.532998 -80.7212)
		(stroke
			(width 0.08255)
			(type default)
		)
		(layer "B.Cu")
	)
	(gr_line
		(start 201.426064 -77.69479)
		(end 201.513948 -77.826362)
		(stroke
			(width 0.08255)
			(type default)
		)
		(layer "B.Cu")
	)
	(gr_line
		(start 201.459846 -55.11673)
		(end 201.48042 -55.112412)
		(stroke
			(width 0.08255)
			(type default)
		)
		(layer "B.Cu")
	)
	(gr_line
		(start 201.48042 -55.112412)
		(end 201.501248 -55.116476)
		(stroke
			(width 0.08255)
			(type default)
		)
		(layer "B.Cu")
	)
	(gr_line
		(start 201.532998 -80.7212)
		(end 201.662284 -80.812132)
		(stroke
			(width 0.08255)
			(type default)
		)
		(layer "B.Cu")
	)
	(gr_line
		(start 201.719434 -30.558232)
		(end 201.741024 -30.55366)
		(stroke
			(width 0.08255)
			(type default)
		)
		(layer "B.Cu")
	)
	(gr_line
		(start 201.741024 -30.55366)
		(end 201.761852 -30.557724)
		(stroke
			(width 0.08255)
			(type default)
		)
		(layer "B.Cu")
	)
	(gr_line
		(start 201.946256 -55.500778)
		(end 202.604878 -55.629048)
		(stroke
			(width 0.08255)
			(type default)
		)
		(layer "B.Cu")
	)
	(gr_line
		(start 201.969116 -55.205122)
		(end 202.112626 -55.108602)
		(stroke
			(width 0.08255)
			(type default)
		)
		(layer "B.Cu")
	)
	(gr_line
		(start 201.979276 -78.219554)
		(end 202.619102 -78.346554)
		(stroke
			(width 0.08255)
			(type default)
		)
		(layer "B.Cu")
	)
	(gr_line
		(start 201.999596 -81.052924)
		(end 202.204828 -81.017618)
		(stroke
			(width 0.08255)
			(type default)
		)
		(layer "B.Cu")
	)
	(gr_line
		(start 202.00112 -48.275494)
		(end 202.022456 -48.271176)
		(stroke
			(width 0.08255)
			(type default)
		)
		(layer "B.Cu")
	)
	(gr_line
		(start 202.004422 -77.923898)
		(end 202.135994 -77.83576)
		(stroke
			(width 0.08255)
			(type default)
		)
		(layer "B.Cu")
	)
	(gr_line
		(start 202.022456 -48.271176)
		(end 202.044046 -48.275494)
		(stroke
			(width 0.08255)
			(type default)
		)
		(layer "B.Cu")
	)
	(gr_line
		(start 202.112626 -55.108602)
		(end 202.598782 -55.20309)
		(stroke
			(width 0.08255)
			(type default)
		)
		(layer "B.Cu")
	)
	(gr_line
		(start 202.135994 -77.83576)
		(end 202.621896 -77.93228)
		(stroke
			(width 0.08255)
			(type default)
		)
		(layer "B.Cu")
	)
	(gr_line
		(start 202.139804 -80.732376)
		(end 202.153266 -80.73009)
		(stroke
			(width 0.08255)
			(type default)
		)
		(layer "B.Cu")
	)
	(gr_line
		(start 202.155298 -80.727042)
		(end 202.24623 -80.59801)
		(stroke
			(width 0.08255)
			(type default)
		)
		(layer "B.Cu")
	)
	(gr_line
		(start 202.15606 -341.383112)
		(end 202.164696 -341.421466)
		(stroke
			(width 0.08255)
			(type default)
		)
		(layer "B.Cu")
	)
	(gr_line
		(start 202.15606 -341.383112)
		(end 202.167236 -341.346282)
		(stroke
			(width 0.08255)
			(type default)
		)
		(layer "B.Cu")
	)
	(gr_line
		(start 202.191112 -53.326538)
		(end 202.212194 -53.32222)
		(stroke
			(width 0.08255)
			(type default)
		)
		(layer "B.Cu")
	)
	(gr_line
		(start 202.212194 -53.32222)
		(end 202.232514 -53.326284)
		(stroke
			(width 0.08255)
			(type default)
		)
		(layer "B.Cu")
	)
	(gr_line
		(start 202.243944 -81.010506)
		(end 202.875134 -80.901286)
		(stroke
			(width 0.08255)
			(type default)
		)
		(layer "B.Cu")
	)
	(gr_line
		(start 202.24623 -80.59801)
		(end 202.734418 -80.513682)
		(stroke
			(width 0.08255)
			(type default)
		)
		(layer "B.Cu")
	)
	(gr_line
		(start 202.598782 -55.20309)
		(end 202.695302 -55.346346)
		(stroke
			(width 0.08255)
			(type default)
		)
		(layer "B.Cu")
	)
	(gr_line
		(start 202.621896 -77.93228)
		(end 202.70978 -78.063852)
		(stroke
			(width 0.08255)
			(type default)
		)
		(layer "B.Cu")
	)
	(gr_line
		(start 202.730354 -358.18064)
		(end 202.736196 -358.15397)
		(stroke
			(width 0.08255)
			(type default)
		)
		(layer "B.Cu")
	)
	(gr_line
		(start 202.730354 -358.18064)
		(end 202.73645 -358.208072)
		(stroke
			(width 0.08255)
			(type default)
		)
		(layer "B.Cu")
	)
	(gr_line
		(start 202.734418 -80.513682)
		(end 202.863704 -80.604868)
		(stroke
			(width 0.08255)
			(type default)
		)
		(layer "B.Cu")
	)
	(gr_line
		(start 202.73645 -358.207818)
		(end 202.73645 -358.208326)
		(stroke
			(width 0.08255)
			(type default)
		)
		(layer "B.Cu")
	)
	(gr_line
		(start 202.753976 -48.71593)
		(end 203.408788 -48.847502)
		(stroke
			(width 0.08255)
			(type default)
		)
		(layer "B.Cu")
	)
	(gr_line
		(start 202.776582 -48.420274)
		(end 202.920346 -48.324516)
		(stroke
			(width 0.08255)
			(type default)
		)
		(layer "B.Cu")
	)
	(gr_line
		(start 202.920346 -48.324516)
		(end 203.405994 -48.422052)
		(stroke
			(width 0.08255)
			(type default)
		)
		(layer "B.Cu")
	)
	(gr_line
		(start 203.163932 -55.73776)
		(end 203.821538 -55.865522)
		(stroke
			(width 0.08255)
			(type default)
		)
		(layer "B.Cu")
	)
	(gr_line
		(start 203.176886 -78.457044)
		(end 203.200762 -78.46187)
		(stroke
			(width 0.08255)
			(type default)
		)
		(layer "B.Cu")
	)
	(gr_line
		(start 203.18603 -55.44185)
		(end 203.329286 -55.34533)
		(stroke
			(width 0.08255)
			(type default)
		)
		(layer "B.Cu")
	)
	(gr_line
		(start 203.200762 -78.46187)
		(end 203.224638 -78.456536)
		(stroke
			(width 0.08255)
			(type default)
		)
		(layer "B.Cu")
	)
	(gr_line
		(start 203.329286 -55.34533)
		(end 203.815442 -55.439818)
		(stroke
			(width 0.08255)
			(type default)
		)
		(layer "B.Cu")
	)
	(gr_line
		(start 203.356718 -80.519778)
		(end 203.447904 -80.390492)
		(stroke
			(width 0.08255)
			(type default)
		)
		(layer "B.Cu")
	)
	(gr_line
		(start 203.371196 -39.043864)
		(end 203.45908 -39.175436)
		(stroke
			(width 0.08255)
			(type default)
		)
		(layer "B.Cu")
	)
	(gr_line
		(start 203.405994 -48.422052)
		(end 203.501752 -48.565816)
		(stroke
			(width 0.08255)
			(type default)
		)
		(layer "B.Cu")
	)
	(gr_line
		(start 203.444348 -80.803242)
		(end 204.078078 -80.693768)
		(stroke
			(width 0.08255)
			(type default)
		)
		(layer "B.Cu")
	)
	(gr_line
		(start 203.447904 -80.390492)
		(end 203.935838 -80.306164)
		(stroke
			(width 0.08255)
			(type default)
		)
		(layer "B.Cu")
	)
	(gr_line
		(start 203.45908 -39.175436)
		(end 203.944982 -39.271956)
		(stroke
			(width 0.08255)
			(type default)
		)
		(layer "B.Cu")
	)
	(gr_line
		(start 203.463906 -38.761924)
		(end 204.099922 -38.888416)
		(stroke
			(width 0.08255)
			(type default)
		)
		(layer "B.Cu")
	)
	(gr_line
		(start 203.575158 -85.430106)
		(end 204.232002 -85.56371)
		(stroke
			(width 0.08255)
			(type default)
		)
		(layer "B.Cu")
	)
	(gr_line
		(start 203.599542 -85.13445)
		(end 203.74356 -85.0392)
		(stroke
			(width 0.08255)
			(type default)
		)
		(layer "B.Cu")
	)
	(gr_line
		(start 203.682854 -78.05293)
		(end 203.775564 -77.907388)
		(stroke
			(width 0.08255)
			(type default)
		)
		(layer "B.Cu")
	)
	(gr_line
		(start 203.73086 -53.922422)
		(end 204.387958 -54.053232)
		(stroke
			(width 0.08255)
			(type default)
		)
		(layer "B.Cu")
	)
	(gr_line
		(start 203.74356 -85.0392)
		(end 204.228954 -85.137752)
		(stroke
			(width 0.08255)
			(type default)
		)
		(layer "B.Cu")
	)
	(gr_line
		(start 203.754736 -53.626766)
		(end 203.898246 -53.530754)
		(stroke
			(width 0.08255)
			(type default)
		)
		(layer "B.Cu")
	)
	(gr_line
		(start 203.775564 -77.907388)
		(end 204.25918 -77.799946)
		(stroke
			(width 0.08255)
			(type default)
		)
		(layer "B.Cu")
	)
	(gr_line
		(start 203.782168 -78.332838)
		(end 204.43317 -78.188312)
		(stroke
			(width 0.08255)
			(type default)
		)
		(layer "B.Cu")
	)
	(gr_line
		(start 203.790042 -83.603338)
		(end 203.801218 -83.605624)
		(stroke
			(width 0.08255)
			(type default)
		)
		(layer "B.Cu")
	)
	(gr_line
		(start 203.801218 -83.605624)
		(end 203.812648 -83.6041)
		(stroke
			(width 0.08255)
			(type default)
		)
		(layer "B.Cu")
	)
	(gr_line
		(start 203.815442 -55.439818)
		(end 203.911962 -55.583074)
		(stroke
			(width 0.08255)
			(type default)
		)
		(layer "B.Cu")
	)
	(gr_line
		(start 203.885546 -341.608156)
		(end 203.894182 -341.64651)
		(stroke
			(width 0.08255)
			(type default)
		)
		(layer "B.Cu")
	)
	(gr_line
		(start 203.885546 -341.608156)
		(end 203.896722 -341.571326)
		(stroke
			(width 0.08255)
			(type default)
		)
		(layer "B.Cu")
	)
	(gr_line
		(start 203.898246 -53.530754)
		(end 204.383894 -53.627528)
		(stroke
			(width 0.08255)
			(type default)
		)
		(layer "B.Cu")
	)
	(gr_line
		(start 203.935838 -80.306164)
		(end 204.065124 -80.39735)
		(stroke
			(width 0.08255)
			(type default)
		)
		(layer "B.Cu")
	)
	(gr_line
		(start 203.944982 -39.271956)
		(end 204.076554 -39.184072)
		(stroke
			(width 0.08255)
			(type default)
		)
		(layer "B.Cu")
	)
	(gr_line
		(start 203.968858 -48.960024)
		(end 204.62367 -49.091596)
		(stroke
			(width 0.08255)
			(type default)
		)
		(layer "B.Cu")
	)
	(gr_line
		(start 203.991972 -48.664368)
		(end 204.135736 -48.56861)
		(stroke
			(width 0.08255)
			(type default)
		)
		(layer "B.Cu")
	)
	(gr_line
		(start 204.135736 -48.56861)
		(end 204.62113 -48.666146)
		(stroke
			(width 0.08255)
			(type default)
		)
		(layer "B.Cu")
	)
	(gr_line
		(start 204.228954 -85.137752)
		(end 204.324204 -85.28177)
		(stroke
			(width 0.08255)
			(type default)
		)
		(layer "B.Cu")
	)
	(gr_line
		(start 204.25918 -77.799946)
		(end 204.404722 -77.89291)
		(stroke
			(width 0.08255)
			(type default)
		)
		(layer "B.Cu")
	)
	(gr_line
		(start 204.30363 -83.241134)
		(end 204.408278 -83.10372)
		(stroke
			(width 0.08255)
			(type default)
		)
		(layer "B.Cu")
	)
	(gr_line
		(start 204.377798 -83.528408)
		(end 205.041246 -83.439508)
		(stroke
			(width 0.08255)
			(type default)
		)
		(layer "B.Cu")
	)
	(gr_line
		(start 204.3811 -55.974488)
		(end 205.038452 -56.10225)
		(stroke
			(width 0.08255)
			(type default)
		)
		(layer "B.Cu")
	)
	(gr_line
		(start 204.383894 -53.627528)
		(end 204.479906 -53.771038)
		(stroke
			(width 0.08255)
			(type default)
		)
		(layer "B.Cu")
	)
	(gr_line
		(start 204.402944 -55.678578)
		(end 204.545946 -55.581804)
		(stroke
			(width 0.08255)
			(type default)
		)
		(layer "B.Cu")
	)
	(gr_line
		(start 204.408278 -83.10372)
		(end 204.89926 -83.037934)
		(stroke
			(width 0.08255)
			(type default)
		)
		(layer "B.Cu")
	)
	(gr_line
		(start 204.464412 -358.46766)
		(end 204.470254 -358.44099)
		(stroke
			(width 0.08255)
			(type default)
		)
		(layer "B.Cu")
	)
	(gr_line
		(start 204.464412 -358.46766)
		(end 204.470508 -358.495092)
		(stroke
			(width 0.08255)
			(type default)
		)
		(layer "B.Cu")
	)
	(gr_line
		(start 204.470508 -358.494838)
		(end 204.470508 -358.495346)
		(stroke
			(width 0.08255)
			(type default)
		)
		(layer "B.Cu")
	)
	(gr_line
		(start 204.545946 -55.581804)
		(end 205.032102 -55.676546)
		(stroke
			(width 0.08255)
			(type default)
		)
		(layer "B.Cu")
	)
	(gr_line
		(start 204.567028 -39.281608)
		(end 204.654912 -39.41318)
		(stroke
			(width 0.08255)
			(type default)
		)
		(layer "B.Cu")
	)
	(gr_line
		(start 204.618336 -351.006156)
		(end 204.624432 -350.978978)
		(stroke
			(width 0.08255)
			(type default)
		)
		(layer "B.Cu")
	)
	(gr_line
		(start 204.618336 -350.9518)
		(end 204.624432 -350.978978)
		(stroke
			(width 0.08255)
			(type default)
		)
		(layer "B.Cu")
	)
	(gr_line
		(start 204.62113 -48.666146)
		(end 204.716888 -48.80991)
		(stroke
			(width 0.08255)
			(type default)
		)
		(layer "B.Cu")
	)
	(gr_line
		(start 204.654912 -39.41318)
		(end 205.140814 -39.5097)
		(stroke
			(width 0.08255)
			(type default)
		)
		(layer "B.Cu")
	)
	(gr_line
		(start 204.658976 -38.999414)
		(end 205.293976 -39.125652)
		(stroke
			(width 0.08255)
			(type default)
		)
		(layer "B.Cu")
	)
	(gr_line
		(start 204.789024 -85.677248)
		(end 205.446884 -85.811106)
		(stroke
			(width 0.08255)
			(type default)
		)
		(layer "B.Cu")
	)
	(gr_line
		(start 204.81417 -85.381592)
		(end 204.958188 -85.286342)
		(stroke
			(width 0.08255)
			(type default)
		)
		(layer "B.Cu")
	)
	(gr_line
		(start 204.89291 -77.784452)
		(end 204.98562 -77.63891)
		(stroke
			(width 0.08255)
			(type default)
		)
		(layer "B.Cu")
	)
	(gr_line
		(start 204.89926 -83.037934)
		(end 205.03642 -83.142836)
		(stroke
			(width 0.08255)
			(type default)
		)
		(layer "B.Cu")
	)
	(gr_line
		(start 204.946504 -54.164484)
		(end 205.603602 -54.295294)
		(stroke
			(width 0.08255)
			(type default)
		)
		(layer "B.Cu")
	)
	(gr_line
		(start 204.958188 -85.286342)
		(end 205.443582 -85.384894)
		(stroke
			(width 0.08255)
			(type default)
		)
		(layer "B.Cu")
	)
	(gr_line
		(start 204.970634 -53.868574)
		(end 205.11389 -53.772816)
		(stroke
			(width 0.08255)
			(type default)
		)
		(layer "B.Cu")
	)
	(gr_line
		(start 204.98562 -77.63891)
		(end 205.469236 -77.531468)
		(stroke
			(width 0.08255)
			(type default)
		)
		(layer "B.Cu")
	)
	(gr_line
		(start 204.991208 -78.06436)
		(end 205.64348 -77.91958)
		(stroke
			(width 0.08255)
			(type default)
		)
		(layer "B.Cu")
	)
	(gr_line
		(start 205.032102 -55.676546)
		(end 205.128876 -55.819802)
		(stroke
			(width 0.08255)
			(type default)
		)
		(layer "B.Cu")
	)
	(gr_line
		(start 205.11389 -53.772816)
		(end 205.599538 -53.869336)
		(stroke
			(width 0.08255)
			(type default)
		)
		(layer "B.Cu")
	)
	(gr_line
		(start 205.140814 -39.5097)
		(end 205.272132 -39.421816)
		(stroke
			(width 0.08255)
			(type default)
		)
		(layer "B.Cu")
	)
	(gr_line
		(start 205.182978 -49.203864)
		(end 205.840838 -49.335944)
		(stroke
			(width 0.08255)
			(type default)
		)
		(layer "B.Cu")
	)
	(gr_line
		(start 205.201012 -52.37099)
		(end 205.861158 -52.502054)
		(stroke
			(width 0.08255)
			(type default)
		)
		(layer "B.Cu")
	)
	(gr_line
		(start 205.206854 -48.908208)
		(end 205.350872 -48.812704)
		(stroke
			(width 0.08255)
			(type default)
		)
		(layer "B.Cu")
	)
	(gr_line
		(start 205.226158 -52.075334)
		(end 205.369668 -51.979322)
		(stroke
			(width 0.08255)
			(type default)
		)
		(layer "B.Cu")
	)
	(gr_line
		(start 205.285594 -35.544252)
		(end 205.37424 -35.67557)
		(stroke
			(width 0.08255)
			(type default)
		)
		(layer "B.Cu")
	)
	(gr_line
		(start 205.350872 -48.812704)
		(end 205.83652 -48.909986)
		(stroke
			(width 0.08255)
			(type default)
		)
		(layer "B.Cu")
	)
	(gr_line
		(start 205.369668 -51.979322)
		(end 205.85557 -52.075842)
		(stroke
			(width 0.08255)
			(type default)
		)
		(layer "B.Cu")
	)
	(gr_line
		(start 205.37424 -35.67557)
		(end 205.860396 -35.770058)
		(stroke
			(width 0.08255)
			(type default)
		)
		(layer "B.Cu")
	)
	(gr_line
		(start 205.37551 -35.26155)
		(end 206.01559 -35.385756)
		(stroke
			(width 0.08255)
			(type default)
		)
		(layer "B.Cu")
	)
	(gr_line
		(start 205.443582 -85.384894)
		(end 205.538832 -85.528912)
		(stroke
			(width 0.08255)
			(type default)
		)
		(layer "B.Cu")
	)
	(gr_line
		(start 205.469236 -77.531468)
		(end 205.615032 -77.624178)
		(stroke
			(width 0.08255)
			(type default)
		)
		(layer "B.Cu")
	)
	(gr_line
		(start 205.531974 -83.076288)
		(end 205.636876 -82.939128)
		(stroke
			(width 0.08255)
			(type default)
		)
		(layer "B.Cu")
	)
	(gr_line
		(start 205.59903 -56.211216)
		(end 206.253588 -56.33847)
		(stroke
			(width 0.08255)
			(type default)
		)
		(layer "B.Cu")
	)
	(gr_line
		(start 205.599538 -53.869336)
		(end 205.695296 -54.012846)
		(stroke
			(width 0.08255)
			(type default)
		)
		(layer "B.Cu")
	)
	(gr_line
		(start 205.606396 -83.363562)
		(end 206.271622 -83.274662)
		(stroke
			(width 0.08255)
			(type default)
		)
		(layer "B.Cu")
	)
	(gr_line
		(start 205.619604 -55.915052)
		(end 205.762606 -55.818532)
		(stroke
			(width 0.08255)
			(type default)
		)
		(layer "B.Cu")
	)
	(gr_line
		(start 205.636876 -82.939128)
		(end 206.127858 -82.873342)
		(stroke
			(width 0.08255)
			(type default)
		)
		(layer "B.Cu")
	)
	(gr_line
		(start 205.639162 -54.302152)
		(end 205.647036 -54.303676)
		(stroke
			(width 0.08255)
			(type default)
		)
		(layer "B.Cu")
	)
	(gr_line
		(start 205.697328 -54.015894)
		(end 205.703932 -54.017164)
		(stroke
			(width 0.08255)
			(type default)
		)
		(layer "B.Cu")
	)
	(gr_line
		(start 205.70571 -342.391492)
		(end 205.714346 -342.429846)
		(stroke
			(width 0.08255)
			(type default)
		)
		(layer "B.Cu")
	)
	(gr_line
		(start 205.70571 -342.391492)
		(end 205.716886 -342.354662)
		(stroke
			(width 0.08255)
			(type default)
		)
		(layer "B.Cu")
	)
	(gr_line
		(start 205.762606 -55.818532)
		(end 206.248762 -55.91302)
		(stroke
			(width 0.08255)
			(type default)
		)
		(layer "B.Cu")
	)
	(gr_line
		(start 205.76286 -39.519352)
		(end 205.850744 -39.650924)
		(stroke
			(width 0.08255)
			(type default)
		)
		(layer "B.Cu")
	)
	(gr_line
		(start 205.83652 -48.909986)
		(end 205.932278 -49.054004)
		(stroke
			(width 0.08255)
			(type default)
		)
		(layer "B.Cu")
	)
	(gr_line
		(start 205.850744 -39.650924)
		(end 206.336646 -39.747444)
		(stroke
			(width 0.08255)
			(type default)
		)
		(layer "B.Cu")
	)
	(gr_line
		(start 205.855062 -39.237412)
		(end 206.489808 -39.363396)
		(stroke
			(width 0.08255)
			(type default)
		)
		(layer "B.Cu")
	)
	(gr_line
		(start 205.85557 -52.075842)
		(end 205.951582 -52.219352)
		(stroke
			(width 0.08255)
			(type default)
		)
		(layer "B.Cu")
	)
	(gr_line
		(start 205.860396 -35.770058)
		(end 205.99146 -35.681412)
		(stroke
			(width 0.08255)
			(type default)
		)
		(layer "B.Cu")
	)
	(gr_line
		(start 206.004668 -85.92439)
		(end 206.009494 -85.925406)
		(stroke
			(width 0.08255)
			(type default)
		)
		(layer "B.Cu")
	)
	(gr_line
		(start 206.009494 -85.925406)
		(end 206.014066 -85.924898)
		(stroke
			(width 0.08255)
			(type default)
		)
		(layer "B.Cu")
	)
	(gr_line
		(start 206.096108 -358.453944)
		(end 206.10195 -358.427274)
		(stroke
			(width 0.08255)
			(type default)
		)
		(layer "B.Cu")
	)
	(gr_line
		(start 206.096108 -358.453944)
		(end 206.102204 -358.481376)
		(stroke
			(width 0.08255)
			(type default)
		)
		(layer "B.Cu")
	)
	(gr_line
		(start 206.102204 -358.481122)
		(end 206.102204 -358.48163)
		(stroke
			(width 0.08255)
			(type default)
		)
		(layer "B.Cu")
	)
	(gr_line
		(start 206.102966 -77.515974)
		(end 206.195676 -77.370178)
		(stroke
			(width 0.08255)
			(type default)
		)
		(layer "B.Cu")
	)
	(gr_line
		(start 206.127858 -82.873342)
		(end 206.265018 -82.978244)
		(stroke
			(width 0.08255)
			(type default)
		)
		(layer "B.Cu")
	)
	(gr_line
		(start 206.160878 -54.406292)
		(end 206.821024 -54.53761)
		(stroke
			(width 0.08255)
			(type default)
		)
		(layer "B.Cu")
	)
	(gr_line
		(start 206.168752 -393.481052)
		(end 206.174594 -393.454382)
		(stroke
			(width 0.08255)
			(type default)
		)
		(layer "B.Cu")
	)
	(gr_line
		(start 206.168752 -393.481052)
		(end 206.174848 -393.508484)
		(stroke
			(width 0.08255)
			(type default)
		)
		(layer "B.Cu")
	)
	(gr_line
		(start 206.174848 -393.50823)
		(end 206.174848 -393.508738)
		(stroke
			(width 0.08255)
			(type default)
		)
		(layer "B.Cu")
	)
	(gr_line
		(start 206.186024 -54.110636)
		(end 206.329534 -54.014624)
		(stroke
			(width 0.08255)
			(type default)
		)
		(layer "B.Cu")
	)
	(gr_line
		(start 206.195676 -77.370178)
		(end 206.679292 -77.26299)
		(stroke
			(width 0.08255)
			(type default)
		)
		(layer "B.Cu")
	)
	(gr_line
		(start 206.20228 -77.795628)
		(end 206.854298 -77.650848)
		(stroke
			(width 0.08255)
			(type default)
		)
		(layer "B.Cu")
	)
	(gr_line
		(start 206.248762 -55.91302)
		(end 206.345536 -56.056276)
		(stroke
			(width 0.08255)
			(type default)
		)
		(layer "B.Cu")
	)
	(gr_line
		(start 206.329534 -54.014624)
		(end 206.815436 -54.111398)
		(stroke
			(width 0.08255)
			(type default)
		)
		(layer "B.Cu")
	)
	(gr_line
		(start 206.336646 -39.747444)
		(end 206.467964 -39.65956)
		(stroke
			(width 0.08255)
			(type default)
		)
		(layer "B.Cu")
	)
	(gr_line
		(start 206.357474 -351.27184)
		(end 206.36357 -351.244662)
		(stroke
			(width 0.08255)
			(type default)
		)
		(layer "B.Cu")
	)
	(gr_line
		(start 206.357474 -351.217484)
		(end 206.36357 -351.244662)
		(stroke
			(width 0.08255)
			(type default)
		)
		(layer "B.Cu")
	)
	(gr_line
		(start 206.417418 -52.612544)
		(end 207.07604 -52.743354)
		(stroke
			(width 0.08255)
			(type default)
		)
		(layer "B.Cu")
	)
	(gr_line
		(start 206.442056 -52.316888)
		(end 206.585566 -52.220876)
		(stroke
			(width 0.08255)
			(type default)
		)
		(layer "B.Cu")
	)
	(gr_line
		(start 206.482442 -35.776916)
		(end 206.571088 -35.90798)
		(stroke
			(width 0.08255)
			(type default)
		)
		(layer "B.Cu")
	)
	(gr_line
		(start 206.571088 -35.90798)
		(end 207.057244 -36.002468)
		(stroke
			(width 0.08255)
			(type default)
		)
		(layer "B.Cu")
	)
	(gr_line
		(start 206.571088 -35.493706)
		(end 207.210152 -35.617912)
		(stroke
			(width 0.08255)
			(type default)
		)
		(layer "B.Cu")
	)
	(gr_line
		(start 206.585566 -52.220876)
		(end 207.071214 -52.317396)
		(stroke
			(width 0.08255)
			(type default)
		)
		(layer "B.Cu")
	)
	(gr_line
		(start 206.679292 -77.26299)
		(end 206.824834 -77.3557)
		(stroke
			(width 0.08255)
			(type default)
		)
		(layer "B.Cu")
	)
	(gr_line
		(start 206.760318 -82.911696)
		(end 206.865474 -82.774536)
		(stroke
			(width 0.08255)
			(type default)
		)
		(layer "B.Cu")
	)
	(gr_line
		(start 206.815436 -54.111398)
		(end 206.911448 -54.254908)
		(stroke
			(width 0.08255)
			(type default)
		)
		(layer "B.Cu")
	)
	(gr_line
		(start 206.832454 -83.199478)
		(end 207.499458 -83.11007)
		(stroke
			(width 0.08255)
			(type default)
		)
		(layer "B.Cu")
	)
	(gr_line
		(start 206.865474 -82.774536)
		(end 207.356202 -82.70875)
		(stroke
			(width 0.08255)
			(type default)
		)
		(layer "B.Cu")
	)
	(gr_line
		(start 206.958438 -39.756842)
		(end 207.046576 -39.888668)
		(stroke
			(width 0.08255)
			(type default)
		)
		(layer "B.Cu")
	)
	(gr_line
		(start 207.046576 -39.888668)
		(end 207.532478 -39.985188)
		(stroke
			(width 0.08255)
			(type default)
		)
		(layer "B.Cu")
	)
	(gr_line
		(start 207.049624 -39.474648)
		(end 207.685894 -39.60114)
		(stroke
			(width 0.08255)
			(type default)
		)
		(layer "B.Cu")
	)
	(gr_line
		(start 207.057244 -36.002468)
		(end 207.188054 -35.914076)
		(stroke
			(width 0.08255)
			(type default)
		)
		(layer "B.Cu")
	)
	(gr_line
		(start 207.071214 -52.317396)
		(end 207.167226 -52.460906)
		(stroke
			(width 0.08255)
			(type default)
		)
		(layer "B.Cu")
	)
	(gr_line
		(start 207.313022 -77.247496)
		(end 207.405732 -77.1017)
		(stroke
			(width 0.08255)
			(type default)
		)
		(layer "B.Cu")
	)
	(gr_line
		(start 207.356202 -82.70875)
		(end 207.493616 -82.813652)
		(stroke
			(width 0.08255)
			(type default)
		)
		(layer "B.Cu")
	)
	(gr_line
		(start 207.362806 -79.828136)
		(end 207.453992 -79.69885)
		(stroke
			(width 0.08255)
			(type default)
		)
		(layer "B.Cu")
	)
	(gr_line
		(start 207.377284 -54.648354)
		(end 208.035906 -54.779418)
		(stroke
			(width 0.08255)
			(type default)
		)
		(layer "B.Cu")
	)
	(gr_line
		(start 207.401922 -54.352444)
		(end 207.545178 -54.256686)
		(stroke
			(width 0.08255)
			(type default)
		)
		(layer "B.Cu")
	)
	(gr_line
		(start 207.405732 -77.1017)
		(end 207.889348 -76.994512)
		(stroke
			(width 0.08255)
			(type default)
		)
		(layer "B.Cu")
	)
	(gr_line
		(start 207.411574 -77.527404)
		(end 208.063592 -77.382624)
		(stroke
			(width 0.08255)
			(type default)
		)
		(layer "B.Cu")
	)
	(gr_line
		(start 207.42656 -342.834214)
		(end 207.435196 -342.872568)
		(stroke
			(width 0.08255)
			(type default)
		)
		(layer "B.Cu")
	)
	(gr_line
		(start 207.42656 -342.834214)
		(end 207.437736 -342.797384)
		(stroke
			(width 0.08255)
			(type default)
		)
		(layer "B.Cu")
	)
	(gr_line
		(start 207.451452 -80.111346)
		(end 208.083912 -80.002126)
		(stroke
			(width 0.08255)
			(type default)
		)
		(layer "B.Cu")
	)
	(gr_line
		(start 207.453992 -79.69885)
		(end 207.94218 -79.614522)
		(stroke
			(width 0.08255)
			(type default)
		)
		(layer "B.Cu")
	)
	(gr_line
		(start 207.532478 -39.985188)
		(end 207.66405 -39.897304)
		(stroke
			(width 0.08255)
			(type default)
		)
		(layer "B.Cu")
	)
	(gr_line
		(start 207.545178 -54.256686)
		(end 208.03108 -54.353206)
		(stroke
			(width 0.08255)
			(type default)
		)
		(layer "B.Cu")
	)
	(gr_line
		(start 207.635348 -52.854098)
		(end 208.290414 -52.9844)
		(stroke
			(width 0.08255)
			(type default)
		)
		(layer "B.Cu")
	)
	(gr_line
		(start 207.6577 -52.558442)
		(end 207.80121 -52.46243)
		(stroke
			(width 0.08255)
			(type default)
		)
		(layer "B.Cu")
	)
	(gr_line
		(start 207.679036 -36.009326)
		(end 207.767682 -36.140644)
		(stroke
			(width 0.08255)
			(type default)
		)
		(layer "B.Cu")
	)
	(gr_line
		(start 207.767682 -36.140644)
		(end 208.254092 -36.235132)
		(stroke
			(width 0.08255)
			(type default)
		)
		(layer "B.Cu")
	)
	(gr_line
		(start 207.76819 -35.726624)
		(end 208.407 -35.850576)
		(stroke
			(width 0.08255)
			(type default)
		)
		(layer "B.Cu")
	)
	(gr_line
		(start 207.785208 -358.410764)
		(end 207.79105 -358.384094)
		(stroke
			(width 0.08255)
			(type default)
		)
		(layer "B.Cu")
	)
	(gr_line
		(start 207.785208 -358.410764)
		(end 207.791304 -358.438196)
		(stroke
			(width 0.08255)
			(type default)
		)
		(layer "B.Cu")
	)
	(gr_line
		(start 207.791304 -358.437942)
		(end 207.791304 -358.43845)
		(stroke
			(width 0.08255)
			(type default)
		)
		(layer "B.Cu")
	)
	(gr_line
		(start 207.80121 -52.46243)
		(end 208.287112 -52.55895)
		(stroke
			(width 0.08255)
			(type default)
		)
		(layer "B.Cu")
	)
	(gr_line
		(start 207.889348 -76.994512)
		(end 208.03489 -77.087222)
		(stroke
			(width 0.08255)
			(type default)
		)
		(layer "B.Cu")
	)
	(gr_line
		(start 207.94218 -79.614522)
		(end 208.071466 -79.705708)
		(stroke
			(width 0.08255)
			(type default)
		)
		(layer "B.Cu")
	)
	(gr_line
		(start 207.99298 -351.24009)
		(end 207.999076 -351.212912)
		(stroke
			(width 0.08255)
			(type default)
		)
		(layer "B.Cu")
	)
	(gr_line
		(start 207.99298 -351.185734)
		(end 207.999076 -351.212912)
		(stroke
			(width 0.08255)
			(type default)
		)
		(layer "B.Cu")
	)
	(gr_line
		(start 208.007966 -392.986006)
		(end 208.013808 -392.959336)
		(stroke
			(width 0.08255)
			(type default)
		)
		(layer "B.Cu")
	)
	(gr_line
		(start 208.007966 -392.986006)
		(end 208.014062 -393.013692)
		(stroke
			(width 0.08255)
			(type default)
		)
		(layer "B.Cu")
	)
	(gr_line
		(start 208.03108 -54.353206)
		(end 208.126838 -54.496716)
		(stroke
			(width 0.08255)
			(type default)
		)
		(layer "B.Cu")
	)
	(gr_line
		(start 208.254092 -36.235132)
		(end 208.385156 -36.14674)
		(stroke
			(width 0.08255)
			(type default)
		)
		(layer "B.Cu")
	)
	(gr_line
		(start 208.287112 -52.55895)
		(end 208.383124 -52.70246)
		(stroke
			(width 0.08255)
			(type default)
		)
		(layer "B.Cu")
	)
	(gr_line
		(start 208.563972 -79.620618)
		(end 208.655412 -79.491332)
		(stroke
			(width 0.08255)
			(type default)
		)
		(layer "B.Cu")
	)
	(gr_line
		(start 208.650586 -79.90459)
		(end 209.286856 -79.794608)
		(stroke
			(width 0.08255)
			(type default)
		)
		(layer "B.Cu")
	)
	(gr_line
		(start 208.655412 -79.491332)
		(end 209.1436 -79.407004)
		(stroke
			(width 0.08255)
			(type default)
		)
		(layer "B.Cu")
	)
	(gr_line
		(start 208.712054 -383.349246)
		(end 208.71815 -383.322068)
		(stroke
			(width 0.08255)
			(type default)
		)
		(layer "B.Cu")
	)
	(gr_line
		(start 208.712054 -383.29489)
		(end 208.71815 -383.322068)
		(stroke
			(width 0.08255)
			(type default)
		)
		(layer "B.Cu")
	)
	(gr_line
		(start 208.852008 -53.095906)
		(end 209.505296 -53.2257)
		(stroke
			(width 0.08255)
			(type default)
		)
		(layer "B.Cu")
	)
	(gr_line
		(start 208.873598 -52.799996)
		(end 209.017108 -52.703984)
		(stroke
			(width 0.08255)
			(type default)
		)
		(layer "B.Cu")
	)
	(gr_line
		(start 208.876138 -36.24199)
		(end 208.96453 -36.373308)
		(stroke
			(width 0.08255)
			(type default)
		)
		(layer "B.Cu")
	)
	(gr_line
		(start 208.96453 -36.373308)
		(end 209.450686 -36.467796)
		(stroke
			(width 0.08255)
			(type default)
		)
		(layer "B.Cu")
	)
	(gr_line
		(start 208.966562 -35.959288)
		(end 209.603594 -36.08324)
		(stroke
			(width 0.08255)
			(type default)
		)
		(layer "B.Cu")
	)
	(gr_line
		(start 209.017108 -52.703984)
		(end 209.502756 -52.800504)
		(stroke
			(width 0.08255)
			(type default)
		)
		(layer "B.Cu")
	)
	(gr_line
		(start 209.1436 -79.407004)
		(end 209.272886 -79.498444)
		(stroke
			(width 0.08255)
			(type default)
		)
		(layer "B.Cu")
	)
	(gr_line
		(start 209.185002 -343.246964)
		(end 209.193638 -343.285318)
		(stroke
			(width 0.08255)
			(type default)
		)
		(layer "B.Cu")
	)
	(gr_line
		(start 209.185002 -343.246964)
		(end 209.196432 -343.209626)
		(stroke
			(width 0.08255)
			(type default)
		)
		(layer "B.Cu")
	)
	(gr_line
		(start 209.382868 -26.303986)
		(end 209.401664 -26.30043)
		(stroke
			(width 0.08255)
			(type default)
		)
		(layer "B.Cu")
	)
	(gr_line
		(start 209.401664 -26.30043)
		(end 209.42046 -26.303986)
		(stroke
			(width 0.08255)
			(type default)
		)
		(layer "B.Cu")
	)
	(gr_line
		(start 209.450686 -36.467796)
		(end 209.582004 -36.379404)
		(stroke
			(width 0.08255)
			(type default)
		)
		(layer "B.Cu")
	)
	(gr_line
		(start 209.466942 -358.431592)
		(end 209.472784 -358.404922)
		(stroke
			(width 0.08255)
			(type default)
		)
		(layer "B.Cu")
	)
	(gr_line
		(start 209.466942 -358.431592)
		(end 209.473038 -358.458516)
		(stroke
			(width 0.08255)
			(type default)
		)
		(layer "B.Cu")
	)
	(gr_line
		(start 209.473038 -358.45877)
		(end 209.473038 -358.459278)
		(stroke
			(width 0.08255)
			(type default)
		)
		(layer "B.Cu")
	)
	(gr_line
		(start 209.502756 -52.800504)
		(end 209.598514 -52.944014)
		(stroke
			(width 0.08255)
			(type default)
		)
		(layer "B.Cu")
	)
	(gr_line
		(start 209.643218 -351.371154)
		(end 209.649314 -351.343976)
		(stroke
			(width 0.08255)
			(type default)
		)
		(layer "B.Cu")
	)
	(gr_line
		(start 209.643218 -351.316798)
		(end 209.649314 -351.343976)
		(stroke
			(width 0.08255)
			(type default)
		)
		(layer "B.Cu")
	)
	(gr_line
		(start 209.752184 -392.594338)
		(end 209.758026 -392.567668)
		(stroke
			(width 0.08255)
			(type default)
		)
		(layer "B.Cu")
	)
	(gr_line
		(start 209.752184 -392.594338)
		(end 209.75828 -392.62177)
		(stroke
			(width 0.08255)
			(type default)
		)
		(layer "B.Cu")
	)
	(gr_line
		(start 209.75828 -392.621516)
		(end 209.75828 -392.622024)
		(stroke
			(width 0.08255)
			(type default)
		)
		(layer "B.Cu")
	)
	(gr_line
		(start 209.765646 -79.413354)
		(end 209.856832 -79.284068)
		(stroke
			(width 0.08255)
			(type default)
		)
		(layer "B.Cu")
	)
	(gr_arc
		(start 209.817716 -407.553922)
		(mid 209.849605 -407.551058)
		(end 209.880454 -407.542492)
		(stroke
			(width 0.08255)
			(type default)
		)
		(layer "B.Cu")
	)
	(gr_line
		(start 209.825082 -24.521922)
		(end 209.843878 -24.518366)
		(stroke
			(width 0.08255)
			(type default)
		)
		(layer "B.Cu")
	)
	(gr_line
		(start 209.843878 -24.518366)
		(end 209.862674 -24.521922)
		(stroke
			(width 0.08255)
			(type default)
		)
		(layer "B.Cu")
	)
	(gr_line
		(start 209.852514 -79.697072)
		(end 210.488022 -79.587344)
		(stroke
			(width 0.08255)
			(type default)
		)
		(layer "B.Cu")
	)
	(gr_line
		(start 209.856832 -79.284068)
		(end 210.34502 -79.19974)
		(stroke
			(width 0.08255)
			(type default)
		)
		(layer "B.Cu")
	)
	(gr_arc
		(start 209.880454 -407.542492)
		(mid 209.967307 -407.474691)
		(end 210.000088 -407.369518)
		(stroke
			(width 0.08255)
			(type default)
		)
		(layer "B.Cu")
	)
	(gr_arc
		(start 210.000088 -408.03068)
		(mid 209.946003 -407.900107)
		(end 209.81543 -407.846022)
		(stroke
			(width 0.08255)
			(type default)
		)
		(layer "B.Cu")
	)
	(gr_line
		(start 210.000088 -408.03068)
		(end 210.000088 -408.399996)
		(stroke
			(width 0.08255)
			(type default)
		)
		(layer "B.Cu")
	)
	(gr_line
		(start 210.000088 -407.000202)
		(end 210.000088 -407.369518)
		(stroke
			(width 0.08255)
			(type default)
		)
		(layer "B.Cu")
	)
	(gr_line
		(start 210.34502 -79.19974)
		(end 210.474306 -79.290926)
		(stroke
			(width 0.08255)
			(type default)
		)
		(layer "B.Cu")
	)
	(gr_line
		(start 210.412584 -383.48158)
		(end 210.41868 -383.454402)
		(stroke
			(width 0.08255)
			(type default)
		)
		(layer "B.Cu")
	)
	(gr_line
		(start 210.412584 -383.427224)
		(end 210.41868 -383.454402)
		(stroke
			(width 0.08255)
			(type default)
		)
		(layer "B.Cu")
	)
	(gr_line
		(start 210.816444 -343.295224)
		(end 210.82508 -343.333578)
		(stroke
			(width 0.08255)
			(type default)
		)
		(layer "B.Cu")
	)
	(gr_line
		(start 210.816444 -343.295224)
		(end 210.82762 -343.258394)
		(stroke
			(width 0.08255)
			(type default)
		)
		(layer "B.Cu")
	)
	(gr_line
		(start 211.150454 -358.201976)
		(end 211.156296 -358.175306)
		(stroke
			(width 0.08255)
			(type default)
		)
		(layer "B.Cu")
	)
	(gr_line
		(start 211.150454 -358.201976)
		(end 211.15655 -358.229408)
		(stroke
			(width 0.08255)
			(type default)
		)
		(layer "B.Cu")
	)
	(gr_line
		(start 211.15655 -358.229154)
		(end 211.15655 -358.229662)
		(stroke
			(width 0.08255)
			(type default)
		)
		(layer "B.Cu")
	)
	(gr_line
		(start 211.31911 -351.419414)
		(end 211.325206 -351.392236)
		(stroke
			(width 0.08255)
			(type default)
		)
		(layer "B.Cu")
	)
	(gr_line
		(start 211.31911 -351.365058)
		(end 211.325206 -351.392236)
		(stroke
			(width 0.08255)
			(type default)
		)
		(layer "B.Cu")
	)
	(gr_arc
		(start 211.617814 -406.553924)
		(mid 211.649703 -406.551061)
		(end 211.680552 -406.542494)
		(stroke
			(width 0.08255)
			(type default)
		)
		(layer "B.Cu")
	)
	(gr_arc
		(start 211.680552 -406.542494)
		(mid 211.767407 -406.474694)
		(end 211.800186 -406.36952)
		(stroke
			(width 0.08255)
			(type default)
		)
		(layer "B.Cu")
	)
	(gr_arc
		(start 211.800186 -407.030682)
		(mid 211.746101 -406.900109)
		(end 211.615528 -406.846024)
		(stroke
			(width 0.08255)
			(type default)
		)
		(layer "B.Cu")
	)
	(gr_line
		(start 211.800186 -407.030682)
		(end 211.800186 -407.399998)
		(stroke
			(width 0.08255)
			(type default)
		)
		(layer "B.Cu")
	)
	(gr_line
		(start 211.800186 -405.99995)
		(end 211.800186 -406.36952)
		(stroke
			(width 0.08255)
			(type default)
		)
		(layer "B.Cu")
	)
	(gr_line
		(start 211.992464 -394.92682)
		(end 211.998306 -394.90015)
		(stroke
			(width 0.08255)
			(type default)
		)
		(layer "B.Cu")
	)
	(gr_line
		(start 211.992464 -394.92682)
		(end 211.99856 -394.954506)
		(stroke
			(width 0.08255)
			(type default)
		)
		(layer "B.Cu")
	)
	(gr_line
		(start 212.05952 -383.528824)
		(end 212.065616 -383.501646)
		(stroke
			(width 0.08255)
			(type default)
		)
		(layer "B.Cu")
	)
	(gr_line
		(start 212.05952 -383.474468)
		(end 212.065616 -383.501646)
		(stroke
			(width 0.08255)
			(type default)
		)
		(layer "B.Cu")
	)
	(gr_line
		(start 212.162898 -22.450552)
		(end 212.18144 -22.446996)
		(stroke
			(width 0.08255)
			(type default)
		)
		(layer "B.Cu")
	)
	(gr_line
		(start 212.18144 -22.446996)
		(end 212.200236 -22.450552)
		(stroke
			(width 0.08255)
			(type default)
		)
		(layer "B.Cu")
	)
	(gr_line
		(start 212.300312 -57.514236)
		(end 212.950298 -57.640728)
		(stroke
			(width 0.08255)
			(type default)
		)
		(layer "B.Cu")
	)
	(gr_line
		(start 212.302598 -20.382738)
		(end 212.32368 -20.37842)
		(stroke
			(width 0.08255)
			(type default)
		)
		(layer "B.Cu")
	)
	(gr_line
		(start 212.319362 -57.218326)
		(end 212.462618 -57.121806)
		(stroke
			(width 0.08255)
			(type default)
		)
		(layer "B.Cu")
	)
	(gr_line
		(start 212.32368 -20.37842)
		(end 212.344254 -20.382484)
		(stroke
			(width 0.08255)
			(type default)
		)
		(layer "B.Cu")
	)
	(gr_line
		(start 212.44306 -50.662078)
		(end 213.08314 -50.790602)
		(stroke
			(width 0.08255)
			(type default)
		)
		(layer "B.Cu")
	)
	(gr_line
		(start 212.462618 -57.121806)
		(end 212.948774 -57.216294)
		(stroke
			(width 0.08255)
			(type default)
		)
		(layer "B.Cu")
	)
	(gr_line
		(start 212.468206 -50.366422)
		(end 212.600286 -50.278538)
		(stroke
			(width 0.08255)
			(type default)
		)
		(layer "B.Cu")
	)
	(gr_line
		(start 212.495892 -343.577418)
		(end 212.504528 -343.615772)
		(stroke
			(width 0.08255)
			(type default)
		)
		(layer "B.Cu")
	)
	(gr_line
		(start 212.495892 -343.577418)
		(end 212.507068 -343.540588)
		(stroke
			(width 0.08255)
			(type default)
		)
		(layer "B.Cu")
	)
	(gr_line
		(start 212.600286 -50.278538)
		(end 213.085934 -50.376074)
		(stroke
			(width 0.08255)
			(type default)
		)
		(layer "B.Cu")
	)
	(gr_line
		(start 212.759544 -82.107786)
		(end 212.8647 -81.970372)
		(stroke
			(width 0.08255)
			(type default)
		)
		(layer "B.Cu")
	)
	(gr_line
		(start 212.83295 -82.395314)
		(end 213.498176 -82.30616)
		(stroke
			(width 0.08255)
			(type default)
		)
		(layer "B.Cu")
	)
	(gr_line
		(start 212.838284 -76.021184)
		(end 212.923374 -75.887834)
		(stroke
			(width 0.08255)
			(type default)
		)
		(layer "B.Cu")
	)
	(gr_line
		(start 212.8647 -81.970372)
		(end 213.355682 -81.904586)
		(stroke
			(width 0.08255)
			(type default)
		)
		(layer "B.Cu")
	)
	(gr_line
		(start 212.894672 -357.830882)
		(end 212.900514 -357.804212)
		(stroke
			(width 0.08255)
			(type default)
		)
		(layer "B.Cu")
	)
	(gr_line
		(start 212.894672 -357.830882)
		(end 212.900768 -357.858314)
		(stroke
			(width 0.08255)
			(type default)
		)
		(layer "B.Cu")
	)
	(gr_line
		(start 212.900768 -357.85806)
		(end 212.900768 -357.858568)
		(stroke
			(width 0.08255)
			(type default)
		)
		(layer "B.Cu")
	)
	(gr_line
		(start 212.923374 -75.887834)
		(end 213.40699 -75.780392)
		(stroke
			(width 0.08255)
			(type default)
		)
		(layer "B.Cu")
	)
	(gr_line
		(start 212.936582 -76.301092)
		(end 213.56828 -76.160884)
		(stroke
			(width 0.08255)
			(type default)
		)
		(layer "B.Cu")
	)
	(gr_line
		(start 212.945472 -351.44456)
		(end 212.951568 -351.417636)
		(stroke
			(width 0.08255)
			(type default)
		)
		(layer "B.Cu")
	)
	(gr_line
		(start 212.945472 -351.390458)
		(end 212.951568 -351.417636)
		(stroke
			(width 0.08255)
			(type default)
		)
		(layer "B.Cu")
	)
	(gr_line
		(start 212.948774 -57.216294)
		(end 213.04504 -57.35955)
		(stroke
			(width 0.08255)
			(type default)
		)
		(layer "B.Cu")
	)
	(gr_line
		(start 213.085934 -50.376074)
		(end 213.173564 -50.508154)
		(stroke
			(width 0.08255)
			(type default)
		)
		(layer "B.Cu")
	)
	(gr_line
		(start 213.355682 -81.904586)
		(end 213.492842 -82.009488)
		(stroke
			(width 0.08255)
			(type default)
		)
		(layer "B.Cu")
	)
	(gr_line
		(start 213.40699 -75.780392)
		(end 213.54034 -75.865482)
		(stroke
			(width 0.08255)
			(type default)
		)
		(layer "B.Cu")
	)
	(gr_arc
		(start 213.417658 -407.553922)
		(mid 213.449545 -407.551051)
		(end 213.480396 -407.542492)
		(stroke
			(width 0.08255)
			(type default)
		)
		(layer "B.Cu")
	)
	(gr_arc
		(start 213.480396 -407.542492)
		(mid 213.56723 -407.474683)
		(end 213.60003 -407.369518)
		(stroke
			(width 0.08255)
			(type default)
		)
		(layer "B.Cu")
	)
	(gr_line
		(start 213.518496 -57.751218)
		(end 214.168228 -57.877456)
		(stroke
			(width 0.08255)
			(type default)
		)
		(layer "B.Cu")
	)
	(gr_line
		(start 213.536022 -57.455054)
		(end 213.679278 -57.35828)
		(stroke
			(width 0.08255)
			(type default)
		)
		(layer "B.Cu")
	)
	(gr_arc
		(start 213.60003 -408.03068)
		(mid 213.545945 -407.900107)
		(end 213.415372 -407.846022)
		(stroke
			(width 0.08255)
			(type default)
		)
		(layer "B.Cu")
	)
	(gr_line
		(start 213.60003 -408.03068)
		(end 213.60003 -408.399996)
		(stroke
			(width 0.08255)
			(type default)
		)
		(layer "B.Cu")
	)
	(gr_line
		(start 213.60003 -407.000202)
		(end 213.60003 -407.369518)
		(stroke
			(width 0.08255)
			(type default)
		)
		(layer "B.Cu")
	)
	(gr_line
		(start 213.638384 -50.902108)
		(end 214.279734 -51.030886)
		(stroke
			(width 0.08255)
			(type default)
		)
		(layer "B.Cu")
	)
	(gr_line
		(start 213.66353 -50.606452)
		(end 213.79561 -50.518568)
		(stroke
			(width 0.08255)
			(type default)
		)
		(layer "B.Cu")
	)
	(gr_line
		(start 213.679278 -57.35828)
		(end 214.165434 -57.453022)
		(stroke
			(width 0.08255)
			(type default)
		)
		(layer "B.Cu")
	)
	(gr_line
		(start 213.79561 -50.518568)
		(end 214.281258 -50.616104)
		(stroke
			(width 0.08255)
			(type default)
		)
		(layer "B.Cu")
	)
	(gr_line
		(start 213.835488 -394.350494)
		(end 213.84133 -394.323824)
		(stroke
			(width 0.08255)
			(type default)
		)
		(layer "B.Cu")
	)
	(gr_line
		(start 213.835488 -394.350494)
		(end 213.841584 -394.37818)
		(stroke
			(width 0.08255)
			(type default)
		)
		(layer "B.Cu")
	)
	(gr_line
		(start 213.988396 -81.943194)
		(end 214.093298 -81.80578)
		(stroke
			(width 0.08255)
			(type default)
		)
		(layer "B.Cu")
	)
	(gr_line
		(start 214.028528 -75.757024)
		(end 214.113618 -75.623674)
		(stroke
			(width 0.08255)
			(type default)
		)
		(layer "B.Cu")
	)
	(gr_line
		(start 214.061548 -82.230722)
		(end 214.726012 -82.141568)
		(stroke
			(width 0.08255)
			(type default)
		)
		(layer "B.Cu")
	)
	(gr_line
		(start 214.093298 -81.80578)
		(end 214.584026 -81.739994)
		(stroke
			(width 0.08255)
			(type default)
		)
		(layer "B.Cu")
	)
	(gr_line
		(start 214.113618 -75.623674)
		(end 214.597234 -75.516232)
		(stroke
			(width 0.08255)
			(type default)
		)
		(layer "B.Cu")
	)
	(gr_line
		(start 214.126826 -76.036932)
		(end 214.759794 -75.89647)
		(stroke
			(width 0.08255)
			(type default)
		)
		(layer "B.Cu")
	)
	(gr_line
		(start 214.165434 -57.453022)
		(end 214.261954 -57.596278)
		(stroke
			(width 0.08255)
			(type default)
		)
		(layer "B.Cu")
	)
	(gr_line
		(start 214.190834 -343.811098)
		(end 214.19947 -343.849452)
		(stroke
			(width 0.08255)
			(type default)
		)
		(layer "B.Cu")
	)
	(gr_line
		(start 214.190834 -343.811098)
		(end 214.20201 -343.774268)
		(stroke
			(width 0.08255)
			(type default)
		)
		(layer "B.Cu")
	)
	(gr_line
		(start 214.281258 -50.616104)
		(end 214.368888 -50.748184)
		(stroke
			(width 0.08255)
			(type default)
		)
		(layer "B.Cu")
	)
	(gr_line
		(start 214.292434 -385.894326)
		(end 214.29853 -385.867148)
		(stroke
			(width 0.08255)
			(type default)
		)
		(layer "B.Cu")
	)
	(gr_line
		(start 214.292434 -385.83997)
		(end 214.29853 -385.867148)
		(stroke
			(width 0.08255)
			(type default)
		)
		(layer "B.Cu")
	)
	(gr_line
		(start 214.536782 -84.8741)
		(end 214.647526 -84.741512)
		(stroke
			(width 0.08255)
			(type default)
		)
		(layer "B.Cu")
	)
	(gr_line
		(start 214.556086 -78.58633)
		(end 214.647272 -78.457044)
		(stroke
			(width 0.08255)
			(type default)
		)
		(layer "B.Cu")
	)
	(gr_line
		(start 214.584026 -81.739994)
		(end 214.72144 -81.844896)
		(stroke
			(width 0.08255)
			(type default)
		)
		(layer "B.Cu")
	)
	(gr_line
		(start 214.585042 -351.550732)
		(end 214.591138 -351.523554)
		(stroke
			(width 0.08255)
			(type default)
		)
		(layer "B.Cu")
	)
	(gr_line
		(start 214.585042 -351.496376)
		(end 214.591138 -351.523554)
		(stroke
			(width 0.08255)
			(type default)
		)
		(layer "B.Cu")
	)
	(gr_line
		(start 214.597234 -75.516232)
		(end 214.730584 -75.601322)
		(stroke
			(width 0.08255)
			(type default)
		)
		(layer "B.Cu")
	)
	(gr_line
		(start 214.599266 -85.163914)
		(end 215.264492 -85.104986)
		(stroke
			(width 0.08255)
			(type default)
		)
		(layer "B.Cu")
	)
	(gr_line
		(start 214.643462 -78.869794)
		(end 215.278716 -78.76032)
		(stroke
			(width 0.08255)
			(type default)
		)
		(layer "B.Cu")
	)
	(gr_line
		(start 214.647272 -78.457044)
		(end 215.13546 -78.372716)
		(stroke
			(width 0.08255)
			(type default)
		)
		(layer "B.Cu")
	)
	(gr_line
		(start 214.647526 -84.741512)
		(end 215.141048 -84.697824)
		(stroke
			(width 0.08255)
			(type default)
		)
		(layer "B.Cu")
	)
	(gr_line
		(start 214.734648 -57.987692)
		(end 215.386666 -58.114692)
		(stroke
			(width 0.08255)
			(type default)
		)
		(layer "B.Cu")
	)
	(gr_line
		(start 214.752682 -57.691528)
		(end 214.895938 -57.595008)
		(stroke
			(width 0.08255)
			(type default)
		)
		(layer "B.Cu")
	)
	(gr_line
		(start 214.764874 -357.876094)
		(end 214.769446 -357.85298)
		(stroke
			(width 0.08255)
			(type default)
		)
		(layer "B.Cu")
	)
	(gr_line
		(start 214.764874 -357.876094)
		(end 214.770208 -357.899716)
		(stroke
			(width 0.08255)
			(type default)
		)
		(layer "B.Cu")
	)
	(gr_line
		(start 214.770208 -357.89997)
		(end 214.770208 -357.900478)
		(stroke
			(width 0.08255)
			(type default)
		)
		(layer "B.Cu")
	)
	(gr_line
		(start 214.831676 -51.141884)
		(end 215.475566 -51.27117)
		(stroke
			(width 0.08255)
			(type default)
		)
		(layer "B.Cu")
	)
	(gr_line
		(start 214.858854 -50.846482)
		(end 214.990934 -50.758598)
		(stroke
			(width 0.08255)
			(type default)
		)
		(layer "B.Cu")
	)
	(gr_line
		(start 214.895938 -57.595008)
		(end 215.382094 -57.689496)
		(stroke
			(width 0.08255)
			(type default)
		)
		(layer "B.Cu")
	)
	(gr_line
		(start 214.90178 -54.297834)
		(end 215.537796 -54.424072)
		(stroke
			(width 0.08255)
			(type default)
		)
		(layer "B.Cu")
	)
	(gr_line
		(start 214.923624 -54.001924)
		(end 215.055196 -53.913786)
		(stroke
			(width 0.08255)
			(type default)
		)
		(layer "B.Cu")
	)
	(gr_line
		(start 214.990934 -50.758598)
		(end 215.476582 -50.856134)
		(stroke
			(width 0.08255)
			(type default)
		)
		(layer "B.Cu")
	)
	(gr_line
		(start 215.055196 -53.913786)
		(end 215.541098 -54.010306)
		(stroke
			(width 0.08255)
			(type default)
		)
		(layer "B.Cu")
	)
	(gr_line
		(start 215.13546 -78.372716)
		(end 215.264746 -78.463902)
		(stroke
			(width 0.08255)
			(type default)
		)
		(layer "B.Cu")
	)
	(gr_line
		(start 215.141048 -84.697824)
		(end 215.273636 -84.808568)
		(stroke
			(width 0.08255)
			(type default)
		)
		(layer "B.Cu")
	)
	(gr_line
		(start 215.216994 -81.778602)
		(end 215.321642 -81.641188)
		(stroke
			(width 0.08255)
			(type default)
		)
		(layer "B.Cu")
	)
	(gr_arc
		(start 215.217756 -406.553924)
		(mid 215.249643 -406.551053)
		(end 215.280494 -406.542494)
		(stroke
			(width 0.08255)
			(type default)
		)
		(layer "B.Cu")
	)
	(gr_line
		(start 215.218772 -75.492864)
		(end 215.303862 -75.359514)
		(stroke
			(width 0.08255)
			(type default)
		)
		(layer "B.Cu")
	)
	(gr_arc
		(start 215.280494 -406.542494)
		(mid 215.36733 -406.474686)
		(end 215.400128 -406.36952)
		(stroke
			(width 0.08255)
			(type default)
		)
		(layer "B.Cu")
	)
	(gr_line
		(start 215.290908 -82.065876)
		(end 215.954102 -81.976976)
		(stroke
			(width 0.08255)
			(type default)
		)
		(layer "B.Cu")
	)
	(gr_line
		(start 215.303862 -75.359514)
		(end 215.787478 -75.252072)
		(stroke
			(width 0.08255)
			(type default)
		)
		(layer "B.Cu")
	)
	(gr_line
		(start 215.316054 -75.77328)
		(end 215.94953 -75.632564)
		(stroke
			(width 0.08255)
			(type default)
		)
		(layer "B.Cu")
	)
	(gr_line
		(start 215.321642 -81.641188)
		(end 215.812624 -81.575402)
		(stroke
			(width 0.08255)
			(type default)
		)
		(layer "B.Cu")
	)
	(gr_line
		(start 215.382094 -57.689496)
		(end 215.478868 -57.832752)
		(stroke
			(width 0.08255)
			(type default)
		)
		(layer "B.Cu")
	)
	(gr_arc
		(start 215.400128 -407.030682)
		(mid 215.346043 -406.900109)
		(end 215.21547 -406.846024)
		(stroke
			(width 0.08255)
			(type default)
		)
		(layer "B.Cu")
	)
	(gr_line
		(start 215.400128 -407.030682)
		(end 215.400128 -407.399998)
		(stroke
			(width 0.08255)
			(type default)
		)
		(layer "B.Cu")
	)
	(gr_line
		(start 215.400128 -405.99995)
		(end 215.400128 -406.36952)
		(stroke
			(width 0.08255)
			(type default)
		)
		(layer "B.Cu")
	)
	(gr_line
		(start 215.476582 -50.856134)
		(end 215.564212 -50.988214)
		(stroke
			(width 0.08255)
			(type default)
		)
		(layer "B.Cu")
	)
	(gr_line
		(start 215.541098 -54.010306)
		(end 215.629236 -54.141878)
		(stroke
			(width 0.08255)
			(type default)
		)
		(layer "B.Cu")
	)
	(gr_line
		(start 215.548464 -56.274716)
		(end 216.193116 -56.402986)
		(stroke
			(width 0.08255)
			(type default)
		)
		(layer "B.Cu")
	)
	(gr_line
		(start 215.57615 -55.979314)
		(end 215.707976 -55.89143)
		(stroke
			(width 0.08255)
			(type default)
		)
		(layer "B.Cu")
	)
	(gr_line
		(start 215.707976 -55.89143)
		(end 216.193624 -55.98795)
		(stroke
			(width 0.08255)
			(type default)
		)
		(layer "B.Cu")
	)
	(gr_line
		(start 215.757506 -78.378812)
		(end 215.848692 -78.249526)
		(stroke
			(width 0.08255)
			(type default)
		)
		(layer "B.Cu")
	)
	(gr_line
		(start 215.771222 -84.764626)
		(end 215.88222 -84.632038)
		(stroke
			(width 0.08255)
			(type default)
		)
		(layer "B.Cu")
	)
	(gr_line
		(start 215.787478 -75.252072)
		(end 215.920828 -75.337162)
		(stroke
			(width 0.08255)
			(type default)
		)
		(layer "B.Cu")
	)
	(gr_line
		(start 215.812624 -81.575402)
		(end 215.950038 -81.680304)
		(stroke
			(width 0.08255)
			(type default)
		)
		(layer "B.Cu")
	)
	(gr_line
		(start 215.831674 -85.054948)
		(end 216.498424 -84.995766)
		(stroke
			(width 0.08255)
			(type default)
		)
		(layer "B.Cu")
	)
	(gr_line
		(start 215.84285 -78.663038)
		(end 216.481152 -78.552802)
		(stroke
			(width 0.08255)
			(type default)
		)
		(layer "B.Cu")
	)
	(gr_line
		(start 215.848692 -78.249526)
		(end 216.33688 -78.165452)
		(stroke
			(width 0.08255)
			(type default)
		)
		(layer "B.Cu")
	)
	(gr_line
		(start 215.88222 -84.632038)
		(end 216.375742 -84.58835)
		(stroke
			(width 0.08255)
			(type default)
		)
		(layer "B.Cu")
	)
	(gr_line
		(start 215.948006 -58.224166)
		(end 216.604088 -58.351674)
		(stroke
			(width 0.08255)
			(type default)
		)
		(layer "B.Cu")
	)
	(gr_line
		(start 215.969342 -57.928256)
		(end 216.112598 -57.831736)
		(stroke
			(width 0.08255)
			(type default)
		)
		(layer "B.Cu")
	)
	(gr_line
		(start 215.991186 -385.96824)
		(end 215.997282 -385.941062)
		(stroke
			(width 0.08255)
			(type default)
		)
		(layer "B.Cu")
	)
	(gr_line
		(start 215.991186 -385.913884)
		(end 215.997282 -385.941062)
		(stroke
			(width 0.08255)
			(type default)
		)
		(layer "B.Cu")
	)
	(gr_line
		(start 216.026746 -51.381914)
		(end 216.670636 -51.5112)
		(stroke
			(width 0.08255)
			(type default)
		)
		(layer "B.Cu")
	)
	(gr_line
		(start 216.054178 -51.086512)
		(end 216.186258 -50.998628)
		(stroke
			(width 0.08255)
			(type default)
		)
		(layer "B.Cu")
	)
	(gr_line
		(start 216.095326 -54.53507)
		(end 216.734644 -54.66207)
		(stroke
			(width 0.08255)
			(type default)
		)
		(layer "B.Cu")
	)
	(gr_line
		(start 216.112598 -57.831736)
		(end 216.598754 -57.926224)
		(stroke
			(width 0.08255)
			(type default)
		)
		(layer "B.Cu")
	)
	(gr_line
		(start 216.119456 -54.239414)
		(end 216.251028 -54.151276)
		(stroke
			(width 0.08255)
			(type default)
		)
		(layer "B.Cu")
	)
	(gr_line
		(start 216.186258 -50.998628)
		(end 216.671906 -51.096164)
		(stroke
			(width 0.08255)
			(type default)
		)
		(layer "B.Cu")
	)
	(gr_line
		(start 216.193624 -55.98795)
		(end 216.281762 -56.119776)
		(stroke
			(width 0.08255)
			(type default)
		)
		(layer "B.Cu")
	)
	(gr_line
		(start 216.251028 -54.151276)
		(end 216.73693 -54.247796)
		(stroke
			(width 0.08255)
			(type default)
		)
		(layer "B.Cu")
	)
	(gr_line
		(start 216.27592 -351.71126)
		(end 216.281254 -351.735136)
		(stroke
			(width 0.08255)
			(type default)
		)
		(layer "B.Cu")
	)
	(gr_line
		(start 216.276428 -351.758758)
		(end 216.281254 -351.735136)
		(stroke
			(width 0.08255)
			(type default)
		)
		(layer "B.Cu")
	)
	(gr_line
		(start 216.315798 -397.500856)
		(end 216.32164 -397.474186)
		(stroke
			(width 0.08255)
			(type default)
		)
		(layer "B.Cu")
	)
	(gr_line
		(start 216.315798 -397.500856)
		(end 216.321894 -397.528288)
		(stroke
			(width 0.08255)
			(type default)
		)
		(layer "B.Cu")
	)
	(gr_line
		(start 216.321894 -397.528034)
		(end 216.321894 -397.528542)
		(stroke
			(width 0.08255)
			(type default)
		)
		(layer "B.Cu")
	)
	(gr_line
		(start 216.33688 -78.165452)
		(end 216.466166 -78.256384)
		(stroke
			(width 0.08255)
			(type default)
		)
		(layer "B.Cu")
	)
	(gr_line
		(start 216.375742 -84.58835)
		(end 216.508076 -84.699348)
		(stroke
			(width 0.08255)
			(type default)
		)
		(layer "B.Cu")
	)
	(gr_line
		(start 216.445592 -81.61401)
		(end 216.55024 -81.476596)
		(stroke
			(width 0.08255)
			(type default)
		)
		(layer "B.Cu")
	)
	(gr_line
		(start 216.519506 -81.901284)
		(end 217.182446 -81.812384)
		(stroke
			(width 0.08255)
			(type default)
		)
		(layer "B.Cu")
	)
	(gr_line
		(start 216.55024 -81.476596)
		(end 217.041222 -81.41081)
		(stroke
			(width 0.08255)
			(type default)
		)
		(layer "B.Cu")
	)
	(gr_line
		(start 216.598754 -57.926224)
		(end 216.695528 -58.06948)
		(stroke
			(width 0.08255)
			(type default)
		)
		(layer "B.Cu")
	)
	(gr_line
		(start 216.671906 -51.096164)
		(end 216.759536 -51.228244)
		(stroke
			(width 0.08255)
			(type default)
		)
		(layer "B.Cu")
	)
	(gr_line
		(start 216.73693 -54.247796)
		(end 216.825068 -54.379622)
		(stroke
			(width 0.08255)
			(type default)
		)
		(layer "B.Cu")
	)
	(gr_line
		(start 216.743534 -56.512714)
		(end 217.38971 -56.641238)
		(stroke
			(width 0.08255)
			(type default)
		)
		(layer "B.Cu")
	)
	(gr_line
		(start 216.771728 -56.217312)
		(end 216.903808 -56.129428)
		(stroke
			(width 0.08255)
			(type default)
		)
		(layer "B.Cu")
	)
	(gr_line
		(start 216.903808 -56.129428)
		(end 217.389456 -56.225948)
		(stroke
			(width 0.08255)
			(type default)
		)
		(layer "B.Cu")
	)
	(gr_line
		(start 216.958926 -78.171294)
		(end 217.050112 -78.042262)
		(stroke
			(width 0.08255)
			(type default)
		)
		(layer "B.Cu")
	)
	(gr_line
		(start 217.005916 -84.655152)
		(end 217.116914 -84.522564)
		(stroke
			(width 0.08255)
			(type default)
		)
		(layer "B.Cu")
	)
	(gr_arc
		(start 217.0176 -407.553922)
		(mid 217.049489 -407.551061)
		(end 217.080338 -407.542492)
		(stroke
			(width 0.08255)
			(type default)
		)
		(layer "B.Cu")
	)
	(gr_line
		(start 217.041222 -81.41081)
		(end 217.178382 -81.515712)
		(stroke
			(width 0.08255)
			(type default)
		)
		(layer "B.Cu")
	)
	(gr_line
		(start 217.045032 -78.45552)
		(end 217.68181 -78.345538)
		(stroke
			(width 0.08255)
			(type default)
		)
		(layer "B.Cu")
	)
	(gr_line
		(start 217.050112 -78.042262)
		(end 217.5383 -77.957934)
		(stroke
			(width 0.08255)
			(type default)
		)
		(layer "B.Cu")
	)
	(gr_line
		(start 217.0684 -84.94522)
		(end 217.733372 -84.886292)
		(stroke
			(width 0.08255)
			(type default)
		)
		(layer "B.Cu")
	)
	(gr_arc
		(start 217.080338 -407.542492)
		(mid 217.167154 -407.474676)
		(end 217.199972 -407.369518)
		(stroke
			(width 0.08255)
			(type default)
		)
		(layer "B.Cu")
	)
	(gr_line
		(start 217.116914 -84.522564)
		(end 217.610436 -84.478876)
		(stroke
			(width 0.08255)
			(type default)
		)
		(layer "B.Cu")
	)
	(gr_arc
		(start 217.199972 -408.03068)
		(mid 217.145887 -407.900107)
		(end 217.015314 -407.846022)
		(stroke
			(width 0.08255)
			(type default)
		)
		(layer "B.Cu")
	)
	(gr_line
		(start 217.199972 -408.03068)
		(end 217.199972 -408.399996)
		(stroke
			(width 0.08255)
			(type default)
		)
		(layer "B.Cu")
	)
	(gr_line
		(start 217.199972 -407.000202)
		(end 217.199972 -407.369518)
		(stroke
			(width 0.08255)
			(type default)
		)
		(layer "B.Cu")
	)
	(gr_line
		(start 217.29192 -54.77256)
		(end 217.92819 -54.899052)
		(stroke
			(width 0.08255)
			(type default)
		)
		(layer "B.Cu")
	)
	(gr_line
		(start 217.315034 -54.476904)
		(end 217.44686 -54.38902)
		(stroke
			(width 0.08255)
			(type default)
		)
		(layer "B.Cu")
	)
	(gr_line
		(start 217.389456 -56.225948)
		(end 217.477594 -56.357774)
		(stroke
			(width 0.08255)
			(type default)
		)
		(layer "B.Cu")
	)
	(gr_line
		(start 217.44686 -54.38902)
		(end 217.932762 -54.48554)
		(stroke
			(width 0.08255)
			(type default)
		)
		(layer "B.Cu")
	)
	(gr_line
		(start 217.5383 -77.957934)
		(end 217.667586 -78.04912)
		(stroke
			(width 0.08255)
			(type default)
		)
		(layer "B.Cu")
	)
	(gr_line
		(start 217.610436 -84.478876)
		(end 217.74277 -84.589874)
		(stroke
			(width 0.08255)
			(type default)
		)
		(layer "B.Cu")
	)
	(gr_line
		(start 217.932762 -54.48554)
		(end 218.0209 -54.617112)
		(stroke
			(width 0.08255)
			(type default)
		)
		(layer "B.Cu")
	)
	(gr_line
		(start 217.939874 -56.750712)
		(end 218.583256 -56.878728)
		(stroke
			(width 0.08255)
			(type default)
		)
		(layer "B.Cu")
	)
	(gr_line
		(start 217.96756 -56.45531)
		(end 218.099386 -56.367426)
		(stroke
			(width 0.08255)
			(type default)
		)
		(layer "B.Cu")
	)
	(gr_line
		(start 218.078812 -396.923768)
		(end 218.085162 -396.895066)
		(stroke
			(width 0.08255)
			(type default)
		)
		(layer "B.Cu")
	)
	(gr_line
		(start 218.078812 -396.923768)
		(end 218.085416 -396.952724)
		(stroke
			(width 0.08255)
			(type default)
		)
		(layer "B.Cu")
	)
	(gr_line
		(start 218.099386 -56.367426)
		(end 218.585288 -56.463946)
		(stroke
			(width 0.08255)
			(type default)
		)
		(layer "B.Cu")
	)
	(gr_line
		(start 218.24061 -84.545678)
		(end 218.351608 -84.413344)
		(stroke
			(width 0.08255)
			(type default)
		)
		(layer "B.Cu")
	)
	(gr_line
		(start 218.302332 -84.836)
		(end 218.968828 -84.776818)
		(stroke
			(width 0.08255)
			(type default)
		)
		(layer "B.Cu")
	)
	(gr_line
		(start 218.351608 -84.413344)
		(end 218.84513 -84.369656)
		(stroke
			(width 0.08255)
			(type default)
		)
		(layer "B.Cu")
	)
	(gr_line
		(start 218.453462 -389.201152)
		(end 218.459558 -389.173974)
		(stroke
			(width 0.08255)
			(type default)
		)
		(layer "B.Cu")
	)
	(gr_line
		(start 218.453462 -389.146796)
		(end 218.459558 -389.173974)
		(stroke
			(width 0.08255)
			(type default)
		)
		(layer "B.Cu")
	)
	(gr_line
		(start 218.489276 -55.010558)
		(end 219.124784 -55.136796)
		(stroke
			(width 0.08255)
			(type default)
		)
		(layer "B.Cu")
	)
	(gr_line
		(start 218.51112 -54.714648)
		(end 218.642692 -54.62651)
		(stroke
			(width 0.08255)
			(type default)
		)
		(layer "B.Cu")
	)
	(gr_line
		(start 218.585288 -56.463946)
		(end 218.673172 -56.595772)
		(stroke
			(width 0.08255)
			(type default)
		)
		(layer "B.Cu")
	)
	(gr_line
		(start 218.642692 -54.62651)
		(end 219.128594 -54.72303)
		(stroke
			(width 0.08255)
			(type default)
		)
		(layer "B.Cu")
	)
	(gr_arc
		(start 218.817698 -406.553924)
		(mid 218.849587 -406.551063)
		(end 218.880436 -406.542494)
		(stroke
			(width 0.08255)
			(type default)
		)
		(layer "B.Cu")
	)
	(gr_line
		(start 218.84513 -84.369656)
		(end 218.977718 -84.4804)
		(stroke
			(width 0.08255)
			(type default)
		)
		(layer "B.Cu")
	)
	(gr_arc
		(start 218.880436 -406.542494)
		(mid 218.967253 -406.474678)
		(end 219.00007 -406.36952)
		(stroke
			(width 0.08255)
			(type default)
		)
		(layer "B.Cu")
	)
	(gr_arc
		(start 219.00007 -407.030682)
		(mid 218.945985 -406.900109)
		(end 218.815412 -406.846024)
		(stroke
			(width 0.08255)
			(type default)
		)
		(layer "B.Cu")
	)
	(gr_line
		(start 219.00007 -407.030682)
		(end 219.00007 -407.399998)
		(stroke
			(width 0.08255)
			(type default)
		)
		(layer "B.Cu")
	)
	(gr_line
		(start 219.00007 -405.99995)
		(end 219.00007 -406.36952)
		(stroke
			(width 0.08255)
			(type default)
		)
		(layer "B.Cu")
	)
	(gr_line
		(start 219.128594 -54.72303)
		(end 219.216732 -54.854602)
		(stroke
			(width 0.08255)
			(type default)
		)
		(layer "B.Cu")
	)
	(gr_line
		(start 219.13596 -56.98871)
		(end 219.781882 -57.117234)
		(stroke
			(width 0.08255)
			(type default)
		)
		(layer "B.Cu")
	)
	(gr_line
		(start 219.163392 -56.693308)
		(end 219.295218 -56.605424)
		(stroke
			(width 0.08255)
			(type default)
		)
		(layer "B.Cu")
	)
	(gr_line
		(start 219.295218 -56.605424)
		(end 219.78112 -56.701944)
		(stroke
			(width 0.08255)
			(type default)
		)
		(layer "B.Cu")
	)
	(gr_line
		(start 219.754704 -396.842488)
		(end 219.760546 -396.815818)
		(stroke
			(width 0.08255)
			(type default)
		)
		(layer "B.Cu")
	)
	(gr_line
		(start 219.754704 -396.842488)
		(end 219.7608 -396.870174)
		(stroke
			(width 0.08255)
			(type default)
		)
		(layer "B.Cu")
	)
	(gr_line
		(start 219.78112 -56.701944)
		(end 219.869004 -56.83377)
		(stroke
			(width 0.08255)
			(type default)
		)
		(layer "B.Cu")
	)
	(gr_line
		(start 220.083888 -141.965172)
		(end 220.087444 -141.983968)
		(stroke
			(width 0.08255)
			(type default)
		)
		(layer "B.Cu")
	)
	(gr_line
		(start 220.083888 -141.965172)
		(end 220.087698 -141.945614)
		(stroke
			(width 0.08255)
			(type default)
		)
		(layer "B.Cu")
	)
	(gr_line
		(start 220.18498 -388.770114)
		(end 220.191076 -388.742936)
		(stroke
			(width 0.08255)
			(type default)
		)
		(layer "B.Cu")
	)
	(gr_line
		(start 220.18498 -388.715758)
		(end 220.191076 -388.742936)
		(stroke
			(width 0.08255)
			(type default)
		)
		(layer "B.Cu")
	)
	(gr_line
		(start 220.602556 -47.76724)
		(end 220.69044 -47.898558)
		(stroke
			(width 0.08255)
			(type default)
		)
		(layer "B.Cu")
	)
	(gr_arc
		(start 220.617796 -407.553922)
		(mid 220.649686 -407.551062)
		(end 220.680534 -407.542492)
		(stroke
			(width 0.08255)
			(type default)
		)
		(layer "B.Cu")
	)
	(gr_arc
		(start 220.680534 -407.542492)
		(mid 220.767351 -407.474676)
		(end 220.800168 -407.369518)
		(stroke
			(width 0.08255)
			(type default)
		)
		(layer "B.Cu")
	)
	(gr_line
		(start 220.69044 -47.898558)
		(end 221.176088 -47.995078)
		(stroke
			(width 0.08255)
			(type default)
		)
		(layer "B.Cu")
	)
	(gr_line
		(start 220.696028 -47.485554)
		(end 221.330012 -47.611538)
		(stroke
			(width 0.08255)
			(type default)
		)
		(layer "B.Cu")
	)
	(gr_arc
		(start 220.800168 -408.03068)
		(mid 220.746083 -407.900107)
		(end 220.61551 -407.846022)
		(stroke
			(width 0.08255)
			(type default)
		)
		(layer "B.Cu")
	)
	(gr_line
		(start 220.800168 -408.03068)
		(end 220.800168 -408.399996)
		(stroke
			(width 0.08255)
			(type default)
		)
		(layer "B.Cu")
	)
	(gr_line
		(start 220.800168 -407.000202)
		(end 220.800168 -407.369518)
		(stroke
			(width 0.08255)
			(type default)
		)
		(layer "B.Cu")
	)
	(gr_line
		(start 221.176088 -47.995078)
		(end 221.30766 -47.907194)
		(stroke
			(width 0.08255)
			(type default)
		)
		(layer "B.Cu")
	)
	(gr_line
		(start 221.358206 -80.955642)
		(end 221.454218 -80.829658)
		(stroke
			(width 0.08255)
			(type default)
		)
		(layer "B.Cu")
	)
	(gr_line
		(start 221.43212 -81.242916)
		(end 222.074232 -81.15681)
		(stroke
			(width 0.08255)
			(type default)
		)
		(layer "B.Cu")
	)
	(gr_line
		(start 221.454218 -80.829658)
		(end 221.9452 -80.763872)
		(stroke
			(width 0.08255)
			(type default)
		)
		(layer "B.Cu")
	)
	(gr_line
		(start 221.71914 -52.52466)
		(end 222.362014 -52.653946)
		(stroke
			(width 0.08255)
			(type default)
		)
		(layer "B.Cu")
	)
	(gr_line
		(start 221.744794 -52.229258)
		(end 221.87662 -52.141374)
		(stroke
			(width 0.08255)
			(type default)
		)
		(layer "B.Cu")
	)
	(gr_line
		(start 221.798388 -48.00473)
		(end 221.886272 -48.136302)
		(stroke
			(width 0.08255)
			(type default)
		)
		(layer "B.Cu")
	)
	(gr_line
		(start 221.838012 -142.532862)
		(end 221.841568 -142.551658)
		(stroke
			(width 0.08255)
			(type default)
		)
		(layer "B.Cu")
	)
	(gr_line
		(start 221.838012 -142.532862)
		(end 221.841822 -142.513304)
		(stroke
			(width 0.08255)
			(type default)
		)
		(layer "B.Cu")
	)
	(gr_line
		(start 221.87662 -52.141374)
		(end 222.362268 -52.23891)
		(stroke
			(width 0.08255)
			(type default)
		)
		(layer "B.Cu")
	)
	(gr_line
		(start 221.886272 -48.136302)
		(end 222.37192 -48.232822)
		(stroke
			(width 0.08255)
			(type default)
		)
		(layer "B.Cu")
	)
	(gr_line
		(start 221.891606 -47.723044)
		(end 222.526098 -47.849282)
		(stroke
			(width 0.08255)
			(type default)
		)
		(layer "B.Cu")
	)
	(gr_line
		(start 221.942406 -388.314184)
		(end 221.948502 -388.287006)
		(stroke
			(width 0.08255)
			(type default)
		)
		(layer "B.Cu")
	)
	(gr_line
		(start 221.942406 -388.259828)
		(end 221.948502 -388.287006)
		(stroke
			(width 0.08255)
			(type default)
		)
		(layer "B.Cu")
	)
	(gr_line
		(start 221.9452 -80.763872)
		(end 222.07093 -80.860138)
		(stroke
			(width 0.08255)
			(type default)
		)
		(layer "B.Cu")
	)
	(gr_line
		(start 222.073724 -73.971404)
		(end 222.166434 -73.826116)
		(stroke
			(width 0.08255)
			(type default)
		)
		(layer "B.Cu")
	)
	(gr_line
		(start 222.166434 -73.826116)
		(end 222.65005 -73.718674)
		(stroke
			(width 0.08255)
			(type default)
		)
		(layer "B.Cu")
	)
	(gr_line
		(start 222.172022 -74.251566)
		(end 222.825564 -74.106532)
		(stroke
			(width 0.08255)
			(type default)
		)
		(layer "B.Cu")
	)
	(gr_line
		(start 222.362268 -52.23891)
		(end 222.450152 -52.37099)
		(stroke
			(width 0.08255)
			(type default)
		)
		(layer "B.Cu")
	)
	(gr_line
		(start 222.37192 -48.232822)
		(end 222.503492 -48.144938)
		(stroke
			(width 0.08255)
			(type default)
		)
		(layer "B.Cu")
	)
	(gr_arc
		(start 222.41764 -406.553924)
		(mid 222.449527 -406.551056)
		(end 222.480378 -406.542494)
		(stroke
			(width 0.08255)
			(type default)
		)
		(layer "B.Cu")
	)
	(gr_arc
		(start 222.480378 -406.542494)
		(mid 222.567221 -406.474689)
		(end 222.600012 -406.36952)
		(stroke
			(width 0.08255)
			(type default)
		)
		(layer "B.Cu")
	)
	(gr_line
		(start 222.566738 -80.79359)
		(end 222.66275 -80.66786)
		(stroke
			(width 0.08255)
			(type default)
		)
		(layer "B.Cu")
	)
	(gr_arc
		(start 222.600012 -407.030682)
		(mid 222.545927 -406.900109)
		(end 222.415354 -406.846024)
		(stroke
			(width 0.08255)
			(type default)
		)
		(layer "B.Cu")
	)
	(gr_line
		(start 222.600012 -407.030682)
		(end 222.600012 -407.399998)
		(stroke
			(width 0.08255)
			(type default)
		)
		(layer "B.Cu")
	)
	(gr_line
		(start 222.600012 -405.99995)
		(end 222.600012 -406.36952)
		(stroke
			(width 0.08255)
			(type default)
		)
		(layer "B.Cu")
	)
	(gr_line
		(start 222.641922 -81.080864)
		(end 223.283526 -80.994758)
		(stroke
			(width 0.08255)
			(type default)
		)
		(layer "B.Cu")
	)
	(gr_line
		(start 222.65005 -73.718674)
		(end 222.795592 -73.811384)
		(stroke
			(width 0.08255)
			(type default)
		)
		(layer "B.Cu")
	)
	(gr_line
		(start 222.66275 -80.66786)
		(end 223.153732 -80.602074)
		(stroke
			(width 0.08255)
			(type default)
		)
		(layer "B.Cu")
	)
	(gr_line
		(start 222.913702 -52.76469)
		(end 223.557084 -52.893976)
		(stroke
			(width 0.08255)
			(type default)
		)
		(layer "B.Cu")
	)
	(gr_line
		(start 222.940118 -52.469288)
		(end 223.071944 -52.381404)
		(stroke
			(width 0.08255)
			(type default)
		)
		(layer "B.Cu")
	)
	(gr_line
		(start 222.99422 -48.242474)
		(end 223.08185 -48.374046)
		(stroke
			(width 0.08255)
			(type default)
		)
		(layer "B.Cu")
	)
	(gr_line
		(start 223.071944 -52.381404)
		(end 223.557592 -52.47894)
		(stroke
			(width 0.08255)
			(type default)
		)
		(layer "B.Cu")
	)
	(gr_line
		(start 223.08185 -48.374046)
		(end 223.567752 -48.470566)
		(stroke
			(width 0.08255)
			(type default)
		)
		(layer "B.Cu")
	)
	(gr_line
		(start 223.085914 -47.96028)
		(end 223.720914 -48.086518)
		(stroke
			(width 0.08255)
			(type default)
		)
		(layer "B.Cu")
	)
	(gr_line
		(start 223.153732 -80.602074)
		(end 223.279462 -80.698086)
		(stroke
			(width 0.08255)
			(type default)
		)
		(layer "B.Cu")
	)
	(gr_line
		(start 223.284034 -73.702926)
		(end 223.37649 -73.557384)
		(stroke
			(width 0.08255)
			(type default)
		)
		(layer "B.Cu")
	)
	(gr_line
		(start 223.37649 -73.557384)
		(end 223.860106 -73.450196)
		(stroke
			(width 0.08255)
			(type default)
		)
		(layer "B.Cu")
	)
	(gr_line
		(start 223.383094 -73.982834)
		(end 224.033842 -73.838308)
		(stroke
			(width 0.08255)
			(type default)
		)
		(layer "B.Cu")
	)
	(gr_line
		(start 223.514666 -142.230348)
		(end 223.518222 -142.249144)
		(stroke
			(width 0.08255)
			(type default)
		)
		(layer "B.Cu")
	)
	(gr_line
		(start 223.514666 -142.230348)
		(end 223.518476 -142.21079)
		(stroke
			(width 0.08255)
			(type default)
		)
		(layer "B.Cu")
	)
	(gr_line
		(start 223.557592 -52.47894)
		(end 223.645476 -52.61102)
		(stroke
			(width 0.08255)
			(type default)
		)
		(layer "B.Cu")
	)
	(gr_line
		(start 223.567752 -48.470566)
		(end 223.69907 -48.382682)
		(stroke
			(width 0.08255)
			(type default)
		)
		(layer "B.Cu")
	)
	(gr_line
		(start 223.702118 -48.38065)
		(end 223.784668 -48.39716)
		(stroke
			(width 0.08255)
			(type default)
		)
		(layer "B.Cu")
	)
	(gr_line
		(start 223.741742 -160.787334)
		(end 223.74606 -160.809178)
		(stroke
			(width 0.08255)
			(type default)
		)
		(layer "B.Cu")
	)
	(gr_line
		(start 223.74606 -160.809178)
		(end 223.757998 -160.826958)
		(stroke
			(width 0.08255)
			(type default)
		)
		(layer "B.Cu")
	)
	(gr_line
		(start 223.751902 -48.092868)
		(end 223.841564 -48.110648)
		(stroke
			(width 0.08255)
			(type default)
		)
		(layer "B.Cu")
	)
	(gr_line
		(start 223.775016 -80.631792)
		(end 223.871028 -80.505808)
		(stroke
			(width 0.08255)
			(type default)
		)
		(layer "B.Cu")
	)
	(gr_line
		(start 223.84893 -80.919066)
		(end 224.491042 -80.83296)
		(stroke
			(width 0.08255)
			(type default)
		)
		(layer "B.Cu")
	)
	(gr_line
		(start 223.860106 -73.450196)
		(end 224.005394 -73.542906)
		(stroke
			(width 0.08255)
			(type default)
		)
		(layer "B.Cu")
	)
	(gr_line
		(start 223.871028 -80.505808)
		(end 224.36201 -80.440022)
		(stroke
			(width 0.08255)
			(type default)
		)
		(layer "B.Cu")
	)
	(gr_line
		(start 224.111058 -53.004974)
		(end 224.7519 -53.133752)
		(stroke
			(width 0.08255)
			(type default)
		)
		(layer "B.Cu")
	)
	(gr_line
		(start 224.135442 -52.709318)
		(end 224.267268 -52.621434)
		(stroke
			(width 0.08255)
			(type default)
		)
		(layer "B.Cu")
	)
	(gr_line
		(start 224.189798 -48.480218)
		(end 224.277682 -48.61179)
		(stroke
			(width 0.08255)
			(type default)
		)
		(layer "B.Cu")
	)
	(gr_line
		(start 224.265998 -73.487534)
		(end 224.492058 -73.437496)
		(stroke
			(width 0.08255)
			(type default)
		)
		(layer "B.Cu")
	)
	(gr_line
		(start 224.267268 -52.621434)
		(end 224.752916 -52.71897)
		(stroke
			(width 0.08255)
			(type default)
		)
		(layer "B.Cu")
	)
	(gr_line
		(start 224.277682 -48.61179)
		(end 224.763584 -48.70831)
		(stroke
			(width 0.08255)
			(type default)
		)
		(layer "B.Cu")
	)
	(gr_line
		(start 224.280984 -48.19777)
		(end 224.917254 -48.324262)
		(stroke
			(width 0.08255)
			(type default)
		)
		(layer "B.Cu")
	)
	(gr_line
		(start 224.36201 -80.440022)
		(end 224.48774 -80.536288)
		(stroke
			(width 0.08255)
			(type default)
		)
		(layer "B.Cu")
	)
	(gr_line
		(start 224.49409 -73.434448)
		(end 224.586546 -73.288906)
		(stroke
			(width 0.08255)
			(type default)
		)
		(layer "B.Cu")
	)
	(gr_line
		(start 224.515426 -73.731628)
		(end 224.56267 -73.72096)
		(stroke
			(width 0.08255)
			(type default)
		)
		(layer "B.Cu")
	)
	(gr_line
		(start 224.544636 -59.59856)
		(end 224.574354 -59.604402)
		(stroke
			(width 0.08255)
			(type default)
		)
		(layer "B.Cu")
	)
	(gr_line
		(start 224.574354 -59.604402)
		(end 224.598738 -59.62269)
		(stroke
			(width 0.08255)
			(type default)
		)
		(layer "B.Cu")
	)
	(gr_line
		(start 224.586546 -73.288906)
		(end 225.070162 -73.181718)
		(stroke
			(width 0.08255)
			(type default)
		)
		(layer "B.Cu")
	)
	(gr_line
		(start 224.593658 -73.714102)
		(end 225.24466 -73.569576)
		(stroke
			(width 0.08255)
			(type default)
		)
		(layer "B.Cu")
	)
	(gr_line
		(start 224.752916 -52.71897)
		(end 224.8408 -52.85105)
		(stroke
			(width 0.08255)
			(type default)
		)
		(layer "B.Cu")
	)
	(gr_line
		(start 224.763584 -48.70831)
		(end 224.894902 -48.620426)
		(stroke
			(width 0.08255)
			(type default)
		)
		(layer "B.Cu")
	)
	(gr_line
		(start 224.82429 -60.157614)
		(end 225.34372 -60.548012)
		(stroke
			(width 0.08255)
			(type default)
		)
		(layer "B.Cu")
	)
	(gr_line
		(start 224.827592 -58.12155)
		(end 225.471228 -58.249566)
		(stroke
			(width 0.08255)
			(type default)
		)
		(layer "B.Cu")
	)
	(gr_line
		(start 224.855532 -57.826148)
		(end 224.987358 -57.738264)
		(stroke
			(width 0.08255)
			(type default)
		)
		(layer "B.Cu")
	)
	(gr_line
		(start 224.9297 -158.440374)
		(end 224.934018 -158.462218)
		(stroke
			(width 0.08255)
			(type default)
		)
		(layer "B.Cu")
	)
	(gr_line
		(start 224.934018 -158.462218)
		(end 224.945956 -158.479998)
		(stroke
			(width 0.08255)
			(type default)
		)
		(layer "B.Cu")
	)
	(gr_line
		(start 224.973388 -59.901328)
		(end 225.13036 -59.87923)
		(stroke
			(width 0.08255)
			(type default)
		)
		(layer "B.Cu")
	)
	(gr_line
		(start 224.983294 -80.46974)
		(end 225.07956 -80.34401)
		(stroke
			(width 0.08255)
			(type default)
		)
		(layer "B.Cu")
	)
	(gr_line
		(start 224.987358 -57.738264)
		(end 225.47326 -57.834784)
		(stroke
			(width 0.08255)
			(type default)
		)
		(layer "B.Cu")
	)
	(gr_line
		(start 225.058224 -80.757014)
		(end 225.700336 -80.670908)
		(stroke
			(width 0.08255)
			(type default)
		)
		(layer "B.Cu")
	)
	(gr_line
		(start 225.070162 -73.181718)
		(end 225.21545 -73.274174)
		(stroke
			(width 0.08255)
			(type default)
		)
		(layer "B.Cu")
	)
	(gr_line
		(start 225.07956 -80.34401)
		(end 225.570288 -80.278224)
		(stroke
			(width 0.08255)
			(type default)
		)
		(layer "B.Cu")
	)
	(gr_line
		(start 225.13036 -59.87923)
		(end 225.526346 -60.176664)
		(stroke
			(width 0.08255)
			(type default)
		)
		(layer "B.Cu")
	)
	(gr_line
		(start 225.255582 -142.335504)
		(end 225.259138 -142.3543)
		(stroke
			(width 0.08255)
			(type default)
		)
		(layer "B.Cu")
	)
	(gr_line
		(start 225.255582 -142.335504)
		(end 225.259392 -142.315946)
		(stroke
			(width 0.08255)
			(type default)
		)
		(layer "B.Cu")
	)
	(gr_line
		(start 225.30562 -53.245004)
		(end 225.94697 -53.373782)
		(stroke
			(width 0.08255)
			(type default)
		)
		(layer "B.Cu")
	)
	(gr_line
		(start 225.330766 -52.949348)
		(end 225.462592 -52.861464)
		(stroke
			(width 0.08255)
			(type default)
		)
		(layer "B.Cu")
	)
	(gr_line
		(start 225.370898 -83.91398)
		(end 225.472244 -83.792568)
		(stroke
			(width 0.08255)
			(type default)
		)
		(layer "B.Cu")
	)
	(gr_line
		(start 225.433128 -84.204048)
		(end 226.078034 -84.146898)
		(stroke
			(width 0.08255)
			(type default)
		)
		(layer "B.Cu")
	)
	(gr_line
		(start 225.462592 -52.861464)
		(end 225.94824 -52.959)
		(stroke
			(width 0.08255)
			(type default)
		)
		(layer "B.Cu")
	)
	(gr_line
		(start 225.472244 -83.792568)
		(end 225.965766 -83.74888)
		(stroke
			(width 0.08255)
			(type default)
		)
		(layer "B.Cu")
	)
	(gr_line
		(start 225.47326 -57.834784)
		(end 225.561144 -57.96661)
		(stroke
			(width 0.08255)
			(type default)
		)
		(layer "B.Cu")
	)
	(gr_line
		(start 225.526346 -60.176664)
		(end 225.548444 -60.333382)
		(stroke
			(width 0.08255)
			(type default)
		)
		(layer "B.Cu")
	)
	(gr_line
		(start 225.570288 -80.278224)
		(end 225.696272 -80.374236)
		(stroke
			(width 0.08255)
			(type default)
		)
		(layer "B.Cu")
	)
	(gr_line
		(start 225.800158 -60.890912)
		(end 226.31908 -61.281056)
		(stroke
			(width 0.08255)
			(type default)
		)
		(layer "B.Cu")
	)
	(gr_line
		(start 225.94824 -60.633864)
		(end 226.104958 -60.611512)
		(stroke
			(width 0.08255)
			(type default)
		)
		(layer "B.Cu")
	)
	(gr_line
		(start 225.94824 -52.959)
		(end 226.036124 -53.09108)
		(stroke
			(width 0.08255)
			(type default)
		)
		(layer "B.Cu")
	)
	(gr_line
		(start 225.965766 -83.74888)
		(end 226.086924 -83.85048)
		(stroke
			(width 0.08255)
			(type default)
		)
		(layer "B.Cu")
	)
	(gr_line
		(start 226.02571 -58.359548)
		(end 226.665536 -58.487056)
		(stroke
			(width 0.08255)
			(type default)
		)
		(layer "B.Cu")
	)
	(gr_line
		(start 226.051364 -58.064146)
		(end 226.18319 -57.976262)
		(stroke
			(width 0.08255)
			(type default)
		)
		(layer "B.Cu")
	)
	(gr_line
		(start 226.104958 -60.611512)
		(end 226.500944 -60.9092)
		(stroke
			(width 0.08255)
			(type default)
		)
		(layer "B.Cu")
	)
	(gr_line
		(start 226.18319 -57.976262)
		(end 226.669092 -58.072782)
		(stroke
			(width 0.08255)
			(type default)
		)
		(layer "B.Cu")
	)
	(gr_line
		(start 226.31654 -156.644594)
		(end 226.320858 -156.666438)
		(stroke
			(width 0.08255)
			(type default)
		)
		(layer "B.Cu")
	)
	(gr_line
		(start 226.320858 -156.666438)
		(end 226.332796 -156.684218)
		(stroke
			(width 0.08255)
			(type default)
		)
		(layer "B.Cu")
	)
	(gr_line
		(start 226.500944 -60.9092)
		(end 226.523296 -61.065918)
		(stroke
			(width 0.08255)
			(type default)
		)
		(layer "B.Cu")
	)
	(gr_line
		(start 226.585018 -83.806284)
		(end 226.686618 -83.684872)
		(stroke
			(width 0.08255)
			(type default)
		)
		(layer "B.Cu")
	)
	(gr_line
		(start 226.646486 -84.096606)
		(end 227.291646 -84.039456)
		(stroke
			(width 0.08255)
			(type default)
		)
		(layer "B.Cu")
	)
	(gr_line
		(start 226.669092 -58.072782)
		(end 226.756976 -58.204608)
		(stroke
			(width 0.08255)
			(type default)
		)
		(layer "B.Cu")
	)
	(gr_line
		(start 226.686618 -83.684872)
		(end 227.18014 -83.641184)
		(stroke
			(width 0.08255)
			(type default)
		)
		(layer "B.Cu")
	)
	(gr_line
		(start 226.772978 -61.622178)
		(end 227.292662 -62.012576)
		(stroke
			(width 0.08255)
			(type default)
		)
		(layer "B.Cu")
	)
	(gr_line
		(start 226.923092 -61.366146)
		(end 227.07981 -61.344048)
		(stroke
			(width 0.08255)
			(type default)
		)
		(layer "B.Cu")
	)
	(gr_line
		(start 227.07981 -61.344048)
		(end 227.475796 -61.641482)
		(stroke
			(width 0.08255)
			(type default)
		)
		(layer "B.Cu")
	)
	(gr_line
		(start 227.18014 -83.641184)
		(end 227.301552 -83.742784)
		(stroke
			(width 0.08255)
			(type default)
		)
		(layer "B.Cu")
	)
	(gr_line
		(start 227.222812 -58.5978)
		(end 227.862384 -58.725054)
		(stroke
			(width 0.08255)
			(type default)
		)
		(layer "B.Cu")
	)
	(gr_line
		(start 227.247196 -58.302144)
		(end 227.379022 -58.21426)
		(stroke
			(width 0.08255)
			(type default)
		)
		(layer "B.Cu")
	)
	(gr_line
		(start 227.379022 -58.21426)
		(end 227.86467 -58.31078)
		(stroke
			(width 0.08255)
			(type default)
		)
		(layer "B.Cu")
	)
	(gr_line
		(start 227.475796 -61.641482)
		(end 227.497894 -61.7982)
		(stroke
			(width 0.08255)
			(type default)
		)
		(layer "B.Cu")
	)
	(gr_line
		(start 227.59416 -154.36723)
		(end 227.598478 -154.389074)
		(stroke
			(width 0.08255)
			(type default)
		)
		(layer "B.Cu")
	)
	(gr_line
		(start 227.598478 -154.389074)
		(end 227.610416 -154.406854)
		(stroke
			(width 0.08255)
			(type default)
		)
		(layer "B.Cu")
	)
	(gr_line
		(start 227.749354 -62.35573)
		(end 228.267006 -62.744604)
		(stroke
			(width 0.08255)
			(type default)
		)
		(layer "B.Cu")
	)
	(gr_line
		(start 227.799646 -83.698588)
		(end 227.901246 -83.57743)
		(stroke
			(width 0.08255)
			(type default)
		)
		(layer "B.Cu")
	)
	(gr_line
		(start 227.861876 -83.98891)
		(end 228.506528 -83.93176)
		(stroke
			(width 0.08255)
			(type default)
		)
		(layer "B.Cu")
	)
	(gr_line
		(start 227.86467 -58.31078)
		(end 227.952808 -58.442606)
		(stroke
			(width 0.08255)
			(type default)
		)
		(layer "B.Cu")
	)
	(gr_line
		(start 227.897944 -62.098682)
		(end 228.054408 -62.07633)
		(stroke
			(width 0.08255)
			(type default)
		)
		(layer "B.Cu")
	)
	(gr_line
		(start 227.900992 -101.751638)
		(end 227.90531 -101.729794)
		(stroke
			(width 0.08255)
			(type default)
		)
		(layer "B.Cu")
	)
	(gr_line
		(start 227.901246 -83.57743)
		(end 228.394514 -83.533488)
		(stroke
			(width 0.08255)
			(type default)
		)
		(layer "B.Cu")
	)
	(gr_line
		(start 227.90531 -101.729794)
		(end 227.917248 -101.712014)
		(stroke
			(width 0.08255)
			(type default)
		)
		(layer "B.Cu")
	)
	(gr_line
		(start 228.035358 -56.906922)
		(end 228.66985 -57.032906)
		(stroke
			(width 0.08255)
			(type default)
		)
		(layer "B.Cu")
	)
	(gr_line
		(start 228.054408 -62.07633)
		(end 228.450394 -62.374018)
		(stroke
			(width 0.08255)
			(type default)
		)
		(layer "B.Cu")
	)
	(gr_line
		(start 228.056694 -56.610758)
		(end 228.188266 -56.522874)
		(stroke
			(width 0.08255)
			(type default)
		)
		(layer "B.Cu")
	)
	(gr_line
		(start 228.188266 -56.522874)
		(end 228.674168 -56.619394)
		(stroke
			(width 0.08255)
			(type default)
		)
		(layer "B.Cu")
	)
	(gr_line
		(start 228.216206 -35.999928)
		(end 228.305106 -36.1315)
		(stroke
			(width 0.08255)
			(type default)
		)
		(layer "B.Cu")
	)
	(gr_line
		(start 228.305106 -36.1315)
		(end 228.791262 -36.225988)
		(stroke
			(width 0.08255)
			(type default)
		)
		(layer "B.Cu")
	)
	(gr_line
		(start 228.306884 -35.717734)
		(end 228.943916 -35.841432)
		(stroke
			(width 0.08255)
			(type default)
		)
		(layer "B.Cu")
	)
	(gr_line
		(start 228.394514 -83.533488)
		(end 228.515926 -83.635342)
		(stroke
			(width 0.08255)
			(type default)
		)
		(layer "B.Cu")
	)
	(gr_line
		(start 228.418644 -58.835798)
		(end 229.058216 -58.963052)
		(stroke
			(width 0.08255)
			(type default)
		)
		(layer "B.Cu")
	)
	(gr_line
		(start 228.443028 -58.540142)
		(end 228.574854 -58.452258)
		(stroke
			(width 0.08255)
			(type default)
		)
		(layer "B.Cu")
	)
	(gr_line
		(start 228.450394 -62.374018)
		(end 228.472746 -62.530736)
		(stroke
			(width 0.08255)
			(type default)
		)
		(layer "B.Cu")
	)
	(gr_line
		(start 228.574854 -58.452258)
		(end 229.060502 -58.548778)
		(stroke
			(width 0.08255)
			(type default)
		)
		(layer "B.Cu")
	)
	(gr_line
		(start 228.674168 -56.619394)
		(end 228.762052 -56.750966)
		(stroke
			(width 0.08255)
			(type default)
		)
		(layer "B.Cu")
	)
	(gr_line
		(start 228.791262 -36.225988)
		(end 228.92258 -36.137342)
		(stroke
			(width 0.08255)
			(type default)
		)
		(layer "B.Cu")
	)
	(gr_line
		(start 229.01402 -83.591146)
		(end 229.11562 -83.469734)
		(stroke
			(width 0.08255)
			(type default)
		)
		(layer "B.Cu")
	)
	(gr_line
		(start 229.060502 -58.548778)
		(end 229.14864 -58.680604)
		(stroke
			(width 0.08255)
			(type default)
		)
		(layer "B.Cu")
	)
	(gr_line
		(start 229.07625 -83.881214)
		(end 229.721664 -83.824064)
		(stroke
			(width 0.08255)
			(type default)
		)
		(layer "B.Cu")
	)
	(gr_line
		(start 229.11562 -83.469734)
		(end 229.608888 -83.426046)
		(stroke
			(width 0.08255)
			(type default)
		)
		(layer "B.Cu")
	)
	(gr_line
		(start 229.230174 -57.144158)
		(end 229.865936 -57.27065)
		(stroke
			(width 0.08255)
			(type default)
		)
		(layer "B.Cu")
	)
	(gr_line
		(start 229.252526 -56.848502)
		(end 229.384098 -56.760364)
		(stroke
			(width 0.08255)
			(type default)
		)
		(layer "B.Cu")
	)
	(gr_line
		(start 229.384098 -56.760364)
		(end 229.87 -56.856884)
		(stroke
			(width 0.08255)
			(type default)
		)
		(layer "B.Cu")
	)
	(gr_line
		(start 229.413308 -36.232592)
		(end 229.5017 -36.364164)
		(stroke
			(width 0.08255)
			(type default)
		)
		(layer "B.Cu")
	)
	(gr_line
		(start 229.458774 -72.332596)
		(end 229.543864 -72.199246)
		(stroke
			(width 0.08255)
			(type default)
		)
		(layer "B.Cu")
	)
	(gr_line
		(start 229.5017 -36.364164)
		(end 229.98811 -36.458652)
		(stroke
			(width 0.08255)
			(type default)
		)
		(layer "B.Cu")
	)
	(gr_line
		(start 229.504494 -35.950398)
		(end 230.14178 -36.07435)
		(stroke
			(width 0.08255)
			(type default)
		)
		(layer "B.Cu")
	)
	(gr_line
		(start 229.543864 -72.199246)
		(end 230.027226 -72.091804)
		(stroke
			(width 0.08255)
			(type default)
		)
		(layer "B.Cu")
	)
	(gr_line
		(start 229.556056 -72.613012)
		(end 230.189532 -72.472296)
		(stroke
			(width 0.08255)
			(type default)
		)
		(layer "B.Cu")
	)
	(gr_line
		(start 229.593902 -58.771536)
		(end 229.624382 -58.777632)
		(stroke
			(width 0.08255)
			(type default)
		)
		(layer "B.Cu")
	)
	(gr_line
		(start 229.608888 -83.426046)
		(end 229.7303 -83.527646)
		(stroke
			(width 0.08255)
			(type default)
		)
		(layer "B.Cu")
	)
	(gr_line
		(start 229.624382 -58.777632)
		(end 229.649274 -58.796682)
		(stroke
			(width 0.08255)
			(type default)
		)
		(layer "B.Cu")
	)
	(gr_line
		(start 229.746556 -101.849682)
		(end 229.750874 -101.827838)
		(stroke
			(width 0.08255)
			(type default)
		)
		(layer "B.Cu")
	)
	(gr_line
		(start 229.750874 -101.827838)
		(end 229.762812 -101.810058)
		(stroke
			(width 0.08255)
			(type default)
		)
		(layer "B.Cu")
	)
	(gr_line
		(start 229.87 -56.856884)
		(end 229.957884 -56.988456)
		(stroke
			(width 0.08255)
			(type default)
		)
		(layer "B.Cu")
	)
	(gr_line
		(start 229.98811 -36.458652)
		(end 230.119428 -36.370006)
		(stroke
			(width 0.08255)
			(type default)
		)
		(layer "B.Cu")
	)
	(gr_line
		(start 230.027226 -72.091804)
		(end 230.160576 -72.176894)
		(stroke
			(width 0.08255)
			(type default)
		)
		(layer "B.Cu")
	)
	(gr_line
		(start 230.425244 -57.381648)
		(end 231.061514 -57.50814)
		(stroke
			(width 0.08255)
			(type default)
		)
		(layer "B.Cu")
	)
	(gr_line
		(start 230.448358 -57.085992)
		(end 230.57993 -56.998108)
		(stroke
			(width 0.08255)
			(type default)
		)
		(layer "B.Cu")
	)
	(gr_line
		(start 230.57993 -56.998108)
		(end 231.065832 -57.094628)
		(stroke
			(width 0.08255)
			(type default)
		)
		(layer "B.Cu")
	)
	(gr_line
		(start 230.609902 -36.465256)
		(end 230.698548 -36.596828)
		(stroke
			(width 0.08255)
			(type default)
		)
		(layer "B.Cu")
	)
	(gr_line
		(start 230.649018 -72.068436)
		(end 230.734108 -71.935086)
		(stroke
			(width 0.08255)
			(type default)
		)
		(layer "B.Cu")
	)
	(gr_line
		(start 230.698548 -36.596828)
		(end 231.184704 -36.691316)
		(stroke
			(width 0.08255)
			(type default)
		)
		(layer "B.Cu")
	)
	(gr_line
		(start 230.700326 -36.182808)
		(end 231.337612 -36.30676)
		(stroke
			(width 0.08255)
			(type default)
		)
		(layer "B.Cu")
	)
	(gr_line
		(start 230.734108 -71.935086)
		(end 231.21747 -71.827644)
		(stroke
			(width 0.08255)
			(type default)
		)
		(layer "B.Cu")
	)
	(gr_line
		(start 230.735886 -79.69885)
		(end 230.831898 -79.57312)
		(stroke
			(width 0.08255)
			(type default)
		)
		(layer "B.Cu")
	)
	(gr_line
		(start 230.747824 -72.34809)
		(end 231.379268 -72.208136)
		(stroke
			(width 0.08255)
			(type default)
		)
		(layer "B.Cu")
	)
	(gr_line
		(start 230.81107 -79.986124)
		(end 231.452674 -79.900018)
		(stroke
			(width 0.08255)
			(type default)
		)
		(layer "B.Cu")
	)
	(gr_line
		(start 230.831898 -79.57312)
		(end 231.32288 -79.507334)
		(stroke
			(width 0.08255)
			(type default)
		)
		(layer "B.Cu")
	)
	(gr_line
		(start 230.99522 -54.387242)
		(end 231.635808 -54.51602)
		(stroke
			(width 0.08255)
			(type default)
		)
		(layer "B.Cu")
	)
	(gr_line
		(start 231.020874 -54.092094)
		(end 231.152954 -54.00421)
		(stroke
			(width 0.08255)
			(type default)
		)
		(layer "B.Cu")
	)
	(gr_line
		(start 231.034844 -64.824356)
		(end 231.552496 -65.21323)
		(stroke
			(width 0.08255)
			(type default)
		)
		(layer "B.Cu")
	)
	(gr_line
		(start 231.065832 -57.094628)
		(end 231.153462 -57.2262)
		(stroke
			(width 0.08255)
			(type default)
		)
		(layer "B.Cu")
	)
	(gr_line
		(start 231.152954 -54.00421)
		(end 231.638348 -54.101746)
		(stroke
			(width 0.08255)
			(type default)
		)
		(layer "B.Cu")
	)
	(gr_line
		(start 231.183434 -64.567308)
		(end 231.339898 -64.544956)
		(stroke
			(width 0.08255)
			(type default)
		)
		(layer "B.Cu")
	)
	(gr_line
		(start 231.184704 -36.691316)
		(end 231.316276 -36.60267)
		(stroke
			(width 0.08255)
			(type default)
		)
		(layer "B.Cu")
	)
	(gr_line
		(start 231.21747 -71.827644)
		(end 231.35082 -71.912734)
		(stroke
			(width 0.08255)
			(type default)
		)
		(layer "B.Cu")
	)
	(gr_line
		(start 231.231186 -102.535482)
		(end 231.235504 -102.513638)
		(stroke
			(width 0.08255)
			(type default)
		)
		(layer "B.Cu")
	)
	(gr_line
		(start 231.235504 -102.513638)
		(end 231.247442 -102.495858)
		(stroke
			(width 0.08255)
			(type default)
		)
		(layer "B.Cu")
	)
	(gr_line
		(start 231.240584 -96.783652)
		(end 231.244394 -96.77781)
		(stroke
			(width 0.08255)
			(type default)
		)
		(layer "B.Cu")
	)
	(gr_line
		(start 231.244394 -96.77781)
		(end 231.250236 -96.773238)
		(stroke
			(width 0.08255)
			(type default)
		)
		(layer "B.Cu")
	)
	(gr_line
		(start 231.32288 -79.507334)
		(end 231.44861 -79.603346)
		(stroke
			(width 0.08255)
			(type default)
		)
		(layer "B.Cu")
	)
	(gr_line
		(start 231.339898 -64.544956)
		(end 231.735884 -64.842644)
		(stroke
			(width 0.08255)
			(type default)
		)
		(layer "B.Cu")
	)
	(gr_line
		(start 231.550972 -172.585888)
		(end 231.581198 -172.43044)
		(stroke
			(width 0.08255)
			(type default)
		)
		(layer "B.Cu")
	)
	(gr_line
		(start 231.550972 -172.585888)
		(end 231.827832 -172.996352)
		(stroke
			(width 0.08255)
			(type default)
		)
		(layer "B.Cu")
	)
	(gr_line
		(start 231.621838 -57.619392)
		(end 232.2576 -57.745884)
		(stroke
			(width 0.08255)
			(type default)
		)
		(layer "B.Cu")
	)
	(gr_line
		(start 231.638348 -54.101746)
		(end 231.726486 -54.233572)
		(stroke
			(width 0.08255)
			(type default)
		)
		(layer "B.Cu")
	)
	(gr_line
		(start 231.64419 -57.323482)
		(end 231.775762 -57.235598)
		(stroke
			(width 0.08255)
			(type default)
		)
		(layer "B.Cu")
	)
	(gr_line
		(start 231.673908 -164.8079)
		(end 231.704134 -164.652706)
		(stroke
			(width 0.08255)
			(type default)
		)
		(layer "B.Cu")
	)
	(gr_line
		(start 231.673908 -164.8079)
		(end 231.951022 -165.218618)
		(stroke
			(width 0.08255)
			(type default)
		)
		(layer "B.Cu")
	)
	(gr_line
		(start 231.697276 -168.694354)
		(end 231.727502 -168.538906)
		(stroke
			(width 0.08255)
			(type default)
		)
		(layer "B.Cu")
	)
	(gr_line
		(start 231.697276 -168.694354)
		(end 231.97439 -169.105072)
		(stroke
			(width 0.08255)
			(type default)
		)
		(layer "B.Cu")
	)
	(gr_line
		(start 231.735884 -64.842644)
		(end 231.758236 -64.999108)
		(stroke
			(width 0.08255)
			(type default)
		)
		(layer "B.Cu")
	)
	(gr_line
		(start 231.775762 -57.235598)
		(end 232.261664 -57.332118)
		(stroke
			(width 0.08255)
			(type default)
		)
		(layer "B.Cu")
	)
	(gr_line
		(start 231.80675 -36.69792)
		(end 231.895396 -36.829492)
		(stroke
			(width 0.08255)
			(type default)
		)
		(layer "B.Cu")
	)
	(gr_line
		(start 231.827832 -172.996352)
		(end 231.98328 -173.026578)
		(stroke
			(width 0.08255)
			(type default)
		)
		(layer "B.Cu")
	)
	(gr_line
		(start 231.84358 -172.292264)
		(end 232.209848 -172.835062)
		(stroke
			(width 0.08255)
			(type default)
		)
		(layer "B.Cu")
	)
	(gr_line
		(start 231.895396 -36.829492)
		(end 232.381552 -36.92398)
		(stroke
			(width 0.08255)
			(type default)
		)
		(layer "B.Cu")
	)
	(gr_line
		(start 231.897936 -36.415726)
		(end 232.535476 -36.539678)
		(stroke
			(width 0.08255)
			(type default)
		)
		(layer "B.Cu")
	)
	(gr_line
		(start 231.944418 -79.536798)
		(end 232.04043 -79.411322)
		(stroke
			(width 0.08255)
			(type default)
		)
		(layer "B.Cu")
	)
	(gr_line
		(start 231.951022 -165.218618)
		(end 232.10647 -165.249098)
		(stroke
			(width 0.08255)
			(type default)
		)
		(layer "B.Cu")
	)
	(gr_line
		(start 231.967786 -164.516054)
		(end 232.332276 -165.056566)
		(stroke
			(width 0.08255)
			(type default)
		)
		(layer "B.Cu")
	)
	(gr_line
		(start 231.97439 -169.105072)
		(end 232.129838 -169.135298)
		(stroke
			(width 0.08255)
			(type default)
		)
		(layer "B.Cu")
	)
	(gr_line
		(start 231.99217 -168.404286)
		(end 232.35412 -168.940988)
		(stroke
			(width 0.08255)
			(type default)
		)
		(layer "B.Cu")
	)
	(gr_line
		(start 232.009696 -65.556638)
		(end 232.526332 -65.94475)
		(stroke
			(width 0.08255)
			(type default)
		)
		(layer "B.Cu")
	)
	(gr_line
		(start 232.019602 -79.823818)
		(end 232.66019 -79.73822)
		(stroke
			(width 0.08255)
			(type default)
		)
		(layer "B.Cu")
	)
	(gr_line
		(start 232.04043 -79.411322)
		(end 232.531412 -79.345536)
		(stroke
			(width 0.08255)
			(type default)
		)
		(layer "B.Cu")
	)
	(gr_line
		(start 232.113328 -161.28746)
		(end 232.143554 -161.132012)
		(stroke
			(width 0.08255)
			(type default)
		)
		(layer "B.Cu")
	)
	(gr_line
		(start 232.113328 -161.28746)
		(end 232.390188 -161.697924)
		(stroke
			(width 0.08255)
			(type default)
		)
		(layer "B.Cu")
	)
	(gr_line
		(start 232.158032 -65.29959)
		(end 232.31475 -65.277492)
		(stroke
			(width 0.08255)
			(type default)
		)
		(layer "B.Cu")
	)
	(gr_line
		(start 232.190036 -54.627272)
		(end 232.832148 -54.756304)
		(stroke
			(width 0.08255)
			(type default)
		)
		(layer "B.Cu")
	)
	(gr_line
		(start 232.216198 -54.332124)
		(end 232.348278 -54.24424)
		(stroke
			(width 0.08255)
			(type default)
		)
		(layer "B.Cu")
	)
	(gr_line
		(start 232.232708 -173.596554)
		(end 232.26268 -173.441106)
		(stroke
			(width 0.08255)
			(type default)
		)
		(layer "B.Cu")
	)
	(gr_line
		(start 232.232708 -173.596554)
		(end 232.509568 -174.007272)
		(stroke
			(width 0.08255)
			(type default)
		)
		(layer "B.Cu")
	)
	(gr_line
		(start 232.261664 -57.332118)
		(end 232.349548 -57.46369)
		(stroke
			(width 0.08255)
			(type default)
		)
		(layer "B.Cu")
	)
	(gr_line
		(start 232.31475 -65.277492)
		(end 232.710736 -65.574926)
		(stroke
			(width 0.08255)
			(type default)
		)
		(layer "B.Cu")
	)
	(gr_line
		(start 232.348278 -54.24424)
		(end 232.833672 -54.341776)
		(stroke
			(width 0.08255)
			(type default)
		)
		(layer "B.Cu")
	)
	(gr_line
		(start 232.355644 -165.81882)
		(end 232.38587 -165.663372)
		(stroke
			(width 0.08255)
			(type default)
		)
		(layer "B.Cu")
	)
	(gr_line
		(start 232.355644 -165.81882)
		(end 232.632758 -166.229538)
		(stroke
			(width 0.08255)
			(type default)
		)
		(layer "B.Cu")
	)
	(gr_line
		(start 232.379012 -169.705274)
		(end 232.409238 -169.549826)
		(stroke
			(width 0.08255)
			(type default)
		)
		(layer "B.Cu")
	)
	(gr_line
		(start 232.379012 -169.705274)
		(end 232.656126 -170.115738)
		(stroke
			(width 0.08255)
			(type default)
		)
		(layer "B.Cu")
	)
	(gr_line
		(start 232.381552 -36.92398)
		(end 232.513124 -36.835334)
		(stroke
			(width 0.08255)
			(type default)
		)
		(layer "B.Cu")
	)
	(gr_line
		(start 232.390188 -161.697924)
		(end 232.545636 -161.72815)
		(stroke
			(width 0.08255)
			(type default)
		)
		(layer "B.Cu")
	)
	(gr_line
		(start 232.407714 -160.997138)
		(end 232.769156 -161.533078)
		(stroke
			(width 0.08255)
			(type default)
		)
		(layer "B.Cu")
	)
	(gr_line
		(start 232.435908 -97.844864)
		(end 232.439718 -97.839022)
		(stroke
			(width 0.08255)
			(type default)
		)
		(layer "B.Cu")
	)
	(gr_line
		(start 232.439718 -97.839022)
		(end 232.44556 -97.83445)
		(stroke
			(width 0.08255)
			(type default)
		)
		(layer "B.Cu")
	)
	(gr_line
		(start 232.509568 -174.007272)
		(end 232.665016 -174.037244)
		(stroke
			(width 0.08255)
			(type default)
		)
		(layer "B.Cu")
	)
	(gr_line
		(start 232.52557 -173.303438)
		(end 232.89133 -173.845474)
		(stroke
			(width 0.08255)
			(type default)
		)
		(layer "B.Cu")
	)
	(gr_line
		(start 232.531412 -79.345536)
		(end 232.656888 -79.441548)
		(stroke
			(width 0.08255)
			(type default)
		)
		(layer "B.Cu")
	)
	(gr_line
		(start 232.632758 -166.229538)
		(end 232.788206 -166.259764)
		(stroke
			(width 0.08255)
			(type default)
		)
		(layer "B.Cu")
	)
	(gr_line
		(start 232.650284 -165.528244)
		(end 233.01325 -166.06647)
		(stroke
			(width 0.08255)
			(type default)
		)
		(layer "B.Cu")
	)
	(gr_line
		(start 232.656126 -170.115738)
		(end 232.811574 -170.146218)
		(stroke
			(width 0.08255)
			(type default)
		)
		(layer "B.Cu")
	)
	(gr_line
		(start 232.673906 -169.41546)
		(end 233.036364 -169.952924)
		(stroke
			(width 0.08255)
			(type default)
		)
		(layer "B.Cu")
	)
	(gr_line
		(start 232.710736 -65.574926)
		(end 232.732834 -65.73139)
		(stroke
			(width 0.08255)
			(type default)
		)
		(layer "B.Cu")
	)
	(gr_line
		(start 232.795064 -162.298126)
		(end 232.82529 -162.142678)
		(stroke
			(width 0.08255)
			(type default)
		)
		(layer "B.Cu")
	)
	(gr_line
		(start 232.795064 -162.298126)
		(end 233.071924 -162.708844)
		(stroke
			(width 0.08255)
			(type default)
		)
		(layer "B.Cu")
	)
	(gr_line
		(start 232.806748 -57.556908)
		(end 232.837228 -57.563004)
		(stroke
			(width 0.08255)
			(type default)
		)
		(layer "B.Cu")
	)
	(gr_line
		(start 232.833672 -54.341776)
		(end 232.92181 -54.473602)
		(stroke
			(width 0.08255)
			(type default)
		)
		(layer "B.Cu")
	)
	(gr_line
		(start 232.837228 -57.563004)
		(end 232.86212 -57.582054)
		(stroke
			(width 0.08255)
			(type default)
		)
		(layer "B.Cu")
	)
	(gr_line
		(start 232.887012 -103.08971)
		(end 232.89133 -103.067612)
		(stroke
			(width 0.08255)
			(type default)
		)
		(layer "B.Cu")
	)
	(gr_line
		(start 232.89133 -103.067612)
		(end 232.903776 -103.04907)
		(stroke
			(width 0.08255)
			(type default)
		)
		(layer "B.Cu")
	)
	(gr_line
		(start 232.914444 -174.607474)
		(end 232.94467 -174.452026)
		(stroke
			(width 0.08255)
			(type default)
		)
		(layer "B.Cu")
	)
	(gr_line
		(start 232.914444 -174.607474)
		(end 233.191304 -175.017938)
		(stroke
			(width 0.08255)
			(type default)
		)
		(layer "B.Cu")
	)
	(gr_line
		(start 232.950004 -66.263266)
		(end 232.958386 -66.269616)
		(stroke
			(width 0.08255)
			(type default)
		)
		(layer "B.Cu")
	)
	(gr_line
		(start 232.98531 -66.289682)
		(end 233.501184 -66.677286)
		(stroke
			(width 0.08255)
			(type default)
		)
		(layer "B.Cu")
	)
	(gr_line
		(start 233.00309 -65.937638)
		(end 233.129328 -66.032634)
		(stroke
			(width 0.08255)
			(type default)
		)
		(layer "B.Cu")
	)
	(gr_line
		(start 233.03738 -166.829486)
		(end 233.067606 -166.674292)
		(stroke
			(width 0.08255)
			(type default)
		)
		(layer "B.Cu")
	)
	(gr_line
		(start 233.03738 -166.829486)
		(end 233.31424 -167.240204)
		(stroke
			(width 0.08255)
			(type default)
		)
		(layer "B.Cu")
	)
	(gr_line
		(start 233.060748 -170.71594)
		(end 233.090974 -170.560492)
		(stroke
			(width 0.08255)
			(type default)
		)
		(layer "B.Cu")
	)
	(gr_line
		(start 233.060748 -170.71594)
		(end 233.337862 -171.126658)
		(stroke
			(width 0.08255)
			(type default)
		)
		(layer "B.Cu")
	)
	(gr_line
		(start 233.071924 -162.708844)
		(end 233.227372 -162.738816)
		(stroke
			(width 0.08255)
			(type default)
		)
		(layer "B.Cu")
	)
	(gr_line
		(start 233.088688 -162.006534)
		(end 233.451146 -162.543998)
		(stroke
			(width 0.08255)
			(type default)
		)
		(layer "B.Cu")
	)
	(gr_line
		(start 233.132884 -66.032126)
		(end 233.289348 -66.009774)
		(stroke
			(width 0.08255)
			(type default)
		)
		(layer "B.Cu")
	)
	(gr_line
		(start 233.152696 -79.375)
		(end 233.248708 -79.24927)
		(stroke
			(width 0.08255)
			(type default)
		)
		(layer "B.Cu")
	)
	(gr_line
		(start 233.191304 -175.017938)
		(end 233.346752 -175.048164)
		(stroke
			(width 0.08255)
			(type default)
		)
		(layer "B.Cu")
	)
	(gr_line
		(start 233.207052 -174.31385)
		(end 233.572812 -174.855886)
		(stroke
			(width 0.08255)
			(type default)
		)
		(layer "B.Cu")
	)
	(gr_line
		(start 233.22788 -79.662274)
		(end 233.869484 -79.576168)
		(stroke
			(width 0.08255)
			(type default)
		)
		(layer "B.Cu")
	)
	(gr_line
		(start 233.248708 -79.24927)
		(end 233.73969 -79.183484)
		(stroke
			(width 0.08255)
			(type default)
		)
		(layer "B.Cu")
	)
	(gr_line
		(start 233.289348 -66.009774)
		(end 233.685334 -66.307462)
		(stroke
			(width 0.08255)
			(type default)
		)
		(layer "B.Cu")
	)
	(gr_line
		(start 233.31424 -167.240204)
		(end 233.469942 -167.270684)
		(stroke
			(width 0.08255)
			(type default)
		)
		(layer "B.Cu")
	)
	(gr_line
		(start 233.331512 -166.538148)
		(end 233.696002 -167.07866)
		(stroke
			(width 0.08255)
			(type default)
		)
		(layer "B.Cu")
	)
	(gr_line
		(start 233.337862 -171.126658)
		(end 233.49331 -171.156884)
		(stroke
			(width 0.08255)
			(type default)
		)
		(layer "B.Cu")
	)
	(gr_line
		(start 233.355388 -170.425364)
		(end 233.718862 -170.964352)
		(stroke
			(width 0.08255)
			(type default)
		)
		(layer "B.Cu")
	)
	(gr_line
		(start 233.4768 -163.309046)
		(end 233.507026 -163.153598)
		(stroke
			(width 0.08255)
			(type default)
		)
		(layer "B.Cu")
	)
	(gr_line
		(start 233.4768 -163.309046)
		(end 233.75366 -163.71951)
		(stroke
			(width 0.08255)
			(type default)
		)
		(layer "B.Cu")
	)
	(gr_line
		(start 233.595926 -175.61814)
		(end 233.626152 -175.462692)
		(stroke
			(width 0.08255)
			(type default)
		)
		(layer "B.Cu")
	)
	(gr_line
		(start 233.595926 -175.61814)
		(end 233.87304 -176.028858)
		(stroke
			(width 0.08255)
			(type default)
		)
		(layer "B.Cu")
	)
	(gr_line
		(start 233.685334 -66.307462)
		(end 233.707686 -66.463926)
		(stroke
			(width 0.08255)
			(type default)
		)
		(layer "B.Cu")
	)
	(gr_line
		(start 233.712512 -98.839528)
		(end 233.715814 -98.834448)
		(stroke
			(width 0.08255)
			(type default)
		)
		(layer "B.Cu")
	)
	(gr_line
		(start 233.715814 -98.834448)
		(end 233.72064 -98.830384)
		(stroke
			(width 0.08255)
			(type default)
		)
		(layer "B.Cu")
	)
	(gr_line
		(start 233.719116 -167.840406)
		(end 233.749342 -167.684958)
		(stroke
			(width 0.08255)
			(type default)
		)
		(layer "B.Cu")
	)
	(gr_line
		(start 233.719116 -167.840406)
		(end 233.995976 -168.251124)
		(stroke
			(width 0.08255)
			(type default)
		)
		(layer "B.Cu")
	)
	(gr_line
		(start 233.73969 -79.183484)
		(end 233.86542 -79.279496)
		(stroke
			(width 0.08255)
			(type default)
		)
		(layer "B.Cu")
	)
	(gr_line
		(start 233.742484 -171.726606)
		(end 233.772964 -171.571412)
		(stroke
			(width 0.08255)
			(type default)
		)
		(layer "B.Cu")
	)
	(gr_line
		(start 233.742484 -171.726606)
		(end 234.019598 -172.137324)
		(stroke
			(width 0.08255)
			(type default)
		)
		(layer "B.Cu")
	)
	(gr_line
		(start 233.75366 -163.71951)
		(end 233.909108 -163.749736)
		(stroke
			(width 0.08255)
			(type default)
		)
		(layer "B.Cu")
	)
	(gr_line
		(start 233.770678 -163.017454)
		(end 234.133644 -163.55568)
		(stroke
			(width 0.08255)
			(type default)
		)
		(layer "B.Cu")
	)
	(gr_line
		(start 233.87304 -176.028858)
		(end 234.028488 -176.05883)
		(stroke
			(width 0.08255)
			(type default)
		)
		(layer "B.Cu")
	)
	(gr_line
		(start 233.890058 -175.326548)
		(end 234.253024 -175.864774)
		(stroke
			(width 0.08255)
			(type default)
		)
		(layer "B.Cu")
	)
	(gr_line
		(start 233.995976 -168.251124)
		(end 234.151678 -168.28135)
		(stroke
			(width 0.08255)
			(type default)
		)
		(layer "B.Cu")
	)
	(gr_line
		(start 234.013502 -167.549322)
		(end 234.376976 -168.08831)
		(stroke
			(width 0.08255)
			(type default)
		)
		(layer "B.Cu")
	)
	(gr_line
		(start 234.019598 -172.137324)
		(end 234.175046 -172.167804)
		(stroke
			(width 0.08255)
			(type default)
		)
		(layer "B.Cu")
	)
	(gr_line
		(start 234.036362 -171.43476)
		(end 234.400852 -171.975272)
		(stroke
			(width 0.08255)
			(type default)
		)
		(layer "B.Cu")
	)
	(gr_line
		(start 234.158536 -164.319712)
		(end 234.188762 -164.164264)
		(stroke
			(width 0.08255)
			(type default)
		)
		(layer "B.Cu")
	)
	(gr_line
		(start 234.158536 -164.319712)
		(end 234.435396 -164.73043)
		(stroke
			(width 0.08255)
			(type default)
		)
		(layer "B.Cu")
	)
	(gr_line
		(start 234.344464 -67.310762)
		(end 234.3912 -67.346068)
		(stroke
			(width 0.08255)
			(type default)
		)
		(layer "B.Cu")
	)
	(gr_line
		(start 234.361228 -79.212948)
		(end 234.45724 -79.087472)
		(stroke
			(width 0.08255)
			(type default)
		)
		(layer "B.Cu")
	)
	(gr_line
		(start 234.367324 -54.766464)
		(end 234.367578 -54.766464)
		(stroke
			(width 0.08255)
			(type default)
		)
		(layer "B.Cu")
	)
	(gr_line
		(start 234.367578 -54.766464)
		(end 234.368086 -54.766718)
		(stroke
			(width 0.08255)
			(type default)
		)
		(layer "B.Cu")
	)
	(gr_line
		(start 234.435396 -164.73043)
		(end 234.590844 -164.760402)
		(stroke
			(width 0.08255)
			(type default)
		)
		(layer "B.Cu")
	)
	(gr_line
		(start 234.436412 -79.499968)
		(end 235.077 -79.41437)
		(stroke
			(width 0.08255)
			(type default)
		)
		(layer "B.Cu")
	)
	(gr_line
		(start 234.451652 -164.027358)
		(end 234.81538 -164.566346)
		(stroke
			(width 0.08255)
			(type default)
		)
		(layer "B.Cu")
	)
	(gr_line
		(start 234.45724 -79.087472)
		(end 234.947968 -79.021686)
		(stroke
			(width 0.08255)
			(type default)
		)
		(layer "B.Cu")
	)
	(gr_line
		(start 234.573064 -59.269122)
		(end 234.621578 -59.30646)
		(stroke
			(width 0.08255)
			(type default)
		)
		(layer "B.Cu")
	)
	(gr_line
		(start 234.62361 -168.977056)
		(end 234.629452 -168.985692)
		(stroke
			(width 0.08255)
			(type default)
		)
		(layer "B.Cu")
	)
	(gr_line
		(start 234.629452 -168.985692)
		(end 234.637326 -168.991534)
		(stroke
			(width 0.08255)
			(type default)
		)
		(layer "B.Cu")
	)
	(gr_line
		(start 234.67949 -177.02022)
		(end 234.685332 -177.028856)
		(stroke
			(width 0.08255)
			(type default)
		)
		(layer "B.Cu")
	)
	(gr_line
		(start 234.685332 -177.028856)
		(end 234.693206 -177.034698)
		(stroke
			(width 0.08255)
			(type default)
		)
		(layer "B.Cu")
	)
	(gr_line
		(start 234.780074 -55.293514)
		(end 234.80649 -55.306468)
		(stroke
			(width 0.08255)
			(type default)
		)
		(layer "B.Cu")
	)
	(gr_line
		(start 234.832144 -173.13783)
		(end 234.837986 -173.146466)
		(stroke
			(width 0.08255)
			(type default)
		)
		(layer "B.Cu")
	)
	(gr_line
		(start 234.837986 -173.146466)
		(end 234.84586 -173.152308)
		(stroke
			(width 0.08255)
			(type default)
		)
		(layer "B.Cu")
	)
	(gr_line
		(start 234.865164 -165.163246)
		(end 234.871006 -165.171882)
		(stroke
			(width 0.08255)
			(type default)
		)
		(layer "B.Cu")
	)
	(gr_line
		(start 234.871006 -165.171882)
		(end 234.87888 -165.177724)
		(stroke
			(width 0.08255)
			(type default)
		)
		(layer "B.Cu")
	)
	(gr_line
		(start 234.947968 -79.021686)
		(end 235.073698 -79.117444)
		(stroke
			(width 0.08255)
			(type default)
		)
		(layer "B.Cu")
	)
	(gr_line
		(start 234.976162 -63.269114)
		(end 235.024676 -63.306452)
		(stroke
			(width 0.08255)
			(type default)
		)
		(layer "B.Cu")
	)
	(gr_line
		(start 235.117894 -99.76739)
		(end 235.121704 -99.761548)
		(stroke
			(width 0.08255)
			(type default)
		)
		(layer "B.Cu")
	)
	(gr_line
		(start 235.121704 -99.761548)
		(end 235.127546 -99.756976)
		(stroke
			(width 0.08255)
			(type default)
		)
		(layer "B.Cu")
	)
	(gr_line
		(start 235.47324 -177.635662)
		(end 235.521754 -177.673)
		(stroke
			(width 0.08255)
			(type default)
		)
		(layer "B.Cu")
	)
	(gr_line
		(start 235.47324 -173.63567)
		(end 235.521754 -173.673008)
		(stroke
			(width 0.08255)
			(type default)
		)
		(layer "B.Cu")
	)
	(gr_line
		(start 235.47324 -169.635678)
		(end 235.521754 -169.673016)
		(stroke
			(width 0.08255)
			(type default)
		)
		(layer "B.Cu")
	)
	(gr_line
		(start 235.47324 -165.635686)
		(end 235.521754 -165.673024)
		(stroke
			(width 0.08255)
			(type default)
		)
		(layer "B.Cu")
	)
	(gr_line
		(start 235.521754 -177.673)
		(end 235.584238 -177.673254)
		(stroke
			(width 0.08255)
			(type default)
		)
		(layer "B.Cu")
	)
	(gr_line
		(start 235.521754 -173.673008)
		(end 235.584238 -173.673262)
		(stroke
			(width 0.08255)
			(type default)
		)
		(layer "B.Cu")
	)
	(gr_line
		(start 235.521754 -169.673016)
		(end 235.584238 -169.67327)
		(stroke
			(width 0.08255)
			(type default)
		)
		(layer "B.Cu")
	)
	(gr_line
		(start 235.521754 -165.673024)
		(end 235.584746 -165.673278)
		(stroke
			(width 0.08255)
			(type default)
		)
		(layer "B.Cu")
	)
	(gr_line
		(start 236.050074 -178.49977)
		(end 236.723682 -178.162458)
		(stroke
			(width 0.08255)
			(type default)
		)
		(layer "B.Cu")
	)
	(gr_line
		(start 236.050074 -174.499778)
		(end 236.723682 -174.162466)
		(stroke
			(width 0.08255)
			(type default)
		)
		(layer "B.Cu")
	)
	(gr_line
		(start 236.050074 -170.499786)
		(end 236.723682 -170.162474)
		(stroke
			(width 0.08255)
			(type default)
		)
		(layer "B.Cu")
	)
	(gr_line
		(start 236.050074 -166.499794)
		(end 236.723682 -166.162482)
		(stroke
			(width 0.08255)
			(type default)
		)
		(layer "B.Cu")
	)
	(gr_line
		(start 236.050074 -82.199988)
		(end 236.710728 -81.861406)
		(stroke
			(width 0.08255)
			(type default)
		)
		(layer "B.Cu")
	)
	(gr_line
		(start 236.050074 -78.199996)
		(end 236.710728 -77.861414)
		(stroke
			(width 0.08255)
			(type default)
		)
		(layer "B.Cu")
	)
	(gr_line
		(start 236.050074 -74.200004)
		(end 236.710728 -73.861422)
		(stroke
			(width 0.08255)
			(type default)
		)
		(layer "B.Cu")
	)
	(gr_line
		(start 236.050074 -70.200012)
		(end 236.710728 -69.86143)
		(stroke
			(width 0.08255)
			(type default)
		)
		(layer "B.Cu")
	)
	(gr_line
		(start 236.050074 -66.20002)
		(end 236.710728 -65.861438)
		(stroke
			(width 0.08255)
			(type default)
		)
		(layer "B.Cu")
	)
	(gr_line
		(start 236.050074 -62.200028)
		(end 236.710728 -61.861446)
		(stroke
			(width 0.08255)
			(type default)
		)
		(layer "B.Cu")
	)
	(gr_line
		(start 236.050074 -58.200036)
		(end 236.710728 -57.861454)
		(stroke
			(width 0.08255)
			(type default)
		)
		(layer "B.Cu")
	)
	(gr_line
		(start 236.050074 -54.200044)
		(end 236.710728 -53.861462)
		(stroke
			(width 0.08255)
			(type default)
		)
		(layer "B.Cu")
	)
	(gr_line
		(start 236.050074 -50.200052)
		(end 236.723682 -49.86274)
		(stroke
			(width 0.08255)
			(type default)
		)
		(layer "B.Cu")
	)
	(gr_line
		(start 236.050074 -46.20006)
		(end 236.723682 -45.862748)
		(stroke
			(width 0.08255)
			(type default)
		)
		(layer "B.Cu")
	)
	(gr_line
		(start 236.050074 -42.200068)
		(end 236.723682 -41.862756)
		(stroke
			(width 0.08255)
			(type default)
		)
		(layer "B.Cu")
	)
	(gr_line
		(start 236.050074 -38.200076)
		(end 236.723682 -37.862764)
		(stroke
			(width 0.08255)
			(type default)
		)
		(layer "B.Cu")
	)
	(gr_line
		(start 236.38256 -173.383702)
		(end 236.388148 -173.383702)
		(stroke
			(width 0.08255)
			(type default)
		)
		(layer "B.Cu")
	)
	(gr_line
		(start 236.38256 -169.38371)
		(end 236.388148 -169.38371)
		(stroke
			(width 0.08255)
			(type default)
		)
		(layer "B.Cu")
	)
	(gr_line
		(start 236.388402 -173.675802)
		(end 236.381544 -173.675802)
		(stroke
			(width 0.08255)
			(type default)
		)
		(layer "B.Cu")
	)
	(gr_line
		(start 236.388402 -169.67581)
		(end 236.381544 -169.67581)
		(stroke
			(width 0.08255)
			(type default)
		)
		(layer "B.Cu")
	)
	(gr_arc
		(start 236.723682 -178.162458)
		(mid 236.784144 -178.111427)
		(end 236.814868 -178.038506)
		(stroke
			(width 0.08255)
			(type default)
		)
		(layer "B.Cu")
	)
	(gr_arc
		(start 236.723682 -174.162466)
		(mid 236.784147 -174.111436)
		(end 236.814868 -174.038514)
		(stroke
			(width 0.08255)
			(type default)
		)
		(layer "B.Cu")
	)
	(gr_arc
		(start 236.723682 -170.162474)
		(mid 236.784149 -170.111444)
		(end 236.814868 -170.038522)
		(stroke
			(width 0.08255)
			(type default)
		)
		(layer "B.Cu")
	)
	(gr_arc
		(start 236.723682 -166.162482)
		(mid 236.784151 -166.111453)
		(end 236.814868 -166.03853)
		(stroke
			(width 0.08255)
			(type default)
		)
		(layer "B.Cu")
	)
	(gr_arc
		(start 236.723682 -49.86274)
		(mid 236.784139 -49.811707)
		(end 236.814868 -49.738788)
		(stroke
			(width 0.08255)
			(type default)
		)
		(layer "B.Cu")
	)
	(gr_arc
		(start 236.723682 -45.862748)
		(mid 236.784141 -45.811716)
		(end 236.814868 -45.738796)
		(stroke
			(width 0.08255)
			(type default)
		)
		(layer "B.Cu")
	)
	(gr_arc
		(start 236.723682 -41.862756)
		(mid 236.784144 -41.811725)
		(end 236.814868 -41.738804)
		(stroke
			(width 0.08255)
			(type default)
		)
		(layer "B.Cu")
	)
	(gr_arc
		(start 236.723682 -37.862764)
		(mid 236.784146 -37.811733)
		(end 236.814868 -37.738812)
		(stroke
			(width 0.08255)
			(type default)
		)
		(layer "B.Cu")
	)
	(gr_arc
		(start 236.814868 -178.038506)
		(mid 236.808861 -177.95978)
		(end 236.767624 -177.892456)
		(stroke
			(width 0.08255)
			(type default)
		)
		(layer "B.Cu")
	)
	(gr_arc
		(start 236.814868 -174.038514)
		(mid 236.808865 -173.959786)
		(end 236.767624 -173.892464)
		(stroke
			(width 0.08255)
			(type default)
		)
		(layer "B.Cu")
	)
	(gr_arc
		(start 236.814868 -170.038522)
		(mid 236.808868 -169.959792)
		(end 236.767624 -169.892472)
		(stroke
			(width 0.08255)
			(type default)
		)
		(layer "B.Cu")
	)
	(gr_arc
		(start 236.814868 -166.03853)
		(mid 236.80883 -165.959823)
		(end 236.767624 -165.89248)
		(stroke
			(width 0.08255)
			(type default)
		)
		(layer "B.Cu")
	)
	(gr_arc
		(start 236.814868 -49.738788)
		(mid 236.808854 -49.660067)
		(end 236.767624 -49.592738)
		(stroke
			(width 0.08255)
			(type default)
		)
		(layer "B.Cu")
	)
	(gr_arc
		(start 236.814868 -45.738796)
		(mid 236.808857 -45.660073)
		(end 236.767624 -45.592746)
		(stroke
			(width 0.08255)
			(type default)
		)
		(layer "B.Cu")
	)
	(gr_arc
		(start 236.814868 -41.738804)
		(mid 236.80886 -41.660079)
		(end 236.767624 -41.592754)
		(stroke
			(width 0.08255)
			(type default)
		)
		(layer "B.Cu")
	)
	(gr_arc
		(start 236.814868 -37.738812)
		(mid 236.808864 -37.660085)
		(end 236.767624 -37.592762)
		(stroke
			(width 0.08255)
			(type default)
		)
		(layer "B.Cu")
	)
	(gr_arc
		(start 236.866176 -81.836514)
		(mid 236.786466 -81.836587)
		(end 236.710728 -81.861406)
		(stroke
			(width 0.08255)
			(type default)
		)
		(layer "B.Cu")
	)
	(gr_line
		(start 236.866176 -81.836514)
		(end 236.88167 -81.839054)
		(stroke
			(width 0.08255)
			(type default)
		)
		(layer "B.Cu")
	)
	(gr_arc
		(start 236.866176 -77.836522)
		(mid 236.786466 -77.836595)
		(end 236.710728 -77.861414)
		(stroke
			(width 0.08255)
			(type default)
		)
		(layer "B.Cu")
	)
	(gr_line
		(start 236.866176 -77.836522)
		(end 236.88167 -77.839062)
		(stroke
			(width 0.08255)
			(type default)
		)
		(layer "B.Cu")
	)
	(gr_arc
		(start 236.866176 -73.83653)
		(mid 236.786466 -73.836603)
		(end 236.710728 -73.861422)
		(stroke
			(width 0.08255)
			(type default)
		)
		(layer "B.Cu")
	)
	(gr_line
		(start 236.866176 -73.83653)
		(end 236.88167 -73.83907)
		(stroke
			(width 0.08255)
			(type default)
		)
		(layer "B.Cu")
	)
	(gr_arc
		(start 236.866176 -69.836538)
		(mid 236.786466 -69.836611)
		(end 236.710728 -69.86143)
		(stroke
			(width 0.08255)
			(type default)
		)
		(layer "B.Cu")
	)
	(gr_line
		(start 236.866176 -69.836538)
		(end 236.88167 -69.839078)
		(stroke
			(width 0.08255)
			(type default)
		)
		(layer "B.Cu")
	)
	(gr_arc
		(start 236.866176 -65.836546)
		(mid 236.786466 -65.836619)
		(end 236.710728 -65.861438)
		(stroke
			(width 0.08255)
			(type default)
		)
		(layer "B.Cu")
	)
	(gr_line
		(start 236.866176 -65.836546)
		(end 236.88167 -65.839086)
		(stroke
			(width 0.08255)
			(type default)
		)
		(layer "B.Cu")
	)
	(gr_arc
		(start 236.866176 -61.836554)
		(mid 236.786466 -61.836627)
		(end 236.710728 -61.861446)
		(stroke
			(width 0.08255)
			(type default)
		)
		(layer "B.Cu")
	)
	(gr_line
		(start 236.866176 -61.836554)
		(end 236.88167 -61.839094)
		(stroke
			(width 0.08255)
			(type default)
		)
		(layer "B.Cu")
	)
	(gr_arc
		(start 236.866176 -57.836562)
		(mid 236.786466 -57.836635)
		(end 236.710728 -57.861454)
		(stroke
			(width 0.08255)
			(type default)
		)
		(layer "B.Cu")
	)
	(gr_line
		(start 236.866176 -57.836562)
		(end 236.88167 -57.839102)
		(stroke
			(width 0.08255)
			(type default)
		)
		(layer "B.Cu")
	)
	(gr_arc
		(start 236.866176 -53.83657)
		(mid 236.786466 -53.836643)
		(end 236.710728 -53.861462)
		(stroke
			(width 0.08255)
			(type default)
		)
		(layer "B.Cu")
	)
	(gr_line
		(start 236.866176 -53.83657)
		(end 236.88167 -53.83911)
		(stroke
			(width 0.08255)
			(type default)
		)
		(layer "B.Cu")
	)
	(gr_arc
		(start 237.021878 -81.910174)
		(mid 236.957412 -81.863502)
		(end 236.88167 -81.839054)
		(stroke
			(width 0.08255)
			(type default)
		)
		(layer "B.Cu")
	)
	(gr_arc
		(start 237.021878 -77.910182)
		(mid 236.957412 -77.86351)
		(end 236.88167 -77.839062)
		(stroke
			(width 0.08255)
			(type default)
		)
		(layer "B.Cu")
	)
	(gr_arc
		(start 237.021878 -73.91019)
		(mid 236.957412 -73.863518)
		(end 236.88167 -73.83907)
		(stroke
			(width 0.08255)
			(type default)
		)
		(layer "B.Cu")
	)
	(gr_arc
		(start 237.021878 -69.910198)
		(mid 236.957412 -69.863526)
		(end 236.88167 -69.839078)
		(stroke
			(width 0.08255)
			(type default)
		)
		(layer "B.Cu")
	)
	(gr_arc
		(start 237.021878 -65.910206)
		(mid 236.957412 -65.863534)
		(end 236.88167 -65.839086)
		(stroke
			(width 0.08255)
			(type default)
		)
		(layer "B.Cu")
	)
	(gr_arc
		(start 237.021878 -61.910214)
		(mid 236.957412 -61.863542)
		(end 236.88167 -61.839094)
		(stroke
			(width 0.08255)
			(type default)
		)
		(layer "B.Cu")
	)
	(gr_arc
		(start 237.021878 -57.910222)
		(mid 236.957412 -57.86355)
		(end 236.88167 -57.839102)
		(stroke
			(width 0.08255)
			(type default)
		)
		(layer "B.Cu")
	)
	(gr_arc
		(start 237.021878 -53.91023)
		(mid 236.957412 -53.863558)
		(end 236.88167 -53.83911)
		(stroke
			(width 0.08255)
			(type default)
		)
		(layer "B.Cu")
	)
	(gr_arc
		(start 237.078266 -177.789586)
		(mid 237.142732 -177.836258)
		(end 237.218474 -177.860706)
		(stroke
			(width 0.08255)
			(type default)
		)
		(layer "B.Cu")
	)
	(gr_arc
		(start 237.078266 -173.789594)
		(mid 237.142732 -173.836266)
		(end 237.218474 -173.860714)
		(stroke
			(width 0.08255)
			(type default)
		)
		(layer "B.Cu")
	)
	(gr_arc
		(start 237.078266 -169.789602)
		(mid 237.142732 -169.836274)
		(end 237.218474 -169.860722)
		(stroke
			(width 0.08255)
			(type default)
		)
		(layer "B.Cu")
	)
	(gr_arc
		(start 237.078266 -165.78961)
		(mid 237.142732 -165.836282)
		(end 237.218474 -165.86073)
		(stroke
			(width 0.08255)
			(type default)
		)
		(layer "B.Cu")
	)
	(gr_arc
		(start 237.078266 -49.489868)
		(mid 237.142732 -49.53654)
		(end 237.218474 -49.560988)
		(stroke
			(width 0.08255)
			(type default)
		)
		(layer "B.Cu")
	)
	(gr_arc
		(start 237.078266 -45.489876)
		(mid 237.142732 -45.536548)
		(end 237.218474 -45.560996)
		(stroke
			(width 0.08255)
			(type default)
		)
		(layer "B.Cu")
	)
	(gr_arc
		(start 237.078266 -41.489884)
		(mid 237.142732 -41.536556)
		(end 237.218474 -41.561004)
		(stroke
			(width 0.08255)
			(type default)
		)
		(layer "B.Cu")
	)
	(gr_arc
		(start 237.078266 -37.489892)
		(mid 237.142732 -37.536564)
		(end 237.218474 -37.561012)
		(stroke
			(width 0.08255)
			(type default)
		)
		(layer "B.Cu")
	)
	(gr_arc
		(start 237.18393 -82.423254)
		(mid 237.219671 -82.369764)
		(end 237.23219 -82.306668)
		(stroke
			(width 0.08255)
			(type default)
		)
		(layer "B.Cu")
	)
	(gr_arc
		(start 237.18393 -78.423262)
		(mid 237.219671 -78.369772)
		(end 237.23219 -78.306676)
		(stroke
			(width 0.08255)
			(type default)
		)
		(layer "B.Cu")
	)
	(gr_arc
		(start 237.18393 -74.42327)
		(mid 237.219671 -74.36978)
		(end 237.23219 -74.306684)
		(stroke
			(width 0.08255)
			(type default)
		)
		(layer "B.Cu")
	)
	(gr_arc
		(start 237.18393 -70.423278)
		(mid 237.219671 -70.369788)
		(end 237.23219 -70.306692)
		(stroke
			(width 0.08255)
			(type default)
		)
		(layer "B.Cu")
	)
	(gr_arc
		(start 237.18393 -66.423286)
		(mid 237.219671 -66.369796)
		(end 237.23219 -66.3067)
		(stroke
			(width 0.08255)
			(type default)
		)
		(layer "B.Cu")
	)
	(gr_arc
		(start 237.18393 -62.423294)
		(mid 237.219671 -62.369804)
		(end 237.23219 -62.306708)
		(stroke
			(width 0.08255)
			(type default)
		)
		(layer "B.Cu")
	)
	(gr_arc
		(start 237.18393 -58.423302)
		(mid 237.219671 -58.369812)
		(end 237.23219 -58.306716)
		(stroke
			(width 0.08255)
			(type default)
		)
		(layer "B.Cu")
	)
	(gr_arc
		(start 237.18393 -54.42331)
		(mid 237.219671 -54.36982)
		(end 237.23219 -54.306724)
		(stroke
			(width 0.08255)
			(type default)
		)
		(layer "B.Cu")
	)
	(gr_line
		(start 237.218474 -177.860706)
		(end 237.233968 -177.863246)
		(stroke
			(width 0.08255)
			(type default)
		)
		(layer "B.Cu")
	)
	(gr_line
		(start 237.218474 -173.860714)
		(end 237.233968 -173.863254)
		(stroke
			(width 0.08255)
			(type default)
		)
		(layer "B.Cu")
	)
	(gr_line
		(start 237.218474 -169.860722)
		(end 237.233968 -169.863262)
		(stroke
			(width 0.08255)
			(type default)
		)
		(layer "B.Cu")
	)
	(gr_line
		(start 237.218474 -165.86073)
		(end 237.233968 -165.86327)
		(stroke
			(width 0.08255)
			(type default)
		)
		(layer "B.Cu")
	)
	(gr_line
		(start 237.218474 -49.560988)
		(end 237.233968 -49.563528)
		(stroke
			(width 0.08255)
			(type default)
		)
		(layer "B.Cu")
	)
	(gr_line
		(start 237.218474 -45.560996)
		(end 237.233968 -45.563536)
		(stroke
			(width 0.08255)
			(type default)
		)
		(layer "B.Cu")
	)
	(gr_line
		(start 237.218474 -41.561004)
		(end 237.233968 -41.563544)
		(stroke
			(width 0.08255)
			(type default)
		)
		(layer "B.Cu")
	)
	(gr_line
		(start 237.218474 -37.561012)
		(end 237.233968 -37.563552)
		(stroke
			(width 0.08255)
			(type default)
		)
		(layer "B.Cu")
	)
	(gr_arc
		(start 237.23219 -82.188812)
		(mid 237.219642 -82.125728)
		(end 237.18393 -82.072226)
		(stroke
			(width 0.08255)
			(type default)
		)
		(layer "B.Cu")
	)
	(gr_arc
		(start 237.23219 -78.18882)
		(mid 237.219642 -78.125736)
		(end 237.18393 -78.072234)
		(stroke
			(width 0.08255)
			(type default)
		)
		(layer "B.Cu")
	)
	(gr_arc
		(start 237.23219 -74.188828)
		(mid 237.219642 -74.125744)
		(end 237.18393 -74.072242)
		(stroke
			(width 0.08255)
			(type default)
		)
		(layer "B.Cu")
	)
	(gr_arc
		(start 237.23219 -70.188836)
		(mid 237.219642 -70.125752)
		(end 237.18393 -70.07225)
		(stroke
			(width 0.08255)
			(type default)
		)
		(layer "B.Cu")
	)
	(gr_arc
		(start 237.23219 -66.188844)
		(mid 237.219642 -66.12576)
		(end 237.18393 -66.072258)
		(stroke
			(width 0.08255)
			(type default)
		)
		(layer "B.Cu")
	)
	(gr_arc
		(start 237.23219 -62.188852)
		(mid 237.219642 -62.125768)
		(end 237.18393 -62.072266)
		(stroke
			(width 0.08255)
			(type default)
		)
		(layer "B.Cu")
	)
	(gr_arc
		(start 237.23219 -58.18886)
		(mid 237.219642 -58.125776)
		(end 237.18393 -58.072274)
		(stroke
			(width 0.08255)
			(type default)
		)
		(layer "B.Cu")
	)
	(gr_arc
		(start 237.23219 -54.188868)
		(mid 237.219642 -54.125784)
		(end 237.18393 -54.072282)
		(stroke
			(width 0.08255)
			(type default)
		)
		(layer "B.Cu")
	)
	(gr_arc
		(start 237.233968 -177.863246)
		(mid 237.313678 -177.863173)
		(end 237.389416 -177.838354)
		(stroke
			(width 0.08255)
			(type default)
		)
		(layer "B.Cu")
	)
	(gr_arc
		(start 237.233968 -173.863254)
		(mid 237.313678 -173.863181)
		(end 237.389416 -173.838362)
		(stroke
			(width 0.08255)
			(type default)
		)
		(layer "B.Cu")
	)
	(gr_arc
		(start 237.233968 -169.863262)
		(mid 237.313678 -169.863189)
		(end 237.389416 -169.83837)
		(stroke
			(width 0.08255)
			(type default)
		)
		(layer "B.Cu")
	)
	(gr_arc
		(start 237.233968 -165.86327)
		(mid 237.313678 -165.863197)
		(end 237.389416 -165.838378)
		(stroke
			(width 0.08255)
			(type default)
		)
		(layer "B.Cu")
	)
	(gr_arc
		(start 237.233968 -49.563528)
		(mid 237.313678 -49.563455)
		(end 237.389416 -49.538636)
		(stroke
			(width 0.08255)
			(type default)
		)
		(layer "B.Cu")
	)
	(gr_arc
		(start 237.233968 -45.563536)
		(mid 237.313678 -45.563463)
		(end 237.389416 -45.538644)
		(stroke
			(width 0.08255)
			(type default)
		)
		(layer "B.Cu")
	)
	(gr_arc
		(start 237.233968 -41.563544)
		(mid 237.313678 -41.563471)
		(end 237.389416 -41.538652)
		(stroke
			(width 0.08255)
			(type default)
		)
		(layer "B.Cu")
	)
	(gr_arc
		(start 237.233968 -37.563552)
		(mid 237.313678 -37.563479)
		(end 237.389416 -37.53866)
		(stroke
			(width 0.08255)
			(type default)
		)
		(layer "B.Cu")
	)
	(gr_arc
		(start 237.285276 -81.661254)
		(mid 237.285165 -81.714653)
		(end 237.301786 -81.765394)
		(stroke
			(width 0.08255)
			(type default)
		)
		(layer "B.Cu")
	)
	(gr_arc
		(start 237.285276 -77.661262)
		(mid 237.285167 -77.71466)
		(end 237.301786 -77.765402)
		(stroke
			(width 0.08255)
			(type default)
		)
		(layer "B.Cu")
	)
	(gr_arc
		(start 237.285276 -73.66127)
		(mid 237.28517 -73.714667)
		(end 237.301786 -73.76541)
		(stroke
			(width 0.08255)
			(type default)
		)
		(layer "B.Cu")
	)
	(gr_arc
		(start 237.285276 -69.661278)
		(mid 237.285172 -69.714675)
		(end 237.301786 -69.765418)
		(stroke
			(width 0.08255)
			(type default)
		)
		(layer "B.Cu")
	)
	(gr_arc
		(start 237.285276 -65.661286)
		(mid 237.285175 -65.714682)
		(end 237.301786 -65.765426)
		(stroke
			(width 0.08255)
			(type default)
		)
		(layer "B.Cu")
	)
	(gr_arc
		(start 237.285276 -61.661294)
		(mid 237.285177 -61.714689)
		(end 237.301786 -61.765434)
		(stroke
			(width 0.08255)
			(type default)
		)
		(layer "B.Cu")
	)
	(gr_arc
		(start 237.285276 -57.661302)
		(mid 237.285179 -57.714696)
		(end 237.301786 -57.765442)
		(stroke
			(width 0.08255)
			(type default)
		)
		(layer "B.Cu")
	)
	(gr_arc
		(start 237.285276 -53.66131)
		(mid 237.285182 -53.714703)
		(end 237.301786 -53.76545)
		(stroke
			(width 0.08255)
			(type default)
		)
		(layer "B.Cu")
	)
	(gr_arc
		(start 237.301786 -81.765394)
		(mid 237.31553 -81.787539)
		(end 237.33252 -81.807304)
		(stroke
			(width 0.08255)
			(type default)
		)
		(layer "B.Cu")
	)
	(gr_arc
		(start 237.301786 -77.765402)
		(mid 237.315531 -77.787546)
		(end 237.33252 -77.807312)
		(stroke
			(width 0.08255)
			(type default)
		)
		(layer "B.Cu")
	)
	(gr_arc
		(start 237.301786 -73.76541)
		(mid 237.315531 -73.787553)
		(end 237.33252 -73.80732)
		(stroke
			(width 0.08255)
			(type default)
		)
		(layer "B.Cu")
	)
	(gr_arc
		(start 237.301786 -69.765418)
		(mid 237.315532 -69.787561)
		(end 237.33252 -69.807328)
		(stroke
			(width 0.08255)
			(type default)
		)
		(layer "B.Cu")
	)
	(gr_arc
		(start 237.301786 -65.765426)
		(mid 237.315523 -65.787577)
		(end 237.33252 -65.807336)
		(stroke
			(width 0.08255)
			(type default)
		)
		(layer "B.Cu")
	)
	(gr_arc
		(start 237.301786 -61.765434)
		(mid 237.315524 -61.787584)
		(end 237.33252 -61.807344)
		(stroke
			(width 0.08255)
			(type default)
		)
		(layer "B.Cu")
	)
	(gr_arc
		(start 237.301786 -57.765442)
		(mid 237.315525 -57.787591)
		(end 237.33252 -57.807352)
		(stroke
			(width 0.08255)
			(type default)
		)
		(layer "B.Cu")
	)
	(gr_arc
		(start 237.301786 -53.76545)
		(mid 237.315525 -53.787599)
		(end 237.33252 -53.80736)
		(stroke
			(width 0.08255)
			(type default)
		)
		(layer "B.Cu")
	)
	(gr_arc
		(start 237.376462 -81.537302)
		(mid 237.315974 -81.588322)
		(end 237.285276 -81.661254)
		(stroke
			(width 0.08255)
			(type default)
		)
		(layer "B.Cu")
	)
	(gr_line
		(start 237.376462 -81.537302)
		(end 238.05007 -81.19999)
		(stroke
			(width 0.08255)
			(type default)
		)
		(layer "B.Cu")
	)
	(gr_arc
		(start 237.376462 -77.53731)
		(mid 237.315976 -77.588331)
		(end 237.285276 -77.661262)
		(stroke
			(width 0.08255)
			(type default)
		)
		(layer "B.Cu")
	)
	(gr_line
		(start 237.376462 -77.53731)
		(end 238.05007 -77.199998)
		(stroke
			(width 0.08255)
			(type default)
		)
		(layer "B.Cu")
	)
	(gr_arc
		(start 237.376462 -73.537318)
		(mid 237.315978 -73.58834)
		(end 237.285276 -73.66127)
		(stroke
			(width 0.08255)
			(type default)
		)
		(layer "B.Cu")
	)
	(gr_line
		(start 237.376462 -73.537318)
		(end 238.05007 -73.200006)
		(stroke
			(width 0.08255)
			(type default)
		)
		(layer "B.Cu")
	)
	(gr_arc
		(start 237.376462 -69.537326)
		(mid 237.315981 -69.588349)
		(end 237.285276 -69.661278)
		(stroke
			(width 0.08255)
			(type default)
		)
		(layer "B.Cu")
	)
	(gr_line
		(start 237.376462 -69.537326)
		(end 238.05007 -69.200014)
		(stroke
			(width 0.08255)
			(type default)
		)
		(layer "B.Cu")
	)
	(gr_arc
		(start 237.376462 -65.537334)
		(mid 237.315983 -65.588357)
		(end 237.285276 -65.661286)
		(stroke
			(width 0.08255)
			(type default)
		)
		(layer "B.Cu")
	)
	(gr_line
		(start 237.376462 -65.537334)
		(end 238.05007 -65.200022)
		(stroke
			(width 0.08255)
			(type default)
		)
		(layer "B.Cu")
	)
	(gr_arc
		(start 237.376462 -61.537342)
		(mid 237.315985 -61.588366)
		(end 237.285276 -61.661294)
		(stroke
			(width 0.08255)
			(type default)
		)
		(layer "B.Cu")
	)
	(gr_line
		(start 237.376462 -61.537342)
		(end 238.05007 -61.20003)
		(stroke
			(width 0.08255)
			(type default)
		)
		(layer "B.Cu")
	)
	(gr_arc
		(start 237.376462 -57.53735)
		(mid 237.315988 -57.588375)
		(end 237.285276 -57.661302)
		(stroke
			(width 0.08255)
			(type default)
		)
		(layer "B.Cu")
	)
	(gr_line
		(start 237.376462 -57.53735)
		(end 238.05007 -57.200038)
		(stroke
			(width 0.08255)
			(type default)
		)
		(layer "B.Cu")
	)
	(gr_arc
		(start 237.376462 -53.537358)
		(mid 237.31599 -53.588384)
		(end 237.285276 -53.66131)
		(stroke
			(width 0.08255)
			(type default)
		)
		(layer "B.Cu")
	)
	(gr_line
		(start 237.376462 -53.537358)
		(end 238.05007 -53.200046)
		(stroke
			(width 0.08255)
			(type default)
		)
		(layer "B.Cu")
	)
	(gr_line
		(start 237.389416 -177.838354)
		(end 238.05007 -177.499772)
		(stroke
			(width 0.08255)
			(type default)
		)
		(layer "B.Cu")
	)
	(gr_line
		(start 237.389416 -173.838362)
		(end 238.05007 -173.49978)
		(stroke
			(width 0.08255)
			(type default)
		)
		(layer "B.Cu")
	)
	(gr_line
		(start 237.389416 -169.83837)
		(end 238.05007 -169.499788)
		(stroke
			(width 0.08255)
			(type default)
		)
		(layer "B.Cu")
	)
	(gr_line
		(start 237.389416 -165.838378)
		(end 238.05007 -165.499796)
		(stroke
			(width 0.08255)
			(type default)
		)
		(layer "B.Cu")
	)
	(gr_line
		(start 237.389416 -49.538636)
		(end 238.05007 -49.200054)
		(stroke
			(width 0.08255)
			(type default)
		)
		(layer "B.Cu")
	)
	(gr_line
		(start 237.389416 -45.538644)
		(end 238.05007 -45.200062)
		(stroke
			(width 0.08255)
			(type default)
		)
		(layer "B.Cu")
	)
	(gr_line
		(start 237.389416 -41.538652)
		(end 238.05007 -41.20007)
		(stroke
			(width 0.08255)
			(type default)
		)
		(layer "B.Cu")
	)
	(gr_line
		(start 237.389416 -37.53866)
		(end 238.05007 -37.200078)
		(stroke
			(width 0.08255)
			(type default)
		)
		(layer "B.Cu")
	)
	(gr_line
		(start 237.417102 -82.60334)
		(end 237.449868 -82.570574)
		(stroke
			(width 0.08255)
			(type default)
		)
		(layer "B.Cu")
	)
	(gr_line
		(start 237.417102 -78.603348)
		(end 237.449868 -78.570582)
		(stroke
			(width 0.08255)
			(type default)
		)
		(layer "B.Cu")
	)
	(gr_line
		(start 237.417102 -74.603356)
		(end 237.449868 -74.57059)
		(stroke
			(width 0.08255)
			(type default)
		)
		(layer "B.Cu")
	)
	(gr_line
		(start 237.417102 -70.603364)
		(end 237.449868 -70.570598)
		(stroke
			(width 0.08255)
			(type default)
		)
		(layer "B.Cu")
	)
	(gr_line
		(start 237.417102 -66.603372)
		(end 237.449868 -66.570606)
		(stroke
			(width 0.08255)
			(type default)
		)
		(layer "B.Cu")
	)
	(gr_line
		(start 237.417102 -58.603388)
		(end 237.449868 -58.570622)
		(stroke
			(width 0.08255)
			(type default)
		)
		(layer "B.Cu")
	)
	(gr_line
		(start 237.417102 -54.603396)
		(end 237.449868 -54.57063)
		(stroke
			(width 0.08255)
			(type default)
		)
		(layer "B.Cu")
	)
	(gr_arc
		(start 237.449868 -82.570574)
		(mid 237.504974 -82.488197)
		(end 237.52429 -82.390996)
		(stroke
			(width 0.08255)
			(type default)
		)
		(layer "B.Cu")
	)
	(gr_arc
		(start 237.449868 -78.570582)
		(mid 237.504974 -78.488205)
		(end 237.52429 -78.391004)
		(stroke
			(width 0.08255)
			(type default)
		)
		(layer "B.Cu")
	)
	(gr_arc
		(start 237.449868 -74.57059)
		(mid 237.504974 -74.488213)
		(end 237.52429 -74.391012)
		(stroke
			(width 0.08255)
			(type default)
		)
		(layer "B.Cu")
	)
	(gr_arc
		(start 237.449868 -70.570598)
		(mid 237.504974 -70.488221)
		(end 237.52429 -70.39102)
		(stroke
			(width 0.08255)
			(type default)
		)
		(layer "B.Cu")
	)
	(gr_arc
		(start 237.449868 -66.570606)
		(mid 237.504974 -66.488229)
		(end 237.52429 -66.391028)
		(stroke
			(width 0.08255)
			(type default)
		)
		(layer "B.Cu")
	)
	(gr_arc
		(start 237.449868 -62.570614)
		(mid 237.504974 -62.488237)
		(end 237.52429 -62.391036)
		(stroke
			(width 0.08255)
			(type default)
		)
		(layer "B.Cu")
	)
	(gr_arc
		(start 237.449868 -58.570622)
		(mid 237.504974 -58.488245)
		(end 237.52429 -58.391044)
		(stroke
			(width 0.08255)
			(type default)
		)
		(layer "B.Cu")
	)
	(gr_arc
		(start 237.449868 -54.57063)
		(mid 237.504974 -54.488253)
		(end 237.52429 -54.391052)
		(stroke
			(width 0.08255)
			(type default)
		)
		(layer "B.Cu")
	)
	(gr_arc
		(start 237.52429 -82.104484)
		(mid 237.50494 -82.007297)
		(end 237.449868 -81.924906)
		(stroke
			(width 0.08255)
			(type default)
		)
		(layer "B.Cu")
	)
	(gr_arc
		(start 237.52429 -78.104492)
		(mid 237.50494 -78.007305)
		(end 237.449868 -77.924914)
		(stroke
			(width 0.08255)
			(type default)
		)
		(layer "B.Cu")
	)
	(gr_arc
		(start 237.52429 -74.1045)
		(mid 237.50494 -74.007313)
		(end 237.449868 -73.924922)
		(stroke
			(width 0.08255)
			(type default)
		)
		(layer "B.Cu")
	)
	(gr_arc
		(start 237.52429 -70.104508)
		(mid 237.50494 -70.007321)
		(end 237.449868 -69.92493)
		(stroke
			(width 0.08255)
			(type default)
		)
		(layer "B.Cu")
	)
	(gr_arc
		(start 237.52429 -66.104516)
		(mid 237.50494 -66.007329)
		(end 237.449868 -65.924938)
		(stroke
			(width 0.08255)
			(type default)
		)
		(layer "B.Cu")
	)
	(gr_arc
		(start 237.52429 -62.104524)
		(mid 237.50494 -62.007337)
		(end 237.449868 -61.924946)
		(stroke
			(width 0.08255)
			(type default)
		)
		(layer "B.Cu")
	)
	(gr_arc
		(start 237.52429 -58.104532)
		(mid 237.50494 -58.007345)
		(end 237.449868 -57.924954)
		(stroke
			(width 0.08255)
			(type default)
		)
		(layer "B.Cu")
	)
	(gr_arc
		(start 237.52429 -54.10454)
		(mid 237.50494 -54.007353)
		(end 237.449868 -53.924962)
		(stroke
			(width 0.08255)
			(type default)
		)
		(layer "B.Cu")
	)
	(gr_line
		(start 241.024918 -28.054046)
		(end 241.08283 -28.111958)
		(stroke
			(width 0.08255)
			(type default)
		)
		(layer "B.Cu")
	)
	(gr_arc
		(start 242.215416 -387.688328)
		(mid 242.412263 -387.606791)
		(end 242.4938 -387.409944)
		(stroke
			(width 0.127)
			(type default)
		)
		(layer "B.Cu")
	)
	(gr_arc
		(start 242.337082 -388.173214)
		(mid 242.278454 -388.152539)
		(end 242.216686 -388.145528)
		(stroke
			(width 0.127)
			(type default)
		)
		(layer "B.Cu")
	)
	(gr_arc
		(start 242.4938 -388.423658)
		(mid 242.451437 -388.275903)
		(end 242.337082 -388.173214)
		(stroke
			(width 0.127)
			(type default)
		)
		(layer "B.Cu")
	)
	(gr_line
		(start 242.4938 -388.423658)
		(end 242.4938 -388.712202)
		(stroke
			(width 0.127)
			(type default)
		)
		(layer "B.Cu")
	)
	(gr_line
		(start 242.4938 -387.1214)
		(end 242.4938 -387.409944)
		(stroke
			(width 0.127)
			(type default)
		)
		(layer "B.Cu")
	)
	(gr_line
		(start 242.861084 -87.811102)
		(end 242.866926 -87.80653)
		(stroke
			(width 0.08255)
			(type default)
		)
		(layer "B.Cu")
	)
	(gr_line
		(start 242.866926 -87.80653)
		(end 242.870736 -87.800688)
		(stroke
			(width 0.08255)
			(type default)
		)
		(layer "B.Cu")
	)
	(gr_line
		(start 242.926616 -27.054048)
		(end 242.965224 -27.078178)
		(stroke
			(width 0.08255)
			(type default)
		)
		(layer "B.Cu")
	)
	(gr_line
		(start 243.00053 -29.054044)
		(end 243.039138 -29.078174)
		(stroke
			(width 0.08255)
			(type default)
		)
		(layer "B.Cu")
	)
	(gr_line
		(start 243.024914 -31.05404)
		(end 243.063522 -31.07817)
		(stroke
			(width 0.08255)
			(type default)
		)
		(layer "B.Cu")
	)
	(gr_line
		(start 243.239036 -33.054036)
		(end 243.304822 -33.151318)
		(stroke
			(width 0.08255)
			(type default)
		)
		(layer "B.Cu")
	)
	(gr_line
		(start 243.451888 -386.07492)
		(end 243.571268 -386.1943)
		(stroke
			(width 0.127)
			(type default)
		)
		(layer "B.Cu")
	)
	(gr_line
		(start 243.451888 -385.42468)
		(end 243.571268 -385.3053)
		(stroke
			(width 0.127)
			(type default)
		)
		(layer "B.Cu")
	)
	(gr_line
		(start 243.571268 -386.1943)
		(end 244.094 -386.1943)
		(stroke
			(width 0.127)
			(type default)
		)
		(layer "B.Cu")
	)
	(gr_line
		(start 243.571268 -385.3053)
		(end 244.094 -385.3053)
		(stroke
			(width 0.127)
			(type default)
		)
		(layer "B.Cu")
	)
	(gr_line
		(start 243.775738 -86.459314)
		(end 243.787676 -86.441534)
		(stroke
			(width 0.08255)
			(type default)
		)
		(layer "B.Cu")
	)
	(gr_line
		(start 243.787676 -86.441534)
		(end 243.791994 -86.41969)
		(stroke
			(width 0.08255)
			(type default)
		)
		(layer "B.Cu")
	)
	(gr_line
		(start 244.094 -386.1943)
		(end 244.616732 -386.1943)
		(stroke
			(width 0.127)
			(type default)
		)
		(layer "B.Cu")
	)
	(gr_line
		(start 244.094 -385.3053)
		(end 244.616732 -385.3053)
		(stroke
			(width 0.127)
			(type default)
		)
		(layer "B.Cu")
	)
	(gr_line
		(start 244.131084 -88.811862)
		(end 244.136926 -88.80729)
		(stroke
			(width 0.08255)
			(type default)
		)
		(layer "B.Cu")
	)
	(gr_line
		(start 244.136926 -88.80729)
		(end 244.140736 -88.801448)
		(stroke
			(width 0.08255)
			(type default)
		)
		(layer "B.Cu")
	)
	(gr_line
		(start 244.45087 -34.850578)
		(end 244.462554 -34.86785)
		(stroke
			(width 0.08255)
			(type default)
		)
		(layer "B.Cu")
	)
	(gr_line
		(start 244.45468 -31.949136)
		(end 244.476524 -31.962852)
		(stroke
			(width 0.08255)
			(type default)
		)
		(layer "B.Cu")
	)
	(gr_line
		(start 244.462554 -34.86785)
		(end 244.466364 -34.888678)
		(stroke
			(width 0.08255)
			(type default)
		)
		(layer "B.Cu")
	)
	(gr_line
		(start 244.476524 -31.962852)
		(end 244.491002 -31.984188)
		(stroke
			(width 0.08255)
			(type default)
		)
		(layer "B.Cu")
	)
	(gr_line
		(start 244.616732 -386.1943)
		(end 244.736112 -386.07492)
		(stroke
			(width 0.127)
			(type default)
		)
		(layer "B.Cu")
	)
	(gr_line
		(start 244.616732 -385.3053)
		(end 244.736112 -385.42468)
		(stroke
			(width 0.127)
			(type default)
		)
		(layer "B.Cu")
	)
	(gr_line
		(start 245.261892 -89.957402)
		(end 245.266718 -89.953338)
		(stroke
			(width 0.08255)
			(type default)
		)
		(layer "B.Cu")
	)
	(gr_line
		(start 245.266718 -89.953338)
		(end 245.27002 -89.948258)
		(stroke
			(width 0.08255)
			(type default)
		)
		(layer "B.Cu")
	)
	(gr_line
		(start 245.62562 -386.07492)
		(end 245.8085 -386.2578)
		(stroke
			(width 0.127)
			(type default)
		)
		(layer "B.Cu")
	)
	(gr_line
		(start 245.62562 -385.42468)
		(end 245.8085 -385.2418)
		(stroke
			(width 0.127)
			(type default)
		)
		(layer "B.Cu")
	)
	(gr_line
		(start 245.675912 -30.729936)
		(end 245.697756 -30.743652)
		(stroke
			(width 0.08255)
			(type default)
		)
		(layer "B.Cu")
	)
	(gr_line
		(start 245.697756 -30.743652)
		(end 245.712234 -30.764988)
		(stroke
			(width 0.08255)
			(type default)
		)
		(layer "B.Cu")
	)
	(gr_line
		(start 245.933976 -34.123376)
		(end 245.946422 -34.141918)
		(stroke
			(width 0.08255)
			(type default)
		)
		(layer "B.Cu")
	)
	(gr_line
		(start 245.946422 -34.141918)
		(end 245.95074 -34.164016)
		(stroke
			(width 0.08255)
			(type default)
		)
		(layer "B.Cu")
	)
	(gr_line
		(start 246.005858 -86.035896)
		(end 246.017796 -86.018116)
		(stroke
			(width 0.08255)
			(type default)
		)
		(layer "B.Cu")
	)
	(gr_line
		(start 246.017796 -86.018116)
		(end 246.022114 -85.996272)
		(stroke
			(width 0.08255)
			(type default)
		)
		(layer "B.Cu")
	)
	(gr_line
		(start 246.52097 -90.969846)
		(end 246.526812 -90.965274)
		(stroke
			(width 0.08255)
			(type default)
		)
		(layer "B.Cu")
	)
	(gr_line
		(start 246.526812 -90.965274)
		(end 246.530622 -90.959432)
		(stroke
			(width 0.08255)
			(type default)
		)
		(layer "B.Cu")
	)
	(gr_line
		(start 246.6975 -386.2578)
		(end 247.04802 -386.2578)
		(stroke
			(width 0.127)
			(type default)
		)
		(layer "B.Cu")
	)
	(gr_line
		(start 246.6975 -385.2418)
		(end 247.04548 -385.2418)
		(stroke
			(width 0.127)
			(type default)
		)
		(layer "B.Cu")
	)
	(gr_line
		(start 247.04548 -385.2418)
		(end 247.22963 -385.42595)
		(stroke
			(width 0.127)
			(type default)
		)
		(layer "B.Cu")
	)
	(gr_line
		(start 247.04802 -386.2578)
		(end 247.22963 -386.07619)
		(stroke
			(width 0.127)
			(type default)
		)
		(layer "B.Cu")
	)
	(gr_line
		(start 247.161304 -29.705808)
		(end 247.183148 -29.719524)
		(stroke
			(width 0.08255)
			(type default)
		)
		(layer "B.Cu")
	)
	(gr_line
		(start 247.183148 -29.719524)
		(end 247.197626 -29.74086)
		(stroke
			(width 0.08255)
			(type default)
		)
		(layer "B.Cu")
	)
	(gr_line
		(start 247.394222 -33.258506)
		(end 247.406668 -33.277048)
		(stroke
			(width 0.08255)
			(type default)
		)
		(layer "B.Cu")
	)
	(gr_line
		(start 247.406668 -33.277048)
		(end 247.410986 -33.299146)
		(stroke
			(width 0.08255)
			(type default)
		)
		(layer "B.Cu")
	)
	(gr_line
		(start 247.495568 -86.649052)
		(end 247.507506 -86.631272)
		(stroke
			(width 0.08255)
			(type default)
		)
		(layer "B.Cu")
	)
	(gr_line
		(start 247.507506 -86.631272)
		(end 247.511824 -86.609428)
		(stroke
			(width 0.08255)
			(type default)
		)
		(layer "B.Cu")
	)
	(gr_line
		(start 247.595898 -388.4422)
		(end 247.72112 -388.316724)
		(stroke
			(width 0.127)
			(type default)
		)
		(layer "B.Cu")
	)
	(gr_line
		(start 247.595898 -387.3754)
		(end 247.712484 -387.49224)
		(stroke
			(width 0.127)
			(type default)
		)
		(layer "B.Cu")
	)
	(gr_arc
		(start 247.712484 -387.49224)
		(mid 247.918067 -387.629522)
		(end 248.16054 -387.67766)
		(stroke
			(width 0.127)
			(type default)
		)
		(layer "B.Cu")
	)
	(gr_arc
		(start 248.16054 -388.13486)
		(mid 247.922747 -388.182097)
		(end 247.72112 -388.316724)
		(stroke
			(width 0.127)
			(type default)
		)
		(layer "B.Cu")
	)
	(gr_line
		(start 248.85396 -32.19704)
		(end 248.865898 -32.21482)
		(stroke
			(width 0.08255)
			(type default)
		)
		(layer "B.Cu")
	)
	(gr_line
		(start 248.865898 -32.214566)
		(end 248.865898 -32.21482)
		(stroke
			(width 0.08255)
			(type default)
		)
		(layer "B.Cu")
	)
	(gr_line
		(start 248.865898 -32.214566)
		(end 248.870216 -32.236664)
		(stroke
			(width 0.08255)
			(type default)
		)
		(layer "B.Cu")
	)
	(gr_line
		(start 249.059954 -87.208868)
		(end 249.071892 -87.191088)
		(stroke
			(width 0.08255)
			(type default)
		)
		(layer "B.Cu")
	)
	(gr_line
		(start 249.071892 -87.191088)
		(end 249.07621 -87.169244)
		(stroke
			(width 0.08255)
			(type default)
		)
		(layer "B.Cu")
	)
	(gr_line
		(start 249.131836 -58.8899)
		(end 249.135646 -58.909458)
		(stroke
			(width 0.08255)
			(type default)
		)
		(layer "B.Cu")
	)
	(gr_line
		(start 249.13209 -58.928254)
		(end 249.135646 -58.909458)
		(stroke
			(width 0.08255)
			(type default)
		)
		(layer "B.Cu")
	)
	(gr_line
		(start 251.020326 -60.243974)
		(end 251.024136 -60.263532)
		(stroke
			(width 0.08255)
			(type default)
		)
		(layer "B.Cu")
	)
	(gr_line
		(start 251.02058 -60.282328)
		(end 251.024136 -60.263532)
		(stroke
			(width 0.08255)
			(type default)
		)
		(layer "B.Cu")
	)
	(gr_line
		(start 252.639068 -60.19292)
		(end 252.642878 -60.212478)
		(stroke
			(width 0.08255)
			(type default)
		)
		(layer "B.Cu")
	)
	(gr_line
		(start 252.639322 -60.231274)
		(end 252.642878 -60.212478)
		(stroke
			(width 0.08255)
			(type default)
		)
		(layer "B.Cu")
	)
	(gr_line
		(start 254.308864 -60.20816)
		(end 254.312674 -60.227718)
		(stroke
			(width 0.08255)
			(type default)
		)
		(layer "B.Cu")
	)
	(gr_line
		(start 254.309118 -60.246514)
		(end 254.312674 -60.227718)
		(stroke
			(width 0.08255)
			(type default)
		)
		(layer "B.Cu")
	)
	(gr_line
		(start 260.301486 -174.578518)
		(end 260.302756 -174.574454)
		(stroke
			(width 0.08255)
			(type default)
		)
		(layer "B.Cu")
	)
	(gr_line
		(start 260.302756 -174.574454)
		(end 260.305042 -174.571152)
		(stroke
			(width 0.08255)
			(type default)
		)
		(layer "B.Cu")
	)
	(gr_line
		(start 260.686042 -190.564008)
		(end 260.87578 -189.938914)
		(stroke
			(width 0.08255)
			(type default)
		)
		(layer "B.Cu")
	)
	(gr_line
		(start 260.788658 -154.05989)
		(end 260.976872 -153.439622)
		(stroke
			(width 0.08255)
			(type default)
		)
		(layer "B.Cu")
	)
	(gr_line
		(start 260.958584 -190.680594)
		(end 261.098538 -190.605918)
		(stroke
			(width 0.08255)
			(type default)
		)
		(layer "B.Cu")
	)
	(gr_line
		(start 260.986778 -153.40711)
		(end 260.988048 -153.403046)
		(stroke
			(width 0.08255)
			(type default)
		)
		(layer "B.Cu")
	)
	(gr_line
		(start 260.988048 -153.403046)
		(end 260.988302 -153.402284)
		(stroke
			(width 0.08255)
			(type default)
		)
		(layer "B.Cu")
	)
	(gr_line
		(start 260.988302 -153.402284)
		(end 261.008622 -153.335228)
		(stroke
			(width 0.08255)
			(type default)
		)
		(layer "B.Cu")
	)
	(gr_line
		(start 261.040626 -189.395608)
		(end 261.229856 -188.771784)
		(stroke
			(width 0.08255)
			(type default)
		)
		(layer "B.Cu")
	)
	(gr_line
		(start 261.060692 -154.178762)
		(end 261.200138 -154.104086)
		(stroke
			(width 0.08255)
			(type default)
		)
		(layer "B.Cu")
	)
	(gr_line
		(start 261.098538 -190.605918)
		(end 261.242302 -190.131954)
		(stroke
			(width 0.08255)
			(type default)
		)
		(layer "B.Cu")
	)
	(gr_line
		(start 261.142734 -152.893014)
		(end 261.331202 -152.271984)
		(stroke
			(width 0.08255)
			(type default)
		)
		(layer "B.Cu")
	)
	(gr_line
		(start 261.167626 -189.992254)
		(end 261.242302 -190.131954)
		(stroke
			(width 0.08255)
			(type default)
		)
		(layer "B.Cu")
	)
	(gr_line
		(start 261.200138 -154.104086)
		(end 261.343902 -153.630122)
		(stroke
			(width 0.08255)
			(type default)
		)
		(layer "B.Cu")
	)
	(gr_line
		(start 261.267702 -153.487374)
		(end 261.288022 -153.420064)
		(stroke
			(width 0.08255)
			(type default)
		)
		(layer "B.Cu")
	)
	(gr_line
		(start 261.26948 -153.490676)
		(end 261.343902 -153.630122)
		(stroke
			(width 0.08255)
			(type default)
		)
		(layer "B.Cu")
	)
	(gr_line
		(start 261.31266 -189.513972)
		(end 261.452614 -189.439296)
		(stroke
			(width 0.08255)
			(type default)
		)
		(layer "B.Cu")
	)
	(gr_line
		(start 261.414768 -153.011886)
		(end 261.554214 -152.93721)
		(stroke
			(width 0.08255)
			(type default)
		)
		(layer "B.Cu")
	)
	(gr_line
		(start 261.452614 -189.439296)
		(end 261.596378 -188.965332)
		(stroke
			(width 0.08255)
			(type default)
		)
		(layer "B.Cu")
	)
	(gr_line
		(start 261.521702 -188.825378)
		(end 261.596378 -188.965332)
		(stroke
			(width 0.08255)
			(type default)
		)
		(layer "B.Cu")
	)
	(gr_line
		(start 261.554214 -152.93721)
		(end 261.697978 -152.463246)
		(stroke
			(width 0.08255)
			(type default)
		)
		(layer "B.Cu")
	)
	(gr_line
		(start 261.57174 -176.008284)
		(end 261.57301 -176.00422)
		(stroke
			(width 0.08255)
			(type default)
		)
		(layer "B.Cu")
	)
	(gr_line
		(start 261.57301 -176.00422)
		(end 261.575296 -176.000918)
		(stroke
			(width 0.08255)
			(type default)
		)
		(layer "B.Cu")
	)
	(gr_line
		(start 261.623302 -152.3238)
		(end 261.697978 -152.463246)
		(stroke
			(width 0.08255)
			(type default)
		)
		(layer "B.Cu")
	)
	(gr_line
		(start 262.147558 -171.73321)
		(end 262.503666 -171.184824)
		(stroke
			(width 0.08255)
			(type default)
		)
		(layer "B.Cu")
	)
	(gr_line
		(start 262.271002 -179.521358)
		(end 262.459978 -178.898296)
		(stroke
			(width 0.08255)
			(type default)
		)
		(layer "B.Cu")
	)
	(gr_line
		(start 262.37692 -171.92117)
		(end 262.532114 -171.888404)
		(stroke
			(width 0.08255)
			(type default)
		)
		(layer "B.Cu")
	)
	(gr_line
		(start 262.399526 -174.73168)
		(end 262.75284 -174.187358)
		(stroke
			(width 0.08255)
			(type default)
		)
		(layer "B.Cu")
	)
	(gr_line
		(start 262.532114 -171.888404)
		(end 262.801862 -171.47286)
		(stroke
			(width 0.08255)
			(type default)
		)
		(layer "B.Cu")
	)
	(gr_line
		(start 262.543036 -179.639722)
		(end 262.682736 -179.5653)
		(stroke
			(width 0.08255)
			(type default)
		)
		(layer "B.Cu")
	)
	(gr_line
		(start 262.625078 -178.354228)
		(end 262.814054 -177.73142)
		(stroke
			(width 0.08255)
			(type default)
		)
		(layer "B.Cu")
	)
	(gr_line
		(start 262.62711 -174.921672)
		(end 262.782304 -174.888652)
		(stroke
			(width 0.08255)
			(type default)
		)
		(layer "B.Cu")
	)
	(gr_line
		(start 262.682736 -179.5653)
		(end 262.8265 -179.091336)
		(stroke
			(width 0.08255)
			(type default)
		)
		(layer "B.Cu")
	)
	(gr_line
		(start 262.725154 -183.843422)
		(end 262.914892 -183.218328)
		(stroke
			(width 0.08255)
			(type default)
		)
		(layer "B.Cu")
	)
	(gr_line
		(start 262.729218 -141.754606)
		(end 262.91794 -141.132814)
		(stroke
			(width 0.08255)
			(type default)
		)
		(layer "B.Cu")
	)
	(gr_line
		(start 262.73887 -154.411172)
		(end 262.928608 -153.786078)
		(stroke
			(width 0.08255)
			(type default)
		)
		(layer "B.Cu")
	)
	(gr_line
		(start 262.751824 -178.951636)
		(end 262.8265 -179.091336)
		(stroke
			(width 0.08255)
			(type default)
		)
		(layer "B.Cu")
	)
	(gr_line
		(start 262.768842 -171.31792)
		(end 262.801862 -171.47286)
		(stroke
			(width 0.08255)
			(type default)
		)
		(layer "B.Cu")
	)
	(gr_line
		(start 262.782304 -174.888652)
		(end 263.052052 -174.473362)
		(stroke
			(width 0.08255)
			(type default)
		)
		(layer "B.Cu")
	)
	(gr_line
		(start 262.810498 -170.71213)
		(end 263.167876 -170.161712)
		(stroke
			(width 0.08255)
			(type default)
		)
		(layer "B.Cu")
	)
	(gr_line
		(start 262.827516 -147.339812)
		(end 263.016238 -146.718274)
		(stroke
			(width 0.08255)
			(type default)
		)
		(layer "B.Cu")
	)
	(gr_line
		(start 262.897112 -178.4731)
		(end 263.036812 -178.398424)
		(stroke
			(width 0.08255)
			(type default)
		)
		(layer "B.Cu")
	)
	(gr_line
		(start 262.979154 -177.187606)
		(end 262.980424 -177.183542)
		(stroke
			(width 0.08255)
			(type default)
		)
		(layer "B.Cu")
	)
	(gr_line
		(start 262.980424 -177.183542)
		(end 262.98271 -177.18024)
		(stroke
			(width 0.08255)
			(type default)
		)
		(layer "B.Cu")
	)
	(gr_line
		(start 262.997696 -183.960008)
		(end 263.13765 -183.885332)
		(stroke
			(width 0.08255)
			(type default)
		)
		(layer "B.Cu")
	)
	(gr_line
		(start 263.001252 -141.87297)
		(end 263.140952 -141.798294)
		(stroke
			(width 0.08255)
			(type default)
		)
		(layer "B.Cu")
	)
	(gr_line
		(start 263.011412 -154.527758)
		(end 263.151366 -154.453082)
		(stroke
			(width 0.08255)
			(type default)
		)
		(layer "B.Cu")
	)
	(gr_line
		(start 263.019032 -174.318422)
		(end 263.052052 -174.473362)
		(stroke
			(width 0.08255)
			(type default)
		)
		(layer "B.Cu")
	)
	(gr_line
		(start 263.036812 -178.398424)
		(end 263.180576 -177.92446)
		(stroke
			(width 0.08255)
			(type default)
		)
		(layer "B.Cu")
	)
	(gr_line
		(start 263.040876 -170.89882)
		(end 263.19607 -170.8658)
		(stroke
			(width 0.08255)
			(type default)
		)
		(layer "B.Cu")
	)
	(gr_line
		(start 263.064244 -173.70806)
		(end 263.417558 -173.163992)
		(stroke
			(width 0.08255)
			(type default)
		)
		(layer "B.Cu")
	)
	(gr_line
		(start 263.079738 -182.675022)
		(end 263.268968 -182.051198)
		(stroke
			(width 0.08255)
			(type default)
		)
		(layer "B.Cu")
	)
	(gr_line
		(start 263.083548 -140.586968)
		(end 263.272016 -139.965938)
		(stroke
			(width 0.08255)
			(type default)
		)
		(layer "B.Cu")
	)
	(gr_line
		(start 263.093454 -153.242772)
		(end 263.282684 -152.618948)
		(stroke
			(width 0.08255)
			(type default)
		)
		(layer "B.Cu")
	)
	(gr_line
		(start 263.09955 -147.458176)
		(end 263.23925 -147.3835)
		(stroke
			(width 0.08255)
			(type default)
		)
		(layer "B.Cu")
	)
	(gr_line
		(start 263.1059 -177.78476)
		(end 263.180576 -177.92446)
		(stroke
			(width 0.08255)
			(type default)
		)
		(layer "B.Cu")
	)
	(gr_line
		(start 263.13765 -183.885332)
		(end 263.281414 -183.411368)
		(stroke
			(width 0.08255)
			(type default)
		)
		(layer "B.Cu")
	)
	(gr_line
		(start 263.140952 -141.798294)
		(end 263.284716 -141.32433)
		(stroke
			(width 0.08255)
			(type default)
		)
		(layer "B.Cu")
	)
	(gr_line
		(start 263.151366 -154.453082)
		(end 263.29513 -153.979118)
		(stroke
			(width 0.08255)
			(type default)
		)
		(layer "B.Cu")
	)
	(gr_line
		(start 263.181592 -146.172428)
		(end 263.370568 -145.54962)
		(stroke
			(width 0.08255)
			(type default)
		)
		(layer "B.Cu")
	)
	(gr_line
		(start 263.19607 -170.8658)
		(end 263.465818 -170.45051)
		(stroke
			(width 0.08255)
			(type default)
		)
		(layer "B.Cu")
	)
	(gr_line
		(start 263.206738 -183.271668)
		(end 263.281414 -183.411368)
		(stroke
			(width 0.08255)
			(type default)
		)
		(layer "B.Cu")
	)
	(gr_line
		(start 263.21004 -141.184884)
		(end 263.284716 -141.32433)
		(stroke
			(width 0.08255)
			(type default)
		)
		(layer "B.Cu")
	)
	(gr_line
		(start 263.220454 -153.839418)
		(end 263.29513 -153.979118)
		(stroke
			(width 0.08255)
			(type default)
		)
		(layer "B.Cu")
	)
	(gr_line
		(start 263.23925 -147.3835)
		(end 263.383014 -146.909536)
		(stroke
			(width 0.08255)
			(type default)
		)
		(layer "B.Cu")
	)
	(gr_line
		(start 263.29132 -173.899068)
		(end 263.44626 -173.866302)
		(stroke
			(width 0.08255)
			(type default)
		)
		(layer "B.Cu")
	)
	(gr_line
		(start 263.308338 -146.769836)
		(end 263.383014 -146.909536)
		(stroke
			(width 0.08255)
			(type default)
		)
		(layer "B.Cu")
	)
	(gr_line
		(start 263.351772 -182.793386)
		(end 263.491472 -182.71871)
		(stroke
			(width 0.08255)
			(type default)
		)
		(layer "B.Cu")
	)
	(gr_line
		(start 263.355328 -140.706348)
		(end 263.495028 -140.631672)
		(stroke
			(width 0.08255)
			(type default)
		)
		(layer "B.Cu")
	)
	(gr_line
		(start 263.365488 -153.361136)
		(end 263.505442 -153.28646)
		(stroke
			(width 0.08255)
			(type default)
		)
		(layer "B.Cu")
	)
	(gr_line
		(start 263.432798 -170.29557)
		(end 263.465818 -170.45051)
		(stroke
			(width 0.08255)
			(type default)
		)
		(layer "B.Cu")
	)
	(gr_line
		(start 263.433814 -181.508146)
		(end 263.62279 -180.885084)
		(stroke
			(width 0.08255)
			(type default)
		)
		(layer "B.Cu")
	)
	(gr_line
		(start 263.43737 -139.420854)
		(end 263.43864 -139.41679)
		(stroke
			(width 0.08255)
			(type default)
		)
		(layer "B.Cu")
	)
	(gr_line
		(start 263.43864 -139.41679)
		(end 263.440926 -139.413488)
		(stroke
			(width 0.08255)
			(type default)
		)
		(layer "B.Cu")
	)
	(gr_line
		(start 263.44626 -173.866302)
		(end 263.716008 -173.450758)
		(stroke
			(width 0.08255)
			(type default)
		)
		(layer "B.Cu")
	)
	(gr_line
		(start 263.453626 -146.2913)
		(end 263.593326 -146.216624)
		(stroke
			(width 0.08255)
			(type default)
		)
		(layer "B.Cu")
	)
	(gr_line
		(start 263.4742 -169.68978)
		(end 263.832594 -169.137838)
		(stroke
			(width 0.08255)
			(type default)
		)
		(layer "B.Cu")
	)
	(gr_line
		(start 263.491472 -182.71871)
		(end 263.63549 -182.244746)
		(stroke
			(width 0.08255)
			(type default)
		)
		(layer "B.Cu")
	)
	(gr_line
		(start 263.495028 -140.631672)
		(end 263.638792 -140.157708)
		(stroke
			(width 0.08255)
			(type default)
		)
		(layer "B.Cu")
	)
	(gr_line
		(start 263.505442 -153.28646)
		(end 263.649206 -152.812496)
		(stroke
			(width 0.08255)
			(type default)
		)
		(layer "B.Cu")
	)
	(gr_line
		(start 263.535414 -145.006314)
		(end 263.724136 -144.384268)
		(stroke
			(width 0.08255)
			(type default)
		)
		(layer "B.Cu")
	)
	(gr_line
		(start 263.560814 -182.104792)
		(end 263.63549 -182.244746)
		(stroke
			(width 0.08255)
			(type default)
		)
		(layer "B.Cu")
	)
	(gr_line
		(start 263.564116 -140.018008)
		(end 263.638792 -140.157708)
		(stroke
			(width 0.08255)
			(type default)
		)
		(layer "B.Cu")
	)
	(gr_line
		(start 263.57453 -152.672542)
		(end 263.649206 -152.812496)
		(stroke
			(width 0.08255)
			(type default)
		)
		(layer "B.Cu")
	)
	(gr_line
		(start 263.593326 -146.216624)
		(end 263.73709 -145.74266)
		(stroke
			(width 0.08255)
			(type default)
		)
		(layer "B.Cu")
	)
	(gr_line
		(start 263.662414 -145.60296)
		(end 263.73709 -145.74266)
		(stroke
			(width 0.08255)
			(type default)
		)
		(layer "B.Cu")
	)
	(gr_line
		(start 263.682988 -173.295818)
		(end 263.716008 -173.450758)
		(stroke
			(width 0.08255)
			(type default)
		)
		(layer "B.Cu")
	)
	(gr_line
		(start 263.704832 -169.876216)
		(end 263.860026 -169.843196)
		(stroke
			(width 0.08255)
			(type default)
		)
		(layer "B.Cu")
	)
	(gr_line
		(start 263.705848 -181.62651)
		(end 263.845548 -181.552088)
		(stroke
			(width 0.08255)
			(type default)
		)
		(layer "B.Cu")
	)
	(gr_line
		(start 263.78789 -180.341016)
		(end 263.976866 -179.718208)
		(stroke
			(width 0.08255)
			(type default)
		)
		(layer "B.Cu")
	)
	(gr_line
		(start 263.807448 -145.124678)
		(end 263.947148 -145.050002)
		(stroke
			(width 0.08255)
			(type default)
		)
		(layer "B.Cu")
	)
	(gr_line
		(start 263.845548 -181.552088)
		(end 263.989312 -181.078124)
		(stroke
			(width 0.08255)
			(type default)
		)
		(layer "B.Cu")
	)
	(gr_line
		(start 263.860026 -169.843196)
		(end 264.129774 -169.427906)
		(stroke
			(width 0.08255)
			(type default)
		)
		(layer "B.Cu")
	)
	(gr_line
		(start 263.888728 -143.84147)
		(end 264.078466 -143.216122)
		(stroke
			(width 0.08255)
			(type default)
		)
		(layer "B.Cu")
	)
	(gr_line
		(start 263.914636 -180.938424)
		(end 263.989312 -181.078124)
		(stroke
			(width 0.08255)
			(type default)
		)
		(layer "B.Cu")
	)
	(gr_line
		(start 263.947148 -145.050002)
		(end 264.090912 -144.576038)
		(stroke
			(width 0.08255)
			(type default)
		)
		(layer "B.Cu")
	)
	(gr_line
		(start 264.016236 -144.436592)
		(end 264.090912 -144.576038)
		(stroke
			(width 0.08255)
			(type default)
		)
		(layer "B.Cu")
	)
	(gr_line
		(start 264.059924 -180.459888)
		(end 264.199624 -180.385212)
		(stroke
			(width 0.08255)
			(type default)
		)
		(layer "B.Cu")
	)
	(gr_line
		(start 264.096754 -169.272966)
		(end 264.129774 -169.427906)
		(stroke
			(width 0.08255)
			(type default)
		)
		(layer "B.Cu")
	)
	(gr_line
		(start 264.139172 -168.665906)
		(end 264.497058 -168.114726)
		(stroke
			(width 0.08255)
			(type default)
		)
		(layer "B.Cu")
	)
	(gr_line
		(start 264.141966 -179.174394)
		(end 264.143236 -179.17033)
		(stroke
			(width 0.08255)
			(type default)
		)
		(layer "B.Cu")
	)
	(gr_line
		(start 264.143236 -179.17033)
		(end 264.145522 -179.167028)
		(stroke
			(width 0.08255)
			(type default)
		)
		(layer "B.Cu")
	)
	(gr_line
		(start 264.161524 -143.958056)
		(end 264.301224 -143.88338)
		(stroke
			(width 0.08255)
			(type default)
		)
		(layer "B.Cu")
	)
	(gr_line
		(start 264.1981 -155.715208)
		(end 264.386822 -155.093162)
		(stroke
			(width 0.08255)
			(type default)
		)
		(layer "B.Cu")
	)
	(gr_line
		(start 264.199624 -180.385212)
		(end 264.343388 -179.911248)
		(stroke
			(width 0.08255)
			(type default)
		)
		(layer "B.Cu")
	)
	(gr_line
		(start 264.268712 -179.771548)
		(end 264.343388 -179.911248)
		(stroke
			(width 0.08255)
			(type default)
		)
		(layer "B.Cu")
	)
	(gr_line
		(start 264.301224 -143.88338)
		(end 264.444988 -143.409416)
		(stroke
			(width 0.08255)
			(type default)
		)
		(layer "B.Cu")
	)
	(gr_line
		(start 264.3505 -138.012424)
		(end 264.705338 -137.46607)
		(stroke
			(width 0.08255)
			(type default)
		)
		(layer "B.Cu")
	)
	(gr_line
		(start 264.369042 -168.853612)
		(end 264.523982 -168.820846)
		(stroke
			(width 0.08255)
			(type default)
		)
		(layer "B.Cu")
	)
	(gr_line
		(start 264.370312 -143.269716)
		(end 264.444988 -143.409416)
		(stroke
			(width 0.08255)
			(type default)
		)
		(layer "B.Cu")
	)
	(gr_line
		(start 264.470388 -155.833318)
		(end 264.609834 -155.758896)
		(stroke
			(width 0.08255)
			(type default)
		)
		(layer "B.Cu")
	)
	(gr_line
		(start 264.523982 -168.820846)
		(end 264.79373 -168.405302)
		(stroke
			(width 0.08255)
			(type default)
		)
		(layer "B.Cu")
	)
	(gr_line
		(start 264.55243 -154.54757)
		(end 264.741152 -153.925778)
		(stroke
			(width 0.08255)
			(type default)
		)
		(layer "B.Cu")
	)
	(gr_line
		(start 264.578846 -138.201908)
		(end 264.733786 -138.169142)
		(stroke
			(width 0.08255)
			(type default)
		)
		(layer "B.Cu")
	)
	(gr_line
		(start 264.609834 -155.758896)
		(end 264.753598 -155.284932)
		(stroke
			(width 0.08255)
			(type default)
		)
		(layer "B.Cu")
	)
	(gr_line
		(start 264.678922 -155.145232)
		(end 264.753598 -155.284932)
		(stroke
			(width 0.08255)
			(type default)
		)
		(layer "B.Cu")
	)
	(gr_line
		(start 264.733786 -138.169142)
		(end 265.003534 -137.753852)
		(stroke
			(width 0.08255)
			(type default)
		)
		(layer "B.Cu")
	)
	(gr_line
		(start 264.739882 -141.036802)
		(end 264.741152 -141.032738)
		(stroke
			(width 0.08255)
			(type default)
		)
		(layer "B.Cu")
	)
	(gr_line
		(start 264.741152 -141.032738)
		(end 264.743438 -141.029436)
		(stroke
			(width 0.08255)
			(type default)
		)
		(layer "B.Cu")
	)
	(gr_line
		(start 264.76071 -168.250108)
		(end 264.79373 -168.405302)
		(stroke
			(width 0.08255)
			(type default)
		)
		(layer "B.Cu")
	)
	(gr_line
		(start 264.777982 -147.690586)
		(end 264.96772 -147.065492)
		(stroke
			(width 0.08255)
			(type default)
		)
		(layer "B.Cu")
	)
	(gr_line
		(start 264.82421 -154.66695)
		(end 264.96391 -154.592274)
		(stroke
			(width 0.08255)
			(type default)
		)
		(layer "B.Cu")
	)
	(gr_line
		(start 264.96391 -154.592274)
		(end 265.107674 -154.11831)
		(stroke
			(width 0.08255)
			(type default)
		)
		(layer "B.Cu")
	)
	(gr_line
		(start 264.970768 -137.598658)
		(end 265.003534 -137.753852)
		(stroke
			(width 0.08255)
			(type default)
		)
		(layer "B.Cu")
	)
	(gr_line
		(start 265.012678 -136.99236)
		(end 265.370056 -136.442196)
		(stroke
			(width 0.08255)
			(type default)
		)
		(layer "B.Cu")
	)
	(gr_line
		(start 265.032998 -153.978356)
		(end 265.107674 -154.11831)
		(stroke
			(width 0.08255)
			(type default)
		)
		(layer "B.Cu")
	)
	(gr_line
		(start 265.050524 -147.807172)
		(end 265.190478 -147.732496)
		(stroke
			(width 0.08255)
			(type default)
		)
		(layer "B.Cu")
	)
	(gr_line
		(start 265.132566 -146.522186)
		(end 265.321796 -145.899124)
		(stroke
			(width 0.08255)
			(type default)
		)
		(layer "B.Cu")
	)
	(gr_line
		(start 265.190478 -147.732496)
		(end 265.334242 -147.258532)
		(stroke
			(width 0.08255)
			(type default)
		)
		(layer "B.Cu")
	)
	(gr_line
		(start 265.242802 -137.179558)
		(end 265.397742 -137.146538)
		(stroke
			(width 0.08255)
			(type default)
		)
		(layer "B.Cu")
	)
	(gr_line
		(start 265.259566 -147.118832)
		(end 265.334242 -147.258532)
		(stroke
			(width 0.08255)
			(type default)
		)
		(layer "B.Cu")
	)
	(gr_line
		(start 265.338814 -173.552358)
		(end 265.691366 -173.009306)
		(stroke
			(width 0.08255)
			(type default)
		)
		(layer "B.Cu")
	)
	(gr_line
		(start 265.397742 -137.146538)
		(end 265.66749 -136.731248)
		(stroke
			(width 0.08255)
			(type default)
		)
		(layer "B.Cu")
	)
	(gr_line
		(start 265.4046 -146.64055)
		(end 265.5443 -146.565874)
		(stroke
			(width 0.08255)
			(type default)
		)
		(layer "B.Cu")
	)
	(gr_line
		(start 265.486388 -145.356072)
		(end 265.675364 -144.733264)
		(stroke
			(width 0.08255)
			(type default)
		)
		(layer "B.Cu")
	)
	(gr_line
		(start 265.5443 -146.565874)
		(end 265.688318 -146.09191)
		(stroke
			(width 0.08255)
			(type default)
		)
		(layer "B.Cu")
	)
	(gr_line
		(start 265.566144 -173.742858)
		(end 265.721084 -173.710092)
		(stroke
			(width 0.08255)
			(type default)
		)
		(layer "B.Cu")
	)
	(gr_line
		(start 265.613642 -145.951956)
		(end 265.688318 -146.09191)
		(stroke
			(width 0.08255)
			(type default)
		)
		(layer "B.Cu")
	)
	(gr_line
		(start 265.634724 -136.576308)
		(end 265.66749 -136.731248)
		(stroke
			(width 0.08255)
			(type default)
		)
		(layer "B.Cu")
	)
	(gr_line
		(start 265.67638 -135.970264)
		(end 266.033758 -135.419846)
		(stroke
			(width 0.08255)
			(type default)
		)
		(layer "B.Cu")
	)
	(gr_line
		(start 265.721084 -173.710092)
		(end 265.990832 -173.294548)
		(stroke
			(width 0.08255)
			(type default)
		)
		(layer "B.Cu")
	)
	(gr_line
		(start 265.758676 -145.473674)
		(end 265.898376 -145.399252)
		(stroke
			(width 0.08255)
			(type default)
		)
		(layer "B.Cu")
	)
	(gr_line
		(start 265.81354 -176.598072)
		(end 266.167616 -176.052988)
		(stroke
			(width 0.08255)
			(type default)
		)
		(layer "B.Cu")
	)
	(gr_line
		(start 265.840718 -144.18818)
		(end 266.029694 -143.565372)
		(stroke
			(width 0.08255)
			(type default)
		)
		(layer "B.Cu")
	)
	(gr_line
		(start 265.898376 -145.399252)
		(end 266.04214 -144.925288)
		(stroke
			(width 0.08255)
			(type default)
		)
		(layer "B.Cu")
	)
	(gr_line
		(start 265.906758 -136.156954)
		(end 266.061698 -136.124188)
		(stroke
			(width 0.08255)
			(type default)
		)
		(layer "B.Cu")
	)
	(gr_line
		(start 265.957812 -173.139862)
		(end 265.990832 -173.294548)
		(stroke
			(width 0.08255)
			(type default)
		)
		(layer "B.Cu")
	)
	(gr_line
		(start 265.967464 -144.785334)
		(end 266.04214 -144.925288)
		(stroke
			(width 0.08255)
			(type default)
		)
		(layer "B.Cu")
	)
	(gr_line
		(start 266.003532 -172.528738)
		(end 266.356084 -171.985686)
		(stroke
			(width 0.08255)
			(type default)
		)
		(layer "B.Cu")
	)
	(gr_line
		(start 266.041886 -176.787302)
		(end 266.196826 -176.754536)
		(stroke
			(width 0.08255)
			(type default)
		)
		(layer "B.Cu")
	)
	(gr_line
		(start 266.061698 -136.124188)
		(end 266.331446 -135.708644)
		(stroke
			(width 0.08255)
			(type default)
		)
		(layer "B.Cu")
	)
	(gr_line
		(start 266.112498 -144.307052)
		(end 266.252452 -144.232376)
		(stroke
			(width 0.08255)
			(type default)
		)
		(layer "B.Cu")
	)
	(gr_line
		(start 266.194794 -143.021812)
		(end 266.19581 -143.018002)
		(stroke
			(width 0.08255)
			(type default)
		)
		(layer "B.Cu")
	)
	(gr_line
		(start 266.19581 -143.018002)
		(end 266.19835 -143.013938)
		(stroke
			(width 0.08255)
			(type default)
		)
		(layer "B.Cu")
	)
	(gr_line
		(start 266.196826 -176.754536)
		(end 266.466574 -176.338992)
		(stroke
			(width 0.08255)
			(type default)
		)
		(layer "B.Cu")
	)
	(gr_line
		(start 266.223496 -168.842436)
		(end 266.57808 -168.29659)
		(stroke
			(width 0.08255)
			(type default)
		)
		(layer "B.Cu")
	)
	(gr_line
		(start 266.2301 -172.720254)
		(end 266.38504 -172.687488)
		(stroke
			(width 0.08255)
			(type default)
		)
		(layer "B.Cu")
	)
	(gr_line
		(start 266.236958 -148.995638)
		(end 266.426188 -148.371306)
		(stroke
			(width 0.08255)
			(type default)
		)
		(layer "B.Cu")
	)
	(gr_line
		(start 266.252452 -144.232376)
		(end 266.396216 -143.758412)
		(stroke
			(width 0.08255)
			(type default)
		)
		(layer "B.Cu")
	)
	(gr_line
		(start 266.29868 -135.553958)
		(end 266.331446 -135.708644)
		(stroke
			(width 0.08255)
			(type default)
		)
		(layer "B.Cu")
	)
	(gr_line
		(start 266.32154 -143.618712)
		(end 266.396216 -143.758412)
		(stroke
			(width 0.08255)
			(type default)
		)
		(layer "B.Cu")
	)
	(gr_line
		(start 266.341098 -134.946898)
		(end 266.696952 -134.39902)
		(stroke
			(width 0.08255)
			(type default)
		)
		(layer "B.Cu")
	)
	(gr_line
		(start 266.38504 -172.687488)
		(end 266.654788 -172.272198)
		(stroke
			(width 0.08255)
			(type default)
		)
		(layer "B.Cu")
	)
	(gr_line
		(start 266.433808 -176.184052)
		(end 266.466574 -176.338992)
		(stroke
			(width 0.08255)
			(type default)
		)
		(layer "B.Cu")
	)
	(gr_line
		(start 266.452096 -169.031412)
		(end 266.607036 -168.998646)
		(stroke
			(width 0.08255)
			(type default)
		)
		(layer "B.Cu")
	)
	(gr_line
		(start 266.478512 -175.574198)
		(end 266.831318 -175.031146)
		(stroke
			(width 0.08255)
			(type default)
		)
		(layer "B.Cu")
	)
	(gr_line
		(start 266.508992 -149.112986)
		(end 266.648946 -149.03831)
		(stroke
			(width 0.08255)
			(type default)
		)
		(layer "B.Cu")
	)
	(gr_line
		(start 266.570714 -135.134604)
		(end 266.725908 -135.101584)
		(stroke
			(width 0.08255)
			(type default)
		)
		(layer "B.Cu")
	)
	(gr_line
		(start 266.591034 -147.828)
		(end 266.780264 -147.204176)
		(stroke
			(width 0.08255)
			(type default)
		)
		(layer "B.Cu")
	)
	(gr_line
		(start 266.607036 -168.998646)
		(end 266.876784 -168.583102)
		(stroke
			(width 0.08255)
			(type default)
		)
		(layer "B.Cu")
	)
	(gr_line
		(start 266.622022 -172.117004)
		(end 266.654788 -172.272198)
		(stroke
			(width 0.08255)
			(type default)
		)
		(layer "B.Cu")
	)
	(gr_line
		(start 266.648946 -149.03831)
		(end 266.79271 -148.564346)
		(stroke
			(width 0.08255)
			(type default)
		)
		(layer "B.Cu")
	)
	(gr_line
		(start 266.66571 -171.508674)
		(end 267.02004 -170.963082)
		(stroke
			(width 0.08255)
			(type default)
		)
		(layer "B.Cu")
	)
	(gr_line
		(start 266.706096 -175.764698)
		(end 266.860782 -175.731932)
		(stroke
			(width 0.08255)
			(type default)
		)
		(layer "B.Cu")
	)
	(gr_line
		(start 266.718034 -148.424646)
		(end 266.79271 -148.564346)
		(stroke
			(width 0.08255)
			(type default)
		)
		(layer "B.Cu")
	)
	(gr_line
		(start 266.725908 -135.101584)
		(end 266.995656 -134.686294)
		(stroke
			(width 0.08255)
			(type default)
		)
		(layer "B.Cu")
	)
	(gr_line
		(start 266.844018 -168.428162)
		(end 266.876784 -168.583102)
		(stroke
			(width 0.08255)
			(type default)
		)
		(layer "B.Cu")
	)
	(gr_line
		(start 266.860782 -175.731932)
		(end 267.13053 -175.316642)
		(stroke
			(width 0.08255)
			(type default)
		)
		(layer "B.Cu")
	)
	(gr_line
		(start 266.863068 -147.946364)
		(end 267.002768 -147.871688)
		(stroke
			(width 0.08255)
			(type default)
		)
		(layer "B.Cu")
	)
	(gr_line
		(start 266.888468 -167.818562)
		(end 267.241782 -167.274748)
		(stroke
			(width 0.08255)
			(type default)
		)
		(layer "B.Cu")
	)
	(gr_line
		(start 266.894056 -171.697904)
		(end 267.048996 -171.664884)
		(stroke
			(width 0.08255)
			(type default)
		)
		(layer "B.Cu")
	)
	(gr_line
		(start 266.936728 -67.558666)
		(end 266.942316 -67.58432)
		(stroke
			(width 0.08255)
			(type default)
		)
		(layer "B.Cu")
	)
	(gr_line
		(start 266.936728 -67.558666)
		(end 266.942316 -67.533012)
		(stroke
			(width 0.08255)
			(type default)
		)
		(layer "B.Cu")
	)
	(gr_line
		(start 266.942316 -67.584574)
		(end 266.94257 -67.58559)
		(stroke
			(width 0.08255)
			(type default)
		)
		(layer "B.Cu")
	)
	(gr_line
		(start 266.94511 -146.661124)
		(end 267.134086 -146.038062)
		(stroke
			(width 0.08255)
			(type default)
		)
		(layer "B.Cu")
	)
	(gr_line
		(start 266.962636 -134.531354)
		(end 266.995656 -134.686294)
		(stroke
			(width 0.08255)
			(type default)
		)
		(layer "B.Cu")
	)
	(gr_line
		(start 267.002768 -147.871688)
		(end 267.146786 -147.397724)
		(stroke
			(width 0.08255)
			(type default)
		)
		(layer "B.Cu")
	)
	(gr_line
		(start 267.048996 -171.664884)
		(end 267.318744 -171.249594)
		(stroke
			(width 0.08255)
			(type default)
		)
		(layer "B.Cu")
	)
	(gr_line
		(start 267.07211 -147.25777)
		(end 267.146786 -147.397724)
		(stroke
			(width 0.08255)
			(type default)
		)
		(layer "B.Cu")
	)
	(gr_line
		(start 267.097764 -175.161702)
		(end 267.13053 -175.316642)
		(stroke
			(width 0.08255)
			(type default)
		)
		(layer "B.Cu")
	)
	(gr_line
		(start 267.098526 -66.827146)
		(end 267.11656 -66.745866)
		(stroke
			(width 0.08255)
			(type default)
		)
		(layer "B.Cu")
	)
	(gr_line
		(start 267.116306 -168.008808)
		(end 267.270992 -167.976042)
		(stroke
			(width 0.08255)
			(type default)
		)
		(layer "B.Cu")
	)
	(gr_line
		(start 267.11656 -66.745866)
		(end 267.116814 -66.745612)
		(stroke
			(width 0.08255)
			(type default)
		)
		(layer "B.Cu")
	)
	(gr_line
		(start 267.116814 -66.745612)
		(end 267.238988 -66.19494)
		(stroke
			(width 0.08255)
			(type default)
		)
		(layer "B.Cu")
	)
	(gr_line
		(start 267.141198 -174.553372)
		(end 267.495782 -174.007526)
		(stroke
			(width 0.08255)
			(type default)
		)
		(layer "B.Cu")
	)
	(gr_line
		(start 267.217144 -146.779488)
		(end 267.356844 -146.705066)
		(stroke
			(width 0.08255)
			(type default)
		)
		(layer "B.Cu")
	)
	(gr_line
		(start 267.270992 -167.976042)
		(end 267.54074 -167.560752)
		(stroke
			(width 0.08255)
			(type default)
		)
		(layer "B.Cu")
	)
	(gr_line
		(start 267.285978 -171.094654)
		(end 267.318744 -171.249594)
		(stroke
			(width 0.08255)
			(type default)
		)
		(layer "B.Cu")
	)
	(gr_line
		(start 267.298424 -163.800536)
		(end 267.657834 -163.246816)
		(stroke
			(width 0.08255)
			(type default)
		)
		(layer "B.Cu")
	)
	(gr_line
		(start 267.299186 -145.493994)
		(end 267.488162 -144.871186)
		(stroke
			(width 0.08255)
			(type default)
		)
		(layer "B.Cu")
	)
	(gr_line
		(start 267.330428 -170.485308)
		(end 267.683742 -169.94124)
		(stroke
			(width 0.08255)
			(type default)
		)
		(layer "B.Cu")
	)
	(gr_line
		(start 267.356844 -146.705066)
		(end 267.500608 -146.231102)
		(stroke
			(width 0.08255)
			(type default)
		)
		(layer "B.Cu")
	)
	(gr_line
		(start 267.362686 -65.636902)
		(end 267.503148 -65.003426)
		(stroke
			(width 0.08255)
			(type default)
		)
		(layer "B.Cu")
	)
	(gr_line
		(start 267.369798 -174.742348)
		(end 267.524992 -174.709328)
		(stroke
			(width 0.08255)
			(type default)
		)
		(layer "B.Cu")
	)
	(gr_line
		(start 267.378688 -66.925444)
		(end 267.512038 -66.840354)
		(stroke
			(width 0.08255)
			(type default)
		)
		(layer "B.Cu")
	)
	(gr_line
		(start 267.425932 -146.091402)
		(end 267.500608 -146.231102)
		(stroke
			(width 0.08255)
			(type default)
		)
		(layer "B.Cu")
	)
	(gr_line
		(start 267.507974 -167.405812)
		(end 267.54074 -167.560752)
		(stroke
			(width 0.08255)
			(type default)
		)
		(layer "B.Cu")
	)
	(gr_line
		(start 267.512038 -66.840354)
		(end 267.61948 -66.356738)
		(stroke
			(width 0.08255)
			(type default)
		)
		(layer "B.Cu")
	)
	(gr_line
		(start 267.524992 -174.709328)
		(end 267.79474 -174.294038)
		(stroke
			(width 0.08255)
			(type default)
		)
		(layer "B.Cu")
	)
	(gr_line
		(start 267.529818 -163.985956)
		(end 267.684758 -163.95319)
		(stroke
			(width 0.08255)
			(type default)
		)
		(layer "B.Cu")
	)
	(gr_line
		(start 267.53439 -66.223134)
		(end 267.61948 -66.356738)
		(stroke
			(width 0.08255)
			(type default)
		)
		(layer "B.Cu")
	)
	(gr_line
		(start 267.551662 -166.797228)
		(end 267.90523 -166.252906)
		(stroke
			(width 0.08255)
			(type default)
		)
		(layer "B.Cu")
	)
	(gr_line
		(start 267.558266 -170.6753)
		(end 267.712952 -170.642534)
		(stroke
			(width 0.08255)
			(type default)
		)
		(layer "B.Cu")
	)
	(gr_line
		(start 267.57122 -145.612866)
		(end 267.71092 -145.53819)
		(stroke
			(width 0.08255)
			(type default)
		)
		(layer "B.Cu")
	)
	(gr_line
		(start 267.626846 -64.445388)
		(end 267.7668 -63.814452)
		(stroke
			(width 0.08255)
			(type default)
		)
		(layer "B.Cu")
	)
	(gr_line
		(start 267.642594 -65.7352)
		(end 267.775944 -65.65011)
		(stroke
			(width 0.08255)
			(type default)
		)
		(layer "B.Cu")
	)
	(gr_line
		(start 267.653262 -144.327372)
		(end 267.654532 -144.323308)
		(stroke
			(width 0.08255)
			(type default)
		)
		(layer "B.Cu")
	)
	(gr_line
		(start 267.654532 -144.323308)
		(end 267.656818 -144.320006)
		(stroke
			(width 0.08255)
			(type default)
		)
		(layer "B.Cu")
	)
	(gr_line
		(start 267.684758 -163.95319)
		(end 267.954506 -163.537646)
		(stroke
			(width 0.08255)
			(type default)
		)
		(layer "B.Cu")
	)
	(gr_line
		(start 267.71092 -145.53819)
		(end 267.854684 -145.064226)
		(stroke
			(width 0.08255)
			(type default)
		)
		(layer "B.Cu")
	)
	(gr_line
		(start 267.712952 -170.642534)
		(end 267.9827 -170.22699)
		(stroke
			(width 0.08255)
			(type default)
		)
		(layer "B.Cu")
	)
	(gr_line
		(start 267.76172 -174.139098)
		(end 267.79474 -174.294038)
		(stroke
			(width 0.08255)
			(type default)
		)
		(layer "B.Cu")
	)
	(gr_line
		(start 267.775944 -65.65011)
		(end 267.883386 -65.166494)
		(stroke
			(width 0.08255)
			(type default)
		)
		(layer "B.Cu")
	)
	(gr_line
		(start 267.780008 -166.986458)
		(end 267.935202 -166.953438)
		(stroke
			(width 0.08255)
			(type default)
		)
		(layer "B.Cu")
	)
	(gr_line
		(start 267.780008 -144.924526)
		(end 267.854684 -145.064226)
		(stroke
			(width 0.08255)
			(type default)
		)
		(layer "B.Cu")
	)
	(gr_line
		(start 267.798296 -65.03289)
		(end 267.883386 -65.166494)
		(stroke
			(width 0.08255)
			(type default)
		)
		(layer "B.Cu")
	)
	(gr_line
		(start 267.8049 -173.531022)
		(end 268.159992 -172.984414)
		(stroke
			(width 0.08255)
			(type default)
		)
		(layer "B.Cu")
	)
	(gr_line
		(start 267.890752 -63.255144)
		(end 268.03096 -62.622938)
		(stroke
			(width 0.08255)
			(type default)
		)
		(layer "B.Cu")
	)
	(gr_line
		(start 267.9065 -64.544702)
		(end 268.03985 -64.459866)
		(stroke
			(width 0.08255)
			(type default)
		)
		(layer "B.Cu")
	)
	(gr_line
		(start 267.92174 -163.382706)
		(end 267.954506 -163.537646)
		(stroke
			(width 0.08255)
			(type default)
		)
		(layer "B.Cu")
	)
	(gr_line
		(start 267.935202 -166.953438)
		(end 268.20495 -166.538148)
		(stroke
			(width 0.08255)
			(type default)
		)
		(layer "B.Cu")
	)
	(gr_line
		(start 267.949934 -170.072304)
		(end 267.9827 -170.22699)
		(stroke
			(width 0.08255)
			(type default)
		)
		(layer "B.Cu")
	)
	(gr_line
		(start 267.962888 -162.77717)
		(end 268.321536 -162.224974)
		(stroke
			(width 0.08255)
			(type default)
		)
		(layer "B.Cu")
	)
	(gr_line
		(start 268.034008 -173.719744)
		(end 268.188948 -173.686978)
		(stroke
			(width 0.08255)
			(type default)
		)
		(layer "B.Cu")
	)
	(gr_line
		(start 268.03985 -64.459866)
		(end 268.147038 -63.97625)
		(stroke
			(width 0.08255)
			(type default)
		)
		(layer "B.Cu")
	)
	(gr_line
		(start 268.062202 -63.842646)
		(end 268.147038 -63.97625)
		(stroke
			(width 0.08255)
			(type default)
		)
		(layer "B.Cu")
	)
	(gr_line
		(start 268.170406 -63.354458)
		(end 268.303756 -63.269368)
		(stroke
			(width 0.08255)
			(type default)
		)
		(layer "B.Cu")
	)
	(gr_line
		(start 268.17193 -166.383208)
		(end 268.20495 -166.538148)
		(stroke
			(width 0.08255)
			(type default)
		)
		(layer "B.Cu")
	)
	(gr_line
		(start 268.188948 -173.686978)
		(end 268.458696 -173.271434)
		(stroke
			(width 0.08255)
			(type default)
		)
		(layer "B.Cu")
	)
	(gr_line
		(start 268.193774 -162.963352)
		(end 268.348714 -162.930586)
		(stroke
			(width 0.08255)
			(type default)
		)
		(layer "B.Cu")
	)
	(gr_line
		(start 268.216126 -165.774116)
		(end 268.56944 -165.230048)
		(stroke
			(width 0.08255)
			(type default)
		)
		(layer "B.Cu")
	)
	(gr_line
		(start 268.303756 -63.269368)
		(end 268.410944 -62.786006)
		(stroke
			(width 0.08255)
			(type default)
		)
		(layer "B.Cu")
	)
	(gr_line
		(start 268.326108 -62.652402)
		(end 268.410944 -62.786006)
		(stroke
			(width 0.08255)
			(type default)
		)
		(layer "B.Cu")
	)
	(gr_line
		(start 268.348714 -162.930586)
		(end 268.618462 -162.515296)
		(stroke
			(width 0.08255)
			(type default)
		)
		(layer "B.Cu")
	)
	(gr_line
		(start 268.425676 -173.116748)
		(end 268.458696 -173.271434)
		(stroke
			(width 0.08255)
			(type default)
		)
		(layer "B.Cu")
	)
	(gr_line
		(start 268.444218 -165.963854)
		(end 268.599158 -165.931088)
		(stroke
			(width 0.08255)
			(type default)
		)
		(layer "B.Cu")
	)
	(gr_line
		(start 268.585696 -162.360102)
		(end 268.618462 -162.515296)
		(stroke
			(width 0.08255)
			(type default)
		)
		(layer "B.Cu")
	)
	(gr_line
		(start 268.599158 -165.931088)
		(end 268.868906 -165.515544)
		(stroke
			(width 0.08255)
			(type default)
		)
		(layer "B.Cu")
	)
	(gr_line
		(start 268.626336 -161.755582)
		(end 268.98473 -161.20364)
		(stroke
			(width 0.08255)
			(type default)
		)
		(layer "B.Cu")
	)
	(gr_line
		(start 268.835886 -165.360858)
		(end 268.868906 -165.515544)
		(stroke
			(width 0.08255)
			(type default)
		)
		(layer "B.Cu")
	)
	(gr_line
		(start 268.85773 -161.941002)
		(end 269.012924 -161.907982)
		(stroke
			(width 0.08255)
			(type default)
		)
		(layer "B.Cu")
	)
	(gr_line
		(start 268.870938 -134.673848)
		(end 269.221966 -134.133336)
		(stroke
			(width 0.08255)
			(type default)
		)
		(layer "B.Cu")
	)
	(gr_line
		(start 268.880844 -142.433802)
		(end 269.235936 -141.886686)
		(stroke
			(width 0.08255)
			(type default)
		)
		(layer "B.Cu")
	)
	(gr_line
		(start 268.931644 -66.87185)
		(end 268.93774 -66.89979)
		(stroke
			(width 0.08255)
			(type default)
		)
		(layer "B.Cu")
	)
	(gr_line
		(start 268.931644 -66.87185)
		(end 268.93774 -66.844418)
		(stroke
			(width 0.08255)
			(type default)
		)
		(layer "B.Cu")
	)
	(gr_line
		(start 268.933422 -138.759692)
		(end 269.285974 -138.21156)
		(stroke
			(width 0.08255)
			(type default)
		)
		(layer "B.Cu")
	)
	(gr_line
		(start 268.93774 -66.899536)
		(end 268.93774 -66.89979)
		(stroke
			(width 0.08255)
			(type default)
		)
		(layer "B.Cu")
	)
	(gr_line
		(start 269.012924 -161.907982)
		(end 269.282672 -161.492692)
		(stroke
			(width 0.08255)
			(type default)
		)
		(layer "B.Cu")
	)
	(gr_line
		(start 269.015464 -66.494406)
		(end 269.033498 -66.413126)
		(stroke
			(width 0.08255)
			(type default)
		)
		(layer "B.Cu")
	)
	(gr_line
		(start 269.033244 -66.413126)
		(end 269.033498 -66.413126)
		(stroke
			(width 0.08255)
			(type default)
		)
		(layer "B.Cu")
	)
	(gr_line
		(start 269.033244 -66.413126)
		(end 269.155926 -65.859914)
		(stroke
			(width 0.08255)
			(type default)
		)
		(layer "B.Cu")
	)
	(gr_line
		(start 269.097506 -134.865364)
		(end 269.252446 -134.832598)
		(stroke
			(width 0.08255)
			(type default)
		)
		(layer "B.Cu")
	)
	(gr_line
		(start 269.109444 -142.623032)
		(end 269.264384 -142.590266)
		(stroke
			(width 0.08255)
			(type default)
		)
		(layer "B.Cu")
	)
	(gr_line
		(start 269.163546 -138.94689)
		(end 269.318486 -138.913108)
		(stroke
			(width 0.08255)
			(type default)
		)
		(layer "B.Cu")
	)
	(gr_line
		(start 269.249652 -161.337752)
		(end 269.282672 -161.492692)
		(stroke
			(width 0.08255)
			(type default)
		)
		(layer "B.Cu")
	)
	(gr_line
		(start 269.252446 -134.832598)
		(end 269.522194 -134.417054)
		(stroke
			(width 0.08255)
			(type default)
		)
		(layer "B.Cu")
	)
	(gr_line
		(start 269.264384 -142.590266)
		(end 269.533878 -142.174722)
		(stroke
			(width 0.08255)
			(type default)
		)
		(layer "B.Cu")
	)
	(gr_line
		(start 269.278608 -65.30594)
		(end 269.419832 -64.669416)
		(stroke
			(width 0.08255)
			(type default)
		)
		(layer "B.Cu")
	)
	(gr_line
		(start 269.29207 -160.730692)
		(end 269.647924 -160.182814)
		(stroke
			(width 0.08255)
			(type default)
		)
		(layer "B.Cu")
	)
	(gr_line
		(start 269.295372 -66.592704)
		(end 269.428722 -66.507614)
		(stroke
			(width 0.08255)
			(type default)
		)
		(layer "B.Cu")
	)
	(gr_line
		(start 269.318486 -138.913108)
		(end 269.586456 -138.496548)
		(stroke
			(width 0.08255)
			(type default)
		)
		(layer "B.Cu")
	)
	(gr_line
		(start 269.428722 -66.507614)
		(end 269.536164 -66.023998)
		(stroke
			(width 0.08255)
			(type default)
		)
		(layer "B.Cu")
	)
	(gr_line
		(start 269.451074 -65.89014)
		(end 269.536164 -66.023998)
		(stroke
			(width 0.08255)
			(type default)
		)
		(layer "B.Cu")
	)
	(gr_line
		(start 269.489174 -134.262368)
		(end 269.522194 -134.417054)
		(stroke
			(width 0.08255)
			(type default)
		)
		(layer "B.Cu")
	)
	(gr_line
		(start 269.501112 -142.019782)
		(end 269.533878 -142.174722)
		(stroke
			(width 0.08255)
			(type default)
		)
		(layer "B.Cu")
	)
	(gr_line
		(start 269.502128 -130.079242)
		(end 269.85849 -129.530602)
		(stroke
			(width 0.08255)
			(type default)
		)
		(layer "B.Cu")
	)
	(gr_line
		(start 269.521686 -160.918398)
		(end 269.67688 -160.885632)
		(stroke
			(width 0.08255)
			(type default)
		)
		(layer "B.Cu")
	)
	(gr_line
		(start 269.53464 -133.651498)
		(end 269.887192 -133.1087)
		(stroke
			(width 0.08255)
			(type default)
		)
		(layer "B.Cu")
	)
	(gr_line
		(start 269.543022 -64.114172)
		(end 269.683738 -63.47968)
		(stroke
			(width 0.08255)
			(type default)
		)
		(layer "B.Cu")
	)
	(gr_line
		(start 269.545054 -141.410944)
		(end 269.899384 -140.86459)
		(stroke
			(width 0.08255)
			(type default)
		)
		(layer "B.Cu")
	)
	(gr_line
		(start 269.552674 -138.341862)
		(end 269.586456 -138.496548)
		(stroke
			(width 0.08255)
			(type default)
		)
		(layer "B.Cu")
	)
	(gr_line
		(start 269.559024 -65.40246)
		(end 269.692882 -65.31737)
		(stroke
			(width 0.08255)
			(type default)
		)
		(layer "B.Cu")
	)
	(gr_line
		(start 269.593568 -137.733278)
		(end 269.945866 -137.1854)
		(stroke
			(width 0.08255)
			(type default)
		)
		(layer "B.Cu")
	)
	(gr_line
		(start 269.67688 -160.885632)
		(end 269.946628 -160.470088)
		(stroke
			(width 0.08255)
			(type default)
		)
		(layer "B.Cu")
	)
	(gr_line
		(start 269.692882 -65.31737)
		(end 269.80007 -64.833754)
		(stroke
			(width 0.08255)
			(type default)
		)
		(layer "B.Cu")
	)
	(gr_line
		(start 269.71498 -64.70015)
		(end 269.80007 -64.833754)
		(stroke
			(width 0.08255)
			(type default)
		)
		(layer "B.Cu")
	)
	(gr_line
		(start 269.731998 -130.266948)
		(end 269.886938 -130.234182)
		(stroke
			(width 0.08255)
			(type default)
		)
		(layer "B.Cu")
	)
	(gr_line
		(start 269.761716 -133.84276)
		(end 269.916402 -133.809994)
		(stroke
			(width 0.08255)
			(type default)
		)
		(layer "B.Cu")
	)
	(gr_line
		(start 269.773146 -141.600428)
		(end 269.928086 -141.567662)
		(stroke
			(width 0.08255)
			(type default)
		)
		(layer "B.Cu")
	)
	(gr_line
		(start 269.806928 -62.923928)
		(end 269.947644 -62.289436)
		(stroke
			(width 0.08255)
			(type default)
		)
		(layer "B.Cu")
	)
	(gr_line
		(start 269.82293 -137.921238)
		(end 269.97787 -137.88771)
		(stroke
			(width 0.08255)
			(type default)
		)
		(layer "B.Cu")
	)
	(gr_line
		(start 269.823184 -64.211962)
		(end 269.956788 -64.127126)
		(stroke
			(width 0.08255)
			(type default)
		)
		(layer "B.Cu")
	)
	(gr_line
		(start 269.886938 -130.234182)
		(end 270.156686 -129.818638)
		(stroke
			(width 0.08255)
			(type default)
		)
		(layer "B.Cu")
	)
	(gr_line
		(start 269.913608 -160.315148)
		(end 269.946628 -160.470088)
		(stroke
			(width 0.08255)
			(type default)
		)
		(layer "B.Cu")
	)
	(gr_line
		(start 269.916402 -133.809994)
		(end 270.18615 -133.394704)
		(stroke
			(width 0.08255)
			(type default)
		)
		(layer "B.Cu")
	)
	(gr_line
		(start 269.928086 -141.567662)
		(end 270.197834 -141.152118)
		(stroke
			(width 0.08255)
			(type default)
		)
		(layer "B.Cu")
	)
	(gr_line
		(start 269.956788 -64.127126)
		(end 270.063976 -63.64351)
		(stroke
			(width 0.08255)
			(type default)
		)
		(layer "B.Cu")
	)
	(gr_line
		(start 269.97787 -137.88771)
		(end 270.245586 -137.47115)
		(stroke
			(width 0.08255)
			(type default)
		)
		(layer "B.Cu")
	)
	(gr_line
		(start 269.978886 -63.509906)
		(end 270.063976 -63.64351)
		(stroke
			(width 0.08255)
			(type default)
		)
		(layer "B.Cu")
	)
	(gr_line
		(start 270.08709 -63.021718)
		(end 270.220694 -62.936628)
		(stroke
			(width 0.08255)
			(type default)
		)
		(layer "B.Cu")
	)
	(gr_line
		(start 270.123666 -129.663952)
		(end 270.156686 -129.818638)
		(stroke
			(width 0.08255)
			(type default)
		)
		(layer "B.Cu")
	)
	(gr_line
		(start 270.132048 -82.053938)
		(end 270.275812 -82.70621)
		(stroke
			(width 0.08255)
			(type default)
		)
		(layer "B.Cu")
	)
	(gr_line
		(start 270.153384 -133.239764)
		(end 270.18615 -133.394704)
		(stroke
			(width 0.08255)
			(type default)
		)
		(layer "B.Cu")
	)
	(gr_line
		(start 270.164814 -140.997432)
		(end 270.197834 -141.152118)
		(stroke
			(width 0.08255)
			(type default)
		)
		(layer "B.Cu")
	)
	(gr_line
		(start 270.166338 -129.056384)
		(end 270.523462 -128.506474)
		(stroke
			(width 0.08255)
			(type default)
		)
		(layer "B.Cu")
	)
	(gr_line
		(start 270.196564 -132.631688)
		(end 270.551656 -132.08508)
		(stroke
			(width 0.08255)
			(type default)
		)
		(layer "B.Cu")
	)
	(gr_line
		(start 270.20774 -140.38961)
		(end 270.56334 -139.841732)
		(stroke
			(width 0.08255)
			(type default)
		)
		(layer "B.Cu")
	)
	(gr_line
		(start 270.212058 -137.31621)
		(end 270.245586 -137.47115)
		(stroke
			(width 0.08255)
			(type default)
		)
		(layer "B.Cu")
	)
	(gr_line
		(start 270.220694 -62.936628)
		(end 270.327882 -62.453266)
		(stroke
			(width 0.08255)
			(type default)
		)
		(layer "B.Cu")
	)
	(gr_line
		(start 270.242792 -62.319662)
		(end 270.327882 -62.453266)
		(stroke
			(width 0.08255)
			(type default)
		)
		(layer "B.Cu")
	)
	(gr_line
		(start 270.251936 -136.70915)
		(end 270.604996 -136.160002)
		(stroke
			(width 0.08255)
			(type default)
		)
		(layer "B.Cu")
	)
	(gr_line
		(start 270.395954 -129.244344)
		(end 270.550894 -129.211578)
		(stroke
			(width 0.08255)
			(type default)
		)
		(layer "B.Cu")
	)
	(gr_line
		(start 270.39824 -83.26247)
		(end 270.542512 -83.917282)
		(stroke
			(width 0.08255)
			(type default)
		)
		(layer "B.Cu")
	)
	(gr_line
		(start 270.411956 -81.955894)
		(end 270.557498 -82.048858)
		(stroke
			(width 0.08255)
			(type default)
		)
		(layer "B.Cu")
	)
	(gr_line
		(start 270.425418 -132.82041)
		(end 270.580358 -132.78739)
		(stroke
			(width 0.08255)
			(type default)
		)
		(layer "B.Cu")
	)
	(gr_line
		(start 270.437102 -140.577824)
		(end 270.591788 -140.545058)
		(stroke
			(width 0.08255)
			(type default)
		)
		(layer "B.Cu")
	)
	(gr_line
		(start 270.482314 -136.89584)
		(end 270.637254 -136.862058)
		(stroke
			(width 0.08255)
			(type default)
		)
		(layer "B.Cu")
	)
	(gr_line
		(start 270.490442 -165.618668)
		(end 270.845026 -165.072822)
		(stroke
			(width 0.08255)
			(type default)
		)
		(layer "B.Cu")
	)
	(gr_line
		(start 270.519144 -180.814472)
		(end 270.534892 -180.873908)
		(stroke
			(width 0.08255)
			(type default)
		)
		(layer "B.Cu")
	)
	(gr_line
		(start 270.519144 -180.814472)
		(end 270.542766 -180.758084)
		(stroke
			(width 0.08255)
			(type default)
		)
		(layer "B.Cu")
	)
	(gr_line
		(start 270.534638 -180.873654)
		(end 270.534892 -180.87467)
		(stroke
			(width 0.08255)
			(type default)
		)
		(layer "B.Cu")
	)
	(gr_line
		(start 270.550894 -129.211578)
		(end 270.820642 -128.796288)
		(stroke
			(width 0.08255)
			(type default)
		)
		(layer "B.Cu")
	)
	(gr_line
		(start 270.557498 -82.048858)
		(end 270.664178 -82.532474)
		(stroke
			(width 0.08255)
			(type default)
		)
		(layer "B.Cu")
	)
	(gr_line
		(start 270.571214 -82.678016)
		(end 270.664178 -82.532474)
		(stroke
			(width 0.08255)
			(type default)
		)
		(layer "B.Cu")
	)
	(gr_line
		(start 270.580358 -132.78739)
		(end 270.850106 -132.3721)
		(stroke
			(width 0.08255)
			(type default)
		)
		(layer "B.Cu")
	)
	(gr_line
		(start 270.591788 -140.545058)
		(end 270.861536 -140.129514)
		(stroke
			(width 0.08255)
			(type default)
		)
		(layer "B.Cu")
	)
	(gr_line
		(start 270.637254 -136.862058)
		(end 270.90497 -136.445498)
		(stroke
			(width 0.08255)
			(type default)
		)
		(layer "B.Cu")
	)
	(gr_line
		(start 270.665194 -84.473796)
		(end 270.80972 -85.129624)
		(stroke
			(width 0.08255)
			(type default)
		)
		(layer "B.Cu")
	)
	(gr_line
		(start 270.678656 -83.166204)
		(end 270.824452 -83.259168)
		(stroke
			(width 0.08255)
			(type default)
		)
		(layer "B.Cu")
	)
	(gr_line
		(start 270.719296 -165.807644)
		(end 270.873982 -165.774878)
		(stroke
			(width 0.08255)
			(type default)
		)
		(layer "B.Cu")
	)
	(gr_line
		(start 270.762222 -66.634614)
		(end 270.76781 -66.60896)
		(stroke
			(width 0.08255)
			(type default)
		)
		(layer "B.Cu")
	)
	(gr_line
		(start 270.762222 -66.634614)
		(end 270.768064 -66.66103)
		(stroke
			(width 0.08255)
			(type default)
		)
		(layer "B.Cu")
	)
	(gr_line
		(start 270.787876 -128.641094)
		(end 270.820642 -128.796288)
		(stroke
			(width 0.08255)
			(type default)
		)
		(layer "B.Cu")
	)
	(gr_line
		(start 270.81734 -132.21716)
		(end 270.850106 -132.3721)
		(stroke
			(width 0.08255)
			(type default)
		)
		(layer "B.Cu")
	)
	(gr_line
		(start 270.824452 -83.259168)
		(end 270.930878 -83.743038)
		(stroke
			(width 0.08255)
			(type default)
		)
		(layer "B.Cu")
	)
	(gr_line
		(start 270.82877 -139.974574)
		(end 270.861536 -140.129514)
		(stroke
			(width 0.08255)
			(type default)
		)
		(layer "B.Cu")
	)
	(gr_line
		(start 270.829278 -128.035558)
		(end 271.187418 -127.484124)
		(stroke
			(width 0.08255)
			(type default)
		)
		(layer "B.Cu")
	)
	(gr_line
		(start 270.837914 -83.88858)
		(end 270.930878 -83.743038)
		(stroke
			(width 0.08255)
			(type default)
		)
		(layer "B.Cu")
	)
	(gr_line
		(start 270.861536 -131.608068)
		(end 271.21485 -131.064)
		(stroke
			(width 0.08255)
			(type default)
		)
		(layer "B.Cu")
	)
	(gr_line
		(start 270.871442 -136.290812)
		(end 270.90497 -136.445498)
		(stroke
			(width 0.08255)
			(type default)
		)
		(layer "B.Cu")
	)
	(gr_line
		(start 270.87195 -139.366244)
		(end 271.226534 -138.820144)
		(stroke
			(width 0.08255)
			(type default)
		)
		(layer "B.Cu")
	)
	(gr_line
		(start 270.873982 -165.774878)
		(end 271.14373 -165.359588)
		(stroke
			(width 0.08255)
			(type default)
		)
		(layer "B.Cu")
	)
	(gr_line
		(start 270.91259 -135.681974)
		(end 271.26438 -135.134604)
		(stroke
			(width 0.08255)
			(type default)
		)
		(layer "B.Cu")
	)
	(gr_line
		(start 270.93164 -85.682836)
		(end 271.020794 -86.087458)
		(stroke
			(width 0.08255)
			(type default)
		)
		(layer "B.Cu")
	)
	(gr_line
		(start 270.94561 -84.376768)
		(end 271.091152 -84.469732)
		(stroke
			(width 0.08255)
			(type default)
		)
		(layer "B.Cu")
	)
	(gr_line
		(start 271.05991 -128.221994)
		(end 271.21485 -128.188974)
		(stroke
			(width 0.08255)
			(type default)
		)
		(layer "B.Cu")
	)
	(gr_line
		(start 271.089628 -131.797806)
		(end 271.244314 -131.76504)
		(stroke
			(width 0.08255)
			(type default)
		)
		(layer "B.Cu")
	)
	(gr_line
		(start 271.091152 -84.469732)
		(end 271.197832 -84.953348)
		(stroke
			(width 0.08255)
			(type default)
		)
		(layer "B.Cu")
	)
	(gr_line
		(start 271.100804 -139.55522)
		(end 271.255744 -139.5222)
		(stroke
			(width 0.08255)
			(type default)
		)
		(layer "B.Cu")
	)
	(gr_line
		(start 271.104868 -85.09889)
		(end 271.197832 -84.953348)
		(stroke
			(width 0.08255)
			(type default)
		)
		(layer "B.Cu")
	)
	(gr_line
		(start 271.110964 -165.204648)
		(end 271.14373 -165.359588)
		(stroke
			(width 0.08255)
			(type default)
		)
		(layer "B.Cu")
	)
	(gr_line
		(start 271.133316 -168.405302)
		(end 271.500346 -167.840152)
		(stroke
			(width 0.08255)
			(type default)
		)
		(layer "B.Cu")
	)
	(gr_line
		(start 271.141698 -135.870188)
		(end 271.296638 -135.83666)
		(stroke
			(width 0.08255)
			(type default)
		)
		(layer "B.Cu")
	)
	(gr_line
		(start 271.154652 -164.596064)
		(end 271.508728 -164.05098)
		(stroke
			(width 0.08255)
			(type default)
		)
		(layer "B.Cu")
	)
	(gr_line
		(start 271.198848 -86.89467)
		(end 271.20215 -86.909402)
		(stroke
			(width 0.08255)
			(type default)
		)
		(layer "B.Cu")
	)
	(gr_line
		(start 271.20215 -86.909402)
		(end 271.210024 -86.921848)
		(stroke
			(width 0.08255)
			(type default)
		)
		(layer "B.Cu")
	)
	(gr_line
		(start 271.21231 -85.587078)
		(end 271.358106 -85.680042)
		(stroke
			(width 0.08255)
			(type default)
		)
		(layer "B.Cu")
	)
	(gr_line
		(start 271.21485 -128.188974)
		(end 271.484598 -127.773684)
		(stroke
			(width 0.08255)
			(type default)
		)
		(layer "B.Cu")
	)
	(gr_line
		(start 271.244314 -131.76504)
		(end 271.514062 -131.349496)
		(stroke
			(width 0.08255)
			(type default)
		)
		(layer "B.Cu")
	)
	(gr_line
		(start 271.255744 -139.5222)
		(end 271.525238 -139.10691)
		(stroke
			(width 0.08255)
			(type default)
		)
		(layer "B.Cu")
	)
	(gr_line
		(start 271.296638 -135.83666)
		(end 271.564354 -135.4201)
		(stroke
			(width 0.08255)
			(type default)
		)
		(layer "B.Cu")
	)
	(gr_line
		(start 271.358106 -85.680042)
		(end 271.464532 -86.163912)
		(stroke
			(width 0.08255)
			(type default)
		)
		(layer "B.Cu")
	)
	(gr_line
		(start 271.362932 -168.593262)
		(end 271.531842 -168.557448)
		(stroke
			(width 0.08255)
			(type default)
		)
		(layer "B.Cu")
	)
	(gr_line
		(start 271.371568 -86.309454)
		(end 271.464532 -86.163912)
		(stroke
			(width 0.08255)
			(type default)
		)
		(layer "B.Cu")
	)
	(gr_line
		(start 271.378934 -160.90392)
		(end 271.730724 -160.362138)
		(stroke
			(width 0.08255)
			(type default)
		)
		(layer "B.Cu")
	)
	(gr_line
		(start 271.383252 -164.785294)
		(end 271.538192 -164.752528)
		(stroke
			(width 0.08255)
			(type default)
		)
		(layer "B.Cu")
	)
	(gr_line
		(start 271.451832 -127.618744)
		(end 271.484598 -127.773684)
		(stroke
			(width 0.08255)
			(type default)
		)
		(layer "B.Cu")
	)
	(gr_line
		(start 271.481296 -131.19481)
		(end 271.514062 -131.349496)
		(stroke
			(width 0.08255)
			(type default)
		)
		(layer "B.Cu")
	)
	(gr_line
		(start 271.492472 -138.95197)
		(end 271.525238 -139.10691)
		(stroke
			(width 0.08255)
			(type default)
		)
		(layer "B.Cu")
	)
	(gr_line
		(start 271.49425 -127.011684)
		(end 271.850866 -126.462536)
		(stroke
			(width 0.08255)
			(type default)
		)
		(layer "B.Cu")
	)
	(gr_line
		(start 271.530826 -135.26516)
		(end 271.564354 -135.4201)
		(stroke
			(width 0.08255)
			(type default)
		)
		(layer "B.Cu")
	)
	(gr_line
		(start 271.531842 -168.557448)
		(end 271.80159 -168.141904)
		(stroke
			(width 0.08255)
			(type default)
		)
		(layer "B.Cu")
	)
	(gr_line
		(start 271.538192 -164.752528)
		(end 271.80794 -164.336984)
		(stroke
			(width 0.08255)
			(type default)
		)
		(layer "B.Cu")
	)
	(gr_line
		(start 271.604994 -161.096198)
		(end 271.759934 -161.063432)
		(stroke
			(width 0.08255)
			(type default)
		)
		(layer "B.Cu")
	)
	(gr_line
		(start 271.72412 -127.19939)
		(end 271.878806 -127.166624)
		(stroke
			(width 0.08255)
			(type default)
		)
		(layer "B.Cu")
	)
	(gr_line
		(start 271.759934 -161.063432)
		(end 272.029682 -160.647888)
		(stroke
			(width 0.08255)
			(type default)
		)
		(layer "B.Cu")
	)
	(gr_line
		(start 271.765776 -167.972994)
		(end 271.80159 -168.141904)
		(stroke
			(width 0.08255)
			(type default)
		)
		(layer "B.Cu")
	)
	(gr_line
		(start 271.77492 -164.182298)
		(end 271.80794 -164.336984)
		(stroke
			(width 0.08255)
			(type default)
		)
		(layer "B.Cu")
	)
	(gr_line
		(start 271.808194 -167.365934)
		(end 272.175986 -166.799514)
		(stroke
			(width 0.08255)
			(type default)
		)
		(layer "B.Cu")
	)
	(gr_line
		(start 271.820132 -163.571682)
		(end 272.173446 -163.027614)
		(stroke
			(width 0.08255)
			(type default)
		)
		(layer "B.Cu")
	)
	(gr_line
		(start 271.842738 -45.430948)
		(end 271.845532 -45.418502)
		(stroke
			(width 0.08255)
			(type default)
		)
		(layer "B.Cu")
	)
	(gr_line
		(start 271.845532 -45.418502)
		(end 271.852644 -45.407326)
		(stroke
			(width 0.08255)
			(type default)
		)
		(layer "B.Cu")
	)
	(gr_line
		(start 271.878806 -127.166624)
		(end 272.148554 -126.75108)
		(stroke
			(width 0.08255)
			(type default)
		)
		(layer "B.Cu")
	)
	(gr_line
		(start 271.9705 -359.504996)
		(end 272.214848 -359.504996)
		(stroke
			(width 0.0635)
			(type default)
		)
		(layer "B.Cu")
	)
	(gr_line
		(start 271.9705 -357.704898)
		(end 272.214848 -357.704898)
		(stroke
			(width 0.0635)
			(type default)
		)
		(layer "B.Cu")
	)
	(gr_line
		(start 271.9705 -355.905054)
		(end 272.214848 -355.905054)
		(stroke
			(width 0.0635)
			(type default)
		)
		(layer "B.Cu")
	)
	(gr_line
		(start 271.9705 -354.104956)
		(end 272.214848 -354.104956)
		(stroke
			(width 0.0635)
			(type default)
		)
		(layer "B.Cu")
	)
	(gr_line
		(start 271.9705 -352.305112)
		(end 272.214848 -352.305112)
		(stroke
			(width 0.0635)
			(type default)
		)
		(layer "B.Cu")
	)
	(gr_line
		(start 271.9705 -350.505014)
		(end 272.214848 -350.505014)
		(stroke
			(width 0.0635)
			(type default)
		)
		(layer "B.Cu")
	)
	(gr_line
		(start 271.9705 -337.90509)
		(end 272.214848 -337.90509)
		(stroke
			(width 0.0635)
			(type default)
		)
		(layer "B.Cu")
	)
	(gr_line
		(start 271.9705 -336.104992)
		(end 272.214848 -336.104992)
		(stroke
			(width 0.0635)
			(type default)
		)
		(layer "B.Cu")
	)
	(gr_line
		(start 271.9705 -334.304894)
		(end 272.214848 -334.304894)
		(stroke
			(width 0.0635)
			(type default)
		)
		(layer "B.Cu")
	)
	(gr_line
		(start 271.9705 -332.50505)
		(end 272.214848 -332.50505)
		(stroke
			(width 0.0635)
			(type default)
		)
		(layer "B.Cu")
	)
	(gr_line
		(start 271.9705 -330.704952)
		(end 272.214848 -330.704952)
		(stroke
			(width 0.0635)
			(type default)
		)
		(layer "B.Cu")
	)
	(gr_line
		(start 271.9705 -328.905108)
		(end 272.214848 -328.905108)
		(stroke
			(width 0.0635)
			(type default)
		)
		(layer "B.Cu")
	)
	(gr_line
		(start 271.9705 -316.30493)
		(end 272.214848 -316.30493)
		(stroke
			(width 0.0635)
			(type default)
		)
		(layer "B.Cu")
	)
	(gr_line
		(start 271.9705 -314.505086)
		(end 272.214848 -314.505086)
		(stroke
			(width 0.0635)
			(type default)
		)
		(layer "B.Cu")
	)
	(gr_line
		(start 271.9705 -312.704988)
		(end 272.214848 -312.704988)
		(stroke
			(width 0.0635)
			(type default)
		)
		(layer "B.Cu")
	)
	(gr_line
		(start 271.9705 -310.90489)
		(end 272.214848 -310.90489)
		(stroke
			(width 0.0635)
			(type default)
		)
		(layer "B.Cu")
	)
	(gr_line
		(start 271.9705 -309.105046)
		(end 272.214848 -309.105046)
		(stroke
			(width 0.0635)
			(type default)
		)
		(layer "B.Cu")
	)
	(gr_line
		(start 271.9705 -307.304948)
		(end 272.214848 -307.304948)
		(stroke
			(width 0.0635)
			(type default)
		)
		(layer "B.Cu")
	)
	(gr_line
		(start 271.996916 -160.492948)
		(end 272.029682 -160.647888)
		(stroke
			(width 0.08255)
			(type default)
		)
		(layer "B.Cu")
	)
	(gr_line
		(start 272.038064 -167.55364)
		(end 272.206974 -167.517826)
		(stroke
			(width 0.08255)
			(type default)
		)
		(layer "B.Cu")
	)
	(gr_line
		(start 272.041366 -159.883602)
		(end 272.39468 -159.33928)
		(stroke
			(width 0.08255)
			(type default)
		)
		(layer "B.Cu")
	)
	(gr_line
		(start 272.047208 -163.76269)
		(end 272.202148 -163.729924)
		(stroke
			(width 0.08255)
			(type default)
		)
		(layer "B.Cu")
	)
	(gr_line
		(start 272.115788 -126.596394)
		(end 272.148554 -126.75108)
		(stroke
			(width 0.08255)
			(type default)
		)
		(layer "B.Cu")
	)
	(gr_line
		(start 272.135092 -186.939682)
		(end 272.149824 -186.995562)
		(stroke
			(width 0.08255)
			(type default)
		)
		(layer "B.Cu")
	)
	(gr_line
		(start 272.149824 -186.995562)
		(end 272.195036 -187.031884)
		(stroke
			(width 0.08255)
			(type default)
		)
		(layer "B.Cu")
	)
	(gr_line
		(start 272.202148 -163.729924)
		(end 272.471896 -163.314634)
		(stroke
			(width 0.08255)
			(type default)
		)
		(layer "B.Cu")
	)
	(gr_line
		(start 272.206974 -167.517826)
		(end 272.476722 -167.102282)
		(stroke
			(width 0.08255)
			(type default)
		)
		(layer "B.Cu")
	)
	(gr_arc
		(start 272.214848 -359.504996)
		(mid 272.342906 -359.451952)
		(end 272.39595 -359.323894)
		(stroke
			(width 0.0635)
			(type default)
		)
		(layer "B.Cu")
	)
	(gr_arc
		(start 272.214848 -357.704898)
		(mid 272.342906 -357.651854)
		(end 272.39595 -357.523796)
		(stroke
			(width 0.0635)
			(type default)
		)
		(layer "B.Cu")
	)
	(gr_arc
		(start 272.214848 -355.905054)
		(mid 272.342906 -355.85201)
		(end 272.39595 -355.723952)
		(stroke
			(width 0.0635)
			(type default)
		)
		(layer "B.Cu")
	)
	(gr_arc
		(start 272.214848 -354.104956)
		(mid 272.342906 -354.051912)
		(end 272.39595 -353.923854)
		(stroke
			(width 0.0635)
			(type default)
		)
		(layer "B.Cu")
	)
	(gr_arc
		(start 272.214848 -352.305112)
		(mid 272.342906 -352.252068)
		(end 272.39595 -352.12401)
		(stroke
			(width 0.0635)
			(type default)
		)
		(layer "B.Cu")
	)
	(gr_arc
		(start 272.214848 -350.505014)
		(mid 272.342906 -350.45197)
		(end 272.39595 -350.323912)
		(stroke
			(width 0.0635)
			(type default)
		)
		(layer "B.Cu")
	)
	(gr_arc
		(start 272.214848 -337.90509)
		(mid 272.342906 -337.852046)
		(end 272.39595 -337.723988)
		(stroke
			(width 0.0635)
			(type default)
		)
		(layer "B.Cu")
	)
	(gr_arc
		(start 272.214848 -336.104992)
		(mid 272.342906 -336.051948)
		(end 272.39595 -335.92389)
		(stroke
			(width 0.0635)
			(type default)
		)
		(layer "B.Cu")
	)
	(gr_arc
		(start 272.214848 -334.304894)
		(mid 272.342906 -334.25185)
		(end 272.39595 -334.123792)
		(stroke
			(width 0.0635)
			(type default)
		)
		(layer "B.Cu")
	)
	(gr_arc
		(start 272.214848 -332.50505)
		(mid 272.342906 -332.452006)
		(end 272.39595 -332.323948)
		(stroke
			(width 0.0635)
			(type default)
		)
		(layer "B.Cu")
	)
	(gr_arc
		(start 272.214848 -330.704952)
		(mid 272.342906 -330.651908)
		(end 272.39595 -330.52385)
		(stroke
			(width 0.0635)
			(type default)
		)
		(layer "B.Cu")
	)
	(gr_arc
		(start 272.214848 -328.905108)
		(mid 272.342906 -328.852064)
		(end 272.39595 -328.724006)
		(stroke
			(width 0.0635)
			(type default)
		)
		(layer "B.Cu")
	)
	(gr_arc
		(start 272.214848 -316.30493)
		(mid 272.342906 -316.251886)
		(end 272.39595 -316.123828)
		(stroke
			(width 0.0635)
			(type default)
		)
		(layer "B.Cu")
	)
	(gr_arc
		(start 272.214848 -314.505086)
		(mid 272.342906 -314.452042)
		(end 272.39595 -314.323984)
		(stroke
			(width 0.0635)
			(type default)
		)
		(layer "B.Cu")
	)
	(gr_arc
		(start 272.214848 -312.704988)
		(mid 272.342906 -312.651944)
		(end 272.39595 -312.523886)
		(stroke
			(width 0.0635)
			(type default)
		)
		(layer "B.Cu")
	)
	(gr_arc
		(start 272.214848 -310.90489)
		(mid 272.342906 -310.851846)
		(end 272.39595 -310.723788)
		(stroke
			(width 0.0635)
			(type default)
		)
		(layer "B.Cu")
	)
	(gr_arc
		(start 272.214848 -309.105046)
		(mid 272.342906 -309.052002)
		(end 272.39595 -308.923944)
		(stroke
			(width 0.0635)
			(type default)
		)
		(layer "B.Cu")
	)
	(gr_arc
		(start 272.214848 -307.304948)
		(mid 272.342906 -307.251904)
		(end 272.39595 -307.123846)
		(stroke
			(width 0.0635)
			(type default)
		)
		(layer "B.Cu")
	)
	(gr_line
		(start 272.26895 -160.073594)
		(end 272.42389 -160.040828)
		(stroke
			(width 0.08255)
			(type default)
		)
		(layer "B.Cu")
	)
	(gr_line
		(start 272.320004 -181.23281)
		(end 272.335752 -181.292246)
		(stroke
			(width 0.08255)
			(type default)
		)
		(layer "B.Cu")
	)
	(gr_line
		(start 272.320004 -181.23281)
		(end 272.343626 -181.176422)
		(stroke
			(width 0.08255)
			(type default)
		)
		(layer "B.Cu")
	)
	(gr_line
		(start 272.335498 -181.291992)
		(end 272.335752 -181.293008)
		(stroke
			(width 0.08255)
			(type default)
		)
		(layer "B.Cu")
	)
	(gr_line
		(start 272.367248 -82.361786)
		(end 272.512028 -83.014058)
		(stroke
			(width 0.08255)
			(type default)
		)
		(layer "B.Cu")
	)
	(gr_line
		(start 272.42389 -160.040828)
		(end 272.693638 -159.625284)
		(stroke
			(width 0.08255)
			(type default)
		)
		(layer "B.Cu")
	)
	(gr_line
		(start 272.43913 -163.15944)
		(end 272.471896 -163.314634)
		(stroke
			(width 0.08255)
			(type default)
		)
		(layer "B.Cu")
	)
	(gr_line
		(start 272.440908 -166.933372)
		(end 272.476722 -167.102282)
		(stroke
			(width 0.08255)
			(type default)
		)
		(layer "B.Cu")
	)
	(gr_line
		(start 272.481548 -162.552634)
		(end 272.837402 -162.004756)
		(stroke
			(width 0.08255)
			(type default)
		)
		(layer "B.Cu")
	)
	(gr_line
		(start 272.48358 -166.326058)
		(end 272.850102 -165.76167)
		(stroke
			(width 0.08255)
			(type default)
		)
		(layer "B.Cu")
	)
	(gr_line
		(start 272.500598 -58.791602)
		(end 272.640552 -58.160666)
		(stroke
			(width 0.08255)
			(type default)
		)
		(layer "B.Cu")
	)
	(gr_line
		(start 272.635726 -83.571588)
		(end 272.779998 -84.222336)
		(stroke
			(width 0.08255)
			(type default)
		)
		(layer "B.Cu")
	)
	(gr_line
		(start 272.647156 -82.262726)
		(end 272.792698 -82.355436)
		(stroke
			(width 0.08255)
			(type default)
		)
		(layer "B.Cu")
	)
	(gr_line
		(start 272.660872 -159.470344)
		(end 272.693638 -159.625284)
		(stroke
			(width 0.08255)
			(type default)
		)
		(layer "B.Cu")
	)
	(gr_arc
		(start 272.68805 -359.323894)
		(mid 272.741089 -359.451973)
		(end 272.869152 -359.504996)
		(stroke
			(width 0.0635)
			(type default)
		)
		(layer "B.Cu")
	)
	(gr_arc
		(start 272.68805 -357.523796)
		(mid 272.741094 -357.651854)
		(end 272.869152 -357.704898)
		(stroke
			(width 0.0635)
			(type default)
		)
		(layer "B.Cu")
	)
	(gr_arc
		(start 272.68805 -355.723952)
		(mid 272.741074 -355.852058)
		(end 272.869152 -355.905054)
		(stroke
			(width 0.0635)
			(type default)
		)
		(layer "B.Cu")
	)
	(gr_arc
		(start 272.68805 -353.923854)
		(mid 272.741094 -354.051912)
		(end 272.869152 -354.104956)
		(stroke
			(width 0.0635)
			(type default)
		)
		(layer "B.Cu")
	)
	(gr_arc
		(start 272.68805 -352.12401)
		(mid 272.741094 -352.252079)
		(end 272.869152 -352.305112)
		(stroke
			(width 0.0635)
			(type default)
		)
		(layer "B.Cu")
	)
	(gr_arc
		(start 272.68805 -350.323912)
		(mid 272.741094 -350.45197)
		(end 272.869152 -350.505014)
		(stroke
			(width 0.0635)
			(type default)
		)
		(layer "B.Cu")
	)
	(gr_arc
		(start 272.68805 -337.723988)
		(mid 272.741086 -337.852071)
		(end 272.869152 -337.90509)
		(stroke
			(width 0.0635)
			(type default)
		)
		(layer "B.Cu")
	)
	(gr_arc
		(start 272.68805 -335.92389)
		(mid 272.741094 -336.051948)
		(end 272.869152 -336.104992)
		(stroke
			(width 0.0635)
			(type default)
		)
		(layer "B.Cu")
	)
	(gr_arc
		(start 272.68805 -334.123792)
		(mid 272.741088 -334.251873)
		(end 272.869152 -334.304894)
		(stroke
			(width 0.0635)
			(type default)
		)
		(layer "B.Cu")
	)
	(gr_arc
		(start 272.68805 -332.323948)
		(mid 272.741094 -332.452006)
		(end 272.869152 -332.50505)
		(stroke
			(width 0.0635)
			(type default)
		)
		(layer "B.Cu")
	)
	(gr_arc
		(start 272.68805 -330.52385)
		(mid 272.741108 -330.651893)
		(end 272.869152 -330.704952)
		(stroke
			(width 0.0635)
			(type default)
		)
		(layer "B.Cu")
	)
	(gr_arc
		(start 272.68805 -328.724006)
		(mid 272.741094 -328.852064)
		(end 272.869152 -328.905108)
		(stroke
			(width 0.0635)
			(type default)
		)
		(layer "B.Cu")
	)
	(gr_arc
		(start 272.68805 -316.123828)
		(mid 272.741101 -316.251885)
		(end 272.869152 -316.30493)
		(stroke
			(width 0.0635)
			(type default)
		)
		(layer "B.Cu")
	)
	(gr_arc
		(start 272.68805 -314.323984)
		(mid 272.741094 -314.452042)
		(end 272.869152 -314.505086)
		(stroke
			(width 0.0635)
			(type default)
		)
		(layer "B.Cu")
	)
	(gr_arc
		(start 272.68805 -312.523886)
		(mid 272.741086 -312.65197)
		(end 272.869152 -312.704988)
		(stroke
			(width 0.0635)
			(type default)
		)
		(layer "B.Cu")
	)
	(gr_arc
		(start 272.68805 -310.723788)
		(mid 272.741094 -310.851846)
		(end 272.869152 -310.90489)
		(stroke
			(width 0.0635)
			(type default)
		)
		(layer "B.Cu")
	)
	(gr_arc
		(start 272.68805 -308.923944)
		(mid 272.741106 -309.051991)
		(end 272.869152 -309.105046)
		(stroke
			(width 0.0635)
			(type default)
		)
		(layer "B.Cu")
	)
	(gr_arc
		(start 272.68805 -307.123846)
		(mid 272.741094 -307.251904)
		(end 272.869152 -307.304948)
		(stroke
			(width 0.0635)
			(type default)
		)
		(layer "B.Cu")
	)
	(gr_line
		(start 272.706084 -158.859982)
		(end 273.058382 -158.317438)
		(stroke
			(width 0.08255)
			(type default)
		)
		(layer "B.Cu")
	)
	(gr_line
		(start 272.711164 -162.74034)
		(end 272.866104 -162.70732)
		(stroke
			(width 0.08255)
			(type default)
		)
		(layer "B.Cu")
	)
	(gr_line
		(start 272.712942 -166.514018)
		(end 272.881852 -166.478204)
		(stroke
			(width 0.08255)
			(type default)
		)
		(layer "B.Cu")
	)
	(gr_line
		(start 272.763996 -57.602628)
		(end 272.904204 -56.970676)
		(stroke
			(width 0.08255)
			(type default)
		)
		(layer "B.Cu")
	)
	(gr_line
		(start 272.780506 -58.890916)
		(end 272.913856 -58.805826)
		(stroke
			(width 0.08255)
			(type default)
		)
		(layer "B.Cu")
	)
	(gr_line
		(start 272.787618 -84.257134)
		(end 272.789142 -84.264246)
		(stroke
			(width 0.08255)
			(type default)
		)
		(layer "B.Cu")
	)
	(gr_line
		(start 272.792698 -82.355436)
		(end 272.899886 -82.838798)
		(stroke
			(width 0.08255)
			(type default)
		)
		(layer "B.Cu")
	)
	(gr_line
		(start 272.807176 -82.984594)
		(end 272.899886 -82.838798)
		(stroke
			(width 0.08255)
			(type default)
		)
		(layer "B.Cu")
	)
	(gr_line
		(start 272.808954 -65.623186)
		(end 272.81378 -65.647316)
		(stroke
			(width 0.08255)
			(type default)
		)
		(layer "B.Cu")
	)
	(gr_line
		(start 272.808954 -65.623186)
		(end 272.814288 -65.599056)
		(stroke
			(width 0.08255)
			(type default)
		)
		(layer "B.Cu")
	)
	(gr_line
		(start 272.866104 -162.70732)
		(end 273.135852 -162.29203)
		(stroke
			(width 0.08255)
			(type default)
		)
		(layer "B.Cu")
	)
	(gr_line
		(start 272.869152 -359.504996)
		(end 273.1135 -359.504996)
		(stroke
			(width 0.0635)
			(type default)
		)
		(layer "B.Cu")
	)
	(gr_line
		(start 272.869152 -357.704898)
		(end 273.1135 -357.704898)
		(stroke
			(width 0.0635)
			(type default)
		)
		(layer "B.Cu")
	)
	(gr_line
		(start 272.869152 -355.905054)
		(end 273.1135 -355.905054)
		(stroke
			(width 0.0635)
			(type default)
		)
		(layer "B.Cu")
	)
	(gr_line
		(start 272.869152 -354.104956)
		(end 273.1135 -354.104956)
		(stroke
			(width 0.0635)
			(type default)
		)
		(layer "B.Cu")
	)
	(gr_line
		(start 272.869152 -352.305112)
		(end 273.1135 -352.305112)
		(stroke
			(width 0.0635)
			(type default)
		)
		(layer "B.Cu")
	)
	(gr_line
		(start 272.869152 -350.505014)
		(end 273.1135 -350.505014)
		(stroke
			(width 0.0635)
			(type default)
		)
		(layer "B.Cu")
	)
	(gr_line
		(start 272.869152 -337.90509)
		(end 273.1135 -337.90509)
		(stroke
			(width 0.0635)
			(type default)
		)
		(layer "B.Cu")
	)
	(gr_line
		(start 272.869152 -336.104992)
		(end 273.1135 -336.104992)
		(stroke
			(width 0.0635)
			(type default)
		)
		(layer "B.Cu")
	)
	(gr_line
		(start 272.869152 -334.304894)
		(end 273.1135 -334.304894)
		(stroke
			(width 0.0635)
			(type default)
		)
		(layer "B.Cu")
	)
	(gr_line
		(start 272.869152 -332.50505)
		(end 273.1135 -332.50505)
		(stroke
			(width 0.0635)
			(type default)
		)
		(layer "B.Cu")
	)
	(gr_line
		(start 272.869152 -330.704952)
		(end 273.1135 -330.704952)
		(stroke
			(width 0.0635)
			(type default)
		)
		(layer "B.Cu")
	)
	(gr_line
		(start 272.869152 -328.905108)
		(end 273.1135 -328.905108)
		(stroke
			(width 0.0635)
			(type default)
		)
		(layer "B.Cu")
	)
	(gr_line
		(start 272.869152 -316.30493)
		(end 273.1135 -316.30493)
		(stroke
			(width 0.0635)
			(type default)
		)
		(layer "B.Cu")
	)
	(gr_line
		(start 272.869152 -314.505086)
		(end 273.1135 -314.505086)
		(stroke
			(width 0.0635)
			(type default)
		)
		(layer "B.Cu")
	)
	(gr_line
		(start 272.869152 -312.704988)
		(end 273.1135 -312.704988)
		(stroke
			(width 0.0635)
			(type default)
		)
		(layer "B.Cu")
	)
	(gr_line
		(start 272.869152 -310.90489)
		(end 273.1135 -310.90489)
		(stroke
			(width 0.0635)
			(type default)
		)
		(layer "B.Cu")
	)
	(gr_line
		(start 272.869152 -309.105046)
		(end 273.1135 -309.105046)
		(stroke
			(width 0.0635)
			(type default)
		)
		(layer "B.Cu")
	)
	(gr_line
		(start 272.869152 -307.304948)
		(end 273.1135 -307.304948)
		(stroke
			(width 0.0635)
			(type default)
		)
		(layer "B.Cu")
	)
	(gr_line
		(start 272.881852 -166.478204)
		(end 273.1516 -166.062914)
		(stroke
			(width 0.08255)
			(type default)
		)
		(layer "B.Cu")
	)
	(gr_line
		(start 272.894298 -65.239646)
		(end 273.036284 -64.598804)
		(stroke
			(width 0.08255)
			(type default)
		)
		(layer "B.Cu")
	)
	(gr_line
		(start 272.90395 -84.781136)
		(end 273.048476 -85.433408)
		(stroke
			(width 0.08255)
			(type default)
		)
		(layer "B.Cu")
	)
	(gr_line
		(start 272.913856 -58.805826)
		(end 273.021044 -58.32221)
		(stroke
			(width 0.08255)
			(type default)
		)
		(layer "B.Cu")
	)
	(gr_line
		(start 272.915634 -83.472782)
		(end 273.061176 -83.565492)
		(stroke
			(width 0.08255)
			(type default)
		)
		(layer "B.Cu")
	)
	(gr_line
		(start 272.93316 -159.05099)
		(end 273.087846 -159.018224)
		(stroke
			(width 0.08255)
			(type default)
		)
		(layer "B.Cu")
	)
	(gr_line
		(start 272.935954 -58.18886)
		(end 273.021044 -58.32221)
		(stroke
			(width 0.08255)
			(type default)
		)
		(layer "B.Cu")
	)
	(gr_line
		(start 273.017234 -154.994102)
		(end 273.383502 -154.430222)
		(stroke
			(width 0.08255)
			(type default)
		)
		(layer "B.Cu")
	)
	(gr_line
		(start 273.018758 -56.453532)
		(end 273.022314 -56.4388)
		(stroke
			(width 0.08255)
			(type default)
		)
		(layer "B.Cu")
	)
	(gr_line
		(start 273.028156 -56.41086)
		(end 273.16811 -55.779924)
		(stroke
			(width 0.08255)
			(type default)
		)
		(layer "B.Cu")
	)
	(gr_line
		(start 273.044158 -57.700672)
		(end 273.177508 -57.615582)
		(stroke
			(width 0.08255)
			(type default)
		)
		(layer "B.Cu")
	)
	(gr_line
		(start 273.061176 -83.565492)
		(end 273.168364 -84.049108)
		(stroke
			(width 0.08255)
			(type default)
		)
		(layer "B.Cu")
	)
	(gr_line
		(start 273.073622 -84.197444)
		(end 273.087846 -84.26196)
		(stroke
			(width 0.08255)
			(type default)
		)
		(layer "B.Cu")
	)
	(gr_line
		(start 273.075654 -84.194396)
		(end 273.168364 -84.049108)
		(stroke
			(width 0.08255)
			(type default)
		)
		(layer "B.Cu")
	)
	(gr_line
		(start 273.087846 -159.018224)
		(end 273.357594 -158.602934)
		(stroke
			(width 0.08255)
			(type default)
		)
		(layer "B.Cu")
	)
	(gr_line
		(start 273.103086 -162.13709)
		(end 273.135852 -162.29203)
		(stroke
			(width 0.08255)
			(type default)
		)
		(layer "B.Cu")
	)
	(gr_line
		(start 273.115786 -165.894004)
		(end 273.1516 -166.062914)
		(stroke
			(width 0.08255)
			(type default)
		)
		(layer "B.Cu")
	)
	(gr_line
		(start 273.147028 -161.528252)
		(end 273.152362 -161.520124)
		(stroke
			(width 0.08255)
			(type default)
		)
		(layer "B.Cu")
	)
	(gr_line
		(start 273.152362 -161.520124)
		(end 273.159728 -161.514282)
		(stroke
			(width 0.08255)
			(type default)
		)
		(layer "B.Cu")
	)
	(gr_line
		(start 273.158458 -64.04864)
		(end 273.30019 -63.408814)
		(stroke
			(width 0.08255)
			(type default)
		)
		(layer "B.Cu")
	)
	(gr_line
		(start 273.172682 -85.992716)
		(end 273.316954 -86.64321)
		(stroke
			(width 0.08255)
			(type default)
		)
		(layer "B.Cu")
	)
	(gr_line
		(start 273.175476 -65.334388)
		(end 273.30908 -65.249044)
		(stroke
			(width 0.08255)
			(type default)
		)
		(layer "B.Cu")
	)
	(gr_line
		(start 273.177508 -57.615582)
		(end 273.284696 -57.131966)
		(stroke
			(width 0.08255)
			(type default)
		)
		(layer "B.Cu")
	)
	(gr_line
		(start 273.183858 -84.682838)
		(end 273.3294 -84.775548)
		(stroke
			(width 0.08255)
			(type default)
		)
		(layer "B.Cu")
	)
	(gr_line
		(start 273.197828 -56.995568)
		(end 273.305016 -56.511952)
		(stroke
			(width 0.08255)
			(type default)
		)
		(layer "B.Cu")
	)
	(gr_line
		(start 273.19986 -56.998616)
		(end 273.284696 -57.131966)
		(stroke
			(width 0.08255)
			(type default)
		)
		(layer "B.Cu")
	)
	(gr_line
		(start 273.245834 -47.416212)
		(end 273.248628 -47.403766)
		(stroke
			(width 0.08255)
			(type default)
		)
		(layer "B.Cu")
	)
	(gr_line
		(start 273.246342 -155.182824)
		(end 273.415252 -155.14701)
		(stroke
			(width 0.08255)
			(type default)
		)
		(layer "B.Cu")
	)
	(gr_line
		(start 273.248628 -47.403766)
		(end 273.25574 -47.39259)
		(stroke
			(width 0.08255)
			(type default)
		)
		(layer "B.Cu")
	)
	(gr_line
		(start 273.292062 -55.221124)
		(end 273.43227 -54.587648)
		(stroke
			(width 0.08255)
			(type default)
		)
		(layer "B.Cu")
	)
	(gr_line
		(start 273.295618 -68.09613)
		(end 273.425158 -68.75399)
		(stroke
			(width 0.08255)
			(type default)
		)
		(layer "B.Cu")
	)
	(gr_line
		(start 273.299936 -131.968494)
		(end 273.66341 -131.403344)
		(stroke
			(width 0.08255)
			(type default)
		)
		(layer "B.Cu")
	)
	(gr_line
		(start 273.308064 -56.50992)
		(end 273.441414 -56.425338)
		(stroke
			(width 0.08255)
			(type default)
		)
		(layer "B.Cu")
	)
	(gr_line
		(start 273.30908 -65.249044)
		(end 273.416268 -64.765428)
		(stroke
			(width 0.08255)
			(type default)
		)
		(layer "B.Cu")
	)
	(gr_line
		(start 273.324828 -158.447994)
		(end 273.357594 -158.602934)
		(stroke
			(width 0.08255)
			(type default)
		)
		(layer "B.Cu")
	)
	(gr_line
		(start 273.3294 -84.775548)
		(end 273.436588 -85.259164)
		(stroke
			(width 0.08255)
			(type default)
		)
		(layer "B.Cu")
	)
	(gr_line
		(start 273.33067 -64.63157)
		(end 273.416268 -64.765428)
		(stroke
			(width 0.08255)
			(type default)
		)
		(layer "B.Cu")
	)
	(gr_line
		(start 273.343878 -85.404452)
		(end 273.436588 -85.259164)
		(stroke
			(width 0.08255)
			(type default)
		)
		(layer "B.Cu")
	)
	(gr_line
		(start 273.368262 -157.839664)
		(end 273.722846 -157.293818)
		(stroke
			(width 0.08255)
			(type default)
		)
		(layer "B.Cu")
	)
	(gr_line
		(start 273.415252 -155.14701)
		(end 273.685 -154.73172)
		(stroke
			(width 0.08255)
			(type default)
		)
		(layer "B.Cu")
	)
	(gr_line
		(start 273.421602 -62.860174)
		(end 273.564096 -62.217808)
		(stroke
			(width 0.08255)
			(type default)
		)
		(layer "B.Cu")
	)
	(gr_line
		(start 273.432016 -85.812884)
		(end 273.449288 -85.891116)
		(stroke
			(width 0.08255)
			(type default)
		)
		(layer "B.Cu")
	)
	(gr_line
		(start 273.438874 -64.144144)
		(end 273.572986 -64.0588)
		(stroke
			(width 0.08255)
			(type default)
		)
		(layer "B.Cu")
	)
	(gr_line
		(start 273.441414 -56.425338)
		(end 273.548602 -55.941722)
		(stroke
			(width 0.08255)
			(type default)
		)
		(layer "B.Cu")
	)
	(gr_line
		(start 273.452336 -85.893148)
		(end 273.597878 -85.985604)
		(stroke
			(width 0.08255)
			(type default)
		)
		(layer "B.Cu")
	)
	(gr_line
		(start 273.463512 -55.808372)
		(end 273.548602 -55.941722)
		(stroke
			(width 0.08255)
			(type default)
		)
		(layer "B.Cu")
	)
	(gr_line
		(start 273.47164 -87.340948)
		(end 273.474434 -87.353394)
		(stroke
			(width 0.08255)
			(type default)
		)
		(layer "B.Cu")
	)
	(gr_line
		(start 273.474434 -87.353394)
		(end 273.481546 -87.36457)
		(stroke
			(width 0.08255)
			(type default)
		)
		(layer "B.Cu")
	)
	(gr_line
		(start 273.529806 -132.155946)
		(end 273.698716 -132.11937)
		(stroke
			(width 0.08255)
			(type default)
		)
		(layer "B.Cu")
	)
	(gr_line
		(start 273.534632 -69.310758)
		(end 273.664426 -69.96938)
		(stroke
			(width 0.08255)
			(type default)
		)
		(layer "B.Cu")
	)
	(gr_line
		(start 273.57197 -55.31993)
		(end 273.70532 -55.23484)
		(stroke
			(width 0.08255)
			(type default)
		)
		(layer "B.Cu")
	)
	(gr_line
		(start 273.572986 -64.0588)
		(end 273.680174 -63.575184)
		(stroke
			(width 0.08255)
			(type default)
		)
		(layer "B.Cu")
	)
	(gr_line
		(start 273.578066 -68.004944)
		(end 273.721576 -68.101464)
		(stroke
			(width 0.08255)
			(type default)
		)
		(layer "B.Cu")
	)
	(gr_line
		(start 273.59483 -63.441326)
		(end 273.680174 -63.575184)
		(stroke
			(width 0.08255)
			(type default)
		)
		(layer "B.Cu")
	)
	(gr_line
		(start 273.596862 -158.02864)
		(end 273.751802 -157.99562)
		(stroke
			(width 0.08255)
			(type default)
		)
		(layer "B.Cu")
	)
	(gr_line
		(start 273.597878 -186.077098)
		(end 273.61261 -186.132978)
		(stroke
			(width 0.08255)
			(type default)
		)
		(layer "B.Cu")
	)
	(gr_line
		(start 273.597878 -85.985604)
		(end 273.705066 -86.46922)
		(stroke
			(width 0.08255)
			(type default)
		)
		(layer "B.Cu")
	)
	(gr_line
		(start 273.60372 -161.157158)
		(end 274.126198 -160.737042)
		(stroke
			(width 0.08255)
			(type default)
		)
		(layer "B.Cu")
	)
	(gr_line
		(start 273.612356 -86.615016)
		(end 273.705066 -86.46922)
		(stroke
			(width 0.08255)
			(type default)
		)
		(layer "B.Cu")
	)
	(gr_line
		(start 273.61261 -186.132978)
		(end 273.657822 -186.1693)
		(stroke
			(width 0.08255)
			(type default)
		)
		(layer "B.Cu")
	)
	(gr_line
		(start 273.622516 -164.572442)
		(end 273.62785 -164.564314)
		(stroke
			(width 0.08255)
			(type default)
		)
		(layer "B.Cu")
	)
	(gr_line
		(start 273.62785 -164.564314)
		(end 273.635216 -164.558472)
		(stroke
			(width 0.08255)
			(type default)
		)
		(layer "B.Cu")
	)
	(gr_line
		(start 273.649186 -154.562556)
		(end 273.685 -154.73172)
		(stroke
			(width 0.08255)
			(type default)
		)
		(layer "B.Cu")
	)
	(gr_line
		(start 273.685508 -61.66993)
		(end 273.828002 -61.027564)
		(stroke
			(width 0.08255)
			(type default)
		)
		(layer "B.Cu")
	)
	(gr_line
		(start 273.691858 -153.955496)
		(end 274.05838 -153.391108)
		(stroke
			(width 0.08255)
			(type default)
		)
		(layer "B.Cu")
	)
	(gr_line
		(start 273.698716 -132.11937)
		(end 273.966686 -131.702556)
		(stroke
			(width 0.08255)
			(type default)
		)
		(layer "B.Cu")
	)
	(gr_line
		(start 273.70278 -62.9539)
		(end 273.836892 -62.868556)
		(stroke
			(width 0.08255)
			(type default)
		)
		(layer "B.Cu")
	)
	(gr_line
		(start 273.70532 -55.23484)
		(end 273.812508 -54.751224)
		(stroke
			(width 0.08255)
			(type default)
		)
		(layer "B.Cu")
	)
	(gr_line
		(start 273.720814 -68.730622)
		(end 273.81708 -68.587366)
		(stroke
			(width 0.08255)
			(type default)
		)
		(layer "B.Cu")
	)
	(gr_line
		(start 273.721576 -68.101464)
		(end 273.81708 -68.587366)
		(stroke
			(width 0.08255)
			(type default)
		)
		(layer "B.Cu")
	)
	(gr_line
		(start 273.727418 -54.617874)
		(end 273.812508 -54.751224)
		(stroke
			(width 0.08255)
			(type default)
		)
		(layer "B.Cu")
	)
	(gr_line
		(start 273.751802 -157.99562)
		(end 274.02155 -157.58033)
		(stroke
			(width 0.08255)
			(type default)
		)
		(layer "B.Cu")
	)
	(gr_line
		(start 273.761454 -161.408364)
		(end 273.933158 -161.42716)
		(stroke
			(width 0.08255)
			(type default)
		)
		(layer "B.Cu")
	)
	(gr_line
		(start 273.774408 -70.528688)
		(end 273.903948 -71.186548)
		(stroke
			(width 0.08255)
			(type default)
		)
		(layer "B.Cu")
	)
	(gr_line
		(start 273.781266 -134.88416)
		(end 274.148296 -134.318756)
		(stroke
			(width 0.08255)
			(type default)
		)
		(layer "B.Cu")
	)
	(gr_line
		(start 273.817334 -69.22135)
		(end 273.960844 -69.317616)
		(stroke
			(width 0.08255)
			(type default)
		)
		(layer "B.Cu")
	)
	(gr_line
		(start 273.836892 -62.868556)
		(end 273.94408 -62.38494)
		(stroke
			(width 0.08255)
			(type default)
		)
		(layer "B.Cu")
	)
	(gr_line
		(start 273.858736 -62.250828)
		(end 273.94408 -62.38494)
		(stroke
			(width 0.08255)
			(type default)
		)
		(layer "B.Cu")
	)
	(gr_line
		(start 273.92122 -154.143456)
		(end 274.09013 -154.107642)
		(stroke
			(width 0.08255)
			(type default)
		)
		(layer "B.Cu")
	)
	(gr_line
		(start 273.929856 -131.5339)
		(end 273.966686 -131.702556)
		(stroke
			(width 0.08255)
			(type default)
		)
		(layer "B.Cu")
	)
	(gr_line
		(start 273.933158 -161.42716)
		(end 274.318984 -161.116772)
		(stroke
			(width 0.08255)
			(type default)
		)
		(layer "B.Cu")
	)
	(gr_line
		(start 273.960082 -69.946774)
		(end 274.056602 -69.803518)
		(stroke
			(width 0.08255)
			(type default)
		)
		(layer "B.Cu")
	)
	(gr_line
		(start 273.960844 -69.317616)
		(end 274.056602 -69.803518)
		(stroke
			(width 0.08255)
			(type default)
		)
		(layer "B.Cu")
	)
	(gr_line
		(start 273.966686 -61.763656)
		(end 274.100798 -61.678312)
		(stroke
			(width 0.08255)
			(type default)
		)
		(layer "B.Cu")
	)
	(gr_line
		(start 273.970496 -130.92557)
		(end 274.334986 -130.358642)
		(stroke
			(width 0.08255)
			(type default)
		)
		(layer "B.Cu")
	)
	(gr_line
		(start 273.977608 -126.8095)
		(end 274.342606 -126.247652)
		(stroke
			(width 0.08255)
			(type default)
		)
		(layer "B.Cu")
	)
	(gr_line
		(start 273.988784 -157.42539)
		(end 274.02155 -157.58033)
		(stroke
			(width 0.08255)
			(type default)
		)
		(layer "B.Cu")
	)
	(gr_line
		(start 274.010882 -135.07212)
		(end 274.179792 -135.036306)
		(stroke
			(width 0.08255)
			(type default)
		)
		(layer "B.Cu")
	)
	(gr_line
		(start 274.013676 -71.74484)
		(end 274.143216 -72.402446)
		(stroke
			(width 0.08255)
			(type default)
		)
		(layer "B.Cu")
	)
	(gr_line
		(start 274.032726 -156.816552)
		(end 274.03806 -156.808424)
		(stroke
			(width 0.08255)
			(type default)
		)
		(layer "B.Cu")
	)
	(gr_line
		(start 274.03806 -156.808424)
		(end 274.045426 -156.802582)
		(stroke
			(width 0.08255)
			(type default)
		)
		(layer "B.Cu")
	)
	(gr_line
		(start 274.056856 -70.437502)
		(end 274.200112 -70.533768)
		(stroke
			(width 0.08255)
			(type default)
		)
		(layer "B.Cu")
	)
	(gr_line
		(start 274.067524 -81.534254)
		(end 274.211796 -82.184748)
		(stroke
			(width 0.08255)
			(type default)
		)
		(layer "B.Cu")
	)
	(gr_line
		(start 274.09013 -154.107642)
		(end 274.359878 -153.692098)
		(stroke
			(width 0.08255)
			(type default)
		)
		(layer "B.Cu")
	)
	(gr_line
		(start 274.093686 -181.54142)
		(end 274.10918 -181.600602)
		(stroke
			(width 0.08255)
			(type default)
		)
		(layer "B.Cu")
	)
	(gr_line
		(start 274.093686 -181.54142)
		(end 274.117308 -181.485032)
		(stroke
			(width 0.08255)
			(type default)
		)
		(layer "B.Cu")
	)
	(gr_line
		(start 274.100798 -61.678312)
		(end 274.207986 -61.194696)
		(stroke
			(width 0.08255)
			(type default)
		)
		(layer "B.Cu")
	)
	(gr_line
		(start 274.122642 -61.060584)
		(end 274.207986 -61.194696)
		(stroke
			(width 0.08255)
			(type default)
		)
		(layer "B.Cu")
	)
	(gr_line
		(start 274.179792 -135.036306)
		(end 274.449286 -134.620762)
		(stroke
			(width 0.08255)
			(type default)
		)
		(layer "B.Cu")
	)
	(gr_line
		(start 274.199604 -71.16318)
		(end 274.29587 -71.01967)
		(stroke
			(width 0.08255)
			(type default)
		)
		(layer "B.Cu")
	)
	(gr_line
		(start 274.200112 -131.113276)
		(end 274.369022 -131.0767)
		(stroke
			(width 0.08255)
			(type default)
		)
		(layer "B.Cu")
	)
	(gr_line
		(start 274.200112 -70.533768)
		(end 274.29587 -71.01967)
		(stroke
			(width 0.08255)
			(type default)
		)
		(layer "B.Cu")
	)
	(gr_line
		(start 274.206208 -126.998476)
		(end 274.375118 -126.962662)
		(stroke
			(width 0.08255)
			(type default)
		)
		(layer "B.Cu")
	)
	(gr_line
		(start 274.219416 -82.220054)
		(end 274.291552 -82.54492)
		(stroke
			(width 0.08255)
			(type default)
		)
		(layer "B.Cu")
	)
	(gr_line
		(start 274.296124 -71.653654)
		(end 274.439634 -71.74992)
		(stroke
			(width 0.08255)
			(type default)
		)
		(layer "B.Cu")
	)
	(gr_line
		(start 274.318984 -161.116772)
		(end 274.33778 -160.945068)
		(stroke
			(width 0.08255)
			(type default)
		)
		(layer "B.Cu")
	)
	(gr_line
		(start 274.324064 -153.523188)
		(end 274.359878 -153.692098)
		(stroke
			(width 0.08255)
			(type default)
		)
		(layer "B.Cu")
	)
	(gr_line
		(start 274.336002 -82.744818)
		(end 274.480274 -83.395566)
		(stroke
			(width 0.08255)
			(type default)
		)
		(layer "B.Cu")
	)
	(gr_line
		(start 274.347178 -81.435448)
		(end 274.49272 -81.528158)
		(stroke
			(width 0.08255)
			(type default)
		)
		(layer "B.Cu")
	)
	(gr_line
		(start 274.367244 -152.915112)
		(end 274.733512 -152.351232)
		(stroke
			(width 0.08255)
			(type default)
		)
		(layer "B.Cu")
	)
	(gr_line
		(start 274.369022 -131.0767)
		(end 274.636992 -130.66014)
		(stroke
			(width 0.08255)
			(type default)
		)
		(layer "B.Cu")
	)
	(gr_line
		(start 274.375118 -126.962662)
		(end 274.64512 -126.547118)
		(stroke
			(width 0.08255)
			(type default)
		)
		(layer "B.Cu")
	)
	(gr_line
		(start 274.413472 -134.452106)
		(end 274.449286 -134.620762)
		(stroke
			(width 0.08255)
			(type default)
		)
		(layer "B.Cu")
	)
	(gr_line
		(start 274.438872 -72.379332)
		(end 274.535138 -72.235822)
		(stroke
			(width 0.08255)
			(type default)
		)
		(layer "B.Cu")
	)
	(gr_line
		(start 274.439634 -71.74992)
		(end 274.535138 -72.235822)
		(stroke
			(width 0.08255)
			(type default)
		)
		(layer "B.Cu")
	)
	(gr_line
		(start 274.45589 -133.844792)
		(end 274.822158 -133.280658)
		(stroke
			(width 0.08255)
			(type default)
		)
		(layer "B.Cu")
	)
	(gr_line
		(start 274.461986 -92.026486)
		(end 274.47621 -92.048584)
		(stroke
			(width 0.08255)
			(type default)
		)
		(layer "B.Cu")
	)
	(gr_line
		(start 274.475956 -92.048584)
		(end 274.47621 -92.048584)
		(stroke
			(width 0.08255)
			(type default)
		)
		(layer "B.Cu")
	)
	(gr_line
		(start 274.475956 -92.048584)
		(end 274.498562 -92.062808)
		(stroke
			(width 0.08255)
			(type default)
		)
		(layer "B.Cu")
	)
	(gr_line
		(start 274.489418 -156.445458)
		(end 275.011642 -156.025596)
		(stroke
			(width 0.08255)
			(type default)
		)
		(layer "B.Cu")
	)
	(gr_line
		(start 274.49272 -81.528158)
		(end 274.600162 -82.011774)
		(stroke
			(width 0.08255)
			(type default)
		)
		(layer "B.Cu")
	)
	(gr_line
		(start 274.50542 -82.160364)
		(end 274.517358 -82.214466)
		(stroke
			(width 0.08255)
			(type default)
		)
		(layer "B.Cu")
	)
	(gr_line
		(start 274.507452 -82.157316)
		(end 274.600162 -82.011774)
		(stroke
			(width 0.08255)
			(type default)
		)
		(layer "B.Cu")
	)
	(gr_line
		(start 274.522692 -83.586574)
		(end 274.59813 -83.926426)
		(stroke
			(width 0.08255)
			(type default)
		)
		(layer "B.Cu")
	)
	(gr_line
		(start 274.536408 -49.606454)
		(end 274.539202 -49.594008)
		(stroke
			(width 0.08255)
			(type default)
		)
		(layer "B.Cu")
	)
	(gr_line
		(start 274.539202 -49.594008)
		(end 274.546314 -49.582832)
		(stroke
			(width 0.08255)
			(type default)
		)
		(layer "B.Cu")
	)
	(gr_line
		(start 274.569682 -160.380426)
		(end 275.091144 -159.961072)
		(stroke
			(width 0.08255)
			(type default)
		)
		(layer "B.Cu")
	)
	(gr_line
		(start 274.596352 -153.103834)
		(end 274.765262 -153.06802)
		(stroke
			(width 0.08255)
			(type default)
		)
		(layer "B.Cu")
	)
	(gr_line
		(start 274.600162 -130.490976)
		(end 274.636992 -130.66014)
		(stroke
			(width 0.08255)
			(type default)
		)
		(layer "B.Cu")
	)
	(gr_line
		(start 274.604734 -83.956398)
		(end 274.748752 -84.60613)
		(stroke
			(width 0.08255)
			(type default)
		)
		(layer "B.Cu")
	)
	(gr_line
		(start 274.609052 -126.378462)
		(end 274.64512 -126.547118)
		(stroke
			(width 0.08255)
			(type default)
		)
		(layer "B.Cu")
	)
	(gr_line
		(start 274.610576 -122.212862)
		(end 274.97786 -121.647458)
		(stroke
			(width 0.08255)
			(type default)
		)
		(layer "B.Cu")
	)
	(gr_line
		(start 274.615656 -82.645504)
		(end 274.761198 -82.738468)
		(stroke
			(width 0.08255)
			(type default)
		)
		(layer "B.Cu")
	)
	(gr_line
		(start 274.641056 -129.882646)
		(end 275.004784 -129.316988)
		(stroke
			(width 0.08255)
			(type default)
		)
		(layer "B.Cu")
	)
	(gr_line
		(start 274.647152 -156.696664)
		(end 274.818602 -156.71546)
		(stroke
			(width 0.08255)
			(type default)
		)
		(layer "B.Cu")
	)
	(gr_line
		(start 274.65401 -125.768354)
		(end 275.017738 -125.20803)
		(stroke
			(width 0.08255)
			(type default)
		)
		(layer "B.Cu")
	)
	(gr_line
		(start 274.68576 -134.032498)
		(end 274.85467 -133.996684)
		(stroke
			(width 0.08255)
			(type default)
		)
		(layer "B.Cu")
	)
	(gr_line
		(start 274.727416 -160.631632)
		(end 274.898866 -160.650428)
		(stroke
			(width 0.08255)
			(type default)
		)
		(layer "B.Cu")
	)
	(gr_line
		(start 274.75688 -84.642452)
		(end 274.757388 -84.644992)
		(stroke
			(width 0.08255)
			(type default)
		)
		(layer "B.Cu")
	)
	(gr_line
		(start 274.761198 -82.738468)
		(end 274.868386 -83.22183)
		(stroke
			(width 0.08255)
			(type default)
		)
		(layer "B.Cu")
	)
	(gr_line
		(start 274.765262 -153.06802)
		(end 275.03501 -152.652476)
		(stroke
			(width 0.08255)
			(type default)
		)
		(layer "B.Cu")
	)
	(gr_line
		(start 274.77593 -83.367372)
		(end 274.868386 -83.22183)
		(stroke
			(width 0.08255)
			(type default)
		)
		(layer "B.Cu")
	)
	(gr_line
		(start 274.810474 -83.535774)
		(end 274.881086 -83.854036)
		(stroke
			(width 0.08255)
			(type default)
		)
		(layer "B.Cu")
	)
	(gr_line
		(start 274.818602 -156.71546)
		(end 275.204682 -156.404818)
		(stroke
			(width 0.08255)
			(type default)
		)
		(layer "B.Cu")
	)
	(gr_line
		(start 274.8407 -122.40006)
		(end 275.00961 -122.364246)
		(stroke
			(width 0.08255)
			(type default)
		)
		(layer "B.Cu")
	)
	(gr_line
		(start 274.85467 -133.996684)
		(end 275.124164 -133.58114)
		(stroke
			(width 0.08255)
			(type default)
		)
		(layer "B.Cu")
	)
	(gr_line
		(start 274.870672 -130.070606)
		(end 275.039328 -130.03403)
		(stroke
			(width 0.08255)
			(type default)
		)
		(layer "B.Cu")
	)
	(gr_line
		(start 274.872958 -85.165946)
		(end 275.017484 -85.816694)
		(stroke
			(width 0.08255)
			(type default)
		)
		(layer "B.Cu")
	)
	(gr_line
		(start 274.88134 -125.958854)
		(end 275.05025 -125.92304)
		(stroke
			(width 0.08255)
			(type default)
		)
		(layer "B.Cu")
	)
	(gr_line
		(start 274.884134 -83.856068)
		(end 275.029676 -83.948524)
		(stroke
			(width 0.08255)
			(type default)
		)
		(layer "B.Cu")
	)
	(gr_line
		(start 274.898866 -160.650428)
		(end 275.284946 -160.34004)
		(stroke
			(width 0.08255)
			(type default)
		)
		(layer "B.Cu")
	)
	(gr_line
		(start 274.999196 -152.483566)
		(end 275.03501 -152.652476)
		(stroke
			(width 0.08255)
			(type default)
		)
		(layer "B.Cu")
	)
	(gr_line
		(start 275.00961 -122.364246)
		(end 275.279612 -121.948702)
		(stroke
			(width 0.08255)
			(type default)
		)
		(layer "B.Cu")
	)
	(gr_line
		(start 275.029676 -83.948524)
		(end 275.136864 -84.43214)
		(stroke
			(width 0.08255)
			(type default)
		)
		(layer "B.Cu")
	)
	(gr_line
		(start 275.039328 -130.03403)
		(end 275.307298 -129.61747)
		(stroke
			(width 0.08255)
			(type default)
		)
		(layer "B.Cu")
	)
	(gr_line
		(start 275.044154 -84.577428)
		(end 275.136864 -84.43214)
		(stroke
			(width 0.08255)
			(type default)
		)
		(layer "B.Cu")
	)
	(gr_line
		(start 275.05025 -125.92304)
		(end 275.319998 -125.50775)
		(stroke
			(width 0.08255)
			(type default)
		)
		(layer "B.Cu")
	)
	(gr_line
		(start 275.065236 -185.224674)
		(end 275.079968 -185.281316)
		(stroke
			(width 0.08255)
			(type default)
		)
		(layer "B.Cu")
	)
	(gr_line
		(start 275.079968 -185.281316)
		(end 275.126196 -185.3184)
		(stroke
			(width 0.08255)
			(type default)
		)
		(layer "B.Cu")
	)
	(gr_line
		(start 275.08835 -133.41223)
		(end 275.124164 -133.58114)
		(stroke
			(width 0.08255)
			(type default)
		)
		(layer "B.Cu")
	)
	(gr_line
		(start 275.110448 -151.771096)
		(end 275.115782 -151.762968)
		(stroke
			(width 0.08255)
			(type default)
		)
		(layer "B.Cu")
	)
	(gr_line
		(start 275.115782 -151.762968)
		(end 275.123148 -151.757126)
		(stroke
			(width 0.08255)
			(type default)
		)
		(layer "B.Cu")
	)
	(gr_line
		(start 275.13153 -132.804154)
		(end 275.497036 -132.24129)
		(stroke
			(width 0.08255)
			(type default)
		)
		(layer "B.Cu")
	)
	(gr_line
		(start 275.141182 -86.37524)
		(end 275.143976 -86.387686)
		(stroke
			(width 0.08255)
			(type default)
		)
		(layer "B.Cu")
	)
	(gr_line
		(start 275.143976 -86.387686)
		(end 275.151088 -86.398862)
		(stroke
			(width 0.08255)
			(type default)
		)
		(layer "B.Cu")
	)
	(gr_line
		(start 275.144484 -85.04174)
		(end 275.149564 -85.064092)
		(stroke
			(width 0.08255)
			(type default)
		)
		(layer "B.Cu")
	)
	(gr_line
		(start 275.152612 -85.066124)
		(end 275.298154 -85.15858)
		(stroke
			(width 0.08255)
			(type default)
		)
		(layer "B.Cu")
	)
	(gr_line
		(start 275.204682 -156.404818)
		(end 275.223478 -156.233114)
		(stroke
			(width 0.08255)
			(type default)
		)
		(layer "B.Cu")
	)
	(gr_line
		(start 275.243544 -121.780046)
		(end 275.279612 -121.948702)
		(stroke
			(width 0.08255)
			(type default)
		)
		(layer "B.Cu")
	)
	(gr_line
		(start 275.270722 -129.44856)
		(end 275.307298 -129.61747)
		(stroke
			(width 0.08255)
			(type default)
		)
		(layer "B.Cu")
	)
	(gr_line
		(start 275.284184 -125.33884)
		(end 275.319998 -125.50775)
		(stroke
			(width 0.08255)
			(type default)
		)
		(layer "B.Cu")
	)
	(gr_line
		(start 275.284946 -160.34004)
		(end 275.303742 -160.168336)
		(stroke
			(width 0.08255)
			(type default)
		)
		(layer "B.Cu")
	)
	(gr_line
		(start 275.287232 -121.171208)
		(end 275.653246 -120.607582)
		(stroke
			(width 0.08255)
			(type default)
		)
		(layer "B.Cu")
	)
	(gr_line
		(start 275.298154 -85.15858)
		(end 275.405342 -85.642196)
		(stroke
			(width 0.08255)
			(type default)
		)
		(layer "B.Cu")
	)
	(gr_line
		(start 275.312632 -85.787738)
		(end 275.405342 -85.642196)
		(stroke
			(width 0.08255)
			(type default)
		)
		(layer "B.Cu")
	)
	(gr_line
		(start 275.329142 -124.728732)
		(end 275.693378 -124.167646)
		(stroke
			(width 0.08255)
			(type default)
		)
		(layer "B.Cu")
	)
	(gr_line
		(start 275.360384 -132.992876)
		(end 275.529548 -132.956808)
		(stroke
			(width 0.08255)
			(type default)
		)
		(layer "B.Cu")
	)
	(gr_line
		(start 275.457158 -155.667202)
		(end 275.97608 -155.24988)
		(stroke
			(width 0.08255)
			(type default)
		)
		(layer "B.Cu")
	)
	(gr_line
		(start 275.515832 -121.360438)
		(end 275.684742 -121.324624)
		(stroke
			(width 0.08255)
			(type default)
		)
		(layer "B.Cu")
	)
	(gr_line
		(start 275.529548 -132.956808)
		(end 275.799042 -132.541518)
		(stroke
			(width 0.08255)
			(type default)
		)
		(layer "B.Cu")
	)
	(gr_line
		(start 275.53666 -159.603186)
		(end 276.057868 -159.183832)
		(stroke
			(width 0.08255)
			(type default)
		)
		(layer "B.Cu")
	)
	(gr_line
		(start 275.554948 -90.623136)
		(end 275.569934 -90.646758)
		(stroke
			(width 0.08255)
			(type default)
		)
		(layer "B.Cu")
	)
	(gr_line
		(start 275.556472 -124.919232)
		(end 275.725382 -124.883418)
		(stroke
			(width 0.08255)
			(type default)
		)
		(layer "B.Cu")
	)
	(gr_line
		(start 275.567394 -151.399748)
		(end 276.07387 -150.992332)
		(stroke
			(width 0.08255)
			(type default)
		)
		(layer "B.Cu")
	)
	(gr_line
		(start 275.569934 -90.646758)
		(end 275.594572 -90.662506)
		(stroke
			(width 0.08255)
			(type default)
		)
		(layer "B.Cu")
	)
	(gr_line
		(start 275.613114 -155.919932)
		(end 275.784564 -155.938474)
		(stroke
			(width 0.08255)
			(type default)
		)
		(layer "B.Cu")
	)
	(gr_line
		(start 275.684742 -121.324624)
		(end 275.95449 -120.909334)
		(stroke
			(width 0.08255)
			(type default)
		)
		(layer "B.Cu")
	)
	(gr_line
		(start 275.689314 -80.258666)
		(end 275.819108 -80.917288)
		(stroke
			(width 0.08255)
			(type default)
		)
		(layer "B.Cu")
	)
	(gr_line
		(start 275.693124 -159.8549)
		(end 275.864828 -159.873696)
		(stroke
			(width 0.08255)
			(type default)
		)
		(layer "B.Cu")
	)
	(gr_line
		(start 275.724874 -151.651208)
		(end 275.8821 -151.66848)
		(stroke
			(width 0.08255)
			(type default)
		)
		(layer "B.Cu")
	)
	(gr_line
		(start 275.725382 -124.883418)
		(end 275.99513 -124.468128)
		(stroke
			(width 0.08255)
			(type default)
		)
		(layer "B.Cu")
	)
	(gr_line
		(start 275.763228 -132.372608)
		(end 275.799042 -132.541518)
		(stroke
			(width 0.08255)
			(type default)
		)
		(layer "B.Cu")
	)
	(gr_line
		(start 275.784564 -155.938474)
		(end 276.170644 -155.628086)
		(stroke
			(width 0.08255)
			(type default)
		)
		(layer "B.Cu")
	)
	(gr_line
		(start 275.864828 -159.873696)
		(end 276.250908 -159.563308)
		(stroke
			(width 0.08255)
			(type default)
		)
		(layer "B.Cu")
	)
	(gr_line
		(start 275.8821 -151.66848)
		(end 276.26818 -151.357838)
		(stroke
			(width 0.08255)
			(type default)
		)
		(layer "B.Cu")
	)
	(gr_line
		(start 275.918676 -120.740424)
		(end 275.95449 -120.909334)
		(stroke
			(width 0.08255)
			(type default)
		)
		(layer "B.Cu")
	)
	(gr_line
		(start 275.928836 -81.47558)
		(end 276.05863 -82.134964)
		(stroke
			(width 0.08255)
			(type default)
		)
		(layer "B.Cu")
	)
	(gr_line
		(start 275.959316 -124.299218)
		(end 275.99513 -124.468128)
		(stroke
			(width 0.08255)
			(type default)
		)
		(layer "B.Cu")
	)
	(gr_line
		(start 275.962872 -120.131332)
		(end 276.328124 -119.568468)
		(stroke
			(width 0.08255)
			(type default)
		)
		(layer "B.Cu")
	)
	(gr_line
		(start 275.972016 -80.169004)
		(end 276.115526 -80.26527)
		(stroke
			(width 0.08255)
			(type default)
		)
		(layer "B.Cu")
	)
	(gr_line
		(start 275.973286 -181.638956)
		(end 275.989034 -181.698392)
		(stroke
			(width 0.08255)
			(type default)
		)
		(layer "B.Cu")
	)
	(gr_line
		(start 275.973286 -181.638956)
		(end 275.996908 -181.582568)
		(stroke
			(width 0.08255)
			(type default)
		)
		(layer "B.Cu")
	)
	(gr_line
		(start 275.98878 -181.698138)
		(end 275.989034 -181.699154)
		(stroke
			(width 0.08255)
			(type default)
		)
		(layer "B.Cu")
	)
	(gr_line
		(start 276.108668 -50.743104)
		(end 276.111462 -50.730658)
		(stroke
			(width 0.08255)
			(type default)
		)
		(layer "B.Cu")
	)
	(gr_line
		(start 276.111462 -50.730658)
		(end 276.118574 -50.719482)
		(stroke
			(width 0.08255)
			(type default)
		)
		(layer "B.Cu")
	)
	(gr_line
		(start 276.115018 -80.894682)
		(end 276.211284 -80.751426)
		(stroke
			(width 0.08255)
			(type default)
		)
		(layer "B.Cu")
	)
	(gr_line
		(start 276.115526 -80.26527)
		(end 276.211284 -80.751426)
		(stroke
			(width 0.08255)
			(type default)
		)
		(layer "B.Cu")
	)
	(gr_line
		(start 276.168104 -82.691986)
		(end 276.297898 -83.35137)
		(stroke
			(width 0.08255)
			(type default)
		)
		(layer "B.Cu")
	)
	(gr_line
		(start 276.170644 -155.628086)
		(end 276.189186 -155.456636)
		(stroke
			(width 0.08255)
			(type default)
		)
		(layer "B.Cu")
	)
	(gr_line
		(start 276.190964 -120.320816)
		(end 276.359874 -120.285002)
		(stroke
			(width 0.08255)
			(type default)
		)
		(layer "B.Cu")
	)
	(gr_line
		(start 276.211538 -81.385156)
		(end 276.354794 -81.481676)
		(stroke
			(width 0.08255)
			(type default)
		)
		(layer "B.Cu")
	)
	(gr_line
		(start 276.250908 -159.563308)
		(end 276.269704 -159.391604)
		(stroke
			(width 0.08255)
			(type default)
		)
		(layer "B.Cu")
	)
	(gr_line
		(start 276.26818 -151.357838)
		(end 276.285198 -151.200612)
		(stroke
			(width 0.08255)
			(type default)
		)
		(layer "B.Cu")
	)
	(gr_line
		(start 276.354286 -82.110834)
		(end 276.450552 -81.967578)
		(stroke
			(width 0.08255)
			(type default)
		)
		(layer "B.Cu")
	)
	(gr_line
		(start 276.354794 -81.481676)
		(end 276.450552 -81.967578)
		(stroke
			(width 0.08255)
			(type default)
		)
		(layer "B.Cu")
	)
	(gr_line
		(start 276.359874 -120.285002)
		(end 276.629622 -119.869712)
		(stroke
			(width 0.08255)
			(type default)
		)
		(layer "B.Cu")
	)
	(gr_line
		(start 276.407118 -83.906614)
		(end 276.537166 -84.565998)
		(stroke
			(width 0.08255)
			(type default)
		)
		(layer "B.Cu")
	)
	(gr_line
		(start 276.422612 -154.890978)
		(end 276.942804 -154.472386)
		(stroke
			(width 0.08255)
			(type default)
		)
		(layer "B.Cu")
	)
	(gr_line
		(start 276.450806 -82.601816)
		(end 276.594316 -82.697828)
		(stroke
			(width 0.08255)
			(type default)
		)
		(layer "B.Cu")
	)
	(gr_line
		(start 276.516084 -150.636478)
		(end 277.022814 -150.229062)
		(stroke
			(width 0.08255)
			(type default)
		)
		(layer "B.Cu")
	)
	(gr_line
		(start 276.578822 -155.142946)
		(end 276.750526 -155.161742)
		(stroke
			(width 0.08255)
			(type default)
		)
		(layer "B.Cu")
	)
	(gr_line
		(start 276.593554 -83.326986)
		(end 276.68982 -83.18373)
		(stroke
			(width 0.08255)
			(type default)
		)
		(layer "B.Cu")
	)
	(gr_line
		(start 276.593808 -119.700802)
		(end 276.629622 -119.869712)
		(stroke
			(width 0.08255)
			(type default)
		)
		(layer "B.Cu")
	)
	(gr_line
		(start 276.594316 -82.697828)
		(end 276.68982 -83.18373)
		(stroke
			(width 0.08255)
			(type default)
		)
		(layer "B.Cu")
	)
	(gr_line
		(start 276.643592 -166.244778)
		(end 276.667976 -166.186866)
		(stroke
			(width 0.08255)
			(type default)
		)
		(layer "B.Cu")
	)
	(gr_line
		(start 276.663404 -37.855144)
		(end 276.677628 -37.832538)
		(stroke
			(width 0.08255)
			(type default)
		)
		(layer "B.Cu")
	)
	(gr_line
		(start 276.667976 -166.186866)
		(end 276.722586 -166.156386)
		(stroke
			(width 0.08255)
			(type default)
		)
		(layer "B.Cu")
	)
	(gr_line
		(start 276.674834 -150.887176)
		(end 276.832314 -150.904194)
		(stroke
			(width 0.08255)
			(type default)
		)
		(layer "B.Cu")
	)
	(gr_line
		(start 276.677628 -37.832538)
		(end 276.700996 -37.817552)
		(stroke
			(width 0.08255)
			(type default)
		)
		(layer "B.Cu")
	)
	(gr_line
		(start 276.67839 -122.650758)
		(end 276.683724 -122.64263)
		(stroke
			(width 0.08255)
			(type default)
		)
		(layer "B.Cu")
	)
	(gr_line
		(start 276.683724 -122.64263)
		(end 276.69109 -122.636788)
		(stroke
			(width 0.08255)
			(type default)
		)
		(layer "B.Cu")
	)
	(gr_line
		(start 276.687788 -130.406902)
		(end 276.693122 -130.398774)
		(stroke
			(width 0.08255)
			(type default)
		)
		(layer "B.Cu")
	)
	(gr_line
		(start 276.68855 -126.698248)
		(end 276.694646 -126.68885)
		(stroke
			(width 0.08255)
			(type default)
		)
		(layer "B.Cu")
	)
	(gr_line
		(start 276.690328 -83.817714)
		(end 276.833584 -83.91398)
		(stroke
			(width 0.08255)
			(type default)
		)
		(layer "B.Cu")
	)
	(gr_line
		(start 276.693122 -130.398774)
		(end 276.700488 -130.392932)
		(stroke
			(width 0.08255)
			(type default)
		)
		(layer "B.Cu")
	)
	(gr_line
		(start 276.694646 -126.68885)
		(end 276.703282 -126.681738)
		(stroke
			(width 0.08255)
			(type default)
		)
		(layer "B.Cu")
	)
	(gr_line
		(start 276.71141 -184.437782)
		(end 276.726904 -184.495948)
		(stroke
			(width 0.08255)
			(type default)
		)
		(layer "B.Cu")
	)
	(gr_line
		(start 276.726904 -184.495948)
		(end 276.727158 -184.495948)
		(stroke
			(width 0.08255)
			(type default)
		)
		(layer "B.Cu")
	)
	(gr_line
		(start 276.727158 -184.495948)
		(end 276.77237 -184.53227)
		(stroke
			(width 0.08255)
			(type default)
		)
		(layer "B.Cu")
	)
	(gr_line
		(start 276.750526 -155.161742)
		(end 277.136352 -154.851354)
		(stroke
			(width 0.08255)
			(type default)
		)
		(layer "B.Cu")
	)
	(gr_line
		(start 276.785832 -41.844722)
		(end 276.80158 -41.820084)
		(stroke
			(width 0.08255)
			(type default)
		)
		(layer "B.Cu")
	)
	(gr_line
		(start 276.80158 -41.820084)
		(end 276.826218 -41.804336)
		(stroke
			(width 0.08255)
			(type default)
		)
		(layer "B.Cu")
	)
	(gr_line
		(start 276.8092 -49.635664)
		(end 276.823424 -49.613566)
		(stroke
			(width 0.08255)
			(type default)
		)
		(layer "B.Cu")
	)
	(gr_line
		(start 276.820376 -86.003638)
		(end 276.823424 -86.020148)
		(stroke
			(width 0.08255)
			(type default)
		)
		(layer "B.Cu")
	)
	(gr_line
		(start 276.823424 -86.020148)
		(end 276.832822 -86.03488)
		(stroke
			(width 0.08255)
			(type default)
		)
		(layer "B.Cu")
	)
	(gr_line
		(start 276.823424 -49.613566)
		(end 276.845522 -49.599342)
		(stroke
			(width 0.08255)
			(type default)
		)
		(layer "B.Cu")
	)
	(gr_line
		(start 276.832314 -150.904194)
		(end 277.21814 -150.593806)
		(stroke
			(width 0.08255)
			(type default)
		)
		(layer "B.Cu")
	)
	(gr_line
		(start 276.833076 -84.543138)
		(end 276.929342 -84.399882)
		(stroke
			(width 0.08255)
			(type default)
		)
		(layer "B.Cu")
	)
	(gr_line
		(start 276.833584 -83.91398)
		(end 276.929342 -84.399882)
		(stroke
			(width 0.08255)
			(type default)
		)
		(layer "B.Cu")
	)
	(gr_line
		(start 276.945598 -170.22953)
		(end 276.969982 -170.171618)
		(stroke
			(width 0.08255)
			(type default)
		)
		(layer "B.Cu")
	)
	(gr_line
		(start 276.969982 -170.171618)
		(end 277.024592 -170.141138)
		(stroke
			(width 0.08255)
			(type default)
		)
		(layer "B.Cu")
	)
	(gr_line
		(start 276.977348 -45.76953)
		(end 276.991572 -45.747432)
		(stroke
			(width 0.08255)
			(type default)
		)
		(layer "B.Cu")
	)
	(gr_line
		(start 276.991572 -45.747432)
		(end 277.01367 -45.733208)
		(stroke
			(width 0.08255)
			(type default)
		)
		(layer "B.Cu")
	)
	(gr_line
		(start 277.136352 -154.851354)
		(end 277.155148 -154.67965)
		(stroke
			(width 0.08255)
			(type default)
		)
		(layer "B.Cu")
	)
	(gr_line
		(start 277.178262 -89.579958)
		(end 277.192486 -89.602056)
		(stroke
			(width 0.08255)
			(type default)
		)
		(layer "B.Cu")
	)
	(gr_line
		(start 277.192486 -89.602056)
		(end 277.214584 -89.61628)
		(stroke
			(width 0.08255)
			(type default)
		)
		(layer "B.Cu")
	)
	(gr_line
		(start 277.21814 -150.593806)
		(end 277.235412 -150.436326)
		(stroke
			(width 0.08255)
			(type default)
		)
		(layer "B.Cu")
	)
	(gr_line
		(start 277.23592 -174.06747)
		(end 277.260304 -174.009558)
		(stroke
			(width 0.08255)
			(type default)
		)
		(layer "B.Cu")
	)
	(gr_line
		(start 277.260304 -174.009558)
		(end 277.314914 -173.979078)
		(stroke
			(width 0.08255)
			(type default)
		)
		(layer "B.Cu")
	)
	(gr_line
		(start 277.312882 -118.052342)
		(end 277.318216 -118.044214)
		(stroke
			(width 0.08255)
			(type default)
		)
		(layer "B.Cu")
	)
	(gr_line
		(start 277.318216 -118.044214)
		(end 277.325582 -118.038372)
		(stroke
			(width 0.08255)
			(type default)
		)
		(layer "B.Cu")
	)
	(gr_line
		(start 277.547324 -177.894488)
		(end 277.57247 -177.835052)
		(stroke
			(width 0.08255)
			(type default)
		)
		(layer "B.Cu")
	)
	(gr_line
		(start 277.569168 -161.394648)
		(end 277.619714 -161.354008)
		(stroke
			(width 0.08255)
			(type default)
		)
		(layer "B.Cu")
	)
	(gr_line
		(start 277.57247 -177.835052)
		(end 277.627842 -177.804318)
		(stroke
			(width 0.08255)
			(type default)
		)
		(layer "B.Cu")
	)
	(gr_line
		(start 277.585678 -191.36868)
		(end 277.598632 -191.379094)
		(stroke
			(width 0.08255)
			(type default)
		)
		(layer "B.Cu")
	)
	(gr_line
		(start 277.598632 -191.379094)
		(end 277.615142 -191.384428)
		(stroke
			(width 0.08255)
			(type default)
		)
		(layer "B.Cu")
	)
	(gr_line
		(start 277.615396 -49.108868)
		(end 277.654258 -49.083976)
		(stroke
			(width 0.08255)
			(type default)
		)
		(layer "B.Cu")
	)
	(gr_line
		(start 277.815548 -37.108638)
		(end 277.85441 -37.084)
		(stroke
			(width 0.08255)
			(type default)
		)
		(layer "B.Cu")
	)
	(gr_line
		(start 277.918926 -41.108884)
		(end 277.958296 -41.083992)
		(stroke
			(width 0.08255)
			(type default)
		)
		(layer "B.Cu")
	)
	(gr_line
		(start 277.94331 -129.39395)
		(end 277.992586 -129.354072)
		(stroke
			(width 0.08255)
			(type default)
		)
		(layer "B.Cu")
	)
	(gr_line
		(start 277.993602 -45.109384)
		(end 278.03348 -45.083984)
		(stroke
			(width 0.08255)
			(type default)
		)
		(layer "B.Cu")
	)
	(gr_line
		(start 278.029416 -189.686184)
		(end 278.04237 -189.696598)
		(stroke
			(width 0.08255)
			(type default)
		)
		(layer "B.Cu")
	)
	(gr_line
		(start 278.04237 -189.696598)
		(end 278.057864 -189.701424)
		(stroke
			(width 0.08255)
			(type default)
		)
		(layer "B.Cu")
	)
	(gr_line
		(start 278.060404 -149.394672)
		(end 278.11095 -149.354032)
		(stroke
			(width 0.08255)
			(type default)
		)
		(layer "B.Cu")
	)
	(gr_line
		(start 278.078438 -165.39972)
		(end 278.113236 -165.380162)
		(stroke
			(width 0.08255)
			(type default)
		)
		(layer "B.Cu")
	)
	(gr_line
		(start 278.113236 -165.380162)
		(end 278.153876 -165.380416)
		(stroke
			(width 0.08255)
			(type default)
		)
		(layer "B.Cu")
	)
	(gr_line
		(start 278.125682 -117.394736)
		(end 278.176228 -117.354096)
		(stroke
			(width 0.08255)
			(type default)
		)
		(layer "B.Cu")
	)
	(gr_line
		(start 278.235664 -121.394728)
		(end 278.28621 -121.354088)
		(stroke
			(width 0.08255)
			(type default)
		)
		(layer "B.Cu")
	)
	(gr_line
		(start 278.23668 -355.905054)
		(end 278.663654 -355.905054)
		(stroke
			(width 0.0635)
			(type default)
		)
		(layer "B.Cu")
	)
	(gr_line
		(start 278.23668 -352.305112)
		(end 278.663654 -352.305112)
		(stroke
			(width 0.0635)
			(type default)
		)
		(layer "B.Cu")
	)
	(gr_line
		(start 278.23668 -348.70517)
		(end 278.663654 -348.70517)
		(stroke
			(width 0.0635)
			(type default)
		)
		(layer "B.Cu")
	)
	(gr_line
		(start 278.23668 -334.305148)
		(end 278.663654 -334.305148)
		(stroke
			(width 0.0635)
			(type default)
		)
		(layer "B.Cu")
	)
	(gr_line
		(start 278.23668 -330.705206)
		(end 278.663654 -330.705206)
		(stroke
			(width 0.0635)
			(type default)
		)
		(layer "B.Cu")
	)
	(gr_line
		(start 278.23668 -327.105264)
		(end 278.663654 -327.105264)
		(stroke
			(width 0.0635)
			(type default)
		)
		(layer "B.Cu")
	)
	(gr_line
		(start 278.23668 -312.705242)
		(end 278.236934 -312.704988)
		(stroke
			(width 0.0635)
			(type default)
		)
		(layer "B.Cu")
	)
	(gr_line
		(start 278.23668 -309.105046)
		(end 278.663654 -309.105046)
		(stroke
			(width 0.0635)
			(type default)
		)
		(layer "B.Cu")
	)
	(gr_line
		(start 278.23668 -305.505104)
		(end 278.663654 -305.505104)
		(stroke
			(width 0.0635)
			(type default)
		)
		(layer "B.Cu")
	)
	(gr_line
		(start 278.236934 -312.704988)
		(end 278.663654 -312.704988)
		(stroke
			(width 0.0635)
			(type default)
		)
		(layer "B.Cu")
	)
	(gr_line
		(start 278.24938 -94.45244)
		(end 278.260556 -94.459552)
		(stroke
			(width 0.08255)
			(type default)
		)
		(layer "B.Cu")
	)
	(gr_line
		(start 278.260556 -94.459552)
		(end 278.273002 -94.462346)
		(stroke
			(width 0.08255)
			(type default)
		)
		(layer "B.Cu")
	)
	(gr_line
		(start 278.282654 -157.394656)
		(end 278.3332 -157.354016)
		(stroke
			(width 0.08255)
			(type default)
		)
		(layer "B.Cu")
	)
	(gr_line
		(start 278.282654 -153.394664)
		(end 278.3332 -153.354024)
		(stroke
			(width 0.08255)
			(type default)
		)
		(layer "B.Cu")
	)
	(gr_line
		(start 278.30399 -125.39472)
		(end 278.354536 -125.35408)
		(stroke
			(width 0.08255)
			(type default)
		)
		(layer "B.Cu")
	)
	(gr_line
		(start 278.33574 -88.394794)
		(end 278.349964 -88.416892)
		(stroke
			(width 0.08255)
			(type default)
		)
		(layer "B.Cu")
	)
	(gr_line
		(start 278.349964 -88.416892)
		(end 278.372062 -88.431116)
		(stroke
			(width 0.08255)
			(type default)
		)
		(layer "B.Cu")
	)
	(gr_line
		(start 278.351742 -173.400212)
		(end 278.386032 -173.381162)
		(stroke
			(width 0.08255)
			(type default)
		)
		(layer "B.Cu")
	)
	(gr_line
		(start 278.351996 -169.40022)
		(end 278.386286 -169.38117)
		(stroke
			(width 0.08255)
			(type default)
		)
		(layer "B.Cu")
	)
	(gr_line
		(start 278.352504 -177.39995)
		(end 278.386286 -177.381154)
		(stroke
			(width 0.08255)
			(type default)
		)
		(layer "B.Cu")
	)
	(gr_line
		(start 278.386032 -173.381162)
		(end 278.424894 -173.381416)
		(stroke
			(width 0.08255)
			(type default)
		)
		(layer "B.Cu")
	)
	(gr_line
		(start 278.386286 -177.381154)
		(end 278.424894 -177.381408)
		(stroke
			(width 0.08255)
			(type default)
		)
		(layer "B.Cu")
	)
	(gr_line
		(start 278.386286 -169.38117)
		(end 278.425148 -169.381424)
		(stroke
			(width 0.08255)
			(type default)
		)
		(layer "B.Cu")
	)
	(gr_line
		(start 278.742902 -188.227208)
		(end 278.755856 -188.237622)
		(stroke
			(width 0.08255)
			(type default)
		)
		(layer "B.Cu")
	)
	(gr_line
		(start 278.750014 -178.49977)
		(end 279.423622 -178.162458)
		(stroke
			(width 0.08255)
			(type default)
		)
		(layer "B.Cu")
	)
	(gr_line
		(start 278.750014 -174.499778)
		(end 279.423622 -174.162466)
		(stroke
			(width 0.08255)
			(type default)
		)
		(layer "B.Cu")
	)
	(gr_line
		(start 278.750014 -170.499786)
		(end 279.423622 -170.162474)
		(stroke
			(width 0.08255)
			(type default)
		)
		(layer "B.Cu")
	)
	(gr_line
		(start 278.750014 -166.499794)
		(end 279.423622 -166.162482)
		(stroke
			(width 0.08255)
			(type default)
		)
		(layer "B.Cu")
	)
	(gr_line
		(start 278.750014 -162.499802)
		(end 279.471882 -162.138614)
		(stroke
			(width 0.08255)
			(type default)
		)
		(layer "B.Cu")
	)
	(gr_line
		(start 278.750014 -158.49981)
		(end 279.471882 -158.138622)
		(stroke
			(width 0.08255)
			(type default)
		)
		(layer "B.Cu")
	)
	(gr_line
		(start 278.750014 -154.499818)
		(end 279.471882 -154.13863)
		(stroke
			(width 0.08255)
			(type default)
		)
		(layer "B.Cu")
	)
	(gr_line
		(start 278.750014 -150.499826)
		(end 279.471882 -150.138638)
		(stroke
			(width 0.08255)
			(type default)
		)
		(layer "B.Cu")
	)
	(gr_line
		(start 278.750014 -130.499866)
		(end 279.471882 -130.138678)
		(stroke
			(width 0.08255)
			(type default)
		)
		(layer "B.Cu")
	)
	(gr_line
		(start 278.750014 -126.499874)
		(end 279.471882 -126.138686)
		(stroke
			(width 0.08255)
			(type default)
		)
		(layer "B.Cu")
	)
	(gr_line
		(start 278.750014 -122.499882)
		(end 279.471882 -122.138694)
		(stroke
			(width 0.08255)
			(type default)
		)
		(layer "B.Cu")
	)
	(gr_line
		(start 278.750014 -118.49989)
		(end 279.471882 -118.138702)
		(stroke
			(width 0.08255)
			(type default)
		)
		(layer "B.Cu")
	)
	(gr_line
		(start 278.750014 -82.199988)
		(end 279.410668 -81.861406)
		(stroke
			(width 0.08255)
			(type default)
		)
		(layer "B.Cu")
	)
	(gr_line
		(start 278.750014 -78.199996)
		(end 279.410668 -77.861414)
		(stroke
			(width 0.08255)
			(type default)
		)
		(layer "B.Cu")
	)
	(gr_line
		(start 278.750014 -74.200004)
		(end 279.410668 -73.861422)
		(stroke
			(width 0.08255)
			(type default)
		)
		(layer "B.Cu")
	)
	(gr_line
		(start 278.750014 -70.200012)
		(end 279.410668 -69.86143)
		(stroke
			(width 0.08255)
			(type default)
		)
		(layer "B.Cu")
	)
	(gr_line
		(start 278.750014 -66.20002)
		(end 279.410668 -65.861438)
		(stroke
			(width 0.08255)
			(type default)
		)
		(layer "B.Cu")
	)
	(gr_line
		(start 278.750014 -62.200028)
		(end 279.410668 -61.861446)
		(stroke
			(width 0.08255)
			(type default)
		)
		(layer "B.Cu")
	)
	(gr_line
		(start 278.750014 -58.200036)
		(end 279.410668 -57.861454)
		(stroke
			(width 0.08255)
			(type default)
		)
		(layer "B.Cu")
	)
	(gr_line
		(start 278.750014 -54.200044)
		(end 279.410668 -53.861462)
		(stroke
			(width 0.08255)
			(type default)
		)
		(layer "B.Cu")
	)
	(gr_line
		(start 278.750014 -50.200052)
		(end 279.423622 -49.86274)
		(stroke
			(width 0.08255)
			(type default)
		)
		(layer "B.Cu")
	)
	(gr_line
		(start 278.750014 -46.20006)
		(end 279.423622 -45.862748)
		(stroke
			(width 0.08255)
			(type default)
		)
		(layer "B.Cu")
	)
	(gr_line
		(start 278.750014 -42.200068)
		(end 279.423622 -41.862756)
		(stroke
			(width 0.08255)
			(type default)
		)
		(layer "B.Cu")
	)
	(gr_line
		(start 278.750014 -38.200076)
		(end 279.423622 -37.862764)
		(stroke
			(width 0.08255)
			(type default)
		)
		(layer "B.Cu")
	)
	(gr_line
		(start 278.755856 -188.237622)
		(end 278.77135 -188.242448)
		(stroke
			(width 0.08255)
			(type default)
		)
		(layer "B.Cu")
	)
	(gr_arc
		(start 278.790654 -356.032054)
		(mid 278.753457 -355.942251)
		(end 278.663654 -355.905054)
		(stroke
			(width 0.0635)
			(type default)
		)
		(layer "B.Cu")
	)
	(gr_arc
		(start 278.790654 -352.432112)
		(mid 278.753457 -352.342309)
		(end 278.663654 -352.305112)
		(stroke
			(width 0.0635)
			(type default)
		)
		(layer "B.Cu")
	)
	(gr_arc
		(start 278.790654 -348.83217)
		(mid 278.753457 -348.742367)
		(end 278.663654 -348.70517)
		(stroke
			(width 0.0635)
			(type default)
		)
		(layer "B.Cu")
	)
	(gr_arc
		(start 278.790654 -334.432148)
		(mid 278.753457 -334.342345)
		(end 278.663654 -334.305148)
		(stroke
			(width 0.0635)
			(type default)
		)
		(layer "B.Cu")
	)
	(gr_arc
		(start 278.790654 -330.832206)
		(mid 278.753457 -330.742403)
		(end 278.663654 -330.705206)
		(stroke
			(width 0.0635)
			(type default)
		)
		(layer "B.Cu")
	)
	(gr_arc
		(start 278.790654 -327.232264)
		(mid 278.753457 -327.142461)
		(end 278.663654 -327.105264)
		(stroke
			(width 0.0635)
			(type default)
		)
		(layer "B.Cu")
	)
	(gr_arc
		(start 278.790654 -312.831988)
		(mid 278.753457 -312.742185)
		(end 278.663654 -312.704988)
		(stroke
			(width 0.0635)
			(type default)
		)
		(layer "B.Cu")
	)
	(gr_arc
		(start 278.790654 -309.232046)
		(mid 278.753457 -309.142243)
		(end 278.663654 -309.105046)
		(stroke
			(width 0.0635)
			(type default)
		)
		(layer "B.Cu")
	)
	(gr_arc
		(start 278.790654 -305.632104)
		(mid 278.753457 -305.542301)
		(end 278.663654 -305.505104)
		(stroke
			(width 0.0635)
			(type default)
		)
		(layer "B.Cu")
	)
	(gr_arc
		(start 279.085802 -312.803032)
		(mid 279.08345 -312.817423)
		(end 279.082754 -312.831988)
		(stroke
			(width 0.0635)
			(type default)
		)
		(layer "B.Cu")
	)
	(gr_arc
		(start 279.209754 -355.905054)
		(mid 279.119951 -355.942251)
		(end 279.082754 -356.032054)
		(stroke
			(width 0.0635)
			(type default)
		)
		(layer "B.Cu")
	)
	(gr_line
		(start 279.209754 -355.905054)
		(end 279.636728 -355.905054)
		(stroke
			(width 0.0635)
			(type default)
		)
		(layer "B.Cu")
	)
	(gr_arc
		(start 279.209754 -352.305112)
		(mid 279.119951 -352.342309)
		(end 279.082754 -352.432112)
		(stroke
			(width 0.0635)
			(type default)
		)
		(layer "B.Cu")
	)
	(gr_line
		(start 279.209754 -352.305112)
		(end 279.636728 -352.305112)
		(stroke
			(width 0.0635)
			(type default)
		)
		(layer "B.Cu")
	)
	(gr_arc
		(start 279.209754 -348.70517)
		(mid 279.119951 -348.742367)
		(end 279.082754 -348.83217)
		(stroke
			(width 0.0635)
			(type default)
		)
		(layer "B.Cu")
	)
	(gr_line
		(start 279.209754 -348.70517)
		(end 279.636728 -348.70517)
		(stroke
			(width 0.0635)
			(type default)
		)
		(layer "B.Cu")
	)
	(gr_arc
		(start 279.209754 -334.305148)
		(mid 279.119951 -334.342345)
		(end 279.082754 -334.432148)
		(stroke
			(width 0.0635)
			(type default)
		)
		(layer "B.Cu")
	)
	(gr_line
		(start 279.209754 -334.305148)
		(end 279.636728 -334.305148)
		(stroke
			(width 0.0635)
			(type default)
		)
		(layer "B.Cu")
	)
	(gr_arc
		(start 279.209754 -330.705206)
		(mid 279.119951 -330.742403)
		(end 279.082754 -330.832206)
		(stroke
			(width 0.0635)
			(type default)
		)
		(layer "B.Cu")
	)
	(gr_line
		(start 279.209754 -330.705206)
		(end 279.636728 -330.705206)
		(stroke
			(width 0.0635)
			(type default)
		)
		(layer "B.Cu")
	)
	(gr_arc
		(start 279.209754 -327.105264)
		(mid 279.119951 -327.142461)
		(end 279.082754 -327.232264)
		(stroke
			(width 0.0635)
			(type default)
		)
		(layer "B.Cu")
	)
	(gr_line
		(start 279.209754 -327.105264)
		(end 279.636728 -327.105264)
		(stroke
			(width 0.0635)
			(type default)
		)
		(layer "B.Cu")
	)
	(gr_arc
		(start 279.209754 -312.704988)
		(mid 279.130631 -312.732375)
		(end 279.085802 -312.803032)
		(stroke
			(width 0.0635)
			(type default)
		)
		(layer "B.Cu")
	)
	(gr_line
		(start 279.209754 -312.704988)
		(end 279.636474 -312.704988)
		(stroke
			(width 0.0635)
			(type default)
		)
		(layer "B.Cu")
	)
	(gr_arc
		(start 279.209754 -309.105046)
		(mid 279.119951 -309.142243)
		(end 279.082754 -309.232046)
		(stroke
			(width 0.0635)
			(type default)
		)
		(layer "B.Cu")
	)
	(gr_line
		(start 279.209754 -309.105046)
		(end 279.636728 -309.105046)
		(stroke
			(width 0.0635)
			(type default)
		)
		(layer "B.Cu")
	)
	(gr_arc
		(start 279.209754 -305.505104)
		(mid 279.119951 -305.542301)
		(end 279.082754 -305.632104)
		(stroke
			(width 0.0635)
			(type default)
		)
		(layer "B.Cu")
	)
	(gr_line
		(start 279.209754 -305.505104)
		(end 279.636728 -305.505104)
		(stroke
			(width 0.0635)
			(type default)
		)
		(layer "B.Cu")
	)
	(gr_line
		(start 279.236678 -357.705152)
		(end 279.663652 -357.705152)
		(stroke
			(width 0.0635)
			(type default)
		)
		(layer "B.Cu")
	)
	(gr_line
		(start 279.236678 -354.10521)
		(end 279.663652 -354.10521)
		(stroke
			(width 0.0635)
			(type default)
		)
		(layer "B.Cu")
	)
	(gr_line
		(start 279.236678 -350.505268)
		(end 279.663652 -350.505268)
		(stroke
			(width 0.0635)
			(type default)
		)
		(layer "B.Cu")
	)
	(gr_line
		(start 279.236678 -336.105246)
		(end 279.663652 -336.105246)
		(stroke
			(width 0.0635)
			(type default)
		)
		(layer "B.Cu")
	)
	(gr_line
		(start 279.236678 -332.50505)
		(end 279.663652 -332.50505)
		(stroke
			(width 0.0635)
			(type default)
		)
		(layer "B.Cu")
	)
	(gr_line
		(start 279.236678 -328.905108)
		(end 279.663652 -328.905108)
		(stroke
			(width 0.0635)
			(type default)
		)
		(layer "B.Cu")
	)
	(gr_line
		(start 279.236678 -314.505086)
		(end 279.663652 -314.505086)
		(stroke
			(width 0.0635)
			(type default)
		)
		(layer "B.Cu")
	)
	(gr_line
		(start 279.236678 -310.905144)
		(end 279.663652 -310.905144)
		(stroke
			(width 0.0635)
			(type default)
		)
		(layer "B.Cu")
	)
	(gr_line
		(start 279.236678 -307.305202)
		(end 279.663652 -307.305202)
		(stroke
			(width 0.0635)
			(type default)
		)
		(layer "B.Cu")
	)
	(gr_line
		(start 279.34539 -93.050868)
		(end 279.356566 -93.05798)
		(stroke
			(width 0.08255)
			(type default)
		)
		(layer "B.Cu")
	)
	(gr_line
		(start 279.356566 -93.05798)
		(end 279.369012 -93.060774)
		(stroke
			(width 0.08255)
			(type default)
		)
		(layer "B.Cu")
	)
	(gr_arc
		(start 279.423622 -178.162458)
		(mid 279.484104 -178.111436)
		(end 279.514808 -178.038506)
		(stroke
			(width 0.08255)
			(type default)
		)
		(layer "B.Cu")
	)
	(gr_arc
		(start 279.423622 -174.162466)
		(mid 279.484106 -174.111445)
		(end 279.514808 -174.038514)
		(stroke
			(width 0.08255)
			(type default)
		)
		(layer "B.Cu")
	)
	(gr_arc
		(start 279.423622 -170.162474)
		(mid 279.484109 -170.111454)
		(end 279.514808 -170.038522)
		(stroke
			(width 0.08255)
			(type default)
		)
		(layer "B.Cu")
	)
	(gr_arc
		(start 279.423622 -166.162482)
		(mid 279.484111 -166.111463)
		(end 279.514808 -166.03853)
		(stroke
			(width 0.08255)
			(type default)
		)
		(layer "B.Cu")
	)
	(gr_arc
		(start 279.423622 -49.86274)
		(mid 279.484104 -49.811717)
		(end 279.514808 -49.738788)
		(stroke
			(width 0.08255)
			(type default)
		)
		(layer "B.Cu")
	)
	(gr_arc
		(start 279.423622 -45.862748)
		(mid 279.484101 -45.811725)
		(end 279.514808 -45.738796)
		(stroke
			(width 0.08255)
			(type default)
		)
		(layer "B.Cu")
	)
	(gr_arc
		(start 279.423622 -41.862756)
		(mid 279.484103 -41.811734)
		(end 279.514808 -41.738804)
		(stroke
			(width 0.08255)
			(type default)
		)
		(layer "B.Cu")
	)
	(gr_arc
		(start 279.423622 -37.862764)
		(mid 279.484106 -37.811743)
		(end 279.514808 -37.738812)
		(stroke
			(width 0.08255)
			(type default)
		)
		(layer "B.Cu")
	)
	(gr_arc
		(start 279.471882 -162.138614)
		(mid 279.554625 -162.043124)
		(end 279.545542 -161.917126)
		(stroke
			(width 0.08255)
			(type default)
		)
		(layer "B.Cu")
	)
	(gr_arc
		(start 279.471882 -158.138622)
		(mid 279.55463 -158.043132)
		(end 279.545542 -157.917134)
		(stroke
			(width 0.08255)
			(type default)
		)
		(layer "B.Cu")
	)
	(gr_arc
		(start 279.471882 -154.13863)
		(mid 279.554572 -154.043147)
		(end 279.545542 -153.917142)
		(stroke
			(width 0.08255)
			(type default)
		)
		(layer "B.Cu")
	)
	(gr_arc
		(start 279.471882 -150.138638)
		(mid 279.554577 -150.043155)
		(end 279.545542 -149.91715)
		(stroke
			(width 0.08255)
			(type default)
		)
		(layer "B.Cu")
	)
	(gr_arc
		(start 279.471882 -130.138678)
		(mid 279.554602 -130.043191)
		(end 279.545542 -129.91719)
		(stroke
			(width 0.08255)
			(type default)
		)
		(layer "B.Cu")
	)
	(gr_arc
		(start 279.471882 -126.138686)
		(mid 279.554607 -126.043199)
		(end 279.545542 -125.917198)
		(stroke
			(width 0.08255)
			(type default)
		)
		(layer "B.Cu")
	)
	(gr_arc
		(start 279.471882 -122.138694)
		(mid 279.554613 -122.043206)
		(end 279.545542 -121.917206)
		(stroke
			(width 0.08255)
			(type default)
		)
		(layer "B.Cu")
	)
	(gr_arc
		(start 279.471882 -118.138702)
		(mid 279.554618 -118.043213)
		(end 279.545542 -117.917214)
		(stroke
			(width 0.08255)
			(type default)
		)
		(layer "B.Cu")
	)
	(gr_line
		(start 279.510744 -186.734958)
		(end 279.523698 -186.745372)
		(stroke
			(width 0.08255)
			(type default)
		)
		(layer "B.Cu")
	)
	(gr_arc
		(start 279.514808 -178.038506)
		(mid 279.508802 -177.959778)
		(end 279.467564 -177.892456)
		(stroke
			(width 0.08255)
			(type default)
		)
		(layer "B.Cu")
	)
	(gr_arc
		(start 279.514808 -174.038514)
		(mid 279.508806 -173.959785)
		(end 279.467564 -173.892464)
		(stroke
			(width 0.08255)
			(type default)
		)
		(layer "B.Cu")
	)
	(gr_arc
		(start 279.514808 -170.038522)
		(mid 279.508809 -169.959791)
		(end 279.467564 -169.892472)
		(stroke
			(width 0.08255)
			(type default)
		)
		(layer "B.Cu")
	)
	(gr_arc
		(start 279.514808 -166.03853)
		(mid 279.508771 -165.959821)
		(end 279.467564 -165.89248)
		(stroke
			(width 0.08255)
			(type default)
		)
		(layer "B.Cu")
	)
	(gr_arc
		(start 279.514808 -49.738788)
		(mid 279.508713 -49.660104)
		(end 279.467564 -49.592738)
		(stroke
			(width 0.08255)
			(type default)
		)
		(layer "B.Cu")
	)
	(gr_arc
		(start 279.514808 -45.738796)
		(mid 279.508798 -45.660071)
		(end 279.467564 -45.592746)
		(stroke
			(width 0.08255)
			(type default)
		)
		(layer "B.Cu")
	)
	(gr_arc
		(start 279.514808 -41.738804)
		(mid 279.508801 -41.660077)
		(end 279.467564 -41.592754)
		(stroke
			(width 0.08255)
			(type default)
		)
		(layer "B.Cu")
	)
	(gr_arc
		(start 279.514808 -37.738812)
		(mid 279.508805 -37.660083)
		(end 279.467564 -37.592762)
		(stroke
			(width 0.08255)
			(type default)
		)
		(layer "B.Cu")
	)
	(gr_line
		(start 279.523698 -186.745372)
		(end 279.539192 -186.750198)
		(stroke
			(width 0.08255)
			(type default)
		)
		(layer "B.Cu")
	)
	(gr_arc
		(start 279.566116 -81.836514)
		(mid 279.486422 -81.836651)
		(end 279.410668 -81.861406)
		(stroke
			(width 0.08255)
			(type default)
		)
		(layer "B.Cu")
	)
	(gr_line
		(start 279.566116 -81.836514)
		(end 279.58161 -81.839054)
		(stroke
			(width 0.08255)
			(type default)
		)
		(layer "B.Cu")
	)
	(gr_arc
		(start 279.566116 -77.836522)
		(mid 279.486422 -77.836659)
		(end 279.410668 -77.861414)
		(stroke
			(width 0.08255)
			(type default)
		)
		(layer "B.Cu")
	)
	(gr_line
		(start 279.566116 -77.836522)
		(end 279.58161 -77.839062)
		(stroke
			(width 0.08255)
			(type default)
		)
		(layer "B.Cu")
	)
	(gr_arc
		(start 279.566116 -73.83653)
		(mid 279.486422 -73.836667)
		(end 279.410668 -73.861422)
		(stroke
			(width 0.08255)
			(type default)
		)
		(layer "B.Cu")
	)
	(gr_line
		(start 279.566116 -73.83653)
		(end 279.58161 -73.83907)
		(stroke
			(width 0.08255)
			(type default)
		)
		(layer "B.Cu")
	)
	(gr_arc
		(start 279.566116 -69.836538)
		(mid 279.486423 -69.836675)
		(end 279.410668 -69.86143)
		(stroke
			(width 0.08255)
			(type default)
		)
		(layer "B.Cu")
	)
	(gr_line
		(start 279.566116 -69.836538)
		(end 279.58161 -69.839078)
		(stroke
			(width 0.08255)
			(type default)
		)
		(layer "B.Cu")
	)
	(gr_arc
		(start 279.566116 -65.836546)
		(mid 279.486423 -65.836683)
		(end 279.410668 -65.861438)
		(stroke
			(width 0.08255)
			(type default)
		)
		(layer "B.Cu")
	)
	(gr_line
		(start 279.566116 -65.836546)
		(end 279.58161 -65.839086)
		(stroke
			(width 0.08255)
			(type default)
		)
		(layer "B.Cu")
	)
	(gr_arc
		(start 279.566116 -61.836554)
		(mid 279.486422 -61.836691)
		(end 279.410668 -61.861446)
		(stroke
			(width 0.08255)
			(type default)
		)
		(layer "B.Cu")
	)
	(gr_line
		(start 279.566116 -61.836554)
		(end 279.58161 -61.839094)
		(stroke
			(width 0.08255)
			(type default)
		)
		(layer "B.Cu")
	)
	(gr_arc
		(start 279.566116 -57.836562)
		(mid 279.486422 -57.836699)
		(end 279.410668 -57.861454)
		(stroke
			(width 0.08255)
			(type default)
		)
		(layer "B.Cu")
	)
	(gr_line
		(start 279.566116 -57.836562)
		(end 279.58161 -57.839102)
		(stroke
			(width 0.08255)
			(type default)
		)
		(layer "B.Cu")
	)
	(gr_arc
		(start 279.566116 -53.83657)
		(mid 279.486406 -53.836643)
		(end 279.410668 -53.861462)
		(stroke
			(width 0.08255)
			(type default)
		)
		(layer "B.Cu")
	)
	(gr_line
		(start 279.566116 -53.83657)
		(end 279.58161 -53.83911)
		(stroke
			(width 0.08255)
			(type default)
		)
		(layer "B.Cu")
	)
	(gr_line
		(start 279.636474 -312.704988)
		(end 279.636728 -312.705242)
		(stroke
			(width 0.0635)
			(type default)
		)
		(layer "B.Cu")
	)
	(gr_line
		(start 279.714452 -161.601912)
		(end 279.715976 -161.604706)
		(stroke
			(width 0.08255)
			(type default)
		)
		(layer "B.Cu")
	)
	(gr_line
		(start 279.714452 -157.60192)
		(end 279.715976 -157.604714)
		(stroke
			(width 0.08255)
			(type default)
		)
		(layer "B.Cu")
	)
	(gr_line
		(start 279.714452 -153.601928)
		(end 279.715976 -153.604722)
		(stroke
			(width 0.08255)
			(type default)
		)
		(layer "B.Cu")
	)
	(gr_line
		(start 279.714452 -149.601936)
		(end 279.715976 -149.60473)
		(stroke
			(width 0.08255)
			(type default)
		)
		(layer "B.Cu")
	)
	(gr_line
		(start 279.714452 -129.601976)
		(end 279.715976 -129.60477)
		(stroke
			(width 0.08255)
			(type default)
		)
		(layer "B.Cu")
	)
	(gr_line
		(start 279.714452 -125.601984)
		(end 279.715976 -125.604778)
		(stroke
			(width 0.08255)
			(type default)
		)
		(layer "B.Cu")
	)
	(gr_line
		(start 279.714452 -121.601992)
		(end 279.715976 -121.604786)
		(stroke
			(width 0.08255)
			(type default)
		)
		(layer "B.Cu")
	)
	(gr_line
		(start 279.714452 -117.602)
		(end 279.715976 -117.604794)
		(stroke
			(width 0.08255)
			(type default)
		)
		(layer "B.Cu")
	)
	(gr_arc
		(start 279.721818 -81.910174)
		(mid 279.657357 -81.863492)
		(end 279.58161 -81.839054)
		(stroke
			(width 0.08255)
			(type default)
		)
		(layer "B.Cu")
	)
	(gr_arc
		(start 279.721818 -77.910182)
		(mid 279.657358 -77.863499)
		(end 279.58161 -77.839062)
		(stroke
			(width 0.08255)
			(type default)
		)
		(layer "B.Cu")
	)
	(gr_arc
		(start 279.721818 -73.91019)
		(mid 279.657358 -73.863505)
		(end 279.58161 -73.83907)
		(stroke
			(width 0.08255)
			(type default)
		)
		(layer "B.Cu")
	)
	(gr_arc
		(start 279.721818 -69.910198)
		(mid 279.657359 -69.863512)
		(end 279.58161 -69.839078)
		(stroke
			(width 0.08255)
			(type default)
		)
		(layer "B.Cu")
	)
	(gr_arc
		(start 279.721818 -65.910206)
		(mid 279.65736 -65.863518)
		(end 279.58161 -65.839086)
		(stroke
			(width 0.08255)
			(type default)
		)
		(layer "B.Cu")
	)
	(gr_arc
		(start 279.721818 -61.910214)
		(mid 279.657354 -61.863542)
		(end 279.58161 -61.839094)
		(stroke
			(width 0.08255)
			(type default)
		)
		(layer "B.Cu")
	)
	(gr_arc
		(start 279.721818 -57.910222)
		(mid 279.657354 -57.863549)
		(end 279.58161 -57.839102)
		(stroke
			(width 0.08255)
			(type default)
		)
		(layer "B.Cu")
	)
	(gr_arc
		(start 279.721818 -53.91023)
		(mid 279.657352 -53.863558)
		(end 279.58161 -53.83911)
		(stroke
			(width 0.08255)
			(type default)
		)
		(layer "B.Cu")
	)
	(gr_arc
		(start 279.778206 -177.789586)
		(mid 279.842672 -177.836258)
		(end 279.918414 -177.860706)
		(stroke
			(width 0.08255)
			(type default)
		)
		(layer "B.Cu")
	)
	(gr_arc
		(start 279.778206 -173.789594)
		(mid 279.842672 -173.836266)
		(end 279.918414 -173.860714)
		(stroke
			(width 0.08255)
			(type default)
		)
		(layer "B.Cu")
	)
	(gr_arc
		(start 279.778206 -169.789602)
		(mid 279.842672 -169.836274)
		(end 279.918414 -169.860722)
		(stroke
			(width 0.08255)
			(type default)
		)
		(layer "B.Cu")
	)
	(gr_arc
		(start 279.778206 -165.78961)
		(mid 279.842672 -165.836282)
		(end 279.918414 -165.86073)
		(stroke
			(width 0.08255)
			(type default)
		)
		(layer "B.Cu")
	)
	(gr_arc
		(start 279.778206 -49.489868)
		(mid 279.842663 -49.536561)
		(end 279.918414 -49.560988)
		(stroke
			(width 0.08255)
			(type default)
		)
		(layer "B.Cu")
	)
	(gr_arc
		(start 279.778206 -45.489876)
		(mid 279.842664 -45.536568)
		(end 279.918414 -45.560996)
		(stroke
			(width 0.08255)
			(type default)
		)
		(layer "B.Cu")
	)
	(gr_arc
		(start 279.778206 -41.489884)
		(mid 279.842672 -41.536556)
		(end 279.918414 -41.561004)
		(stroke
			(width 0.08255)
			(type default)
		)
		(layer "B.Cu")
	)
	(gr_arc
		(start 279.778206 -37.489892)
		(mid 279.842659 -37.536599)
		(end 279.918414 -37.561012)
		(stroke
			(width 0.08255)
			(type default)
		)
		(layer "B.Cu")
	)
	(gr_arc
		(start 279.790652 -357.832152)
		(mid 279.753455 -357.742349)
		(end 279.663652 -357.705152)
		(stroke
			(width 0.0635)
			(type default)
		)
		(layer "B.Cu")
	)
	(gr_arc
		(start 279.790652 -354.23221)
		(mid 279.753455 -354.142407)
		(end 279.663652 -354.10521)
		(stroke
			(width 0.0635)
			(type default)
		)
		(layer "B.Cu")
	)
	(gr_arc
		(start 279.790652 -350.632268)
		(mid 279.753455 -350.542465)
		(end 279.663652 -350.505268)
		(stroke
			(width 0.0635)
			(type default)
		)
		(layer "B.Cu")
	)
	(gr_arc
		(start 279.790652 -336.232246)
		(mid 279.753455 -336.142443)
		(end 279.663652 -336.105246)
		(stroke
			(width 0.0635)
			(type default)
		)
		(layer "B.Cu")
	)
	(gr_arc
		(start 279.790652 -332.63205)
		(mid 279.753455 -332.542247)
		(end 279.663652 -332.50505)
		(stroke
			(width 0.0635)
			(type default)
		)
		(layer "B.Cu")
	)
	(gr_arc
		(start 279.790652 -329.032108)
		(mid 279.753455 -328.942305)
		(end 279.663652 -328.905108)
		(stroke
			(width 0.0635)
			(type default)
		)
		(layer "B.Cu")
	)
	(gr_arc
		(start 279.790652 -314.632086)
		(mid 279.753455 -314.542283)
		(end 279.663652 -314.505086)
		(stroke
			(width 0.0635)
			(type default)
		)
		(layer "B.Cu")
	)
	(gr_arc
		(start 279.790652 -311.032144)
		(mid 279.753455 -310.942341)
		(end 279.663652 -310.905144)
		(stroke
			(width 0.0635)
			(type default)
		)
		(layer "B.Cu")
	)
	(gr_arc
		(start 279.790652 -307.432202)
		(mid 279.753455 -307.342399)
		(end 279.663652 -307.305202)
		(stroke
			(width 0.0635)
			(type default)
		)
		(layer "B.Cu")
	)
	(gr_arc
		(start 279.807162 -161.786824)
		(mid 279.902579 -161.869636)
		(end 280.02865 -161.860738)
		(stroke
			(width 0.08255)
			(type default)
		)
		(layer "B.Cu")
	)
	(gr_arc
		(start 279.807162 -157.786832)
		(mid 279.902579 -157.869644)
		(end 280.02865 -157.860746)
		(stroke
			(width 0.08255)
			(type default)
		)
		(layer "B.Cu")
	)
	(gr_arc
		(start 279.807162 -153.78684)
		(mid 279.902579 -153.869652)
		(end 280.02865 -153.860754)
		(stroke
			(width 0.08255)
			(type default)
		)
		(layer "B.Cu")
	)
	(gr_arc
		(start 279.807162 -149.786848)
		(mid 279.902579 -149.86966)
		(end 280.02865 -149.860762)
		(stroke
			(width 0.08255)
			(type default)
		)
		(layer "B.Cu")
	)
	(gr_arc
		(start 279.807162 -129.786888)
		(mid 279.902579 -129.8697)
		(end 280.02865 -129.860802)
		(stroke
			(width 0.08255)
			(type default)
		)
		(layer "B.Cu")
	)
	(gr_arc
		(start 279.807162 -125.786896)
		(mid 279.902579 -125.869708)
		(end 280.02865 -125.86081)
		(stroke
			(width 0.08255)
			(type default)
		)
		(layer "B.Cu")
	)
	(gr_arc
		(start 279.807162 -121.786904)
		(mid 279.902579 -121.869716)
		(end 280.02865 -121.860818)
		(stroke
			(width 0.08255)
			(type default)
		)
		(layer "B.Cu")
	)
	(gr_arc
		(start 279.807162 -117.786912)
		(mid 279.902579 -117.869724)
		(end 280.02865 -117.860826)
		(stroke
			(width 0.08255)
			(type default)
		)
		(layer "B.Cu")
	)
	(gr_line
		(start 279.918414 -177.860706)
		(end 279.933908 -177.863246)
		(stroke
			(width 0.08255)
			(type default)
		)
		(layer "B.Cu")
	)
	(gr_line
		(start 279.918414 -173.860714)
		(end 279.933908 -173.863254)
		(stroke
			(width 0.08255)
			(type default)
		)
		(layer "B.Cu")
	)
	(gr_line
		(start 279.918414 -169.860722)
		(end 279.933908 -169.863262)
		(stroke
			(width 0.08255)
			(type default)
		)
		(layer "B.Cu")
	)
	(gr_line
		(start 279.918414 -165.86073)
		(end 279.933908 -165.86327)
		(stroke
			(width 0.08255)
			(type default)
		)
		(layer "B.Cu")
	)
	(gr_line
		(start 279.918414 -49.560988)
		(end 279.933908 -49.563528)
		(stroke
			(width 0.08255)
			(type default)
		)
		(layer "B.Cu")
	)
	(gr_line
		(start 279.918414 -45.560996)
		(end 279.933908 -45.563536)
		(stroke
			(width 0.08255)
			(type default)
		)
		(layer "B.Cu")
	)
	(gr_line
		(start 279.918414 -41.561004)
		(end 279.933908 -41.563544)
		(stroke
			(width 0.08255)
			(type default)
		)
		(layer "B.Cu")
	)
	(gr_line
		(start 279.918414 -37.561012)
		(end 279.933908 -37.563552)
		(stroke
			(width 0.08255)
			(type default)
		)
		(layer "B.Cu")
	)
	(gr_arc
		(start 279.933908 -177.863246)
		(mid 280.013618 -177.863173)
		(end 280.089356 -177.838354)
		(stroke
			(width 0.08255)
			(type default)
		)
		(layer "B.Cu")
	)
	(gr_arc
		(start 279.933908 -173.863254)
		(mid 280.013618 -173.863181)
		(end 280.089356 -173.838362)
		(stroke
			(width 0.08255)
			(type default)
		)
		(layer "B.Cu")
	)
	(gr_arc
		(start 279.933908 -169.863262)
		(mid 280.013618 -169.863189)
		(end 280.089356 -169.83837)
		(stroke
			(width 0.08255)
			(type default)
		)
		(layer "B.Cu")
	)
	(gr_arc
		(start 279.933908 -165.86327)
		(mid 280.013618 -165.863197)
		(end 280.089356 -165.838378)
		(stroke
			(width 0.08255)
			(type default)
		)
		(layer "B.Cu")
	)
	(gr_arc
		(start 279.933908 -49.563528)
		(mid 280.013609 -49.563414)
		(end 280.089356 -49.538636)
		(stroke
			(width 0.08255)
			(type default)
		)
		(layer "B.Cu")
	)
	(gr_arc
		(start 279.933908 -45.563536)
		(mid 280.013609 -45.563422)
		(end 280.089356 -45.538644)
		(stroke
			(width 0.08255)
			(type default)
		)
		(layer "B.Cu")
	)
	(gr_arc
		(start 279.933908 -41.563544)
		(mid 280.013618 -41.563471)
		(end 280.089356 -41.538652)
		(stroke
			(width 0.08255)
			(type default)
		)
		(layer "B.Cu")
	)
	(gr_arc
		(start 279.933908 -37.563552)
		(mid 280.01361 -37.563438)
		(end 280.089356 -37.53866)
		(stroke
			(width 0.08255)
			(type default)
		)
		(layer "B.Cu")
	)
	(gr_arc
		(start 279.985216 -81.661254)
		(mid 279.991311 -81.739938)
		(end 280.03246 -81.807304)
		(stroke
			(width 0.08255)
			(type default)
		)
		(layer "B.Cu")
	)
	(gr_arc
		(start 279.985216 -77.661262)
		(mid 279.991311 -77.739946)
		(end 280.03246 -77.807312)
		(stroke
			(width 0.08255)
			(type default)
		)
		(layer "B.Cu")
	)
	(gr_arc
		(start 279.985216 -73.66127)
		(mid 279.991311 -73.739954)
		(end 280.03246 -73.80732)
		(stroke
			(width 0.08255)
			(type default)
		)
		(layer "B.Cu")
	)
	(gr_arc
		(start 279.985216 -69.661278)
		(mid 279.991311 -69.739962)
		(end 280.03246 -69.807328)
		(stroke
			(width 0.08255)
			(type default)
		)
		(layer "B.Cu")
	)
	(gr_arc
		(start 279.985216 -65.661286)
		(mid 279.991311 -65.73997)
		(end 280.03246 -65.807336)
		(stroke
			(width 0.08255)
			(type default)
		)
		(layer "B.Cu")
	)
	(gr_arc
		(start 279.985216 -61.661294)
		(mid 279.991311 -61.739978)
		(end 280.03246 -61.807344)
		(stroke
			(width 0.08255)
			(type default)
		)
		(layer "B.Cu")
	)
	(gr_arc
		(start 279.985216 -57.661302)
		(mid 279.991311 -57.739986)
		(end 280.03246 -57.807352)
		(stroke
			(width 0.08255)
			(type default)
		)
		(layer "B.Cu")
	)
	(gr_arc
		(start 279.985216 -53.66131)
		(mid 279.991311 -53.739994)
		(end 280.03246 -53.80736)
		(stroke
			(width 0.08255)
			(type default)
		)
		(layer "B.Cu")
	)
	(gr_line
		(start 280.02865 -161.860738)
		(end 280.75001 -161.499804)
		(stroke
			(width 0.08255)
			(type default)
		)
		(layer "B.Cu")
	)
	(gr_line
		(start 280.02865 -157.860746)
		(end 280.75001 -157.499812)
		(stroke
			(width 0.08255)
			(type default)
		)
		(layer "B.Cu")
	)
	(gr_line
		(start 280.02865 -153.860754)
		(end 280.75001 -153.49982)
		(stroke
			(width 0.08255)
			(type default)
		)
		(layer "B.Cu")
	)
	(gr_line
		(start 280.02865 -149.860762)
		(end 280.75001 -149.499828)
		(stroke
			(width 0.08255)
			(type default)
		)
		(layer "B.Cu")
	)
	(gr_line
		(start 280.02865 -129.860802)
		(end 280.75001 -129.499868)
		(stroke
			(width 0.08255)
			(type default)
		)
		(layer "B.Cu")
	)
	(gr_line
		(start 280.02865 -125.86081)
		(end 280.75001 -125.499876)
		(stroke
			(width 0.08255)
			(type default)
		)
		(layer "B.Cu")
	)
	(gr_line
		(start 280.02865 -121.860818)
		(end 280.75001 -121.499884)
		(stroke
			(width 0.08255)
			(type default)
		)
		(layer "B.Cu")
	)
	(gr_line
		(start 280.02865 -117.860826)
		(end 280.75001 -117.499892)
		(stroke
			(width 0.08255)
			(type default)
		)
		(layer "B.Cu")
	)
	(gr_arc
		(start 280.076402 -81.537302)
		(mid 280.01592 -81.588325)
		(end 279.985216 -81.661254)
		(stroke
			(width 0.08255)
			(type default)
		)
		(layer "B.Cu")
	)
	(gr_line
		(start 280.076402 -81.537302)
		(end 280.75001 -81.19999)
		(stroke
			(width 0.08255)
			(type default)
		)
		(layer "B.Cu")
	)
	(gr_arc
		(start 280.076402 -77.53731)
		(mid 280.01592 -77.588333)
		(end 279.985216 -77.661262)
		(stroke
			(width 0.08255)
			(type default)
		)
		(layer "B.Cu")
	)
	(gr_line
		(start 280.076402 -77.53731)
		(end 280.75001 -77.199998)
		(stroke
			(width 0.08255)
			(type default)
		)
		(layer "B.Cu")
	)
	(gr_arc
		(start 280.076402 -73.537318)
		(mid 280.01592 -73.588341)
		(end 279.985216 -73.66127)
		(stroke
			(width 0.08255)
			(type default)
		)
		(layer "B.Cu")
	)
	(gr_line
		(start 280.076402 -73.537318)
		(end 280.75001 -73.200006)
		(stroke
			(width 0.08255)
			(type default)
		)
		(layer "B.Cu")
	)
	(gr_arc
		(start 280.076402 -69.537326)
		(mid 280.01592 -69.588349)
		(end 279.985216 -69.661278)
		(stroke
			(width 0.08255)
			(type default)
		)
		(layer "B.Cu")
	)
	(gr_line
		(start 280.076402 -69.537326)
		(end 280.75001 -69.200014)
		(stroke
			(width 0.08255)
			(type default)
		)
		(layer "B.Cu")
	)
	(gr_arc
		(start 280.076402 -65.537334)
		(mid 280.01592 -65.588357)
		(end 279.985216 -65.661286)
		(stroke
			(width 0.08255)
			(type default)
		)
		(layer "B.Cu")
	)
	(gr_line
		(start 280.076402 -65.537334)
		(end 280.75001 -65.200022)
		(stroke
			(width 0.08255)
			(type default)
		)
		(layer "B.Cu")
	)
	(gr_arc
		(start 280.076402 -61.537342)
		(mid 280.01592 -61.588365)
		(end 279.985216 -61.661294)
		(stroke
			(width 0.08255)
			(type default)
		)
		(layer "B.Cu")
	)
	(gr_line
		(start 280.076402 -61.537342)
		(end 280.75001 -61.20003)
		(stroke
			(width 0.08255)
			(type default)
		)
		(layer "B.Cu")
	)
	(gr_arc
		(start 280.076402 -57.53735)
		(mid 280.01592 -57.588373)
		(end 279.985216 -57.661302)
		(stroke
			(width 0.08255)
			(type default)
		)
		(layer "B.Cu")
	)
	(gr_line
		(start 280.076402 -57.53735)
		(end 280.75001 -57.200038)
		(stroke
			(width 0.08255)
			(type default)
		)
		(layer "B.Cu")
	)
	(gr_arc
		(start 280.076402 -53.537358)
		(mid 280.01592 -53.588381)
		(end 279.985216 -53.66131)
		(stroke
			(width 0.08255)
			(type default)
		)
		(layer "B.Cu")
	)
	(gr_line
		(start 280.076402 -53.537358)
		(end 280.75001 -53.200046)
		(stroke
			(width 0.08255)
			(type default)
		)
		(layer "B.Cu")
	)
	(gr_line
		(start 280.089356 -177.838354)
		(end 280.75001 -177.499772)
		(stroke
			(width 0.08255)
			(type default)
		)
		(layer "B.Cu")
	)
	(gr_line
		(start 280.089356 -173.838362)
		(end 280.75001 -173.49978)
		(stroke
			(width 0.08255)
			(type default)
		)
		(layer "B.Cu")
	)
	(gr_line
		(start 280.089356 -169.83837)
		(end 280.75001 -169.499788)
		(stroke
			(width 0.08255)
			(type default)
		)
		(layer "B.Cu")
	)
	(gr_line
		(start 280.089356 -165.838378)
		(end 280.75001 -165.499796)
		(stroke
			(width 0.08255)
			(type default)
		)
		(layer "B.Cu")
	)
	(gr_line
		(start 280.089356 -49.538636)
		(end 280.75001 -49.200054)
		(stroke
			(width 0.08255)
			(type default)
		)
		(layer "B.Cu")
	)
	(gr_line
		(start 280.089356 -45.538644)
		(end 280.75001 -45.200062)
		(stroke
			(width 0.08255)
			(type default)
		)
		(layer "B.Cu")
	)
	(gr_line
		(start 280.089356 -41.538652)
		(end 280.75001 -41.20007)
		(stroke
			(width 0.08255)
			(type default)
		)
		(layer "B.Cu")
	)
	(gr_line
		(start 280.089356 -37.53866)
		(end 280.75001 -37.200078)
		(stroke
			(width 0.08255)
			(type default)
		)
		(layer "B.Cu")
	)
	(gr_line
		(start 280.124154 -91.469972)
		(end 280.13533 -91.477084)
		(stroke
			(width 0.08255)
			(type default)
		)
		(layer "B.Cu")
	)
	(gr_line
		(start 280.13533 -91.477084)
		(end 280.147776 -91.479878)
		(stroke
			(width 0.08255)
			(type default)
		)
		(layer "B.Cu")
	)
	(gr_arc
		(start 280.209752 -357.705152)
		(mid 280.119963 -357.742363)
		(end 280.082752 -357.832152)
		(stroke
			(width 0.0635)
			(type default)
		)
		(layer "B.Cu")
	)
	(gr_line
		(start 280.209752 -357.705152)
		(end 280.636726 -357.705152)
		(stroke
			(width 0.0635)
			(type default)
		)
		(layer "B.Cu")
	)
	(gr_arc
		(start 280.209752 -354.10521)
		(mid 280.119984 -354.142425)
		(end 280.082752 -354.23221)
		(stroke
			(width 0.0635)
			(type default)
		)
		(layer "B.Cu")
	)
	(gr_line
		(start 280.209752 -354.10521)
		(end 280.636726 -354.10521)
		(stroke
			(width 0.0635)
			(type default)
		)
		(layer "B.Cu")
	)
	(gr_arc
		(start 280.209752 -350.505268)
		(mid 280.119969 -350.54248)
		(end 280.082752 -350.632268)
		(stroke
			(width 0.0635)
			(type default)
		)
		(layer "B.Cu")
	)
	(gr_line
		(start 280.209752 -350.505268)
		(end 280.636726 -350.505268)
		(stroke
			(width 0.0635)
			(type default)
		)
		(layer "B.Cu")
	)
	(gr_arc
		(start 280.209752 -336.105246)
		(mid 280.119997 -336.142463)
		(end 280.082752 -336.232246)
		(stroke
			(width 0.0635)
			(type default)
		)
		(layer "B.Cu")
	)
	(gr_line
		(start 280.209752 -336.105246)
		(end 280.636726 -336.105246)
		(stroke
			(width 0.0635)
			(type default)
		)
		(layer "B.Cu")
	)
	(gr_arc
		(start 280.209752 -332.50505)
		(mid 280.119998 -332.542267)
		(end 280.082752 -332.63205)
		(stroke
			(width 0.0635)
			(type default)
		)
		(layer "B.Cu")
	)
	(gr_line
		(start 280.209752 -332.50505)
		(end 280.636726 -332.50505)
		(stroke
			(width 0.0635)
			(type default)
		)
		(layer "B.Cu")
	)
	(gr_arc
		(start 280.209752 -328.905108)
		(mid 280.119983 -328.942323)
		(end 280.082752 -329.032108)
		(stroke
			(width 0.0635)
			(type default)
		)
		(layer "B.Cu")
	)
	(gr_line
		(start 280.209752 -328.905108)
		(end 280.636726 -328.905108)
		(stroke
			(width 0.0635)
			(type default)
		)
		(layer "B.Cu")
	)
	(gr_arc
		(start 280.209752 -314.505086)
		(mid 280.119976 -314.5423)
		(end 280.082752 -314.632086)
		(stroke
			(width 0.0635)
			(type default)
		)
		(layer "B.Cu")
	)
	(gr_line
		(start 280.209752 -314.505086)
		(end 280.636726 -314.505086)
		(stroke
			(width 0.0635)
			(type default)
		)
		(layer "B.Cu")
	)
	(gr_arc
		(start 280.209752 -310.905144)
		(mid 280.119996 -310.942361)
		(end 280.082752 -311.032144)
		(stroke
			(width 0.0635)
			(type default)
		)
		(layer "B.Cu")
	)
	(gr_line
		(start 280.209752 -310.905144)
		(end 280.636726 -310.905144)
		(stroke
			(width 0.0635)
			(type default)
		)
		(layer "B.Cu")
	)
	(gr_arc
		(start 280.209752 -307.305202)
		(mid 280.119981 -307.342417)
		(end 280.082752 -307.432202)
		(stroke
			(width 0.0635)
			(type default)
		)
		(layer "B.Cu")
	)
	(gr_line
		(start 280.209752 -307.305202)
		(end 280.636726 -307.305202)
		(stroke
			(width 0.0635)
			(type default)
		)
		(layer "B.Cu")
	)
	(gr_line
		(start 280.731976 -89.93505)
		(end 280.743152 -89.942162)
		(stroke
			(width 0.08255)
			(type default)
		)
		(layer "B.Cu")
	)
	(gr_line
		(start 280.743152 -89.942162)
		(end 280.755598 -89.944956)
		(stroke
			(width 0.08255)
			(type default)
		)
		(layer "B.Cu")
	)
	(gr_line
		(start 281.4193 -189.088268)
		(end 281.472894 -189.105286)
		(stroke
			(width 0.08255)
			(type default)
		)
		(layer "B.Cu")
	)
	(gr_line
		(start 281.46502 -192.612518)
		(end 281.51836 -192.629536)
		(stroke
			(width 0.08255)
			(type default)
		)
		(layer "B.Cu")
	)
	(gr_line
		(start 281.472894 -189.105286)
		(end 281.526488 -189.088268)
		(stroke
			(width 0.08255)
			(type default)
		)
		(layer "B.Cu")
	)
	(gr_line
		(start 281.513534 -187.381134)
		(end 281.567128 -187.398152)
		(stroke
			(width 0.08255)
			(type default)
		)
		(layer "B.Cu")
	)
	(gr_line
		(start 281.51836 -192.629536)
		(end 281.571192 -192.612518)
		(stroke
			(width 0.08255)
			(type default)
		)
		(layer "B.Cu")
	)
	(gr_line
		(start 281.567128 -187.398152)
		(end 281.620722 -187.381134)
		(stroke
			(width 0.08255)
			(type default)
		)
		(layer "B.Cu")
	)
	(gr_line
		(start 281.66187 -190.852552)
		(end 281.715464 -190.86957)
		(stroke
			(width 0.08255)
			(type default)
		)
		(layer "B.Cu")
	)
	(gr_line
		(start 281.715464 -190.86957)
		(end 281.769058 -190.852552)
		(stroke
			(width 0.08255)
			(type default)
		)
		(layer "B.Cu")
	)
	(gr_line
		(start 281.905964 -90.199972)
		(end 281.931618 -90.20556)
		(stroke
			(width 0.08255)
			(type default)
		)
		(layer "B.Cu")
	)
	(gr_line
		(start 281.931618 -90.20556)
		(end 281.957272 -90.199972)
		(stroke
			(width 0.08255)
			(type default)
		)
		(layer "B.Cu")
	)
	(gr_line
		(start 282.02255 -91.895676)
		(end 282.047188 -91.90101)
		(stroke
			(width 0.08255)
			(type default)
		)
		(layer "B.Cu")
	)
	(gr_line
		(start 282.047188 -91.90101)
		(end 282.071064 -91.89593)
		(stroke
			(width 0.08255)
			(type default)
		)
		(layer "B.Cu")
	)
	(gr_line
		(start 282.946094 -93.854016)
		(end 282.971748 -93.859604)
		(stroke
			(width 0.08255)
			(type default)
		)
		(layer "B.Cu")
	)
	(gr_line
		(start 282.971748 -93.859604)
		(end 282.997402 -93.854016)
		(stroke
			(width 0.08255)
			(type default)
		)
		(layer "B.Cu")
	)
	(gr_line
		(start 283.203396 -93.509084)
		(end 283.455364 -93.453204)
		(stroke
			(width 0.08255)
			(type default)
		)
		(layer "B.Cu")
	)
	(gr_line
		(start 283.266642 -93.794326)
		(end 283.521912 -93.737684)
		(stroke
			(width 0.08255)
			(type default)
		)
		(layer "B.Cu")
	)
	(gr_line
		(start 283.344112 -95.586042)
		(end 283.369766 -95.59163)
		(stroke
			(width 0.08255)
			(type default)
		)
		(layer "B.Cu")
	)
	(gr_line
		(start 283.369766 -95.59163)
		(end 283.39542 -95.586042)
		(stroke
			(width 0.08255)
			(type default)
		)
		(layer "B.Cu")
	)
	(gr_line
		(start 283.457396 -93.450156)
		(end 283.549852 -93.304614)
		(stroke
			(width 0.08255)
			(type default)
		)
		(layer "B.Cu")
	)
	(gr_line
		(start 283.549852 -93.304614)
		(end 284.033468 -93.197426)
		(stroke
			(width 0.08255)
			(type default)
		)
		(layer "B.Cu")
	)
	(gr_line
		(start 283.556456 -93.730064)
		(end 284.207712 -93.585792)
		(stroke
			(width 0.08255)
			(type default)
		)
		(layer "B.Cu")
	)
	(gr_line
		(start 283.931868 -186.643772)
		(end 283.948124 -186.638692)
		(stroke
			(width 0.08255)
			(type default)
		)
		(layer "B.Cu")
	)
	(gr_line
		(start 283.948124 -186.638692)
		(end 283.962348 -186.627262)
		(stroke
			(width 0.08255)
			(type default)
		)
		(layer "B.Cu")
	)
	(gr_line
		(start 284.033468 -93.197426)
		(end 284.178756 -93.290136)
		(stroke
			(width 0.08255)
			(type default)
		)
		(layer "B.Cu")
	)
	(gr_line
		(start 284.181804 -93.292168)
		(end 284.29204 -93.267784)
		(stroke
			(width 0.08255)
			(type default)
		)
		(layer "B.Cu")
	)
	(gr_line
		(start 284.667198 -93.181932)
		(end 284.759908 -93.03639)
		(stroke
			(width 0.08255)
			(type default)
		)
		(layer "B.Cu")
	)
	(gr_line
		(start 284.759908 -93.03639)
		(end 285.243524 -92.929202)
		(stroke
			(width 0.08255)
			(type default)
		)
		(layer "B.Cu")
	)
	(gr_line
		(start 284.764988 -93.462094)
		(end 285.418276 -93.31706)
		(stroke
			(width 0.08255)
			(type default)
		)
		(layer "B.Cu")
	)
	(gr_line
		(start 284.784292 -188.0489)
		(end 284.799786 -188.044074)
		(stroke
			(width 0.08255)
			(type default)
		)
		(layer "B.Cu")
	)
	(gr_line
		(start 284.799786 -188.044074)
		(end 284.81274 -188.03366)
		(stroke
			(width 0.08255)
			(type default)
		)
		(layer "B.Cu")
	)
	(gr_line
		(start 285.243524 -92.929202)
		(end 285.389066 -93.021912)
		(stroke
			(width 0.08255)
			(type default)
		)
		(layer "B.Cu")
	)
	(gr_line
		(start 285.284672 -189.730126)
		(end 285.300166 -189.7253)
		(stroke
			(width 0.08255)
			(type default)
		)
		(layer "B.Cu")
	)
	(gr_line
		(start 285.300166 -189.7253)
		(end 285.31312 -189.714886)
		(stroke
			(width 0.08255)
			(type default)
		)
		(layer "B.Cu")
	)
	(gr_line
		(start 285.436564 -345.105228)
		(end 285.863538 -345.105228)
		(stroke
			(width 0.0635)
			(type default)
		)
		(layer "B.Cu")
	)
	(gr_line
		(start 285.436564 -341.505032)
		(end 285.863538 -341.505032)
		(stroke
			(width 0.0635)
			(type default)
		)
		(layer "B.Cu")
	)
	(gr_line
		(start 285.436564 -337.90509)
		(end 285.863538 -337.90509)
		(stroke
			(width 0.0635)
			(type default)
		)
		(layer "B.Cu")
	)
	(gr_line
		(start 285.436564 -323.505068)
		(end 285.863538 -323.505068)
		(stroke
			(width 0.0635)
			(type default)
		)
		(layer "B.Cu")
	)
	(gr_line
		(start 285.436564 -319.905126)
		(end 285.863538 -319.905126)
		(stroke
			(width 0.0635)
			(type default)
		)
		(layer "B.Cu")
	)
	(gr_line
		(start 285.436564 -316.305184)
		(end 285.863538 -316.305184)
		(stroke
			(width 0.0635)
			(type default)
		)
		(layer "B.Cu")
	)
	(gr_line
		(start 285.436564 -301.905162)
		(end 285.863538 -301.905162)
		(stroke
			(width 0.0635)
			(type default)
		)
		(layer "B.Cu")
	)
	(gr_line
		(start 285.436564 -298.30522)
		(end 285.863538 -298.30522)
		(stroke
			(width 0.0635)
			(type default)
		)
		(layer "B.Cu")
	)
	(gr_line
		(start 285.877254 -92.913708)
		(end 285.970218 -92.768166)
		(stroke
			(width 0.08255)
			(type default)
		)
		(layer "B.Cu")
	)
	(gr_line
		(start 285.970218 -92.768166)
		(end 286.45358 -92.660978)
		(stroke
			(width 0.08255)
			(type default)
		)
		(layer "B.Cu")
	)
	(gr_line
		(start 285.975806 -93.193616)
		(end 286.62757 -93.04909)
		(stroke
			(width 0.08255)
			(type default)
		)
		(layer "B.Cu")
	)
	(gr_arc
		(start 285.990538 -345.232228)
		(mid 285.953341 -345.142425)
		(end 285.863538 -345.105228)
		(stroke
			(width 0.0635)
			(type default)
		)
		(layer "B.Cu")
	)
	(gr_arc
		(start 285.990538 -341.632032)
		(mid 285.953341 -341.542229)
		(end 285.863538 -341.505032)
		(stroke
			(width 0.0635)
			(type default)
		)
		(layer "B.Cu")
	)
	(gr_arc
		(start 285.990538 -338.03209)
		(mid 285.953341 -337.942287)
		(end 285.863538 -337.90509)
		(stroke
			(width 0.0635)
			(type default)
		)
		(layer "B.Cu")
	)
	(gr_arc
		(start 285.990538 -323.632068)
		(mid 285.953332 -323.542273)
		(end 285.863538 -323.505068)
		(stroke
			(width 0.0635)
			(type default)
		)
		(layer "B.Cu")
	)
	(gr_arc
		(start 285.990538 -320.032126)
		(mid 285.953341 -319.942323)
		(end 285.863538 -319.905126)
		(stroke
			(width 0.0635)
			(type default)
		)
		(layer "B.Cu")
	)
	(gr_arc
		(start 285.990538 -316.432184)
		(mid 285.953337 -316.342378)
		(end 285.863538 -316.305184)
		(stroke
			(width 0.0635)
			(type default)
		)
		(layer "B.Cu")
	)
	(gr_arc
		(start 285.990538 -302.032162)
		(mid 285.953329 -301.942371)
		(end 285.863538 -301.905162)
		(stroke
			(width 0.0635)
			(type default)
		)
		(layer "B.Cu")
	)
	(gr_arc
		(start 285.990538 -298.43222)
		(mid 285.953341 -298.342417)
		(end 285.863538 -298.30522)
		(stroke
			(width 0.0635)
			(type default)
		)
		(layer "B.Cu")
	)
	(gr_line
		(start 285.99765 -184.990994)
		(end 286.001206 -184.987946)
		(stroke
			(width 0.08255)
			(type default)
		)
		(layer "B.Cu")
	)
	(gr_line
		(start 286.001206 -184.987946)
		(end 286.004 -184.984136)
		(stroke
			(width 0.08255)
			(type default)
		)
		(layer "B.Cu")
	)
	(gr_line
		(start 286.03829 -191.183006)
		(end 286.054546 -191.177672)
		(stroke
			(width 0.08255)
			(type default)
		)
		(layer "B.Cu")
	)
	(gr_line
		(start 286.054546 -191.177672)
		(end 286.0675 -191.167258)
		(stroke
			(width 0.08255)
			(type default)
		)
		(layer "B.Cu")
	)
	(gr_line
		(start 286.140906 -53.346096)
		(end 286.180784 -53.320696)
		(stroke
			(width 0.08255)
			(type default)
		)
		(layer "B.Cu")
	)
	(gr_arc
		(start 286.409638 -345.105228)
		(mid 286.319821 -345.142414)
		(end 286.282638 -345.232228)
		(stroke
			(width 0.0635)
			(type default)
		)
		(layer "B.Cu")
	)
	(gr_line
		(start 286.409638 -345.105228)
		(end 286.836612 -345.105228)
		(stroke
			(width 0.0635)
			(type default)
		)
		(layer "B.Cu")
	)
	(gr_arc
		(start 286.409638 -341.505032)
		(mid 286.319822 -341.542218)
		(end 286.282638 -341.632032)
		(stroke
			(width 0.0635)
			(type default)
		)
		(layer "B.Cu")
	)
	(gr_line
		(start 286.409638 -341.505032)
		(end 286.836612 -341.505032)
		(stroke
			(width 0.0635)
			(type default)
		)
		(layer "B.Cu")
	)
	(gr_arc
		(start 286.409638 -337.90509)
		(mid 286.319807 -337.942273)
		(end 286.282638 -338.03209)
		(stroke
			(width 0.0635)
			(type default)
		)
		(layer "B.Cu")
	)
	(gr_line
		(start 286.409638 -337.90509)
		(end 286.836612 -337.90509)
		(stroke
			(width 0.0635)
			(type default)
		)
		(layer "B.Cu")
	)
	(gr_arc
		(start 286.409638 -323.505068)
		(mid 286.319835 -323.542265)
		(end 286.282638 -323.632068)
		(stroke
			(width 0.0635)
			(type default)
		)
		(layer "B.Cu")
	)
	(gr_line
		(start 286.409638 -323.505068)
		(end 286.836612 -323.505068)
		(stroke
			(width 0.0635)
			(type default)
		)
		(layer "B.Cu")
	)
	(gr_arc
		(start 286.409638 -319.905126)
		(mid 286.319835 -319.942323)
		(end 286.282638 -320.032126)
		(stroke
			(width 0.0635)
			(type default)
		)
		(layer "B.Cu")
	)
	(gr_line
		(start 286.409638 -319.905126)
		(end 286.836612 -319.905126)
		(stroke
			(width 0.0635)
			(type default)
		)
		(layer "B.Cu")
	)
	(gr_arc
		(start 286.409638 -316.305184)
		(mid 286.319805 -316.342367)
		(end 286.282638 -316.432184)
		(stroke
			(width 0.0635)
			(type default)
		)
		(layer "B.Cu")
	)
	(gr_line
		(start 286.409638 -316.305184)
		(end 286.836612 -316.305184)
		(stroke
			(width 0.0635)
			(type default)
		)
		(layer "B.Cu")
	)
	(gr_arc
		(start 286.409638 -301.905162)
		(mid 286.319835 -301.942359)
		(end 286.282638 -302.032162)
		(stroke
			(width 0.0635)
			(type default)
		)
		(layer "B.Cu")
	)
	(gr_line
		(start 286.409638 -301.905162)
		(end 286.836612 -301.905162)
		(stroke
			(width 0.0635)
			(type default)
		)
		(layer "B.Cu")
	)
	(gr_arc
		(start 286.409638 -298.30522)
		(mid 286.319818 -298.342405)
		(end 286.282638 -298.43222)
		(stroke
			(width 0.0635)
			(type default)
		)
		(layer "B.Cu")
	)
	(gr_line
		(start 286.409638 -298.30522)
		(end 286.836612 -298.30522)
		(stroke
			(width 0.0635)
			(type default)
		)
		(layer "B.Cu")
	)
	(gr_line
		(start 286.436562 -346.905072)
		(end 286.863536 -346.905072)
		(stroke
			(width 0.0635)
			(type default)
		)
		(layer "B.Cu")
	)
	(gr_line
		(start 286.436562 -343.30513)
		(end 286.863536 -343.30513)
		(stroke
			(width 0.0635)
			(type default)
		)
		(layer "B.Cu")
	)
	(gr_line
		(start 286.436562 -339.705188)
		(end 286.863536 -339.705188)
		(stroke
			(width 0.0635)
			(type default)
		)
		(layer "B.Cu")
	)
	(gr_line
		(start 286.436562 -325.305166)
		(end 286.863536 -325.305166)
		(stroke
			(width 0.0635)
			(type default)
		)
		(layer "B.Cu")
	)
	(gr_line
		(start 286.436562 -321.705224)
		(end 286.863536 -321.705224)
		(stroke
			(width 0.0635)
			(type default)
		)
		(layer "B.Cu")
	)
	(gr_line
		(start 286.436562 -318.105028)
		(end 286.863536 -318.105028)
		(stroke
			(width 0.0635)
			(type default)
		)
		(layer "B.Cu")
	)
	(gr_line
		(start 286.436562 -303.70526)
		(end 286.863536 -303.70526)
		(stroke
			(width 0.0635)
			(type default)
		)
		(layer "B.Cu")
	)
	(gr_line
		(start 286.436562 -300.105064)
		(end 286.863536 -300.105064)
		(stroke
			(width 0.0635)
			(type default)
		)
		(layer "B.Cu")
	)
	(gr_line
		(start 286.45358 -92.660978)
		(end 286.599122 -92.753434)
		(stroke
			(width 0.08255)
			(type default)
		)
		(layer "B.Cu")
	)
	(gr_line
		(start 286.465264 -81.34604)
		(end 286.507682 -81.317592)
		(stroke
			(width 0.08255)
			(type default)
		)
		(layer "B.Cu")
	)
	(gr_line
		(start 286.769302 -92.718382)
		(end 287.085786 -92.648278)
		(stroke
			(width 0.08255)
			(type default)
		)
		(layer "B.Cu")
	)
	(gr_arc
		(start 286.990536 -347.032072)
		(mid 286.953339 -346.942269)
		(end 286.863536 -346.905072)
		(stroke
			(width 0.0635)
			(type default)
		)
		(layer "B.Cu")
	)
	(gr_arc
		(start 286.990536 -343.43213)
		(mid 286.953339 -343.342327)
		(end 286.863536 -343.30513)
		(stroke
			(width 0.0635)
			(type default)
		)
		(layer "B.Cu")
	)
	(gr_arc
		(start 286.990536 -339.832188)
		(mid 286.953339 -339.742385)
		(end 286.863536 -339.705188)
		(stroke
			(width 0.0635)
			(type default)
		)
		(layer "B.Cu")
	)
	(gr_arc
		(start 286.990536 -325.432166)
		(mid 286.953339 -325.342363)
		(end 286.863536 -325.305166)
		(stroke
			(width 0.0635)
			(type default)
		)
		(layer "B.Cu")
	)
	(gr_arc
		(start 286.990536 -321.832224)
		(mid 286.953339 -321.742421)
		(end 286.863536 -321.705224)
		(stroke
			(width 0.0635)
			(type default)
		)
		(layer "B.Cu")
	)
	(gr_arc
		(start 286.990536 -318.232028)
		(mid 286.953351 -318.142195)
		(end 286.863536 -318.105028)
		(stroke
			(width 0.0635)
			(type default)
		)
		(layer "B.Cu")
	)
	(gr_arc
		(start 286.990536 -303.83226)
		(mid 286.953327 -303.742471)
		(end 286.863536 -303.70526)
		(stroke
			(width 0.0635)
			(type default)
		)
		(layer "B.Cu")
	)
	(gr_arc
		(start 286.990536 -300.232064)
		(mid 286.953328 -300.142272)
		(end 286.863536 -300.105064)
		(stroke
			(width 0.0635)
			(type default)
		)
		(layer "B.Cu")
	)
	(gr_line
		(start 287.011618 -182.800498)
		(end 287.040574 -182.9562)
		(stroke
			(width 0.08255)
			(type default)
		)
		(layer "B.Cu")
	)
	(gr_line
		(start 287.011618 -182.800498)
		(end 287.292288 -182.39232)
		(stroke
			(width 0.08255)
			(type default)
		)
		(layer "B.Cu")
	)
	(gr_line
		(start 287.087818 -92.64523)
		(end 287.180274 -92.499688)
		(stroke
			(width 0.08255)
			(type default)
		)
		(layer "B.Cu")
	)
	(gr_line
		(start 287.180274 -92.499688)
		(end 287.66389 -92.3925)
		(stroke
			(width 0.08255)
			(type default)
		)
		(layer "B.Cu")
	)
	(gr_line
		(start 287.185862 -92.925392)
		(end 287.84042 -92.780358)
		(stroke
			(width 0.08255)
			(type default)
		)
		(layer "B.Cu")
	)
	(gr_line
		(start 287.186116 -320.951098)
		(end 287.575498 -320.951098)
		(stroke
			(width 0.0635)
			(type default)
		)
		(layer "B.Cu")
	)
	(gr_line
		(start 287.292288 -182.39232)
		(end 287.447736 -182.363618)
		(stroke
			(width 0.08255)
			(type default)
		)
		(layer "B.Cu")
	)
	(gr_line
		(start 287.303464 -183.09336)
		(end 287.669732 -182.560722)
		(stroke
			(width 0.08255)
			(type default)
		)
		(layer "B.Cu")
	)
	(gr_line
		(start 287.307274 -56.719978)
		(end 287.394904 -56.588406)
		(stroke
			(width 0.08255)
			(type default)
		)
		(layer "B.Cu")
	)
	(gr_line
		(start 287.339786 -69.346064)
		(end 287.359344 -69.337682)
		(stroke
			(width 0.08255)
			(type default)
		)
		(layer "B.Cu")
	)
	(gr_line
		(start 287.394904 -56.588406)
		(end 287.880552 -56.491378)
		(stroke
			(width 0.08255)
			(type default)
		)
		(layer "B.Cu")
	)
	(gr_arc
		(start 287.409636 -346.905072)
		(mid 287.319833 -346.942269)
		(end 287.282636 -347.032072)
		(stroke
			(width 0.0635)
			(type default)
		)
		(layer "B.Cu")
	)
	(gr_line
		(start 287.409636 -346.905072)
		(end 287.83661 -346.905072)
		(stroke
			(width 0.0635)
			(type default)
		)
		(layer "B.Cu")
	)
	(gr_arc
		(start 287.409636 -343.30513)
		(mid 287.319821 -343.342317)
		(end 287.282636 -343.43213)
		(stroke
			(width 0.0635)
			(type default)
		)
		(layer "B.Cu")
	)
	(gr_line
		(start 287.409636 -343.30513)
		(end 287.83661 -343.30513)
		(stroke
			(width 0.0635)
			(type default)
		)
		(layer "B.Cu")
	)
	(gr_arc
		(start 287.409636 -339.705188)
		(mid 287.319806 -339.742372)
		(end 287.282636 -339.832188)
		(stroke
			(width 0.0635)
			(type default)
		)
		(layer "B.Cu")
	)
	(gr_line
		(start 287.409636 -339.705188)
		(end 287.83661 -339.705188)
		(stroke
			(width 0.0635)
			(type default)
		)
		(layer "B.Cu")
	)
	(gr_arc
		(start 287.409636 -325.305166)
		(mid 287.319798 -325.342349)
		(end 287.282636 -325.432166)
		(stroke
			(width 0.0635)
			(type default)
		)
		(layer "B.Cu")
	)
	(gr_line
		(start 287.409636 -325.305166)
		(end 287.83661 -325.305166)
		(stroke
			(width 0.0635)
			(type default)
		)
		(layer "B.Cu")
	)
	(gr_arc
		(start 287.409636 -321.705224)
		(mid 287.319819 -321.74241)
		(end 287.282636 -321.832224)
		(stroke
			(width 0.0635)
			(type default)
		)
		(layer "B.Cu")
	)
	(gr_line
		(start 287.409636 -321.705224)
		(end 287.83661 -321.705224)
		(stroke
			(width 0.0635)
			(type default)
		)
		(layer "B.Cu")
	)
	(gr_arc
		(start 287.409636 -318.105028)
		(mid 287.31982 -318.142214)
		(end 287.282636 -318.232028)
		(stroke
			(width 0.0635)
			(type default)
		)
		(layer "B.Cu")
	)
	(gr_line
		(start 287.409636 -318.105028)
		(end 287.83661 -318.105028)
		(stroke
			(width 0.0635)
			(type default)
		)
		(layer "B.Cu")
	)
	(gr_arc
		(start 287.409636 -303.70526)
		(mid 287.319796 -303.742442)
		(end 287.282636 -303.83226)
		(stroke
			(width 0.0635)
			(type default)
		)
		(layer "B.Cu")
	)
	(gr_line
		(start 287.409636 -303.70526)
		(end 287.83661 -303.70526)
		(stroke
			(width 0.0635)
			(type default)
		)
		(layer "B.Cu")
	)
	(gr_arc
		(start 287.409636 -300.105064)
		(mid 287.319797 -300.142247)
		(end 287.282636 -300.232064)
		(stroke
			(width 0.0635)
			(type default)
		)
		(layer "B.Cu")
	)
	(gr_line
		(start 287.409636 -300.105064)
		(end 287.83661 -300.105064)
		(stroke
			(width 0.0635)
			(type default)
		)
		(layer "B.Cu")
	)
	(gr_line
		(start 287.477962 -320.658998)
		(end 287.478216 -320.659252)
		(stroke
			(width 0.0635)
			(type default)
		)
		(layer "B.Cu")
	)
	(gr_line
		(start 287.478216 -320.659252)
		(end 287.867598 -320.659252)
		(stroke
			(width 0.0635)
			(type default)
		)
		(layer "B.Cu")
	)
	(gr_line
		(start 287.547558 -185.835036)
		(end 287.55213 -185.83148)
		(stroke
			(width 0.08255)
			(type default)
		)
		(layer "B.Cu")
	)
	(gr_line
		(start 287.55213 -185.83148)
		(end 287.555686 -185.8264)
		(stroke
			(width 0.08255)
			(type default)
		)
		(layer "B.Cu")
	)
	(gr_line
		(start 287.575498 -320.951098)
		(end 287.575752 -320.951352)
		(stroke
			(width 0.0635)
			(type default)
		)
		(layer "B.Cu")
	)
	(gr_line
		(start 287.651444 -56.951626)
		(end 288.034222 -56.875172)
		(stroke
			(width 0.08255)
			(type default)
		)
		(layer "B.Cu")
	)
	(gr_line
		(start 287.66389 -92.3925)
		(end 287.809432 -92.48521)
		(stroke
			(width 0.08255)
			(type default)
		)
		(layer "B.Cu")
	)
	(gr_line
		(start 287.702244 -181.795928)
		(end 287.730946 -181.951376)
		(stroke
			(width 0.08255)
			(type default)
		)
		(layer "B.Cu")
	)
	(gr_line
		(start 287.702244 -181.795928)
		(end 287.982914 -181.38775)
		(stroke
			(width 0.08255)
			(type default)
		)
		(layer "B.Cu")
	)
	(gr_line
		(start 287.816798 -80.081628)
		(end 287.83534 -80.069182)
		(stroke
			(width 0.08255)
			(type default)
		)
		(layer "B.Cu")
	)
	(gr_line
		(start 287.83534 -80.069182)
		(end 287.857438 -80.064864)
		(stroke
			(width 0.08255)
			(type default)
		)
		(layer "B.Cu")
	)
	(gr_line
		(start 287.880552 -56.491378)
		(end 288.012124 -56.579008)
		(stroke
			(width 0.08255)
			(type default)
		)
		(layer "B.Cu")
	)
	(gr_line
		(start 287.982914 -181.38775)
		(end 288.138362 -181.359048)
		(stroke
			(width 0.08255)
			(type default)
		)
		(layer "B.Cu")
	)
	(gr_line
		(start 287.994598 -182.088282)
		(end 288.360612 -181.555644)
		(stroke
			(width 0.08255)
			(type default)
		)
		(layer "B.Cu")
	)
	(gr_line
		(start 288.068004 -51.76901)
		(end 288.102294 -51.614578)
		(stroke
			(width 0.08255)
			(type default)
		)
		(layer "B.Cu")
	)
	(gr_line
		(start 288.102294 -51.614578)
		(end 288.520124 -51.348386)
		(stroke
			(width 0.08255)
			(type default)
		)
		(layer "B.Cu")
	)
	(gr_line
		(start 288.141918 -181.358286)
		(end 288.143188 -181.356254)
		(stroke
			(width 0.08255)
			(type default)
		)
		(layer "B.Cu")
	)
	(gr_line
		(start 288.25571 -51.99888)
		(end 288.803334 -51.650138)
		(stroke
			(width 0.08255)
			(type default)
		)
		(layer "B.Cu")
	)
	(gr_line
		(start 288.285428 -338.951062)
		(end 288.309812 -338.951062)
		(stroke
			(width 0.0635)
			(type default)
		)
		(layer "B.Cu")
	)
	(gr_line
		(start 288.297366 -338.658962)
		(end 288.29762 -338.659216)
		(stroke
			(width 0.0635)
			(type default)
		)
		(layer "B.Cu")
	)
	(gr_line
		(start 288.29762 -338.659216)
		(end 288.29889 -338.658962)
		(stroke
			(width 0.0635)
			(type default)
		)
		(layer "B.Cu")
	)
	(gr_line
		(start 288.32937 -338.951062)
		(end 288.329624 -338.951316)
		(stroke
			(width 0.0635)
			(type default)
		)
		(layer "B.Cu")
	)
	(gr_line
		(start 288.382202 -181.524402)
		(end 288.528252 -181.311804)
		(stroke
			(width 0.08255)
			(type default)
		)
		(layer "B.Cu")
	)
	(gr_line
		(start 288.39287 -180.791104)
		(end 288.421826 -180.946806)
		(stroke
			(width 0.08255)
			(type default)
		)
		(layer "B.Cu")
	)
	(gr_line
		(start 288.39287 -180.791104)
		(end 288.67354 -180.382926)
		(stroke
			(width 0.08255)
			(type default)
		)
		(layer "B.Cu")
	)
	(gr_line
		(start 288.411412 -183.86298)
		(end 288.440368 -184.018682)
		(stroke
			(width 0.08255)
			(type default)
		)
		(layer "B.Cu")
	)
	(gr_line
		(start 288.411412 -183.86298)
		(end 288.692082 -183.454548)
		(stroke
			(width 0.08255)
			(type default)
		)
		(layer "B.Cu")
	)
	(gr_line
		(start 288.502598 -56.480964)
		(end 288.590482 -56.349392)
		(stroke
			(width 0.08255)
			(type default)
		)
		(layer "B.Cu")
	)
	(gr_line
		(start 288.520124 -51.348386)
		(end 288.674556 -51.382676)
		(stroke
			(width 0.08255)
			(type default)
		)
		(layer "B.Cu")
	)
	(gr_line
		(start 288.574226 -299.216826)
		(end 288.586672 -299.214032)
		(stroke
			(width 0.0635)
			(type default)
		)
		(layer "B.Cu")
	)
	(gr_line
		(start 288.586672 -299.214032)
		(end 288.597848 -299.20692)
		(stroke
			(width 0.0635)
			(type default)
		)
		(layer "B.Cu")
	)
	(gr_line
		(start 288.590482 -56.349392)
		(end 289.07613 -56.25211)
		(stroke
			(width 0.08255)
			(type default)
		)
		(layer "B.Cu")
	)
	(gr_line
		(start 288.595816 -56.76265)
		(end 289.229546 -56.635904)
		(stroke
			(width 0.08255)
			(type default)
		)
		(layer "B.Cu")
	)
	(gr_line
		(start 288.67354 -180.382926)
		(end 288.829242 -180.35397)
		(stroke
			(width 0.08255)
			(type default)
		)
		(layer "B.Cu")
	)
	(gr_line
		(start 288.684716 -181.083966)
		(end 289.050984 -180.551328)
		(stroke
			(width 0.08255)
			(type default)
		)
		(layer "B.Cu")
	)
	(gr_line
		(start 288.692082 -183.454548)
		(end 288.847784 -183.425592)
		(stroke
			(width 0.08255)
			(type default)
		)
		(layer "B.Cu")
	)
	(gr_line
		(start 288.702496 -184.157112)
		(end 289.070288 -183.62168)
		(stroke
			(width 0.08255)
			(type default)
		)
		(layer "B.Cu")
	)
	(gr_line
		(start 288.815526 -79.876396)
		(end 288.903918 -79.745078)
		(stroke
			(width 0.08255)
			(type default)
		)
		(layer "B.Cu")
	)
	(gr_line
		(start 288.882328 -94.067884)
		(end 288.975292 -93.922342)
		(stroke
			(width 0.08255)
			(type default)
		)
		(layer "B.Cu")
	)
	(gr_line
		(start 288.903918 -79.745078)
		(end 289.390074 -79.65059)
		(stroke
			(width 0.08255)
			(type default)
		)
		(layer "B.Cu")
	)
	(gr_line
		(start 288.905696 -80.159098)
		(end 289.543744 -80.034892)
		(stroke
			(width 0.08255)
			(type default)
		)
		(layer "B.Cu")
	)
	(gr_line
		(start 288.975292 -93.922342)
		(end 289.458654 -93.815154)
		(stroke
			(width 0.08255)
			(type default)
		)
		(layer "B.Cu")
	)
	(gr_line
		(start 288.981134 -94.347538)
		(end 289.632136 -94.203266)
		(stroke
			(width 0.08255)
			(type default)
		)
		(layer "B.Cu")
	)
	(gr_line
		(start 289.07613 -56.25211)
		(end 289.207956 -56.339994)
		(stroke
			(width 0.08255)
			(type default)
		)
		(layer "B.Cu")
	)
	(gr_line
		(start 289.08375 -179.786534)
		(end 289.112452 -179.941728)
		(stroke
			(width 0.08255)
			(type default)
		)
		(layer "B.Cu")
	)
	(gr_line
		(start 289.08375 -179.786534)
		(end 289.364166 -179.378356)
		(stroke
			(width 0.08255)
			(type default)
		)
		(layer "B.Cu")
	)
	(gr_line
		(start 289.09645 -51.113944)
		(end 289.130486 -50.959512)
		(stroke
			(width 0.08255)
			(type default)
		)
		(layer "B.Cu")
	)
	(gr_line
		(start 289.102038 -182.858156)
		(end 289.130994 -183.013858)
		(stroke
			(width 0.08255)
			(type default)
		)
		(layer "B.Cu")
	)
	(gr_line
		(start 289.102038 -182.858156)
		(end 289.382454 -182.449724)
		(stroke
			(width 0.08255)
			(type default)
		)
		(layer "B.Cu")
	)
	(gr_line
		(start 289.130486 -50.959512)
		(end 289.548316 -50.69332)
		(stroke
			(width 0.08255)
			(type default)
		)
		(layer "B.Cu")
	)
	(gr_line
		(start 289.26409 -180.241448)
		(end 289.355784 -180.108098)
		(stroke
			(width 0.08255)
			(type default)
		)
		(layer "B.Cu")
	)
	(gr_line
		(start 289.284156 -51.343814)
		(end 289.832034 -50.994818)
		(stroke
			(width 0.08255)
			(type default)
		)
		(layer "B.Cu")
	)
	(gr_line
		(start 289.364166 -179.378356)
		(end 289.519614 -179.349654)
		(stroke
			(width 0.08255)
			(type default)
		)
		(layer "B.Cu")
	)
	(gr_line
		(start 289.376612 -180.077618)
		(end 289.741864 -179.546504)
		(stroke
			(width 0.08255)
			(type default)
		)
		(layer "B.Cu")
	)
	(gr_line
		(start 289.382454 -182.449724)
		(end 289.53841 -182.420768)
		(stroke
			(width 0.08255)
			(type default)
		)
		(layer "B.Cu")
	)
	(gr_line
		(start 289.390074 -79.65059)
		(end 289.521392 -79.739236)
		(stroke
			(width 0.08255)
			(type default)
		)
		(layer "B.Cu")
	)
	(gr_line
		(start 289.393884 -183.150764)
		(end 289.760406 -182.617618)
		(stroke
			(width 0.08255)
			(type default)
		)
		(layer "B.Cu")
	)
	(gr_line
		(start 289.423856 -300.978316)
		(end 289.437572 -300.975268)
		(stroke
			(width 0.0635)
			(type default)
		)
		(layer "B.Cu")
	)
	(gr_line
		(start 289.437572 -300.975268)
		(end 289.44951 -300.967648)
		(stroke
			(width 0.0635)
			(type default)
		)
		(layer "B.Cu")
	)
	(gr_line
		(start 289.440112 -186.397646)
		(end 289.443668 -186.394598)
		(stroke
			(width 0.08255)
			(type default)
		)
		(layer "B.Cu")
	)
	(gr_line
		(start 289.443668 -186.394598)
		(end 289.446462 -186.390788)
		(stroke
			(width 0.08255)
			(type default)
		)
		(layer "B.Cu")
	)
	(gr_line
		(start 289.458654 -93.815154)
		(end 289.604196 -93.907864)
		(stroke
			(width 0.08255)
			(type default)
		)
		(layer "B.Cu")
	)
	(gr_line
		(start 289.527234 -317.036196)
		(end 289.53968 -317.033402)
		(stroke
			(width 0.0635)
			(type default)
		)
		(layer "B.Cu")
	)
	(gr_line
		(start 289.53968 -317.033402)
		(end 289.550856 -317.02629)
		(stroke
			(width 0.0635)
			(type default)
		)
		(layer "B.Cu")
	)
	(gr_line
		(start 289.548316 -50.69332)
		(end 289.702748 -50.72761)
		(stroke
			(width 0.08255)
			(type default)
		)
		(layer "B.Cu")
	)
	(gr_line
		(start 289.568128 -338.676742)
		(end 289.580574 -338.673948)
		(stroke
			(width 0.0635)
			(type default)
		)
		(layer "B.Cu")
	)
	(gr_line
		(start 289.580574 -338.673948)
		(end 289.59175 -338.666836)
		(stroke
			(width 0.0635)
			(type default)
		)
		(layer "B.Cu")
	)
	(gr_line
		(start 289.69843 -56.241696)
		(end 289.78606 -56.110124)
		(stroke
			(width 0.08255)
			(type default)
		)
		(layer "B.Cu")
	)
	(gr_line
		(start 289.78606 -56.110124)
		(end 290.271708 -56.013096)
		(stroke
			(width 0.08255)
			(type default)
		)
		(layer "B.Cu")
	)
	(gr_line
		(start 289.792156 -56.523382)
		(end 290.425378 -56.39689)
		(stroke
			(width 0.08255)
			(type default)
		)
		(layer "B.Cu")
	)
	(gr_line
		(start 289.79241 -181.853332)
		(end 289.821366 -182.009034)
		(stroke
			(width 0.08255)
			(type default)
		)
		(layer "B.Cu")
	)
	(gr_line
		(start 289.79241 -181.853332)
		(end 290.07308 -181.4449)
		(stroke
			(width 0.08255)
			(type default)
		)
		(layer "B.Cu")
	)
	(gr_line
		(start 289.918394 -302.546004)
		(end 289.93084 -302.54321)
		(stroke
			(width 0.0635)
			(type default)
		)
		(layer "B.Cu")
	)
	(gr_line
		(start 289.93084 -302.54321)
		(end 289.942016 -302.536098)
		(stroke
			(width 0.0635)
			(type default)
		)
		(layer "B.Cu")
	)
	(gr_line
		(start 289.982148 -304.379122)
		(end 289.99561 -304.376074)
		(stroke
			(width 0.0635)
			(type default)
		)
		(layer "B.Cu")
	)
	(gr_line
		(start 289.99561 -304.376074)
		(end 290.007294 -304.368708)
		(stroke
			(width 0.0635)
			(type default)
		)
		(layer "B.Cu")
	)
	(gr_line
		(start 290.01212 -79.643732)
		(end 290.100766 -79.512414)
		(stroke
			(width 0.08255)
			(type default)
		)
		(layer "B.Cu")
	)
	(gr_line
		(start 290.07308 -181.4449)
		(end 290.228782 -181.415944)
		(stroke
			(width 0.08255)
			(type default)
		)
		(layer "B.Cu")
	)
	(gr_line
		(start 290.084256 -182.146194)
		(end 290.45154 -181.611778)
		(stroke
			(width 0.08255)
			(type default)
		)
		(layer "B.Cu")
	)
	(gr_line
		(start 290.092638 -93.799406)
		(end 290.185348 -93.653864)
		(stroke
			(width 0.08255)
			(type default)
		)
		(layer "B.Cu")
	)
	(gr_line
		(start 290.100766 -79.512414)
		(end 290.586922 -79.417926)
		(stroke
			(width 0.08255)
			(type default)
		)
		(layer "B.Cu")
	)
	(gr_line
		(start 290.102036 -79.926434)
		(end 290.73983 -79.802482)
		(stroke
			(width 0.08255)
			(type default)
		)
		(layer "B.Cu")
	)
	(gr_line
		(start 290.124642 -50.458878)
		(end 290.158932 -50.304446)
		(stroke
			(width 0.08255)
			(type default)
		)
		(layer "B.Cu")
	)
	(gr_line
		(start 290.158932 -50.304446)
		(end 290.576508 -50.038254)
		(stroke
			(width 0.08255)
			(type default)
		)
		(layer "B.Cu")
	)
	(gr_line
		(start 290.185348 -93.653864)
		(end 290.668964 -93.546676)
		(stroke
			(width 0.08255)
			(type default)
		)
		(layer "B.Cu")
	)
	(gr_line
		(start 290.192714 -94.07906)
		(end 290.8427 -93.935042)
		(stroke
			(width 0.08255)
			(type default)
		)
		(layer "B.Cu")
	)
	(gr_line
		(start 290.207192 -184.566052)
		(end 290.236148 -184.721754)
		(stroke
			(width 0.08255)
			(type default)
		)
		(layer "B.Cu")
	)
	(gr_line
		(start 290.207192 -184.566052)
		(end 290.487862 -184.157874)
		(stroke
			(width 0.08255)
			(type default)
		)
		(layer "B.Cu")
	)
	(gr_line
		(start 290.21405 -318.850264)
		(end 290.226496 -318.84747)
		(stroke
			(width 0.0635)
			(type default)
		)
		(layer "B.Cu")
	)
	(gr_line
		(start 290.226496 -318.84747)
		(end 290.237672 -318.840358)
		(stroke
			(width 0.0635)
			(type default)
		)
		(layer "B.Cu")
	)
	(gr_line
		(start 290.271708 -56.013096)
		(end 290.40328 -56.100726)
		(stroke
			(width 0.08255)
			(type default)
		)
		(layer "B.Cu")
	)
	(gr_line
		(start 290.311586 -50.689256)
		(end 290.859972 -50.340006)
		(stroke
			(width 0.08255)
			(type default)
		)
		(layer "B.Cu")
	)
	(gr_line
		(start 290.483036 -180.848508)
		(end 290.511992 -181.00421)
		(stroke
			(width 0.08255)
			(type default)
		)
		(layer "B.Cu")
	)
	(gr_line
		(start 290.483036 -180.848508)
		(end 290.763452 -180.440076)
		(stroke
			(width 0.08255)
			(type default)
		)
		(layer "B.Cu")
	)
	(gr_line
		(start 290.487862 -184.157874)
		(end 290.64331 -184.129172)
		(stroke
			(width 0.08255)
			(type default)
		)
		(layer "B.Cu")
	)
	(gr_line
		(start 290.499292 -184.85866)
		(end 290.865052 -184.32653)
		(stroke
			(width 0.08255)
			(type default)
		)
		(layer "B.Cu")
	)
	(gr_line
		(start 290.576508 -50.038254)
		(end 290.73094 -50.072544)
		(stroke
			(width 0.08255)
			(type default)
		)
		(layer "B.Cu")
	)
	(gr_line
		(start 290.586922 -79.417926)
		(end 290.717986 -79.506572)
		(stroke
			(width 0.08255)
			(type default)
		)
		(layer "B.Cu")
	)
	(gr_line
		(start 290.608004 -326.002142)
		(end 290.62045 -325.999348)
		(stroke
			(width 0.0635)
			(type default)
		)
		(layer "B.Cu")
	)
	(gr_line
		(start 290.62045 -325.999348)
		(end 290.631626 -325.992236)
		(stroke
			(width 0.0635)
			(type default)
		)
		(layer "B.Cu")
	)
	(gr_line
		(start 290.62426 -72.077072)
		(end 290.71951 -71.933054)
		(stroke
			(width 0.08255)
			(type default)
		)
		(layer "B.Cu")
	)
	(gr_line
		(start 290.668964 -93.546676)
		(end 290.814252 -93.63964)
		(stroke
			(width 0.08255)
			(type default)
		)
		(layer "B.Cu")
	)
	(gr_line
		(start 290.682426 -322.247768)
		(end 290.694872 -322.244974)
		(stroke
			(width 0.0635)
			(type default)
		)
		(layer "B.Cu")
	)
	(gr_line
		(start 290.688776 -320.396616)
		(end 290.701222 -320.393822)
		(stroke
			(width 0.0635)
			(type default)
		)
		(layer "B.Cu")
	)
	(gr_line
		(start 290.694872 -322.244974)
		(end 290.706048 -322.237862)
		(stroke
			(width 0.0635)
			(type default)
		)
		(layer "B.Cu")
	)
	(gr_line
		(start 290.701222 -320.393822)
		(end 290.712398 -320.38671)
		(stroke
			(width 0.0635)
			(type default)
		)
		(layer "B.Cu")
	)
	(gr_line
		(start 290.717478 -72.358758)
		(end 291.372798 -72.225408)
		(stroke
			(width 0.08255)
			(type default)
		)
		(layer "B.Cu")
	)
	(gr_line
		(start 290.71951 -71.933054)
		(end 291.204904 -71.834248)
		(stroke
			(width 0.08255)
			(type default)
		)
		(layer "B.Cu")
	)
	(gr_line
		(start 290.763452 -180.440076)
		(end 290.919408 -180.41112)
		(stroke
			(width 0.08255)
			(type default)
		)
		(layer "B.Cu")
	)
	(gr_line
		(start 290.775136 -181.140608)
		(end 291.140642 -180.608732)
		(stroke
			(width 0.08255)
			(type default)
		)
		(layer "B.Cu")
	)
	(gr_line
		(start 290.8935 -56.002682)
		(end 290.981384 -55.87111)
		(stroke
			(width 0.08255)
			(type default)
		)
		(layer "B.Cu")
	)
	(gr_line
		(start 290.897818 -183.561228)
		(end 290.926774 -183.71693)
		(stroke
			(width 0.08255)
			(type default)
		)
		(layer "B.Cu")
	)
	(gr_line
		(start 290.897818 -183.561228)
		(end 291.178488 -183.15305)
		(stroke
			(width 0.08255)
			(type default)
		)
		(layer "B.Cu")
	)
	(gr_line
		(start 290.981384 -55.87111)
		(end 291.467286 -55.773828)
		(stroke
			(width 0.08255)
			(type default)
		)
		(layer "B.Cu")
	)
	(gr_line
		(start 290.985448 -56.284876)
		(end 291.622988 -56.157368)
		(stroke
			(width 0.08255)
			(type default)
		)
		(layer "B.Cu")
	)
	(gr_line
		(start 291.083746 -340.27618)
		(end 291.098478 -340.272878)
		(stroke
			(width 0.0635)
			(type default)
		)
		(layer "B.Cu")
	)
	(gr_line
		(start 291.098478 -340.272878)
		(end 291.110924 -340.265004)
		(stroke
			(width 0.0635)
			(type default)
		)
		(layer "B.Cu")
	)
	(gr_line
		(start 291.152834 -49.803812)
		(end 291.187124 -49.64938)
		(stroke
			(width 0.08255)
			(type default)
		)
		(layer "B.Cu")
	)
	(gr_line
		(start 291.178488 -183.15305)
		(end 291.333936 -183.124348)
		(stroke
			(width 0.08255)
			(type default)
		)
		(layer "B.Cu")
	)
	(gr_line
		(start 291.184584 -323.764402)
		(end 291.19703 -323.761608)
		(stroke
			(width 0.0635)
			(type default)
		)
		(layer "B.Cu")
	)
	(gr_line
		(start 291.187124 -49.64938)
		(end 291.604954 -49.383188)
		(stroke
			(width 0.08255)
			(type default)
		)
		(layer "B.Cu")
	)
	(gr_line
		(start 291.189664 -183.854344)
		(end 291.55644 -183.320944)
		(stroke
			(width 0.08255)
			(type default)
		)
		(layer "B.Cu")
	)
	(gr_line
		(start 291.19703 -323.761608)
		(end 291.208206 -323.754496)
		(stroke
			(width 0.0635)
			(type default)
		)
		(layer "B.Cu")
	)
	(gr_line
		(start 291.204904 -71.834248)
		(end 291.348922 -71.929498)
		(stroke
			(width 0.08255)
			(type default)
		)
		(layer "B.Cu")
	)
	(gr_line
		(start 291.208968 -79.411068)
		(end 291.29736 -79.27975)
		(stroke
			(width 0.08255)
			(type default)
		)
		(layer "B.Cu")
	)
	(gr_line
		(start 291.29736 -79.27975)
		(end 291.78377 -79.185262)
		(stroke
			(width 0.08255)
			(type default)
		)
		(layer "B.Cu")
	)
	(gr_line
		(start 291.300154 -79.693516)
		(end 291.936678 -79.569818)
		(stroke
			(width 0.08255)
			(type default)
		)
		(layer "B.Cu")
	)
	(gr_line
		(start 291.302694 -93.531182)
		(end 291.395404 -93.38564)
		(stroke
			(width 0.08255)
			(type default)
		)
		(layer "B.Cu")
	)
	(gr_line
		(start 291.34054 -50.033682)
		(end 291.888164 -49.68494)
		(stroke
			(width 0.08255)
			(type default)
		)
		(layer "B.Cu")
	)
	(gr_line
		(start 291.395404 -93.38564)
		(end 291.87902 -93.278452)
		(stroke
			(width 0.08255)
			(type default)
		)
		(layer "B.Cu")
	)
	(gr_line
		(start 291.401754 -93.81109)
		(end 292.054788 -93.66631)
		(stroke
			(width 0.08255)
			(type default)
		)
		(layer "B.Cu")
	)
	(gr_line
		(start 291.467286 -55.773828)
		(end 291.598858 -55.861712)
		(stroke
			(width 0.08255)
			(type default)
		)
		(layer "B.Cu")
	)
	(gr_line
		(start 291.588444 -182.556404)
		(end 291.6174 -182.712106)
		(stroke
			(width 0.08255)
			(type default)
		)
		(layer "B.Cu")
	)
	(gr_line
		(start 291.588444 -182.556404)
		(end 291.869114 -182.148226)
		(stroke
			(width 0.08255)
			(type default)
		)
		(layer "B.Cu")
	)
	(gr_line
		(start 291.597842 -343.742518)
		(end 291.610288 -343.739724)
		(stroke
			(width 0.0635)
			(type default)
		)
		(layer "B.Cu")
	)
	(gr_line
		(start 291.604954 -49.383188)
		(end 291.759386 -49.417478)
		(stroke
			(width 0.08255)
			(type default)
		)
		(layer "B.Cu")
	)
	(gr_line
		(start 291.610288 -343.739724)
		(end 291.621464 -343.732612)
		(stroke
			(width 0.0635)
			(type default)
		)
		(layer "B.Cu")
	)
	(gr_line
		(start 291.67455 -89.553288)
		(end 291.768784 -89.408508)
		(stroke
			(width 0.08255)
			(type default)
		)
		(layer "B.Cu")
	)
	(gr_line
		(start 291.705792 -297.226228)
		(end 291.728398 -297.21175)
		(stroke
			(width 0.0635)
			(type default)
		)
		(layer "B.Cu")
	)
	(gr_line
		(start 291.728398 -297.21175)
		(end 291.742368 -297.189906)
		(stroke
			(width 0.0635)
			(type default)
		)
		(layer "B.Cu")
	)
	(gr_line
		(start 291.758878 -341.771986)
		(end 291.771324 -341.769192)
		(stroke
			(width 0.0635)
			(type default)
		)
		(layer "B.Cu")
	)
	(gr_line
		(start 291.768784 -89.408508)
		(end 292.253162 -89.305638)
		(stroke
			(width 0.08255)
			(type default)
		)
		(layer "B.Cu")
	)
	(gr_line
		(start 291.770054 -89.834212)
		(end 292.424358 -89.69502)
		(stroke
			(width 0.08255)
			(type default)
		)
		(layer "B.Cu")
	)
	(gr_line
		(start 291.771324 -341.769192)
		(end 291.7825 -341.76208)
		(stroke
			(width 0.0635)
			(type default)
		)
		(layer "B.Cu")
	)
	(gr_line
		(start 291.78377 -79.185262)
		(end 291.915088 -79.273908)
		(stroke
			(width 0.08255)
			(type default)
		)
		(layer "B.Cu")
	)
	(gr_line
		(start 291.838888 -71.82993)
		(end 291.934138 -71.685912)
		(stroke
			(width 0.08255)
			(type default)
		)
		(layer "B.Cu")
	)
	(gr_line
		(start 291.869114 -182.148226)
		(end 292.024562 -182.119524)
		(stroke
			(width 0.08255)
			(type default)
		)
		(layer "B.Cu")
	)
	(gr_line
		(start 291.87902 -93.278452)
		(end 292.024816 -93.371162)
		(stroke
			(width 0.08255)
			(type default)
		)
		(layer "B.Cu")
	)
	(gr_line
		(start 291.880036 -182.850028)
		(end 292.24732 -182.315866)
		(stroke
			(width 0.08255)
			(type default)
		)
		(layer "B.Cu")
	)
	(gr_line
		(start 291.930328 -296.047922)
		(end 291.97935 -296.26941)
		(stroke
			(width 0.0635)
			(type default)
		)
		(layer "B.Cu")
	)
	(gr_line
		(start 291.930328 -296.047922)
		(end 292.135052 -295.726612)
		(stroke
			(width 0.0635)
			(type default)
		)
		(layer "B.Cu")
	)
	(gr_line
		(start 291.931598 -72.11187)
		(end 292.588442 -71.978266)
		(stroke
			(width 0.08255)
			(type default)
		)
		(layer "B.Cu")
	)
	(gr_line
		(start 291.934138 -71.685912)
		(end 292.419532 -71.587106)
		(stroke
			(width 0.08255)
			(type default)
		)
		(layer "B.Cu")
	)
	(gr_line
		(start 292.135052 -295.726612)
		(end 292.35654 -295.67759)
		(stroke
			(width 0.0635)
			(type default)
		)
		(layer "B.Cu")
	)
	(gr_line
		(start 292.246558 -296.398442)
		(end 292.586156 -295.865296)
		(stroke
			(width 0.0635)
			(type default)
		)
		(layer "B.Cu")
	)
	(gr_line
		(start 292.247574 -186.199272)
		(end 292.25113 -186.196224)
		(stroke
			(width 0.08255)
			(type default)
		)
		(layer "B.Cu")
	)
	(gr_line
		(start 292.25113 -186.196224)
		(end 292.253924 -186.192414)
		(stroke
			(width 0.08255)
			(type default)
		)
		(layer "B.Cu")
	)
	(gr_line
		(start 292.253162 -89.305638)
		(end 292.397942 -89.399618)
		(stroke
			(width 0.08255)
			(type default)
		)
		(layer "B.Cu")
	)
	(gr_line
		(start 292.27907 -181.551834)
		(end 292.308026 -181.707282)
		(stroke
			(width 0.08255)
			(type default)
		)
		(layer "B.Cu")
	)
	(gr_line
		(start 292.27907 -181.551834)
		(end 292.55974 -181.143656)
		(stroke
			(width 0.08255)
			(type default)
		)
		(layer "B.Cu")
	)
	(gr_line
		(start 292.33749 -185.353452)
		(end 292.366446 -185.5089)
		(stroke
			(width 0.08255)
			(type default)
		)
		(layer "B.Cu")
	)
	(gr_line
		(start 292.33749 -185.353452)
		(end 292.61816 -184.945274)
		(stroke
			(width 0.08255)
			(type default)
		)
		(layer "B.Cu")
	)
	(gr_line
		(start 292.405562 -79.178658)
		(end 292.494208 -79.04734)
		(stroke
			(width 0.08255)
			(type default)
		)
		(layer "B.Cu")
	)
	(gr_line
		(start 292.419532 -71.587106)
		(end 292.56355 -71.68261)
		(stroke
			(width 0.08255)
			(type default)
		)
		(layer "B.Cu")
	)
	(gr_line
		(start 292.494208 -79.04734)
		(end 292.980364 -78.952598)
		(stroke
			(width 0.08255)
			(type default)
		)
		(layer "B.Cu")
	)
	(gr_line
		(start 292.497002 -79.460598)
		(end 293.132256 -79.337154)
		(stroke
			(width 0.08255)
			(type default)
		)
		(layer "B.Cu")
	)
	(gr_line
		(start 292.51275 -93.262958)
		(end 292.605714 -93.117416)
		(stroke
			(width 0.08255)
			(type default)
		)
		(layer "B.Cu")
	)
	(gr_line
		(start 292.514528 -295.131236)
		(end 292.56355 -295.35247)
		(stroke
			(width 0.0635)
			(type default)
		)
		(layer "B.Cu")
	)
	(gr_line
		(start 292.514528 -295.131236)
		(end 292.719252 -294.809926)
		(stroke
			(width 0.0635)
			(type default)
		)
		(layer "B.Cu")
	)
	(gr_line
		(start 292.55974 -181.143656)
		(end 292.715188 -181.1147)
		(stroke
			(width 0.08255)
			(type default)
		)
		(layer "B.Cu")
	)
	(gr_line
		(start 292.570408 -181.845712)
		(end 292.937946 -181.310788)
		(stroke
			(width 0.08255)
			(type default)
		)
		(layer "B.Cu")
	)
	(gr_line
		(start 292.605714 -93.117416)
		(end 293.089076 -93.010228)
		(stroke
			(width 0.08255)
			(type default)
		)
		(layer "B.Cu")
	)
	(gr_line
		(start 292.61054 -93.54312)
		(end 293.264336 -93.398086)
		(stroke
			(width 0.08255)
			(type default)
		)
		(layer "B.Cu")
	)
	(gr_line
		(start 292.61816 -184.945274)
		(end 292.773608 -184.916572)
		(stroke
			(width 0.08255)
			(type default)
		)
		(layer "B.Cu")
	)
	(gr_line
		(start 292.629082 -185.646822)
		(end 292.99662 -185.112406)
		(stroke
			(width 0.08255)
			(type default)
		)
		(layer "B.Cu")
	)
	(gr_line
		(start 292.69436 -91.402154)
		(end 292.779196 -91.26855)
		(stroke
			(width 0.08255)
			(type default)
		)
		(layer "B.Cu")
	)
	(gr_line
		(start 292.697662 -315.021976)
		(end 292.71976 -315.007752)
		(stroke
			(width 0.0635)
			(type default)
		)
		(layer "B.Cu")
	)
	(gr_line
		(start 292.699948 -63.545212)
		(end 292.763956 -63.384938)
		(stroke
			(width 0.08255)
			(type default)
		)
		(layer "B.Cu")
	)
	(gr_line
		(start 292.719252 -294.809926)
		(end 292.940486 -294.760904)
		(stroke
			(width 0.0635)
			(type default)
		)
		(layer "B.Cu")
	)
	(gr_line
		(start 292.71976 -315.007752)
		(end 292.733984 -314.985654)
		(stroke
			(width 0.0635)
			(type default)
		)
		(layer "B.Cu")
	)
	(gr_line
		(start 292.763956 -63.384938)
		(end 293.219378 -63.189866)
		(stroke
			(width 0.08255)
			(type default)
		)
		(layer "B.Cu")
	)
	(gr_line
		(start 292.779196 -91.26855)
		(end 293.262812 -91.161362)
		(stroke
			(width 0.08255)
			(type default)
		)
		(layer "B.Cu")
	)
	(gr_line
		(start 292.79215 -91.682316)
		(end 293.426896 -91.5416)
		(stroke
			(width 0.08255)
			(type default)
		)
		(layer "B.Cu")
	)
	(gr_line
		(start 292.821868 -89.311988)
		(end 292.885114 -89.298526)
		(stroke
			(width 0.08255)
			(type default)
		)
		(layer "B.Cu")
	)
	(gr_line
		(start 292.83025 -295.482518)
		(end 293.170356 -294.94861)
		(stroke
			(width 0.0635)
			(type default)
		)
		(layer "B.Cu")
	)
	(gr_line
		(start 292.847268 -63.802768)
		(end 293.464234 -63.538608)
		(stroke
			(width 0.08255)
			(type default)
		)
		(layer "B.Cu")
	)
	(gr_line
		(start 292.882574 -89.597738)
		(end 292.94836 -89.583768)
		(stroke
			(width 0.08255)
			(type default)
		)
		(layer "B.Cu")
	)
	(gr_line
		(start 292.887146 -89.295478)
		(end 292.981126 -89.150698)
		(stroke
			(width 0.08255)
			(type default)
		)
		(layer "B.Cu")
	)
	(gr_line
		(start 292.980364 -78.952598)
		(end 293.111936 -79.041244)
		(stroke
			(width 0.08255)
			(type default)
		)
		(layer "B.Cu")
	)
	(gr_line
		(start 292.981126 -89.150698)
		(end 293.465504 -89.047828)
		(stroke
			(width 0.08255)
			(type default)
		)
		(layer "B.Cu")
	)
	(gr_line
		(start 292.984682 -89.575894)
		(end 293.6367 -89.43721)
		(stroke
			(width 0.08255)
			(type default)
		)
		(layer "B.Cu")
	)
	(gr_line
		(start 293.02837 -184.348882)
		(end 293.057326 -184.50433)
		(stroke
			(width 0.08255)
			(type default)
		)
		(layer "B.Cu")
	)
	(gr_line
		(start 293.02837 -184.348882)
		(end 293.30904 -183.940704)
		(stroke
			(width 0.08255)
			(type default)
		)
		(layer "B.Cu")
	)
	(gr_line
		(start 293.053516 -71.582788)
		(end 293.148766 -71.43877)
		(stroke
			(width 0.08255)
			(type default)
		)
		(layer "B.Cu")
	)
	(gr_line
		(start 293.089076 -93.010228)
		(end 293.234872 -93.102938)
		(stroke
			(width 0.08255)
			(type default)
		)
		(layer "B.Cu")
	)
	(gr_line
		(start 293.098728 -294.214296)
		(end 293.14775 -294.43553)
		(stroke
			(width 0.0635)
			(type default)
		)
		(layer "B.Cu")
	)
	(gr_line
		(start 293.098728 -294.214296)
		(end 293.303452 -293.892986)
		(stroke
			(width 0.0635)
			(type default)
		)
		(layer "B.Cu")
	)
	(gr_line
		(start 293.145464 -71.864982)
		(end 293.803578 -71.731124)
		(stroke
			(width 0.08255)
			(type default)
		)
		(layer "B.Cu")
	)
	(gr_line
		(start 293.148766 -71.43877)
		(end 293.63416 -71.339964)
		(stroke
			(width 0.08255)
			(type default)
		)
		(layer "B.Cu")
	)
	(gr_line
		(start 293.219378 -63.189866)
		(end 293.379652 -63.254128)
		(stroke
			(width 0.08255)
			(type default)
		)
		(layer "B.Cu")
	)
	(gr_line
		(start 293.24808 -298.547028)
		(end 293.270178 -298.532804)
		(stroke
			(width 0.0635)
			(type default)
		)
		(layer "B.Cu")
	)
	(gr_line
		(start 293.262812 -91.161362)
		(end 293.396416 -91.246452)
		(stroke
			(width 0.08255)
			(type default)
		)
		(layer "B.Cu")
	)
	(gr_line
		(start 293.270178 -298.532804)
		(end 293.284402 -298.510706)
		(stroke
			(width 0.0635)
			(type default)
		)
		(layer "B.Cu")
	)
	(gr_line
		(start 293.303452 -293.892986)
		(end 293.524686 -293.843964)
		(stroke
			(width 0.0635)
			(type default)
		)
		(layer "B.Cu")
	)
	(gr_line
		(start 293.30904 -183.940704)
		(end 293.464742 -183.911748)
		(stroke
			(width 0.08255)
			(type default)
		)
		(layer "B.Cu")
	)
	(gr_line
		(start 293.319708 -184.64276)
		(end 293.688008 -184.107328)
		(stroke
			(width 0.08255)
			(type default)
		)
		(layer "B.Cu")
	)
	(gr_line
		(start 293.415212 -294.564308)
		(end 293.753794 -294.032686)
		(stroke
			(width 0.0635)
			(type default)
		)
		(layer "B.Cu")
	)
	(gr_line
		(start 293.465504 -89.047828)
		(end 293.610284 -89.141808)
		(stroke
			(width 0.08255)
			(type default)
		)
		(layer "B.Cu")
	)
	(gr_line
		(start 293.63416 -71.339964)
		(end 293.778178 -71.435468)
		(stroke
			(width 0.08255)
			(type default)
		)
		(layer "B.Cu")
	)
	(gr_line
		(start 293.638478 -297.108626)
		(end 293.687246 -297.32986)
		(stroke
			(width 0.0635)
			(type default)
		)
		(layer "B.Cu")
	)
	(gr_line
		(start 293.638478 -297.108626)
		(end 293.843202 -296.787316)
		(stroke
			(width 0.0635)
			(type default)
		)
		(layer "B.Cu")
	)
	(gr_line
		(start 293.71925 -183.344312)
		(end 293.748206 -183.49976)
		(stroke
			(width 0.08255)
			(type default)
		)
		(layer "B.Cu")
	)
	(gr_line
		(start 293.71925 -183.344312)
		(end 293.99992 -182.936134)
		(stroke
			(width 0.08255)
			(type default)
		)
		(layer "B.Cu")
	)
	(gr_line
		(start 293.730172 -316.616842)
		(end 293.75227 -316.602618)
		(stroke
			(width 0.0635)
			(type default)
		)
		(layer "B.Cu")
	)
	(gr_line
		(start 293.75227 -316.602618)
		(end 293.766494 -316.58052)
		(stroke
			(width 0.0635)
			(type default)
		)
		(layer "B.Cu")
	)
	(gr_line
		(start 293.839138 -63.057532)
		(end 293.9034 -62.897004)
		(stroke
			(width 0.08255)
			(type default)
		)
		(layer "B.Cu")
	)
	(gr_line
		(start 293.843202 -296.787316)
		(end 294.064182 -296.738294)
		(stroke
			(width 0.0635)
			(type default)
		)
		(layer "B.Cu")
	)
	(gr_line
		(start 293.884604 -91.138248)
		(end 293.969694 -91.004644)
		(stroke
			(width 0.08255)
			(type default)
		)
		(layer "B.Cu")
	)
	(gr_line
		(start 293.9034 -62.897004)
		(end 294.358822 -62.701932)
		(stroke
			(width 0.08255)
			(type default)
		)
		(layer "B.Cu")
	)
	(gr_line
		(start 293.954962 -297.457876)
		(end 294.155622 -297.14317)
		(stroke
			(width 0.0635)
			(type default)
		)
		(layer "B.Cu")
	)
	(gr_line
		(start 293.969694 -91.004644)
		(end 294.453056 -90.897456)
		(stroke
			(width 0.08255)
			(type default)
		)
		(layer "B.Cu")
	)
	(gr_line
		(start 293.981632 -91.418664)
		(end 294.617902 -91.277694)
		(stroke
			(width 0.08255)
			(type default)
		)
		(layer "B.Cu")
	)
	(gr_line
		(start 293.985188 -63.315596)
		(end 294.604694 -63.05042)
		(stroke
			(width 0.08255)
			(type default)
		)
		(layer "B.Cu")
	)
	(gr_line
		(start 293.99992 -182.936134)
		(end 294.155622 -182.907178)
		(stroke
			(width 0.08255)
			(type default)
		)
		(layer "B.Cu")
	)
	(gr_line
		(start 294.010334 -183.638444)
		(end 294.378634 -183.103012)
		(stroke
			(width 0.08255)
			(type default)
		)
		(layer "B.Cu")
	)
	(gr_line
		(start 294.01262 -335.850738)
		(end 294.034718 -335.836514)
		(stroke
			(width 0.0635)
			(type default)
		)
		(layer "B.Cu")
	)
	(gr_line
		(start 294.034718 -335.836514)
		(end 294.048942 -335.814416)
		(stroke
			(width 0.0635)
			(type default)
		)
		(layer "B.Cu")
	)
	(gr_line
		(start 294.222424 -296.19194)
		(end 294.271446 -296.41292)
		(stroke
			(width 0.0635)
			(type default)
		)
		(layer "B.Cu")
	)
	(gr_line
		(start 294.222424 -296.19194)
		(end 294.427148 -295.87063)
		(stroke
			(width 0.0635)
			(type default)
		)
		(layer "B.Cu")
	)
	(gr_line
		(start 294.268144 -71.335646)
		(end 294.363394 -71.191628)
		(stroke
			(width 0.08255)
			(type default)
		)
		(layer "B.Cu")
	)
	(gr_line
		(start 294.358822 -62.701932)
		(end 294.519096 -62.766194)
		(stroke
			(width 0.08255)
			(type default)
		)
		(layer "B.Cu")
	)
	(gr_line
		(start 294.360854 -71.617586)
		(end 295.017698 -71.483982)
		(stroke
			(width 0.08255)
			(type default)
		)
		(layer "B.Cu")
	)
	(gr_line
		(start 294.363394 -71.191628)
		(end 294.848788 -71.092822)
		(stroke
			(width 0.08255)
			(type default)
		)
		(layer "B.Cu")
	)
	(gr_line
		(start 294.41013 -182.339742)
		(end 294.438832 -182.49519)
		(stroke
			(width 0.08255)
			(type default)
		)
		(layer "B.Cu")
	)
	(gr_line
		(start 294.41013 -182.339742)
		(end 294.6908 -181.931564)
		(stroke
			(width 0.08255)
			(type default)
		)
		(layer "B.Cu")
	)
	(gr_line
		(start 294.427148 -295.87063)
		(end 294.648128 -295.821608)
		(stroke
			(width 0.0635)
			(type default)
		)
		(layer "B.Cu")
	)
	(gr_line
		(start 294.453056 -90.897456)
		(end 294.58666 -90.982546)
		(stroke
			(width 0.08255)
			(type default)
		)
		(layer "B.Cu")
	)
	(gr_line
		(start 294.538908 -296.541444)
		(end 294.876982 -296.010838)
		(stroke
			(width 0.0635)
			(type default)
		)
		(layer "B.Cu")
	)
	(gr_line
		(start 294.680132 -337.993228)
		(end 294.70223 -337.979004)
		(stroke
			(width 0.0635)
			(type default)
		)
		(layer "B.Cu")
	)
	(gr_line
		(start 294.6908 -181.931564)
		(end 294.846502 -181.902608)
		(stroke
			(width 0.08255)
			(type default)
		)
		(layer "B.Cu")
	)
	(gr_line
		(start 294.701468 -182.633874)
		(end 295.070276 -182.09768)
		(stroke
			(width 0.08255)
			(type default)
		)
		(layer "B.Cu")
	)
	(gr_line
		(start 294.70223 -337.979004)
		(end 294.716454 -337.956906)
		(stroke
			(width 0.0635)
			(type default)
		)
		(layer "B.Cu")
	)
	(gr_line
		(start 294.774112 -299.45838)
		(end 294.79621 -299.444156)
		(stroke
			(width 0.0635)
			(type default)
		)
		(layer "B.Cu")
	)
	(gr_line
		(start 294.79621 -299.444156)
		(end 294.810434 -299.422058)
		(stroke
			(width 0.0635)
			(type default)
		)
		(layer "B.Cu")
	)
	(gr_line
		(start 294.806624 -295.275)
		(end 294.855646 -295.49598)
		(stroke
			(width 0.0635)
			(type default)
		)
		(layer "B.Cu")
	)
	(gr_line
		(start 294.806624 -295.275)
		(end 295.011348 -294.95369)
		(stroke
			(width 0.0635)
			(type default)
		)
		(layer "B.Cu")
	)
	(gr_line
		(start 294.848788 -71.092822)
		(end 294.992806 -71.188326)
		(stroke
			(width 0.08255)
			(type default)
		)
		(layer "B.Cu")
	)
	(gr_line
		(start 294.978582 -62.569598)
		(end 295.042844 -62.40907)
		(stroke
			(width 0.08255)
			(type default)
		)
		(layer "B.Cu")
	)
	(gr_line
		(start 295.011348 -294.95369)
		(end 295.232328 -294.904668)
		(stroke
			(width 0.0635)
			(type default)
		)
		(layer "B.Cu")
	)
	(gr_line
		(start 295.042844 -62.40907)
		(end 295.498266 -62.213998)
		(stroke
			(width 0.08255)
			(type default)
		)
		(layer "B.Cu")
	)
	(gr_line
		(start 295.074848 -90.874342)
		(end 295.159938 -90.740738)
		(stroke
			(width 0.08255)
			(type default)
		)
		(layer "B.Cu")
	)
	(gr_line
		(start 295.124124 -295.622472)
		(end 295.461182 -295.093644)
		(stroke
			(width 0.0635)
			(type default)
		)
		(layer "B.Cu")
	)
	(gr_line
		(start 295.124886 -62.827408)
		(end 295.742868 -62.56274)
		(stroke
			(width 0.08255)
			(type default)
		)
		(layer "B.Cu")
	)
	(gr_line
		(start 295.129458 -310.375554)
		(end 295.17848 -310.596788)
		(stroke
			(width 0.0635)
			(type default)
		)
		(layer "B.Cu")
	)
	(gr_line
		(start 295.129458 -310.375554)
		(end 295.334182 -310.054244)
		(stroke
			(width 0.0635)
			(type default)
		)
		(layer "B.Cu")
	)
	(gr_line
		(start 295.159938 -90.740738)
		(end 295.643554 -90.63355)
		(stroke
			(width 0.08255)
			(type default)
		)
		(layer "B.Cu")
	)
	(gr_line
		(start 295.171368 -91.155012)
		(end 295.808654 -91.013534)
		(stroke
			(width 0.08255)
			(type default)
		)
		(layer "B.Cu")
	)
	(gr_line
		(start 295.184068 -297.988482)
		(end 295.23309 -298.209716)
		(stroke
			(width 0.0635)
			(type default)
		)
		(layer "B.Cu")
	)
	(gr_line
		(start 295.184068 -297.988482)
		(end 295.388792 -297.667172)
		(stroke
			(width 0.0635)
			(type default)
		)
		(layer "B.Cu")
	)
	(gr_line
		(start 295.266872 -317.483744)
		(end 295.289986 -317.469012)
		(stroke
			(width 0.0635)
			(type default)
		)
		(layer "B.Cu")
	)
	(gr_line
		(start 295.289986 -317.469012)
		(end 295.304464 -317.445898)
		(stroke
			(width 0.0635)
			(type default)
		)
		(layer "B.Cu")
	)
	(gr_line
		(start 295.334182 -310.054244)
		(end 295.555162 -310.005222)
		(stroke
			(width 0.0635)
			(type default)
		)
		(layer "B.Cu")
	)
	(gr_line
		(start 295.388792 -297.667172)
		(end 295.609772 -297.61815)
		(stroke
			(width 0.0635)
			(type default)
		)
		(layer "B.Cu")
	)
	(gr_line
		(start 295.445688 -310.726074)
		(end 295.78554 -310.192166)
		(stroke
			(width 0.0635)
			(type default)
		)
		(layer "B.Cu")
	)
	(gr_line
		(start 295.498266 -62.213998)
		(end 295.65854 -62.27826)
		(stroke
			(width 0.08255)
			(type default)
		)
		(layer "B.Cu")
	)
	(gr_line
		(start 295.500552 -298.33824)
		(end 295.839642 -297.805856)
		(stroke
			(width 0.0635)
			(type default)
		)
		(layer "B.Cu")
	)
	(gr_line
		(start 295.643554 -90.63355)
		(end 295.776904 -90.71864)
		(stroke
			(width 0.08255)
			(type default)
		)
		(layer "B.Cu")
	)
	(gr_line
		(start 295.71315 -309.458614)
		(end 295.762426 -309.67934)
		(stroke
			(width 0.0635)
			(type default)
		)
		(layer "B.Cu")
	)
	(gr_line
		(start 295.71315 -309.458614)
		(end 295.917874 -309.13705)
		(stroke
			(width 0.0635)
			(type default)
		)
		(layer "B.Cu")
	)
	(gr_line
		(start 295.742614 -71.336408)
		(end 295.7449 -71.3359)
		(stroke
			(width 0.08255)
			(type default)
		)
		(layer "B.Cu")
	)
	(gr_line
		(start 295.7449 -71.3359)
		(end 295.747186 -71.334884)
		(stroke
			(width 0.08255)
			(type default)
		)
		(layer "B.Cu")
	)
	(gr_line
		(start 295.768014 -297.071542)
		(end 295.817036 -297.292776)
		(stroke
			(width 0.0635)
			(type default)
		)
		(layer "B.Cu")
	)
	(gr_line
		(start 295.768014 -297.071542)
		(end 295.972738 -296.750232)
		(stroke
			(width 0.0635)
			(type default)
		)
		(layer "B.Cu")
	)
	(gr_line
		(start 295.917874 -309.13705)
		(end 296.138854 -309.088028)
		(stroke
			(width 0.0635)
			(type default)
		)
		(layer "B.Cu")
	)
	(gr_line
		(start 295.967404 -169.755058)
		(end 295.9989 -169.92473)
		(stroke
			(width 0.08255)
			(type default)
		)
		(layer "B.Cu")
	)
	(gr_line
		(start 295.967404 -169.755058)
		(end 296.24782 -169.34688)
		(stroke
			(width 0.08255)
			(type default)
		)
		(layer "B.Cu")
	)
	(gr_line
		(start 295.972738 -296.750232)
		(end 296.193718 -296.70121)
		(stroke
			(width 0.0635)
			(type default)
		)
		(layer "B.Cu")
	)
	(gr_line
		(start 296.029634 -309.80888)
		(end 296.368978 -309.275734)
		(stroke
			(width 0.0635)
			(type default)
		)
		(layer "B.Cu")
	)
	(gr_line
		(start 296.084498 -297.4213)
		(end 296.423588 -296.888916)
		(stroke
			(width 0.0635)
			(type default)
		)
		(layer "B.Cu")
	)
	(gr_line
		(start 296.101008 -299.730922)
		(end 296.15003 -299.952156)
		(stroke
			(width 0.0635)
			(type default)
		)
		(layer "B.Cu")
	)
	(gr_line
		(start 296.101008 -299.730922)
		(end 296.305732 -299.409612)
		(stroke
			(width 0.0635)
			(type default)
		)
		(layer "B.Cu")
	)
	(gr_line
		(start 296.118026 -62.08141)
		(end 296.182288 -61.921136)
		(stroke
			(width 0.08255)
			(type default)
		)
		(layer "B.Cu")
	)
	(gr_line
		(start 296.133774 -300.503844)
		(end 296.157396 -300.489112)
		(stroke
			(width 0.0635)
			(type default)
		)
		(layer "B.Cu")
	)
	(gr_line
		(start 296.157396 -300.489112)
		(end 296.17289 -300.464982)
		(stroke
			(width 0.0635)
			(type default)
		)
		(layer "B.Cu")
	)
	(gr_line
		(start 296.182288 -61.921136)
		(end 296.637456 -61.726064)
		(stroke
			(width 0.08255)
			(type default)
		)
		(layer "B.Cu")
	)
	(gr_line
		(start 296.24782 -169.34688)
		(end 296.417746 -169.31513)
		(stroke
			(width 0.08255)
			(type default)
		)
		(layer "B.Cu")
	)
	(gr_line
		(start 296.262298 -170.061128)
		(end 296.639488 -169.512234)
		(stroke
			(width 0.08255)
			(type default)
		)
		(layer "B.Cu")
	)
	(gr_line
		(start 296.264838 -62.33922)
		(end 296.88155 -62.07506)
		(stroke
			(width 0.08255)
			(type default)
		)
		(layer "B.Cu")
	)
	(gr_line
		(start 296.265092 -90.610436)
		(end 296.350182 -90.476832)
		(stroke
			(width 0.08255)
			(type default)
		)
		(layer "B.Cu")
	)
	(gr_line
		(start 296.297096 -308.54142)
		(end 296.346118 -308.762654)
		(stroke
			(width 0.0635)
			(type default)
		)
		(layer "B.Cu")
	)
	(gr_line
		(start 296.297096 -308.54142)
		(end 296.501566 -308.22011)
		(stroke
			(width 0.0635)
			(type default)
		)
		(layer "B.Cu")
	)
	(gr_line
		(start 296.305732 -299.409612)
		(end 296.526966 -299.36059)
		(stroke
			(width 0.0635)
			(type default)
		)
		(layer "B.Cu")
	)
	(gr_line
		(start 296.350182 -90.476832)
		(end 296.833798 -90.369644)
		(stroke
			(width 0.08255)
			(type default)
		)
		(layer "B.Cu")
	)
	(gr_line
		(start 296.35196 -296.154602)
		(end 296.400982 -296.375582)
		(stroke
			(width 0.0635)
			(type default)
		)
		(layer "B.Cu")
	)
	(gr_line
		(start 296.35196 -296.154602)
		(end 296.556684 -295.833292)
		(stroke
			(width 0.0635)
			(type default)
		)
		(layer "B.Cu")
	)
	(gr_line
		(start 296.361358 -90.891106)
		(end 296.998644 -90.749882)
		(stroke
			(width 0.08255)
			(type default)
		)
		(layer "B.Cu")
	)
	(gr_line
		(start 296.417492 -300.08068)
		(end 296.756074 -299.549058)
		(stroke
			(width 0.0635)
			(type default)
		)
		(layer "B.Cu")
	)
	(gr_line
		(start 296.501566 -308.22011)
		(end 296.722546 -308.171088)
		(stroke
			(width 0.0635)
			(type default)
		)
		(layer "B.Cu")
	)
	(gr_line
		(start 296.556684 -295.833292)
		(end 296.777664 -295.78427)
		(stroke
			(width 0.0635)
			(type default)
		)
		(layer "B.Cu")
	)
	(gr_line
		(start 296.613834 -308.89067)
		(end 296.951908 -308.35981)
		(stroke
			(width 0.0635)
			(type default)
		)
		(layer "B.Cu")
	)
	(gr_line
		(start 296.637456 -61.726064)
		(end 296.797984 -61.790326)
		(stroke
			(width 0.08255)
			(type default)
		)
		(layer "B.Cu")
	)
	(gr_line
		(start 296.668698 -296.504106)
		(end 297.00728 -295.97223)
		(stroke
			(width 0.0635)
			(type default)
		)
		(layer "B.Cu")
	)
	(gr_line
		(start 296.66946 -168.73347)
		(end 296.700956 -168.903396)
		(stroke
			(width 0.08255)
			(type default)
		)
		(layer "B.Cu")
	)
	(gr_line
		(start 296.66946 -168.73347)
		(end 296.95013 -168.325292)
		(stroke
			(width 0.08255)
			(type default)
		)
		(layer "B.Cu")
	)
	(gr_line
		(start 296.684954 -298.813982)
		(end 296.733976 -299.03547)
		(stroke
			(width 0.0635)
			(type default)
		)
		(layer "B.Cu")
	)
	(gr_line
		(start 296.684954 -298.813982)
		(end 296.889678 -298.492672)
		(stroke
			(width 0.0635)
			(type default)
		)
		(layer "B.Cu")
	)
	(gr_line
		(start 296.733976 -318.397636)
		(end 296.756074 -318.383412)
		(stroke
			(width 0.0635)
			(type default)
		)
		(layer "B.Cu")
	)
	(gr_line
		(start 296.756074 -318.383412)
		(end 296.770298 -318.361314)
		(stroke
			(width 0.0635)
			(type default)
		)
		(layer "B.Cu")
	)
	(gr_line
		(start 296.833798 -90.369644)
		(end 296.967148 -90.454734)
		(stroke
			(width 0.08255)
			(type default)
		)
		(layer "B.Cu")
	)
	(gr_line
		(start 296.889678 -298.492672)
		(end 297.111166 -298.44365)
		(stroke
			(width 0.0635)
			(type default)
		)
		(layer "B.Cu")
	)
	(gr_line
		(start 296.95013 -168.325292)
		(end 297.119802 -168.293796)
		(stroke
			(width 0.08255)
			(type default)
		)
		(layer "B.Cu")
	)
	(gr_line
		(start 296.9641 -169.039794)
		(end 297.340782 -168.491916)
		(stroke
			(width 0.08255)
			(type default)
		)
		(layer "B.Cu")
	)
	(gr_line
		(start 296.98315 -310.681116)
		(end 297.032172 -310.90235)
		(stroke
			(width 0.0635)
			(type default)
		)
		(layer "B.Cu")
	)
	(gr_line
		(start 296.98315 -310.681116)
		(end 297.187874 -310.359806)
		(stroke
			(width 0.0635)
			(type default)
		)
		(layer "B.Cu")
	)
	(gr_line
		(start 297.000676 -299.165518)
		(end 297.341036 -298.631102)
		(stroke
			(width 0.0635)
			(type default)
		)
		(layer "B.Cu")
	)
	(gr_line
		(start 297.187874 -310.359806)
		(end 297.408854 -310.310784)
		(stroke
			(width 0.0635)
			(type default)
		)
		(layer "B.Cu")
	)
	(gr_line
		(start 297.269154 -297.897296)
		(end 297.318176 -298.118276)
		(stroke
			(width 0.0635)
			(type default)
		)
		(layer "B.Cu")
	)
	(gr_line
		(start 297.269154 -297.897296)
		(end 297.473878 -297.575986)
		(stroke
			(width 0.0635)
			(type default)
		)
		(layer "B.Cu")
	)
	(gr_line
		(start 297.299888 -311.03062)
		(end 297.638216 -310.498998)
		(stroke
			(width 0.0635)
			(type default)
		)
		(layer "B.Cu")
	)
	(gr_line
		(start 297.37177 -167.712136)
		(end 297.403266 -167.881808)
		(stroke
			(width 0.08255)
			(type default)
		)
		(layer "B.Cu")
	)
	(gr_line
		(start 297.37177 -167.712136)
		(end 297.652186 -167.303958)
		(stroke
			(width 0.08255)
			(type default)
		)
		(layer "B.Cu")
	)
	(gr_line
		(start 297.473878 -297.575986)
		(end 297.694858 -297.526964)
		(stroke
			(width 0.0635)
			(type default)
		)
		(layer "B.Cu")
	)
	(gr_line
		(start 297.516042 -170.595544)
		(end 297.547792 -170.76547)
		(stroke
			(width 0.08255)
			(type default)
		)
		(layer "B.Cu")
	)
	(gr_line
		(start 297.516042 -170.595544)
		(end 297.796712 -170.187366)
		(stroke
			(width 0.08255)
			(type default)
		)
		(layer "B.Cu")
	)
	(gr_line
		(start 297.567096 -309.764176)
		(end 297.616118 -309.985156)
		(stroke
			(width 0.0635)
			(type default)
		)
		(layer "B.Cu")
	)
	(gr_line
		(start 297.567096 -309.764176)
		(end 297.771566 -309.442612)
		(stroke
			(width 0.0635)
			(type default)
		)
		(layer "B.Cu")
	)
	(gr_line
		(start 297.585384 -298.247562)
		(end 297.924474 -297.715178)
		(stroke
			(width 0.0635)
			(type default)
		)
		(layer "B.Cu")
	)
	(gr_line
		(start 297.652186 -167.303958)
		(end 297.821858 -167.272716)
		(stroke
			(width 0.08255)
			(type default)
		)
		(layer "B.Cu")
	)
	(gr_line
		(start 297.66768 -168.016428)
		(end 298.042584 -167.47109)
		(stroke
			(width 0.08255)
			(type default)
		)
		(layer "B.Cu")
	)
	(gr_line
		(start 297.771566 -309.442612)
		(end 297.9928 -309.39359)
		(stroke
			(width 0.0635)
			(type default)
		)
		(layer "B.Cu")
	)
	(gr_line
		(start 297.796712 -170.187366)
		(end 297.966638 -170.15587)
		(stroke
			(width 0.08255)
			(type default)
		)
		(layer "B.Cu")
	)
	(gr_line
		(start 297.811444 -170.90136)
		(end 298.188126 -170.352974)
		(stroke
			(width 0.08255)
			(type default)
		)
		(layer "B.Cu")
	)
	(gr_line
		(start 297.883834 -310.113426)
		(end 298.222162 -309.581804)
		(stroke
			(width 0.0635)
			(type default)
		)
		(layer "B.Cu")
	)
	(gr_line
		(start 298.064936 -167.43934)
		(end 298.067476 -167.43553)
		(stroke
			(width 0.08255)
			(type default)
		)
		(layer "B.Cu")
	)
	(gr_line
		(start 298.073826 -166.690548)
		(end 298.105322 -166.860474)
		(stroke
			(width 0.08255)
			(type default)
		)
		(layer "B.Cu")
	)
	(gr_line
		(start 298.073826 -166.690548)
		(end 298.354496 -166.28237)
		(stroke
			(width 0.08255)
			(type default)
		)
		(layer "B.Cu")
	)
	(gr_line
		(start 298.150788 -308.846982)
		(end 298.19981 -309.068216)
		(stroke
			(width 0.0635)
			(type default)
		)
		(layer "B.Cu")
	)
	(gr_line
		(start 298.150788 -308.846982)
		(end 298.355512 -308.525672)
		(stroke
			(width 0.0635)
			(type default)
		)
		(layer "B.Cu")
	)
	(gr_line
		(start 298.194984 -319.303146)
		(end 298.217082 -319.288922)
		(stroke
			(width 0.0635)
			(type default)
		)
		(layer "B.Cu")
	)
	(gr_line
		(start 298.217082 -319.288922)
		(end 298.231306 -319.266824)
		(stroke
			(width 0.0635)
			(type default)
		)
		(layer "B.Cu")
	)
	(gr_line
		(start 298.218098 -169.573956)
		(end 298.249594 -169.744136)
		(stroke
			(width 0.08255)
			(type default)
		)
		(layer "B.Cu")
	)
	(gr_line
		(start 298.218098 -169.573956)
		(end 298.498768 -169.165778)
		(stroke
			(width 0.08255)
			(type default)
		)
		(layer "B.Cu")
	)
	(gr_line
		(start 298.354496 -166.28237)
		(end 298.524168 -166.250874)
		(stroke
			(width 0.08255)
			(type default)
		)
		(layer "B.Cu")
	)
	(gr_line
		(start 298.355512 -308.525672)
		(end 298.576492 -308.47665)
		(stroke
			(width 0.0635)
			(type default)
		)
		(layer "B.Cu")
	)
	(gr_line
		(start 298.369482 -166.995602)
		(end 298.745148 -166.44874)
		(stroke
			(width 0.08255)
			(type default)
		)
		(layer "B.Cu")
	)
	(gr_line
		(start 298.40936 -311.747154)
		(end 298.458128 -311.968642)
		(stroke
			(width 0.0635)
			(type default)
		)
		(layer "B.Cu")
	)
	(gr_line
		(start 298.40936 -311.747154)
		(end 298.614846 -311.426352)
		(stroke
			(width 0.0635)
			(type default)
		)
		(layer "B.Cu")
	)
	(gr_line
		(start 298.467018 -309.197502)
		(end 298.806362 -308.664356)
		(stroke
			(width 0.0635)
			(type default)
		)
		(layer "B.Cu")
	)
	(gr_line
		(start 298.498768 -169.165778)
		(end 298.66844 -169.134282)
		(stroke
			(width 0.08255)
			(type default)
		)
		(layer "B.Cu")
	)
	(gr_line
		(start 298.512484 -169.881042)
		(end 298.889928 -169.331894)
		(stroke
			(width 0.08255)
			(type default)
		)
		(layer "B.Cu")
	)
	(gr_line
		(start 298.614846 -311.426352)
		(end 298.83608 -311.377584)
		(stroke
			(width 0.0635)
			(type default)
		)
		(layer "B.Cu")
	)
	(gr_line
		(start 298.72432 -312.099452)
		(end 299.066458 -311.564782)
		(stroke
			(width 0.0635)
			(type default)
		)
		(layer "B.Cu")
	)
	(gr_line
		(start 298.920154 -168.552368)
		(end 298.95165 -168.722548)
		(stroke
			(width 0.08255)
			(type default)
		)
		(layer "B.Cu")
	)
	(gr_line
		(start 298.920154 -168.552368)
		(end 299.20057 -168.14419)
		(stroke
			(width 0.08255)
			(type default)
		)
		(layer "B.Cu")
	)
	(gr_line
		(start 298.995338 -310.831484)
		(end 299.043852 -311.052718)
		(stroke
			(width 0.0635)
			(type default)
		)
		(layer "B.Cu")
	)
	(gr_line
		(start 298.995338 -310.831484)
		(end 299.20057 -310.510428)
		(stroke
			(width 0.0635)
			(type default)
		)
		(layer "B.Cu")
	)
	(gr_line
		(start 299.20057 -310.510428)
		(end 299.421804 -310.461914)
		(stroke
			(width 0.0635)
			(type default)
		)
		(layer "B.Cu")
	)
	(gr_line
		(start 299.20057 -168.14419)
		(end 299.370496 -168.112694)
		(stroke
			(width 0.08255)
			(type default)
		)
		(layer "B.Cu")
	)
	(gr_line
		(start 299.215048 -168.858692)
		(end 299.591984 -168.310306)
		(stroke
			(width 0.08255)
			(type default)
		)
		(layer "B.Cu")
	)
	(gr_line
		(start 299.232066 -171.417996)
		(end 299.263562 -171.587922)
		(stroke
			(width 0.08255)
			(type default)
		)
		(layer "B.Cu")
	)
	(gr_line
		(start 299.232066 -171.417996)
		(end 299.512482 -171.009818)
		(stroke
			(width 0.08255)
			(type default)
		)
		(layer "B.Cu")
	)
	(gr_line
		(start 299.310806 -311.182512)
		(end 299.650912 -310.650636)
		(stroke
			(width 0.0635)
			(type default)
		)
		(layer "B.Cu")
	)
	(gr_line
		(start 299.512482 -171.009818)
		(end 299.682408 -170.978322)
		(stroke
			(width 0.08255)
			(type default)
		)
		(layer "B.Cu")
	)
	(gr_line
		(start 299.525436 -171.727114)
		(end 299.905928 -171.173648)
		(stroke
			(width 0.08255)
			(type default)
		)
		(layer "B.Cu")
	)
	(gr_line
		(start 299.581062 -309.91556)
		(end 299.629576 -310.136794)
		(stroke
			(width 0.0635)
			(type default)
		)
		(layer "B.Cu")
	)
	(gr_line
		(start 299.581062 -309.91556)
		(end 299.786294 -309.594504)
		(stroke
			(width 0.0635)
			(type default)
		)
		(layer "B.Cu")
	)
	(gr_line
		(start 299.62221 -167.53078)
		(end 299.653706 -167.700706)
		(stroke
			(width 0.08255)
			(type default)
		)
		(layer "B.Cu")
	)
	(gr_line
		(start 299.62221 -167.53078)
		(end 299.902626 -167.122602)
		(stroke
			(width 0.08255)
			(type default)
		)
		(layer "B.Cu")
	)
	(gr_line
		(start 299.786294 -309.594504)
		(end 300.007528 -309.54599)
		(stroke
			(width 0.0635)
			(type default)
		)
		(layer "B.Cu")
	)
	(gr_line
		(start 299.872654 -312.64733)
		(end 299.921676 -312.868056)
		(stroke
			(width 0.0635)
			(type default)
		)
		(layer "B.Cu")
	)
	(gr_line
		(start 299.872654 -312.64733)
		(end 300.077378 -312.32602)
		(stroke
			(width 0.0635)
			(type default)
		)
		(layer "B.Cu")
	)
	(gr_line
		(start 299.89653 -310.266588)
		(end 300.237144 -309.73395)
		(stroke
			(width 0.0635)
			(type default)
		)
		(layer "B.Cu")
	)
	(gr_line
		(start 299.89907 -320.088514)
		(end 299.921168 -320.07429)
		(stroke
			(width 0.0635)
			(type default)
		)
		(layer "B.Cu")
	)
	(gr_line
		(start 299.902626 -167.122602)
		(end 300.072552 -167.091106)
		(stroke
			(width 0.08255)
			(type default)
		)
		(layer "B.Cu")
	)
	(gr_line
		(start 299.917104 -167.837104)
		(end 300.294802 -167.287702)
		(stroke
			(width 0.08255)
			(type default)
		)
		(layer "B.Cu")
	)
	(gr_line
		(start 299.921168 -320.07429)
		(end 299.935392 -320.052192)
		(stroke
			(width 0.0635)
			(type default)
		)
		(layer "B.Cu")
	)
	(gr_line
		(start 299.934122 -170.396408)
		(end 299.965618 -170.566334)
		(stroke
			(width 0.08255)
			(type default)
		)
		(layer "B.Cu")
	)
	(gr_line
		(start 299.934122 -170.396408)
		(end 300.214792 -169.98823)
		(stroke
			(width 0.08255)
			(type default)
		)
		(layer "B.Cu")
	)
	(gr_line
		(start 300.077378 -312.32602)
		(end 300.298358 -312.276998)
		(stroke
			(width 0.0635)
			(type default)
		)
		(layer "B.Cu")
	)
	(gr_line
		(start 300.188884 -312.997596)
		(end 300.528482 -312.464704)
		(stroke
			(width 0.0635)
			(type default)
		)
		(layer "B.Cu")
	)
	(gr_line
		(start 300.214792 -169.98823)
		(end 300.384464 -169.956734)
		(stroke
			(width 0.08255)
			(type default)
		)
		(layer "B.Cu")
	)
	(gr_line
		(start 300.227746 -170.705018)
		(end 300.607476 -170.152568)
		(stroke
			(width 0.08255)
			(type default)
		)
		(layer "B.Cu")
	)
	(gr_line
		(start 300.369732 -336.291428)
		(end 300.392338 -336.277204)
		(stroke
			(width 0.0635)
			(type default)
		)
		(layer "B.Cu")
	)
	(gr_line
		(start 300.392338 -336.277204)
		(end 300.407324 -336.253836)
		(stroke
			(width 0.0635)
			(type default)
		)
		(layer "B.Cu")
	)
	(gr_line
		(start 300.456854 -311.73039)
		(end 300.505876 -311.951624)
		(stroke
			(width 0.0635)
			(type default)
		)
		(layer "B.Cu")
	)
	(gr_line
		(start 300.456854 -311.73039)
		(end 300.661578 -311.40908)
		(stroke
			(width 0.0635)
			(type default)
		)
		(layer "B.Cu")
	)
	(gr_line
		(start 300.636178 -169.375074)
		(end 300.667674 -169.545)
		(stroke
			(width 0.08255)
			(type default)
		)
		(layer "B.Cu")
	)
	(gr_line
		(start 300.636178 -169.375074)
		(end 300.916848 -168.966896)
		(stroke
			(width 0.08255)
			(type default)
		)
		(layer "B.Cu")
	)
	(gr_line
		(start 300.661578 -311.40908)
		(end 300.882558 -311.360312)
		(stroke
			(width 0.0635)
			(type default)
		)
		(layer "B.Cu")
	)
	(gr_line
		(start 300.773084 -312.080402)
		(end 301.112428 -311.548272)
		(stroke
			(width 0.0635)
			(type default)
		)
		(layer "B.Cu")
	)
	(gr_line
		(start 300.916848 -168.966896)
		(end 301.086774 -168.935146)
		(stroke
			(width 0.08255)
			(type default)
		)
		(layer "B.Cu")
	)
	(gr_line
		(start 300.930056 -169.683176)
		(end 301.31004 -169.130472)
		(stroke
			(width 0.08255)
			(type default)
		)
		(layer "B.Cu")
	)
	(gr_line
		(start 301.00651 -172.730922)
		(end 301.038006 -172.900594)
		(stroke
			(width 0.08255)
			(type default)
		)
		(layer "B.Cu")
	)
	(gr_line
		(start 301.00651 -172.730922)
		(end 301.28718 -172.322744)
		(stroke
			(width 0.08255)
			(type default)
		)
		(layer "B.Cu")
	)
	(gr_line
		(start 301.041054 -310.813704)
		(end 301.090076 -311.034938)
		(stroke
			(width 0.0635)
			(type default)
		)
		(layer "B.Cu")
	)
	(gr_line
		(start 301.041054 -310.813704)
		(end 301.246032 -310.492394)
		(stroke
			(width 0.0635)
			(type default)
		)
		(layer "B.Cu")
	)
	(gr_line
		(start 301.246032 -310.492394)
		(end 301.467012 -310.443372)
		(stroke
			(width 0.0635)
			(type default)
		)
		(layer "B.Cu")
	)
	(gr_line
		(start 301.28718 -172.322744)
		(end 301.456852 -172.291248)
		(stroke
			(width 0.08255)
			(type default)
		)
		(layer "B.Cu")
	)
	(gr_line
		(start 301.29988 -173.04004)
		(end 301.681388 -172.485558)
		(stroke
			(width 0.08255)
			(type default)
		)
		(layer "B.Cu")
	)
	(gr_line
		(start 301.338234 -168.353486)
		(end 301.369984 -168.523412)
		(stroke
			(width 0.08255)
			(type default)
		)
		(layer "B.Cu")
	)
	(gr_line
		(start 301.338234 -168.353486)
		(end 301.618904 -167.945308)
		(stroke
			(width 0.08255)
			(type default)
		)
		(layer "B.Cu")
	)
	(gr_line
		(start 301.357538 -311.163716)
		(end 301.696882 -310.631078)
		(stroke
			(width 0.0635)
			(type default)
		)
		(layer "B.Cu")
	)
	(gr_line
		(start 301.368714 -91.299792)
		(end 301.453804 -91.166188)
		(stroke
			(width 0.08255)
			(type default)
		)
		(layer "B.Cu")
	)
	(gr_line
		(start 301.421546 -313.411616)
		(end 301.470568 -313.632596)
		(stroke
			(width 0.0635)
			(type default)
		)
		(layer "B.Cu")
	)
	(gr_line
		(start 301.421546 -313.411616)
		(end 301.62627 -313.090306)
		(stroke
			(width 0.0635)
			(type default)
		)
		(layer "B.Cu")
	)
	(gr_line
		(start 301.453804 -91.166188)
		(end 301.93742 -91.059)
		(stroke
			(width 0.08255)
			(type default)
		)
		(layer "B.Cu")
	)
	(gr_line
		(start 301.465742 -91.580208)
		(end 302.10125 -91.439238)
		(stroke
			(width 0.08255)
			(type default)
		)
		(layer "B.Cu")
	)
	(gr_line
		(start 301.618904 -167.945308)
		(end 301.78883 -167.913812)
		(stroke
			(width 0.08255)
			(type default)
		)
		(layer "B.Cu")
	)
	(gr_line
		(start 301.62627 -313.090306)
		(end 301.84725 -313.041284)
		(stroke
			(width 0.0635)
			(type default)
		)
		(layer "B.Cu")
	)
	(gr_line
		(start 301.632874 -168.660318)
		(end 302.010826 -168.110662)
		(stroke
			(width 0.08255)
			(type default)
		)
		(layer "B.Cu")
	)
	(gr_line
		(start 301.70882 -171.709588)
		(end 301.740316 -171.879514)
		(stroke
			(width 0.08255)
			(type default)
		)
		(layer "B.Cu")
	)
	(gr_line
		(start 301.70882 -171.709588)
		(end 301.98949 -171.30141)
		(stroke
			(width 0.08255)
			(type default)
		)
		(layer "B.Cu")
	)
	(gr_line
		(start 301.739046 -313.759088)
		(end 302.076358 -313.229752)
		(stroke
			(width 0.0635)
			(type default)
		)
		(layer "B.Cu")
	)
	(gr_line
		(start 301.830232 -316.230762)
		(end 301.879254 -316.451996)
		(stroke
			(width 0.0635)
			(type default)
		)
		(layer "B.Cu")
	)
	(gr_line
		(start 301.830232 -316.230762)
		(end 302.034956 -315.909452)
		(stroke
			(width 0.0635)
			(type default)
		)
		(layer "B.Cu")
	)
	(gr_line
		(start 301.931324 -89.354152)
		(end 302.016414 -89.220548)
		(stroke
			(width 0.08255)
			(type default)
		)
		(layer "B.Cu")
	)
	(gr_line
		(start 301.93742 -91.059)
		(end 302.071024 -91.14409)
		(stroke
			(width 0.08255)
			(type default)
		)
		(layer "B.Cu")
	)
	(gr_line
		(start 301.98949 -171.30141)
		(end 302.159416 -171.269914)
		(stroke
			(width 0.08255)
			(type default)
		)
		(layer "B.Cu")
	)
	(gr_line
		(start 302.001936 -172.019214)
		(end 302.384206 -171.463462)
		(stroke
			(width 0.08255)
			(type default)
		)
		(layer "B.Cu")
	)
	(gr_line
		(start 302.005492 -312.494676)
		(end 302.054514 -312.71591)
		(stroke
			(width 0.0635)
			(type default)
		)
		(layer "B.Cu")
	)
	(gr_line
		(start 302.005492 -312.494676)
		(end 302.210216 -312.173366)
		(stroke
			(width 0.0635)
			(type default)
		)
		(layer "B.Cu")
	)
	(gr_line
		(start 302.016414 -89.220548)
		(end 302.50003 -89.11336)
		(stroke
			(width 0.08255)
			(type default)
		)
		(layer "B.Cu")
	)
	(gr_line
		(start 302.02759 -89.634822)
		(end 302.66513 -89.493598)
		(stroke
			(width 0.08255)
			(type default)
		)
		(layer "B.Cu")
	)
	(gr_line
		(start 302.034956 -315.909452)
		(end 302.255936 -315.86043)
		(stroke
			(width 0.0635)
			(type default)
		)
		(layer "B.Cu")
	)
	(gr_line
		(start 302.147224 -316.579504)
		(end 302.485806 -316.047882)
		(stroke
			(width 0.0635)
			(type default)
		)
		(layer "B.Cu")
	)
	(gr_line
		(start 302.196754 -336.995516)
		(end 302.218852 -336.981292)
		(stroke
			(width 0.0635)
			(type default)
		)
		(layer "B.Cu")
	)
	(gr_line
		(start 302.210216 -312.173366)
		(end 302.431196 -312.124344)
		(stroke
			(width 0.0635)
			(type default)
		)
		(layer "B.Cu")
	)
	(gr_line
		(start 302.218852 -336.981292)
		(end 302.233076 -336.959194)
		(stroke
			(width 0.0635)
			(type default)
		)
		(layer "B.Cu")
	)
	(gr_line
		(start 302.321722 -312.844688)
		(end 302.660558 -312.313066)
		(stroke
			(width 0.0635)
			(type default)
		)
		(layer "B.Cu")
	)
	(gr_line
		(start 302.41113 -170.688254)
		(end 302.442626 -170.857926)
		(stroke
			(width 0.08255)
			(type default)
		)
		(layer "B.Cu")
	)
	(gr_line
		(start 302.41113 -170.688254)
		(end 302.6918 -170.28033)
		(stroke
			(width 0.08255)
			(type default)
		)
		(layer "B.Cu")
	)
	(gr_line
		(start 302.414178 -315.314076)
		(end 302.4632 -315.535056)
		(stroke
			(width 0.0635)
			(type default)
		)
		(layer "B.Cu")
	)
	(gr_line
		(start 302.414178 -315.314076)
		(end 302.618902 -314.992512)
		(stroke
			(width 0.0635)
			(type default)
		)
		(layer "B.Cu")
	)
	(gr_line
		(start 302.50003 -89.11336)
		(end 302.633634 -89.19845)
		(stroke
			(width 0.08255)
			(type default)
		)
		(layer "B.Cu")
	)
	(gr_line
		(start 302.558958 -91.03614)
		(end 302.644048 -90.902536)
		(stroke
			(width 0.08255)
			(type default)
		)
		(layer "B.Cu")
	)
	(gr_line
		(start 302.589438 -311.577736)
		(end 302.63846 -311.79897)
		(stroke
			(width 0.0635)
			(type default)
		)
		(layer "B.Cu")
	)
	(gr_line
		(start 302.589438 -311.577736)
		(end 302.794162 -311.256426)
		(stroke
			(width 0.0635)
			(type default)
		)
		(layer "B.Cu")
	)
	(gr_line
		(start 302.618902 -314.992512)
		(end 302.840136 -314.94349)
		(stroke
			(width 0.0635)
			(type default)
		)
		(layer "B.Cu")
	)
	(gr_line
		(start 302.644048 -90.902536)
		(end 303.127664 -90.795094)
		(stroke
			(width 0.08255)
			(type default)
		)
		(layer "B.Cu")
	)
	(gr_line
		(start 302.655224 -91.316556)
		(end 303.292256 -91.175332)
		(stroke
			(width 0.08255)
			(type default)
		)
		(layer "B.Cu")
	)
	(gr_line
		(start 302.6918 -170.28033)
		(end 302.861726 -170.24858)
		(stroke
			(width 0.08255)
			(type default)
		)
		(layer "B.Cu")
	)
	(gr_line
		(start 302.704754 -170.997626)
		(end 303.086516 -170.442382)
		(stroke
			(width 0.08255)
			(type default)
		)
		(layer "B.Cu")
	)
	(gr_line
		(start 302.730408 -315.664342)
		(end 303.069752 -315.13145)
		(stroke
			(width 0.0635)
			(type default)
		)
		(layer "B.Cu")
	)
	(gr_line
		(start 302.768762 -215.500458)
		(end 302.77435 -215.474804)
		(stroke
			(width 0.0635)
			(type default)
		)
		(layer "B.Cu")
	)
	(gr_line
		(start 302.768762 -215.500458)
		(end 302.774604 -215.526874)
		(stroke
			(width 0.0635)
			(type default)
		)
		(layer "B.Cu")
	)
	(gr_line
		(start 302.794162 -311.256426)
		(end 303.015396 -311.207404)
		(stroke
			(width 0.0635)
			(type default)
		)
		(layer "B.Cu")
	)
	(gr_line
		(start 302.815752 -57.439814)
		(end 302.87976 -57.279794)
		(stroke
			(width 0.08255)
			(type default)
		)
		(layer "B.Cu")
	)
	(gr_line
		(start 302.87976 -57.279794)
		(end 303.335182 -57.084722)
		(stroke
			(width 0.08255)
			(type default)
		)
		(layer "B.Cu")
	)
	(gr_line
		(start 302.905668 -311.928256)
		(end 303.245012 -311.395364)
		(stroke
			(width 0.0635)
			(type default)
		)
		(layer "B.Cu")
	)
	(gr_line
		(start 302.965612 -57.6961)
		(end 303.578514 -57.433464)
		(stroke
			(width 0.08255)
			(type default)
		)
		(layer "B.Cu")
	)
	(gr_line
		(start 302.998378 -314.397136)
		(end 303.0474 -314.618116)
		(stroke
			(width 0.0635)
			(type default)
		)
		(layer "B.Cu")
	)
	(gr_line
		(start 302.998378 -314.397136)
		(end 303.203102 -314.075826)
		(stroke
			(width 0.0635)
			(type default)
		)
		(layer "B.Cu")
	)
	(gr_line
		(start 303.113694 -169.66692)
		(end 303.14519 -169.836846)
		(stroke
			(width 0.08255)
			(type default)
		)
		(layer "B.Cu")
	)
	(gr_line
		(start 303.113694 -169.66692)
		(end 303.394364 -169.258996)
		(stroke
			(width 0.08255)
			(type default)
		)
		(layer "B.Cu")
	)
	(gr_line
		(start 303.121568 -89.090246)
		(end 303.206658 -88.956642)
		(stroke
			(width 0.08255)
			(type default)
		)
		(layer "B.Cu")
	)
	(gr_line
		(start 303.127664 -90.795094)
		(end 303.261522 -90.880184)
		(stroke
			(width 0.08255)
			(type default)
		)
		(layer "B.Cu")
	)
	(gr_line
		(start 303.132236 -279.311354)
		(end 303.139348 -279.300178)
		(stroke
			(width 0.0635)
			(type default)
		)
		(layer "B.Cu")
	)
	(gr_line
		(start 303.139348 -279.300178)
		(end 303.142142 -279.287732)
		(stroke
			(width 0.0635)
			(type default)
		)
		(layer "B.Cu")
	)
	(gr_line
		(start 303.203102 -314.075826)
		(end 303.424082 -314.026804)
		(stroke
			(width 0.0635)
			(type default)
		)
		(layer "B.Cu")
	)
	(gr_line
		(start 303.206658 -88.956642)
		(end 303.690274 -88.849454)
		(stroke
			(width 0.08255)
			(type default)
		)
		(layer "B.Cu")
	)
	(gr_line
		(start 303.218088 -89.370916)
		(end 303.854866 -89.229692)
		(stroke
			(width 0.08255)
			(type default)
		)
		(layer "B.Cu")
	)
	(gr_line
		(start 303.315116 -314.746386)
		(end 303.653444 -314.215018)
		(stroke
			(width 0.0635)
			(type default)
		)
		(layer "B.Cu")
	)
	(gr_line
		(start 303.335182 -57.084722)
		(end 303.495456 -57.14873)
		(stroke
			(width 0.08255)
			(type default)
		)
		(layer "B.Cu")
	)
	(gr_line
		(start 303.394364 -169.258996)
		(end 303.564036 -169.2275)
		(stroke
			(width 0.08255)
			(type default)
		)
		(layer "B.Cu")
	)
	(gr_line
		(start 303.406302 -169.977562)
		(end 303.78908 -169.421048)
		(stroke
			(width 0.08255)
			(type default)
		)
		(layer "B.Cu")
	)
	(gr_line
		(start 303.40681 -85.4456)
		(end 303.421542 -85.442298)
		(stroke
			(width 0.08255)
			(type default)
		)
		(layer "B.Cu")
	)
	(gr_line
		(start 303.421542 -85.442298)
		(end 303.433988 -85.434424)
		(stroke
			(width 0.08255)
			(type default)
		)
		(layer "B.Cu")
	)
	(gr_line
		(start 303.457356 -85.070188)
		(end 303.491646 -84.915502)
		(stroke
			(width 0.08255)
			(type default)
		)
		(layer "B.Cu")
	)
	(gr_line
		(start 303.491646 -84.915502)
		(end 303.909476 -84.64931)
		(stroke
			(width 0.08255)
			(type default)
		)
		(layer "B.Cu")
	)
	(gr_line
		(start 303.646078 -85.299296)
		(end 304.193194 -84.950808)
		(stroke
			(width 0.08255)
			(type default)
		)
		(layer "B.Cu")
	)
	(gr_line
		(start 303.688242 -330.2508)
		(end 303.737264 -330.472034)
		(stroke
			(width 0.0635)
			(type default)
		)
		(layer "B.Cu")
	)
	(gr_line
		(start 303.688242 -330.2508)
		(end 303.892966 -329.92949)
		(stroke
			(width 0.0635)
			(type default)
		)
		(layer "B.Cu")
	)
	(gr_line
		(start 303.690274 -88.849454)
		(end 303.823878 -88.934544)
		(stroke
			(width 0.08255)
			(type default)
		)
		(layer "B.Cu")
	)
	(gr_line
		(start 303.748948 -90.772234)
		(end 303.834292 -90.63863)
		(stroke
			(width 0.08255)
			(type default)
		)
		(layer "B.Cu")
	)
	(gr_line
		(start 303.834292 -90.63863)
		(end 304.317908 -90.531442)
		(stroke
			(width 0.08255)
			(type default)
		)
		(layer "B.Cu")
	)
	(gr_line
		(start 303.845468 -91.05265)
		(end 304.480976 -90.91168)
		(stroke
			(width 0.08255)
			(type default)
		)
		(layer "B.Cu")
	)
	(gr_line
		(start 303.892966 -329.92949)
		(end 304.113946 -329.880468)
		(stroke
			(width 0.0635)
			(type default)
		)
		(layer "B.Cu")
	)
	(gr_line
		(start 303.909476 -84.64931)
		(end 304.063908 -84.6836)
		(stroke
			(width 0.08255)
			(type default)
		)
		(layer "B.Cu")
	)
	(gr_line
		(start 303.954942 -56.952134)
		(end 304.019204 -56.791606)
		(stroke
			(width 0.08255)
			(type default)
		)
		(layer "B.Cu")
	)
	(gr_line
		(start 303.965356 -158.138114)
		(end 303.994312 -158.293816)
		(stroke
			(width 0.08255)
			(type default)
		)
		(layer "B.Cu")
	)
	(gr_line
		(start 303.965356 -158.138114)
		(end 304.246026 -157.729936)
		(stroke
			(width 0.08255)
			(type default)
		)
		(layer "B.Cu")
	)
	(gr_line
		(start 304.004472 -330.60132)
		(end 304.343562 -330.068428)
		(stroke
			(width 0.0635)
			(type default)
		)
		(layer "B.Cu")
	)
	(gr_line
		(start 304.019204 -56.791606)
		(end 304.474372 -56.596788)
		(stroke
			(width 0.08255)
			(type default)
		)
		(layer "B.Cu")
	)
	(gr_line
		(start 304.10404 -57.208674)
		(end 304.71872 -56.94553)
		(stroke
			(width 0.08255)
			(type default)
		)
		(layer "B.Cu")
	)
	(gr_line
		(start 304.246026 -157.729936)
		(end 304.401728 -157.70098)
		(stroke
			(width 0.08255)
			(type default)
		)
		(layer "B.Cu")
	)
	(gr_line
		(start 304.257964 -158.429706)
		(end 304.622962 -157.898846)
		(stroke
			(width 0.08255)
			(type default)
		)
		(layer "B.Cu")
	)
	(gr_line
		(start 304.271934 -329.33386)
		(end 304.320956 -329.55484)
		(stroke
			(width 0.0635)
			(type default)
		)
		(layer "B.Cu")
	)
	(gr_line
		(start 304.271934 -329.33386)
		(end 304.476404 -329.012296)
		(stroke
			(width 0.0635)
			(type default)
		)
		(layer "B.Cu")
	)
	(gr_line
		(start 304.286158 -281.24277)
		(end 304.29327 -281.231594)
		(stroke
			(width 0.0635)
			(type default)
		)
		(layer "B.Cu")
	)
	(gr_line
		(start 304.29327 -281.231594)
		(end 304.296064 -281.219148)
		(stroke
			(width 0.0635)
			(type default)
		)
		(layer "B.Cu")
	)
	(gr_line
		(start 304.311812 -88.82634)
		(end 304.397156 -88.692736)
		(stroke
			(width 0.08255)
			(type default)
		)
		(layer "B.Cu")
	)
	(gr_line
		(start 304.317908 -90.531442)
		(end 304.451512 -90.616532)
		(stroke
			(width 0.08255)
			(type default)
		)
		(layer "B.Cu")
	)
	(gr_line
		(start 304.397156 -88.692736)
		(end 304.880518 -88.585548)
		(stroke
			(width 0.08255)
			(type default)
		)
		(layer "B.Cu")
	)
	(gr_line
		(start 304.407824 -89.106756)
		(end 305.04511 -88.965532)
		(stroke
			(width 0.08255)
			(type default)
		)
		(layer "B.Cu")
	)
	(gr_line
		(start 304.474372 -56.596788)
		(end 304.6349 -56.660796)
		(stroke
			(width 0.08255)
			(type default)
		)
		(layer "B.Cu")
	)
	(gr_line
		(start 304.476404 -329.012296)
		(end 304.697638 -328.963274)
		(stroke
			(width 0.0635)
			(type default)
		)
		(layer "B.Cu")
	)
	(gr_line
		(start 304.485802 -84.414868)
		(end 304.519838 -84.260436)
		(stroke
			(width 0.08255)
			(type default)
		)
		(layer "B.Cu")
	)
	(gr_line
		(start 304.519838 -84.260436)
		(end 304.937668 -83.994244)
		(stroke
			(width 0.08255)
			(type default)
		)
		(layer "B.Cu")
	)
	(gr_line
		(start 304.529998 -215.732614)
		(end 304.547778 -215.812878)
		(stroke
			(width 0.0635)
			(type default)
		)
		(layer "B.Cu")
	)
	(gr_line
		(start 304.529998 -215.732614)
		(end 304.564034 -215.679528)
		(stroke
			(width 0.0635)
			(type default)
		)
		(layer "B.Cu")
	)
	(gr_line
		(start 304.588164 -329.684126)
		(end 304.927254 -329.151234)
		(stroke
			(width 0.0635)
			(type default)
		)
		(layer "B.Cu")
	)
	(gr_line
		(start 304.655982 -157.13329)
		(end 304.684938 -157.289246)
		(stroke
			(width 0.08255)
			(type default)
		)
		(layer "B.Cu")
	)
	(gr_line
		(start 304.655982 -157.13329)
		(end 304.936652 -156.725112)
		(stroke
			(width 0.08255)
			(type default)
		)
		(layer "B.Cu")
	)
	(gr_line
		(start 304.673508 -84.644738)
		(end 305.221386 -84.295742)
		(stroke
			(width 0.08255)
			(type default)
		)
		(layer "B.Cu")
	)
	(gr_line
		(start 304.842926 -215.782398)
		(end 304.844704 -215.77427)
		(stroke
			(width 0.0635)
			(type default)
		)
		(layer "B.Cu")
	)
	(gr_line
		(start 304.855626 -328.416666)
		(end 304.904648 -328.637646)
		(stroke
			(width 0.0635)
			(type default)
		)
		(layer "B.Cu")
	)
	(gr_line
		(start 304.855626 -328.416666)
		(end 305.060096 -328.095102)
		(stroke
			(width 0.0635)
			(type default)
		)
		(layer "B.Cu")
	)
	(gr_line
		(start 304.880518 -88.585548)
		(end 305.014376 -88.670638)
		(stroke
			(width 0.08255)
			(type default)
		)
		(layer "B.Cu")
	)
	(gr_line
		(start 304.936652 -156.725112)
		(end 305.092354 -156.69641)
		(stroke
			(width 0.08255)
			(type default)
		)
		(layer "B.Cu")
	)
	(gr_line
		(start 304.937668 -83.994244)
		(end 305.0921 -84.028534)
		(stroke
			(width 0.08255)
			(type default)
		)
		(layer "B.Cu")
	)
	(gr_line
		(start 304.9397 -90.508328)
		(end 305.02479 -90.374724)
		(stroke
			(width 0.08255)
			(type default)
		)
		(layer "B.Cu")
	)
	(gr_line
		(start 304.94859 -157.425136)
		(end 305.313588 -156.894276)
		(stroke
			(width 0.08255)
			(type default)
		)
		(layer "B.Cu")
	)
	(gr_line
		(start 305.02479 -90.374724)
		(end 305.508152 -90.267536)
		(stroke
			(width 0.08255)
			(type default)
		)
		(layer "B.Cu")
	)
	(gr_line
		(start 305.03749 -90.78849)
		(end 305.67249 -90.647774)
		(stroke
			(width 0.08255)
			(type default)
		)
		(layer "B.Cu")
	)
	(gr_line
		(start 305.060096 -328.095102)
		(end 305.28133 -328.04608)
		(stroke
			(width 0.0635)
			(type default)
		)
		(layer "B.Cu")
	)
	(gr_line
		(start 305.094386 -56.4642)
		(end 305.158648 -56.303672)
		(stroke
			(width 0.08255)
			(type default)
		)
		(layer "B.Cu")
	)
	(gr_line
		(start 305.158648 -56.303672)
		(end 305.613816 -56.1086)
		(stroke
			(width 0.08255)
			(type default)
		)
		(layer "B.Cu")
	)
	(gr_line
		(start 305.171856 -328.766932)
		(end 305.510438 -328.234802)
		(stroke
			(width 0.0635)
			(type default)
		)
		(layer "B.Cu")
	)
	(gr_line
		(start 305.24196 -56.721248)
		(end 305.857148 -56.45785)
		(stroke
			(width 0.08255)
			(type default)
		)
		(layer "B.Cu")
	)
	(gr_line
		(start 305.346862 -156.12872)
		(end 305.375818 -156.284422)
		(stroke
			(width 0.08255)
			(type default)
		)
		(layer "B.Cu")
	)
	(gr_line
		(start 305.346862 -156.12872)
		(end 305.627278 -155.720542)
		(stroke
			(width 0.08255)
			(type default)
		)
		(layer "B.Cu")
	)
	(gr_line
		(start 305.502056 -88.562434)
		(end 305.5874 -88.42883)
		(stroke
			(width 0.08255)
			(type default)
		)
		(layer "B.Cu")
	)
	(gr_line
		(start 305.508152 -90.267536)
		(end 305.641756 -90.352626)
		(stroke
			(width 0.08255)
			(type default)
		)
		(layer "B.Cu")
	)
	(gr_line
		(start 305.513994 -83.759802)
		(end 305.548284 -83.60537)
		(stroke
			(width 0.08255)
			(type default)
		)
		(layer "B.Cu")
	)
	(gr_line
		(start 305.531774 -327.656952)
		(end 305.544728 -327.636632)
		(stroke
			(width 0.0635)
			(type default)
		)
		(layer "B.Cu")
	)
	(gr_line
		(start 305.544728 -327.636632)
		(end 305.564286 -327.623678)
		(stroke
			(width 0.0635)
			(type default)
		)
		(layer "B.Cu")
	)
	(gr_line
		(start 305.548284 -83.60537)
		(end 305.96586 -83.339178)
		(stroke
			(width 0.08255)
			(type default)
		)
		(layer "B.Cu")
	)
	(gr_line
		(start 305.586384 -282.500578)
		(end 305.593496 -282.489402)
		(stroke
			(width 0.0635)
			(type default)
		)
		(layer "B.Cu")
	)
	(gr_line
		(start 305.5874 -88.42883)
		(end 306.070762 -88.321388)
		(stroke
			(width 0.08255)
			(type default)
		)
		(layer "B.Cu")
	)
	(gr_line
		(start 305.593496 -282.489402)
		(end 305.59629 -282.476956)
		(stroke
			(width 0.0635)
			(type default)
		)
		(layer "B.Cu")
	)
	(gr_line
		(start 305.59883 -88.84285)
		(end 306.236116 -88.701372)
		(stroke
			(width 0.08255)
			(type default)
		)
		(layer "B.Cu")
	)
	(gr_line
		(start 305.613816 -56.1086)
		(end 305.774344 -56.172862)
		(stroke
			(width 0.08255)
			(type default)
		)
		(layer "B.Cu")
	)
	(gr_line
		(start 305.627278 -155.720542)
		(end 305.78298 -155.691586)
		(stroke
			(width 0.08255)
			(type default)
		)
		(layer "B.Cu")
	)
	(gr_line
		(start 305.640486 -156.418534)
		(end 306.004468 -155.889198)
		(stroke
			(width 0.08255)
			(type default)
		)
		(layer "B.Cu")
	)
	(gr_line
		(start 305.7017 -83.989672)
		(end 306.24907 -83.64093)
		(stroke
			(width 0.08255)
			(type default)
		)
		(layer "B.Cu")
	)
	(gr_line
		(start 305.96586 -83.339178)
		(end 306.120546 -83.373468)
		(stroke
			(width 0.08255)
			(type default)
		)
		(layer "B.Cu")
	)
	(gr_line
		(start 306.037488 -155.123896)
		(end 306.066444 -155.279598)
		(stroke
			(width 0.08255)
			(type default)
		)
		(layer "B.Cu")
	)
	(gr_line
		(start 306.037488 -155.123896)
		(end 306.317904 -154.715718)
		(stroke
			(width 0.08255)
			(type default)
		)
		(layer "B.Cu")
	)
	(gr_line
		(start 306.070762 -88.321388)
		(end 306.20462 -88.406732)
		(stroke
			(width 0.08255)
			(type default)
		)
		(layer "B.Cu")
	)
	(gr_line
		(start 306.23383 -55.976012)
		(end 306.298092 -55.815738)
		(stroke
			(width 0.08255)
			(type default)
		)
		(layer "B.Cu")
	)
	(gr_line
		(start 306.298092 -55.815738)
		(end 306.75326 -55.620666)
		(stroke
			(width 0.08255)
			(type default)
		)
		(layer "B.Cu")
	)
	(gr_line
		(start 306.303172 -215.34247)
		(end 306.30876 -215.316816)
		(stroke
			(width 0.0635)
			(type default)
		)
		(layer "B.Cu")
	)
	(gr_line
		(start 306.303172 -215.34247)
		(end 306.309014 -215.368886)
		(stroke
			(width 0.0635)
			(type default)
		)
		(layer "B.Cu")
	)
	(gr_line
		(start 306.317904 -154.715718)
		(end 306.473606 -154.687016)
		(stroke
			(width 0.08255)
			(type default)
		)
		(layer "B.Cu")
	)
	(gr_line
		(start 306.330604 -155.414726)
		(end 306.695094 -154.884628)
		(stroke
			(width 0.08255)
			(type default)
		)
		(layer "B.Cu")
	)
	(gr_line
		(start 306.382166 -56.23306)
		(end 306.996846 -55.969662)
		(stroke
			(width 0.08255)
			(type default)
		)
		(layer "B.Cu")
	)
	(gr_line
		(start 306.383436 -293.54399)
		(end 306.39131 -293.531544)
		(stroke
			(width 0.0635)
			(type default)
		)
		(layer "B.Cu")
	)
	(gr_line
		(start 306.39131 -293.531544)
		(end 306.394612 -293.516812)
		(stroke
			(width 0.0635)
			(type default)
		)
		(layer "B.Cu")
	)
	(gr_line
		(start 306.542186 -83.104736)
		(end 306.576476 -82.950304)
		(stroke
			(width 0.08255)
			(type default)
		)
		(layer "B.Cu")
	)
	(gr_line
		(start 306.576476 -82.950304)
		(end 306.994052 -82.684112)
		(stroke
			(width 0.08255)
			(type default)
		)
		(layer "B.Cu")
	)
	(gr_line
		(start 306.677314 -318.336168)
		(end 306.726336 -318.557148)
		(stroke
			(width 0.0635)
			(type default)
		)
		(layer "B.Cu")
	)
	(gr_line
		(start 306.677314 -318.336168)
		(end 306.882038 -318.014858)
		(stroke
			(width 0.0635)
			(type default)
		)
		(layer "B.Cu")
	)
	(gr_line
		(start 306.729384 -83.335114)
		(end 307.278532 -82.985356)
		(stroke
			(width 0.08255)
			(type default)
		)
		(layer "B.Cu")
	)
	(gr_line
		(start 306.738528 -86.652354)
		(end 306.754784 -86.648798)
		(stroke
			(width 0.08255)
			(type default)
		)
		(layer "B.Cu")
	)
	(gr_line
		(start 306.75326 -55.620666)
		(end 306.913534 -55.684928)
		(stroke
			(width 0.08255)
			(type default)
		)
		(layer "B.Cu")
	)
	(gr_line
		(start 306.754784 -86.648798)
		(end 306.768246 -86.639908)
		(stroke
			(width 0.08255)
			(type default)
		)
		(layer "B.Cu")
	)
	(gr_line
		(start 306.882038 -318.014858)
		(end 307.103018 -317.965836)
		(stroke
			(width 0.0635)
			(type default)
		)
		(layer "B.Cu")
	)
	(gr_line
		(start 306.992782 -283.479494)
		(end 307.000656 -283.467048)
		(stroke
			(width 0.0635)
			(type default)
		)
		(layer "B.Cu")
	)
	(gr_line
		(start 306.99329 -318.686942)
		(end 307.33238 -318.154558)
		(stroke
			(width 0.0635)
			(type default)
		)
		(layer "B.Cu")
	)
	(gr_line
		(start 306.994052 -82.684112)
		(end 307.148738 -82.718402)
		(stroke
			(width 0.08255)
			(type default)
		)
		(layer "B.Cu")
	)
	(gr_line
		(start 307.000656 -283.467048)
		(end 307.003958 -283.452316)
		(stroke
			(width 0.0635)
			(type default)
		)
		(layer "B.Cu")
	)
	(gr_line
		(start 307.057044 -86.101174)
		(end 307.092858 -85.932264)
		(stroke
			(width 0.08255)
			(type default)
		)
		(layer "B.Cu")
	)
	(gr_line
		(start 307.092858 -85.932264)
		(end 307.508402 -85.662516)
		(stroke
			(width 0.08255)
			(type default)
		)
		(layer "B.Cu")
	)
	(gr_line
		(start 307.179472 -328.64806)
		(end 307.192426 -328.62774)
		(stroke
			(width 0.0635)
			(type default)
		)
		(layer "B.Cu")
	)
	(gr_line
		(start 307.192426 -328.62774)
		(end 307.211984 -328.614786)
		(stroke
			(width 0.0635)
			(type default)
		)
		(layer "B.Cu")
	)
	(gr_line
		(start 307.247036 -86.329012)
		(end 307.807614 -85.96503)
		(stroke
			(width 0.08255)
			(type default)
		)
		(layer "B.Cu")
	)
	(gr_line
		(start 307.248306 -159.772858)
		(end 307.277262 -159.928814)
		(stroke
			(width 0.08255)
			(type default)
		)
		(layer "B.Cu")
	)
	(gr_line
		(start 307.248306 -159.772858)
		(end 307.528976 -159.36468)
		(stroke
			(width 0.08255)
			(type default)
		)
		(layer "B.Cu")
	)
	(gr_line
		(start 307.261514 -317.419228)
		(end 307.310536 -317.640208)
		(stroke
			(width 0.0635)
			(type default)
		)
		(layer "B.Cu")
	)
	(gr_line
		(start 307.261514 -317.419228)
		(end 307.466238 -317.097918)
		(stroke
			(width 0.0635)
			(type default)
		)
		(layer "B.Cu")
	)
	(gr_line
		(start 307.466238 -317.097918)
		(end 307.687218 -317.048896)
		(stroke
			(width 0.0635)
			(type default)
		)
		(layer "B.Cu")
	)
	(gr_line
		(start 307.508402 -85.662516)
		(end 307.677312 -85.69833)
		(stroke
			(width 0.08255)
			(type default)
		)
		(layer "B.Cu")
	)
	(gr_line
		(start 307.528976 -159.36468)
		(end 307.684932 -159.335724)
		(stroke
			(width 0.08255)
			(type default)
		)
		(layer "B.Cu")
	)
	(gr_line
		(start 307.539898 -160.066482)
		(end 307.907182 -159.53232)
		(stroke
			(width 0.08255)
			(type default)
		)
		(layer "B.Cu")
	)
	(gr_line
		(start 307.57876 -317.767208)
		(end 307.915818 -317.23838)
		(stroke
			(width 0.0635)
			(type default)
		)
		(layer "B.Cu")
	)
	(gr_line
		(start 307.845714 -316.502288)
		(end 307.894736 -316.723268)
		(stroke
			(width 0.0635)
			(type default)
		)
		(layer "B.Cu")
	)
	(gr_line
		(start 307.845714 -316.502288)
		(end 308.050438 -316.180978)
		(stroke
			(width 0.0635)
			(type default)
		)
		(layer "B.Cu")
	)
	(gr_line
		(start 307.938932 -158.768288)
		(end 307.967888 -158.92399)
		(stroke
			(width 0.08255)
			(type default)
		)
		(layer "B.Cu")
	)
	(gr_line
		(start 307.938932 -158.768288)
		(end 308.219602 -158.36011)
		(stroke
			(width 0.08255)
			(type default)
		)
		(layer "B.Cu")
	)
	(gr_line
		(start 308.050438 -316.180978)
		(end 308.271418 -316.131956)
		(stroke
			(width 0.0635)
			(type default)
		)
		(layer "B.Cu")
	)
	(gr_line
		(start 308.096666 -85.426042)
		(end 308.13248 -85.257132)
		(stroke
			(width 0.08255)
			(type default)
		)
		(layer "B.Cu")
	)
	(gr_line
		(start 308.13248 -85.257132)
		(end 308.548024 -84.987384)
		(stroke
			(width 0.08255)
			(type default)
		)
		(layer "B.Cu")
	)
	(gr_line
		(start 308.163214 -316.850014)
		(end 308.500526 -316.320424)
		(stroke
			(width 0.0635)
			(type default)
		)
		(layer "B.Cu")
	)
	(gr_line
		(start 308.219602 -158.36011)
		(end 308.375304 -158.331154)
		(stroke
			(width 0.08255)
			(type default)
		)
		(layer "B.Cu")
	)
	(gr_line
		(start 308.229762 -159.063182)
		(end 308.598316 -158.526988)
		(stroke
			(width 0.08255)
			(type default)
		)
		(layer "B.Cu")
	)
	(gr_line
		(start 308.28615 -85.654388)
		(end 308.849014 -85.288882)
		(stroke
			(width 0.08255)
			(type default)
		)
		(layer "B.Cu")
	)
	(gr_line
		(start 308.334156 -217.016838)
		(end 308.341014 -217.047572)
		(stroke
			(width 0.0635)
			(type default)
		)
		(layer "B.Cu")
	)
	(gr_line
		(start 308.357016 -293.663116)
		(end 308.364128 -293.65194)
		(stroke
			(width 0.0635)
			(type default)
		)
		(layer "B.Cu")
	)
	(gr_line
		(start 308.364128 -293.65194)
		(end 308.366922 -293.639494)
		(stroke
			(width 0.0635)
			(type default)
		)
		(layer "B.Cu")
	)
	(gr_line
		(start 308.548024 -84.987384)
		(end 308.716934 -85.023198)
		(stroke
			(width 0.08255)
			(type default)
		)
		(layer "B.Cu")
	)
	(gr_line
		(start 308.556406 -315.68898)
		(end 308.569868 -315.668152)
		(stroke
			(width 0.0635)
			(type default)
		)
		(layer "B.Cu")
	)
	(gr_line
		(start 308.569868 -315.668152)
		(end 308.589172 -315.655452)
		(stroke
			(width 0.0635)
			(type default)
		)
		(layer "B.Cu")
	)
	(gr_line
		(start 308.629558 -157.763464)
		(end 308.658514 -157.91942)
		(stroke
			(width 0.08255)
			(type default)
		)
		(layer "B.Cu")
	)
	(gr_line
		(start 308.629558 -157.763464)
		(end 308.910228 -157.355286)
		(stroke
			(width 0.08255)
			(type default)
		)
		(layer "B.Cu")
	)
	(gr_line
		(start 308.910228 -157.355286)
		(end 309.06593 -157.32633)
		(stroke
			(width 0.08255)
			(type default)
		)
		(layer "B.Cu")
	)
	(gr_line
		(start 308.920896 -158.057596)
		(end 309.288942 -157.522164)
		(stroke
			(width 0.08255)
			(type default)
		)
		(layer "B.Cu")
	)
	(gr_line
		(start 309.025036 -161.089594)
		(end 309.053992 -161.24555)
		(stroke
			(width 0.08255)
			(type default)
		)
		(layer "B.Cu")
	)
	(gr_line
		(start 309.025036 -161.089594)
		(end 309.305706 -160.68167)
		(stroke
			(width 0.08255)
			(type default)
		)
		(layer "B.Cu")
	)
	(gr_line
		(start 309.136288 -84.75091)
		(end 309.172102 -84.582)
		(stroke
			(width 0.08255)
			(type default)
		)
		(layer "B.Cu")
	)
	(gr_line
		(start 309.172102 -84.582)
		(end 309.587392 -84.312252)
		(stroke
			(width 0.08255)
			(type default)
		)
		(layer "B.Cu")
	)
	(gr_line
		(start 309.305706 -160.68167)
		(end 309.461662 -160.652714)
		(stroke
			(width 0.08255)
			(type default)
		)
		(layer "B.Cu")
	)
	(gr_line
		(start 309.314596 -161.387028)
		(end 309.68696 -160.845754)
		(stroke
			(width 0.08255)
			(type default)
		)
		(layer "B.Cu")
	)
	(gr_line
		(start 309.320184 -156.75864)
		(end 309.34914 -156.914596)
		(stroke
			(width 0.08255)
			(type default)
		)
		(layer "B.Cu")
	)
	(gr_line
		(start 309.320184 -156.75864)
		(end 309.600854 -156.350462)
		(stroke
			(width 0.08255)
			(type default)
		)
		(layer "B.Cu")
	)
	(gr_line
		(start 309.32501 -84.980018)
		(end 309.889652 -84.613242)
		(stroke
			(width 0.08255)
			(type default)
		)
		(layer "B.Cu")
	)
	(gr_line
		(start 309.587392 -84.312252)
		(end 309.756556 -84.348066)
		(stroke
			(width 0.08255)
			(type default)
		)
		(layer "B.Cu")
	)
	(gr_line
		(start 309.600854 -156.350462)
		(end 309.75681 -156.321506)
		(stroke
			(width 0.08255)
			(type default)
		)
		(layer "B.Cu")
	)
	(gr_line
		(start 309.61076 -157.054296)
		(end 309.980584 -156.51607)
		(stroke
			(width 0.08255)
			(type default)
		)
		(layer "B.Cu")
	)
	(gr_line
		(start 309.715916 -160.085278)
		(end 309.744872 -160.24098)
		(stroke
			(width 0.08255)
			(type default)
		)
		(layer "B.Cu")
	)
	(gr_line
		(start 309.715916 -160.085278)
		(end 309.996586 -159.6771)
		(stroke
			(width 0.08255)
			(type default)
		)
		(layer "B.Cu")
	)
	(gr_line
		(start 309.996586 -159.6771)
		(end 310.152542 -159.648144)
		(stroke
			(width 0.08255)
			(type default)
		)
		(layer "B.Cu")
	)
	(gr_line
		(start 310.006492 -160.38068)
		(end 310.376824 -159.842454)
		(stroke
			(width 0.08255)
			(type default)
		)
		(layer "B.Cu")
	)
	(gr_line
		(start 310.169814 -247.59539)
		(end 310.175656 -247.568974)
		(stroke
			(width 0.0635)
			(type default)
		)
		(layer "B.Cu")
	)
	(gr_line
		(start 310.170068 -247.54332)
		(end 310.175656 -247.568974)
		(stroke
			(width 0.0635)
			(type default)
		)
		(layer "B.Cu")
	)
	(gr_line
		(start 310.17591 -84.075778)
		(end 310.211724 -83.907122)
		(stroke
			(width 0.08255)
			(type default)
		)
		(layer "B.Cu")
	)
	(gr_line
		(start 310.211724 -83.907122)
		(end 310.627014 -83.637374)
		(stroke
			(width 0.08255)
			(type default)
		)
		(layer "B.Cu")
	)
	(gr_line
		(start 310.294528 -218.664028)
		(end 310.300116 -218.638374)
		(stroke
			(width 0.0635)
			(type default)
		)
		(layer "B.Cu")
	)
	(gr_line
		(start 310.294528 -218.664028)
		(end 310.30037 -218.690444)
		(stroke
			(width 0.0635)
			(type default)
		)
		(layer "B.Cu")
	)
	(gr_line
		(start 310.364124 -84.30514)
		(end 310.927496 -83.939126)
		(stroke
			(width 0.08255)
			(type default)
		)
		(layer "B.Cu")
	)
	(gr_line
		(start 310.406796 -159.080708)
		(end 310.435752 -159.23641)
		(stroke
			(width 0.08255)
			(type default)
		)
		(layer "B.Cu")
	)
	(gr_line
		(start 310.406796 -159.080708)
		(end 310.687466 -158.67253)
		(stroke
			(width 0.08255)
			(type default)
		)
		(layer "B.Cu")
	)
	(gr_line
		(start 310.605932 -89.252298)
		(end 310.691022 -89.118694)
		(stroke
			(width 0.08255)
			(type default)
		)
		(layer "B.Cu")
	)
	(gr_line
		(start 310.627014 -83.637374)
		(end 310.795924 -83.673188)
		(stroke
			(width 0.08255)
			(type default)
		)
		(layer "B.Cu")
	)
	(gr_line
		(start 310.687466 -158.67253)
		(end 310.843422 -158.643574)
		(stroke
			(width 0.08255)
			(type default)
		)
		(layer "B.Cu")
	)
	(gr_line
		(start 310.691022 -89.118694)
		(end 311.174638 -89.011506)
		(stroke
			(width 0.08255)
			(type default)
		)
		(layer "B.Cu")
	)
	(gr_line
		(start 310.697372 -159.37611)
		(end 311.067704 -158.837884)
		(stroke
			(width 0.08255)
			(type default)
		)
		(layer "B.Cu")
	)
	(gr_line
		(start 310.702452 -89.532714)
		(end 311.338468 -89.391744)
		(stroke
			(width 0.08255)
			(type default)
		)
		(layer "B.Cu")
	)
	(gr_line
		(start 310.979058 -292.9382)
		(end 310.98617 -292.927278)
		(stroke
			(width 0.0635)
			(type default)
		)
		(layer "B.Cu")
	)
	(gr_line
		(start 310.98617 -292.927278)
		(end 310.989218 -292.913562)
		(stroke
			(width 0.0635)
			(type default)
		)
		(layer "B.Cu")
	)
	(gr_line
		(start 311.097676 -158.076138)
		(end 311.126632 -158.232094)
		(stroke
			(width 0.08255)
			(type default)
		)
		(layer "B.Cu")
	)
	(gr_line
		(start 311.097676 -158.076138)
		(end 311.378346 -157.66796)
		(stroke
			(width 0.08255)
			(type default)
		)
		(layer "B.Cu")
	)
	(gr_line
		(start 311.174638 -89.011506)
		(end 311.307988 -89.096596)
		(stroke
			(width 0.08255)
			(type default)
		)
		(layer "B.Cu")
	)
	(gr_line
		(start 311.378346 -157.66796)
		(end 311.534302 -157.639004)
		(stroke
			(width 0.08255)
			(type default)
		)
		(layer "B.Cu")
	)
	(gr_line
		(start 311.38876 -158.370524)
		(end 311.757822 -157.834076)
		(stroke
			(width 0.08255)
			(type default)
		)
		(layer "B.Cu")
	)
	(gr_line
		(start 311.747154 -146.818096)
		(end 311.77611 -146.973798)
		(stroke
			(width 0.08255)
			(type default)
		)
		(layer "B.Cu")
	)
	(gr_line
		(start 311.747154 -146.818096)
		(end 312.027824 -146.409918)
		(stroke
			(width 0.08255)
			(type default)
		)
		(layer "B.Cu")
	)
	(gr_line
		(start 311.795922 -88.988392)
		(end 311.881266 -88.854788)
		(stroke
			(width 0.08255)
			(type default)
		)
		(layer "B.Cu")
	)
	(gr_line
		(start 311.815988 -247.290082)
		(end 311.82183 -247.263666)
		(stroke
			(width 0.0635)
			(type default)
		)
		(layer "B.Cu")
	)
	(gr_line
		(start 311.816242 -247.238012)
		(end 311.82183 -247.263666)
		(stroke
			(width 0.0635)
			(type default)
		)
		(layer "B.Cu")
	)
	(gr_line
		(start 311.881266 -88.854788)
		(end 312.364882 -88.7476)
		(stroke
			(width 0.08255)
			(type default)
		)
		(layer "B.Cu")
	)
	(gr_line
		(start 311.890918 -89.269316)
		(end 312.52922 -89.127838)
		(stroke
			(width 0.08255)
			(type default)
		)
		(layer "B.Cu")
	)
	(gr_line
		(start 312.027824 -146.409918)
		(end 312.183526 -146.380962)
		(stroke
			(width 0.08255)
			(type default)
		)
		(layer "B.Cu")
	)
	(gr_line
		(start 312.038492 -147.111974)
		(end 312.40603 -146.577558)
		(stroke
			(width 0.08255)
			(type default)
		)
		(layer "B.Cu")
	)
	(gr_line
		(start 312.364882 -88.7476)
		(end 312.498486 -88.83269)
		(stroke
			(width 0.08255)
			(type default)
		)
		(layer "B.Cu")
	)
	(gr_line
		(start 312.380122 -274.187158)
		(end 312.382916 -274.174712)
		(stroke
			(width 0.0635)
			(type default)
		)
		(layer "B.Cu")
	)
	(gr_line
		(start 312.382916 -274.174712)
		(end 312.390028 -274.163536)
		(stroke
			(width 0.0635)
			(type default)
		)
		(layer "B.Cu")
	)
	(gr_line
		(start 312.438034 -145.813272)
		(end 312.46699 -145.968974)
		(stroke
			(width 0.08255)
			(type default)
		)
		(layer "B.Cu")
	)
	(gr_line
		(start 312.438034 -145.813272)
		(end 312.71845 -145.405094)
		(stroke
			(width 0.08255)
			(type default)
		)
		(layer "B.Cu")
	)
	(gr_line
		(start 312.71845 -145.405094)
		(end 312.874406 -145.376138)
		(stroke
			(width 0.08255)
			(type default)
		)
		(layer "B.Cu")
	)
	(gr_line
		(start 312.730134 -146.105626)
		(end 313.096148 -145.572988)
		(stroke
			(width 0.08255)
			(type default)
		)
		(layer "B.Cu")
	)
	(gr_line
		(start 312.986674 -88.724486)
		(end 313.07151 -88.590882)
		(stroke
			(width 0.08255)
			(type default)
		)
		(layer "B.Cu")
	)
	(gr_line
		(start 313.07151 -88.590882)
		(end 313.555126 -88.483694)
		(stroke
			(width 0.08255)
			(type default)
		)
		(layer "B.Cu")
	)
	(gr_line
		(start 313.084464 -89.004648)
		(end 313.71921 -88.863932)
		(stroke
			(width 0.08255)
			(type default)
		)
		(layer "B.Cu")
	)
	(gr_line
		(start 313.12866 -144.808702)
		(end 313.157616 -144.96415)
		(stroke
			(width 0.08255)
			(type default)
		)
		(layer "B.Cu")
	)
	(gr_line
		(start 313.12866 -144.808702)
		(end 313.409076 -144.400524)
		(stroke
			(width 0.08255)
			(type default)
		)
		(layer "B.Cu")
	)
	(gr_line
		(start 313.26201 -147.699476)
		(end 313.290966 -147.855432)
		(stroke
			(width 0.08255)
			(type default)
		)
		(layer "B.Cu")
	)
	(gr_line
		(start 313.26201 -147.699476)
		(end 313.542426 -147.291298)
		(stroke
			(width 0.08255)
			(type default)
		)
		(layer "B.Cu")
	)
	(gr_line
		(start 313.408822 -292.254178)
		(end 313.415934 -292.243002)
		(stroke
			(width 0.0635)
			(type default)
		)
		(layer "B.Cu")
	)
	(gr_line
		(start 313.409076 -144.400524)
		(end 313.565032 -144.371568)
		(stroke
			(width 0.08255)
			(type default)
		)
		(layer "B.Cu")
	)
	(gr_line
		(start 313.415934 -292.243002)
		(end 313.418728 -292.230556)
		(stroke
			(width 0.0635)
			(type default)
		)
		(layer "B.Cu")
	)
	(gr_line
		(start 313.421522 -145.099786)
		(end 313.786774 -144.568672)
		(stroke
			(width 0.08255)
			(type default)
		)
		(layer "B.Cu")
	)
	(gr_line
		(start 313.53887 -246.664734)
		(end 313.544712 -246.638318)
		(stroke
			(width 0.0635)
			(type default)
		)
		(layer "B.Cu")
	)
	(gr_line
		(start 313.539124 -246.612664)
		(end 313.544712 -246.638318)
		(stroke
			(width 0.0635)
			(type default)
		)
		(layer "B.Cu")
	)
	(gr_line
		(start 313.542426 -147.291298)
		(end 313.698382 -147.262342)
		(stroke
			(width 0.08255)
			(type default)
		)
		(layer "B.Cu")
	)
	(gr_line
		(start 313.553602 -147.992846)
		(end 313.920632 -147.458938)
		(stroke
			(width 0.08255)
			(type default)
		)
		(layer "B.Cu")
	)
	(gr_line
		(start 313.555126 -88.483694)
		(end 313.68873 -88.568784)
		(stroke
			(width 0.08255)
			(type default)
		)
		(layer "B.Cu")
	)
	(gr_line
		(start 313.812428 -87.02167)
		(end 313.833002 -87.017098)
		(stroke
			(width 0.08255)
			(type default)
		)
		(layer "B.Cu")
	)
	(gr_line
		(start 313.819286 -143.803878)
		(end 313.848242 -143.95958)
		(stroke
			(width 0.08255)
			(type default)
		)
		(layer "B.Cu")
	)
	(gr_line
		(start 313.819286 -143.803878)
		(end 314.099956 -143.3957)
		(stroke
			(width 0.08255)
			(type default)
		)
		(layer "B.Cu")
	)
	(gr_line
		(start 313.833002 -87.017098)
		(end 313.850528 -87.004906)
		(stroke
			(width 0.08255)
			(type default)
		)
		(layer "B.Cu")
	)
	(gr_line
		(start 313.952636 -146.694652)
		(end 313.981592 -146.850608)
		(stroke
			(width 0.08255)
			(type default)
		)
		(layer "B.Cu")
	)
	(gr_line
		(start 313.952636 -146.694652)
		(end 314.233052 -146.286474)
		(stroke
			(width 0.08255)
			(type default)
		)
		(layer "B.Cu")
	)
	(gr_line
		(start 314.099956 -143.3957)
		(end 314.255658 -143.366744)
		(stroke
			(width 0.08255)
			(type default)
		)
		(layer "B.Cu")
	)
	(gr_line
		(start 314.112402 -144.094708)
		(end 314.4774 -143.563594)
		(stroke
			(width 0.08255)
			(type default)
		)
		(layer "B.Cu")
	)
	(gr_line
		(start 314.118752 -86.456774)
		(end 314.146184 -86.300564)
		(stroke
			(width 0.08255)
			(type default)
		)
		(layer "B.Cu")
	)
	(gr_line
		(start 314.146184 -86.300564)
		(end 314.551822 -86.016084)
		(stroke
			(width 0.08255)
			(type default)
		)
		(layer "B.Cu")
	)
	(gr_line
		(start 314.176918 -88.46058)
		(end 314.262008 -88.326976)
		(stroke
			(width 0.08255)
			(type default)
		)
		(layer "B.Cu")
	)
	(gr_line
		(start 314.233052 -146.286474)
		(end 314.389008 -146.257518)
		(stroke
			(width 0.08255)
			(type default)
		)
		(layer "B.Cu")
	)
	(gr_line
		(start 314.245244 -146.986498)
		(end 314.611258 -146.454114)
		(stroke
			(width 0.08255)
			(type default)
		)
		(layer "B.Cu")
	)
	(gr_line
		(start 314.262008 -88.326976)
		(end 314.74537 -88.219788)
		(stroke
			(width 0.08255)
			(type default)
		)
		(layer "B.Cu")
	)
	(gr_line
		(start 314.273946 -88.740996)
		(end 314.909708 -88.600026)
		(stroke
			(width 0.08255)
			(type default)
		)
		(layer "B.Cu")
	)
	(gr_line
		(start 314.315602 -86.678516)
		(end 314.848748 -86.304628)
		(stroke
			(width 0.08255)
			(type default)
		)
		(layer "B.Cu")
	)
	(gr_line
		(start 314.540392 -275.546566)
		(end 314.543186 -275.53412)
		(stroke
			(width 0.0635)
			(type default)
		)
		(layer "B.Cu")
	)
	(gr_line
		(start 314.543186 -275.53412)
		(end 314.550298 -275.522944)
		(stroke
			(width 0.0635)
			(type default)
		)
		(layer "B.Cu")
	)
	(gr_line
		(start 314.551822 -86.016084)
		(end 314.707778 -86.043516)
		(stroke
			(width 0.08255)
			(type default)
		)
		(layer "B.Cu")
	)
	(gr_line
		(start 314.643008 -145.689828)
		(end 314.671964 -145.845784)
		(stroke
			(width 0.08255)
			(type default)
		)
		(layer "B.Cu")
	)
	(gr_line
		(start 314.643008 -145.689828)
		(end 314.923424 -145.28165)
		(stroke
			(width 0.08255)
			(type default)
		)
		(layer "B.Cu")
	)
	(gr_line
		(start 314.74537 -88.219788)
		(end 314.878974 -88.304878)
		(stroke
			(width 0.08255)
			(type default)
		)
		(layer "B.Cu")
	)
	(gr_line
		(start 314.831984 -57.251854)
		(end 314.896246 -57.091326)
		(stroke
			(width 0.08255)
			(type default)
		)
		(layer "B.Cu")
	)
	(gr_line
		(start 314.896246 -57.091326)
		(end 315.351668 -56.896254)
		(stroke
			(width 0.08255)
			(type default)
		)
		(layer "B.Cu")
	)
	(gr_line
		(start 314.923424 -145.28165)
		(end 315.07938 -145.252694)
		(stroke
			(width 0.08255)
			(type default)
		)
		(layer "B.Cu")
	)
	(gr_line
		(start 314.935108 -145.98269)
		(end 315.302392 -145.448274)
		(stroke
			(width 0.08255)
			(type default)
		)
		(layer "B.Cu")
	)
	(gr_line
		(start 314.979812 -57.508902)
		(end 315.595762 -57.24525)
		(stroke
			(width 0.08255)
			(type default)
		)
		(layer "B.Cu")
	)
	(gr_line
		(start 315.004958 -148.4884)
		(end 315.033914 -148.644102)
		(stroke
			(width 0.08255)
			(type default)
		)
		(layer "B.Cu")
	)
	(gr_line
		(start 315.004958 -148.4884)
		(end 315.285628 -148.080222)
		(stroke
			(width 0.08255)
			(type default)
		)
		(layer "B.Cu")
	)
	(gr_line
		(start 315.116972 -85.756496)
		(end 315.144404 -85.60054)
		(stroke
			(width 0.08255)
			(type default)
		)
		(layer "B.Cu")
	)
	(gr_line
		(start 315.144404 -85.60054)
		(end 315.549788 -85.31606)
		(stroke
			(width 0.08255)
			(type default)
		)
		(layer "B.Cu")
	)
	(gr_line
		(start 315.157866 -246.502428)
		(end 315.15812 -246.50192)
		(stroke
			(width 0.0635)
			(type default)
		)
		(layer "B.Cu")
	)
	(gr_line
		(start 315.15812 -246.502174)
		(end 315.163708 -246.476266)
		(stroke
			(width 0.0635)
			(type default)
		)
		(layer "B.Cu")
	)
	(gr_line
		(start 315.15812 -246.45112)
		(end 315.163708 -246.476266)
		(stroke
			(width 0.0635)
			(type default)
		)
		(layer "B.Cu")
	)
	(gr_line
		(start 315.285628 -148.080222)
		(end 315.441076 -148.051266)
		(stroke
			(width 0.08255)
			(type default)
		)
		(layer "B.Cu")
	)
	(gr_line
		(start 315.296296 -148.782532)
		(end 315.66485 -148.246338)
		(stroke
			(width 0.08255)
			(type default)
		)
		(layer "B.Cu")
	)
	(gr_line
		(start 315.314838 -85.97773)
		(end 315.847476 -85.604096)
		(stroke
			(width 0.08255)
			(type default)
		)
		(layer "B.Cu")
	)
	(gr_line
		(start 315.33338 -144.685004)
		(end 315.36259 -144.84096)
		(stroke
			(width 0.08255)
			(type default)
		)
		(layer "B.Cu")
	)
	(gr_line
		(start 315.33338 -144.685004)
		(end 315.61405 -144.276826)
		(stroke
			(width 0.08255)
			(type default)
		)
		(layer "B.Cu")
	)
	(gr_line
		(start 315.351668 -56.896254)
		(end 315.512196 -56.960516)
		(stroke
			(width 0.08255)
			(type default)
		)
		(layer "B.Cu")
	)
	(gr_line
		(start 315.357256 -301.521368)
		(end 315.406278 -301.742602)
		(stroke
			(width 0.0635)
			(type default)
		)
		(layer "B.Cu")
	)
	(gr_line
		(start 315.357256 -301.521368)
		(end 315.56198 -301.200058)
		(stroke
			(width 0.0635)
			(type default)
		)
		(layer "B.Cu")
	)
	(gr_line
		(start 315.464952 -88.476836)
		(end 315.485526 -88.472264)
		(stroke
			(width 0.08255)
			(type default)
		)
		(layer "B.Cu")
	)
	(gr_line
		(start 315.485526 -88.472264)
		(end 315.503052 -88.460072)
		(stroke
			(width 0.08255)
			(type default)
		)
		(layer "B.Cu")
	)
	(gr_line
		(start 315.549788 -85.31606)
		(end 315.705744 -85.343492)
		(stroke
			(width 0.08255)
			(type default)
		)
		(layer "B.Cu")
	)
	(gr_line
		(start 315.56198 -301.200058)
		(end 315.783214 -301.151036)
		(stroke
			(width 0.0635)
			(type default)
		)
		(layer "B.Cu")
	)
	(gr_line
		(start 315.61405 -144.276826)
		(end 315.770006 -144.24787)
		(stroke
			(width 0.08255)
			(type default)
		)
		(layer "B.Cu")
	)
	(gr_line
		(start 315.62548 -144.977866)
		(end 315.992002 -144.44472)
		(stroke
			(width 0.08255)
			(type default)
		)
		(layer "B.Cu")
	)
	(gr_line
		(start 315.672978 -301.872904)
		(end 316.013846 -301.337726)
		(stroke
			(width 0.0635)
			(type default)
		)
		(layer "B.Cu")
	)
	(gr_line
		(start 315.695584 -147.483576)
		(end 315.72454 -147.639278)
		(stroke
			(width 0.08255)
			(type default)
		)
		(layer "B.Cu")
	)
	(gr_line
		(start 315.695584 -147.483576)
		(end 315.976254 -147.075398)
		(stroke
			(width 0.08255)
			(type default)
		)
		(layer "B.Cu")
	)
	(gr_line
		(start 315.941456 -300.604682)
		(end 315.990478 -300.825662)
		(stroke
			(width 0.0635)
			(type default)
		)
		(layer "B.Cu")
	)
	(gr_line
		(start 315.941456 -300.604682)
		(end 316.14618 -300.283372)
		(stroke
			(width 0.0635)
			(type default)
		)
		(layer "B.Cu")
	)
	(gr_line
		(start 315.971174 -56.76392)
		(end 316.03569 -56.603392)
		(stroke
			(width 0.08255)
			(type default)
		)
		(layer "B.Cu")
	)
	(gr_line
		(start 315.976254 -147.075398)
		(end 316.131956 -147.046442)
		(stroke
			(width 0.08255)
			(type default)
		)
		(layer "B.Cu")
	)
	(gr_line
		(start 315.98743 -147.776438)
		(end 316.354206 -147.243038)
		(stroke
			(width 0.08255)
			(type default)
		)
		(layer "B.Cu")
	)
	(gr_line
		(start 316.03569 -56.603392)
		(end 316.491112 -56.40832)
		(stroke
			(width 0.08255)
			(type default)
		)
		(layer "B.Cu")
	)
	(gr_line
		(start 316.051692 -155.571698)
		(end 316.055756 -155.553664)
		(stroke
			(width 0.0635)
			(type default)
		)
		(layer "B.Cu")
	)
	(gr_line
		(start 316.055756 -155.553664)
		(end 316.06617 -155.538424)
		(stroke
			(width 0.0635)
			(type default)
		)
		(layer "B.Cu")
	)
	(gr_line
		(start 316.102746 -87.679276)
		(end 316.129924 -87.523574)
		(stroke
			(width 0.08255)
			(type default)
		)
		(layer "B.Cu")
	)
	(gr_line
		(start 316.114938 -85.056472)
		(end 316.14237 -84.900262)
		(stroke
			(width 0.08255)
			(type default)
		)
		(layer "B.Cu")
	)
	(gr_line
		(start 316.119002 -57.020968)
		(end 316.734444 -56.75757)
		(stroke
			(width 0.08255)
			(type default)
		)
		(layer "B.Cu")
	)
	(gr_line
		(start 316.129924 -87.523574)
		(end 316.535562 -87.239094)
		(stroke
			(width 0.08255)
			(type default)
		)
		(layer "B.Cu")
	)
	(gr_line
		(start 316.14237 -84.900262)
		(end 316.548008 -84.615782)
		(stroke
			(width 0.08255)
			(type default)
		)
		(layer "B.Cu")
	)
	(gr_line
		(start 316.14618 -300.283372)
		(end 316.36716 -300.23435)
		(stroke
			(width 0.0635)
			(type default)
		)
		(layer "B.Cu")
	)
	(gr_line
		(start 316.23889 -74.846434)
		(end 316.256924 -74.842878)
		(stroke
			(width 0.08255)
			(type default)
		)
		(layer "B.Cu")
	)
	(gr_line
		(start 316.256924 -74.842878)
		(end 316.272418 -74.832972)
		(stroke
			(width 0.08255)
			(type default)
		)
		(layer "B.Cu")
	)
	(gr_line
		(start 316.257686 -300.954948)
		(end 316.596776 -300.422564)
		(stroke
			(width 0.0635)
			(type default)
		)
		(layer "B.Cu")
	)
	(gr_line
		(start 316.300358 -87.900764)
		(end 316.83198 -87.527638)
		(stroke
			(width 0.08255)
			(type default)
		)
		(layer "B.Cu")
	)
	(gr_line
		(start 316.311788 -85.278214)
		(end 316.844934 -84.904326)
		(stroke
			(width 0.08255)
			(type default)
		)
		(layer "B.Cu")
	)
	(gr_line
		(start 316.370716 -300.233588)
		(end 316.57544 -299.912278)
		(stroke
			(width 0.0635)
			(type default)
		)
		(layer "B.Cu")
	)
	(gr_line
		(start 316.38621 -146.479006)
		(end 316.415166 -146.634454)
		(stroke
			(width 0.08255)
			(type default)
		)
		(layer "B.Cu")
	)
	(gr_line
		(start 316.38621 -146.479006)
		(end 316.66688 -146.070828)
		(stroke
			(width 0.08255)
			(type default)
		)
		(layer "B.Cu")
	)
	(gr_line
		(start 316.491112 -56.40832)
		(end 316.651386 -56.472582)
		(stroke
			(width 0.08255)
			(type default)
		)
		(layer "B.Cu")
	)
	(gr_line
		(start 316.525656 -299.687742)
		(end 316.574678 -299.908722)
		(stroke
			(width 0.0635)
			(type default)
		)
		(layer "B.Cu")
	)
	(gr_line
		(start 316.525656 -299.687742)
		(end 316.73038 -299.366432)
		(stroke
			(width 0.0635)
			(type default)
		)
		(layer "B.Cu")
	)
	(gr_line
		(start 316.535562 -87.239094)
		(end 316.691518 -87.266526)
		(stroke
			(width 0.08255)
			(type default)
		)
		(layer "B.Cu")
	)
	(gr_line
		(start 316.548008 -84.615782)
		(end 316.703964 -84.643214)
		(stroke
			(width 0.08255)
			(type default)
		)
		(layer "B.Cu")
	)
	(gr_line
		(start 316.66688 -146.070828)
		(end 316.822328 -146.041872)
		(stroke
			(width 0.08255)
			(type default)
		)
		(layer "B.Cu")
	)
	(gr_line
		(start 316.67831 -146.77136)
		(end 317.044578 -146.238722)
		(stroke
			(width 0.08255)
			(type default)
		)
		(layer "B.Cu")
	)
	(gr_line
		(start 316.680342 -276.171406)
		(end 316.683136 -276.15896)
		(stroke
			(width 0.0635)
			(type default)
		)
		(layer "B.Cu")
	)
	(gr_line
		(start 316.683136 -276.15896)
		(end 316.690248 -276.147784)
		(stroke
			(width 0.0635)
			(type default)
		)
		(layer "B.Cu")
	)
	(gr_line
		(start 316.713362 -149.911054)
		(end 316.742064 -150.067264)
		(stroke
			(width 0.08255)
			(type default)
		)
		(layer "B.Cu")
	)
	(gr_line
		(start 316.713362 -149.911054)
		(end 316.994032 -149.50313)
		(stroke
			(width 0.08255)
			(type default)
		)
		(layer "B.Cu")
	)
	(gr_line
		(start 316.73038 -299.366432)
		(end 316.95136 -299.31741)
		(stroke
			(width 0.0635)
			(type default)
		)
		(layer "B.Cu")
	)
	(gr_line
		(start 316.762892 -246.546116)
		(end 316.763146 -246.545608)
		(stroke
			(width 0.0635)
			(type default)
		)
		(layer "B.Cu")
	)
	(gr_line
		(start 316.763146 -246.545354)
		(end 316.768734 -246.519954)
		(stroke
			(width 0.0635)
			(type default)
		)
		(layer "B.Cu")
	)
	(gr_line
		(start 316.763146 -246.494808)
		(end 316.768734 -246.519954)
		(stroke
			(width 0.0635)
			(type default)
		)
		(layer "B.Cu")
	)
	(gr_line
		(start 316.818772 -300.074076)
		(end 316.824868 -300.064424)
		(stroke
			(width 0.0635)
			(type default)
		)
		(layer "B.Cu")
	)
	(gr_line
		(start 316.842648 -300.036484)
		(end 317.180976 -299.50537)
		(stroke
			(width 0.0635)
			(type default)
		)
		(layer "B.Cu")
	)
	(gr_line
		(start 316.994032 -149.50313)
		(end 317.149988 -149.474174)
		(stroke
			(width 0.08255)
			(type default)
		)
		(layer "B.Cu")
	)
	(gr_line
		(start 317.003938 -150.206202)
		(end 317.372746 -149.670008)
		(stroke
			(width 0.08255)
			(type default)
		)
		(layer "B.Cu")
	)
	(gr_line
		(start 317.076836 -145.474182)
		(end 317.105538 -145.62963)
		(stroke
			(width 0.08255)
			(type default)
		)
		(layer "B.Cu")
	)
	(gr_line
		(start 317.076836 -145.474182)
		(end 317.357506 -145.066004)
		(stroke
			(width 0.08255)
			(type default)
		)
		(layer "B.Cu")
	)
	(gr_line
		(start 317.100712 -86.979252)
		(end 317.128144 -86.823296)
		(stroke
			(width 0.08255)
			(type default)
		)
		(layer "B.Cu")
	)
	(gr_line
		(start 317.110618 -56.275986)
		(end 317.175134 -56.115458)
		(stroke
			(width 0.08255)
			(type default)
		)
		(layer "B.Cu")
	)
	(gr_line
		(start 317.128144 -86.823296)
		(end 317.533528 -86.538816)
		(stroke
			(width 0.08255)
			(type default)
		)
		(layer "B.Cu")
	)
	(gr_line
		(start 317.175134 -56.115458)
		(end 317.630556 -55.920386)
		(stroke
			(width 0.08255)
			(type default)
		)
		(layer "B.Cu")
	)
	(gr_line
		(start 317.258954 -56.53278)
		(end 317.873634 -56.269636)
		(stroke
			(width 0.08255)
			(type default)
		)
		(layer "B.Cu")
	)
	(gr_line
		(start 317.297816 -87.201248)
		(end 317.831978 -86.826344)
		(stroke
			(width 0.08255)
			(type default)
		)
		(layer "B.Cu")
	)
	(gr_line
		(start 317.357506 -145.066004)
		(end 317.512954 -145.037048)
		(stroke
			(width 0.08255)
			(type default)
		)
		(layer "B.Cu")
	)
	(gr_line
		(start 317.36919 -145.766282)
		(end 317.735458 -145.233644)
		(stroke
			(width 0.08255)
			(type default)
		)
		(layer "B.Cu")
	)
	(gr_line
		(start 317.404242 -148.906484)
		(end 317.433198 -149.06244)
		(stroke
			(width 0.08255)
			(type default)
		)
		(layer "B.Cu")
	)
	(gr_line
		(start 317.404242 -148.906484)
		(end 317.684912 -148.49856)
		(stroke
			(width 0.08255)
			(type default)
		)
		(layer "B.Cu")
	)
	(gr_line
		(start 317.533528 -86.538816)
		(end 317.689738 -86.566248)
		(stroke
			(width 0.08255)
			(type default)
		)
		(layer "B.Cu")
	)
	(gr_line
		(start 317.630556 -55.920386)
		(end 317.79083 -55.984648)
		(stroke
			(width 0.08255)
			(type default)
		)
		(layer "B.Cu")
	)
	(gr_line
		(start 317.684912 -148.49856)
		(end 317.840868 -148.469604)
		(stroke
			(width 0.08255)
			(type default)
		)
		(layer "B.Cu")
	)
	(gr_line
		(start 317.695834 -149.200362)
		(end 318.063626 -148.665438)
		(stroke
			(width 0.08255)
			(type default)
		)
		(layer "B.Cu")
	)
	(gr_line
		(start 317.842646 -155.799028)
		(end 317.846964 -155.779724)
		(stroke
			(width 0.0635)
			(type default)
		)
		(layer "B.Cu")
	)
	(gr_line
		(start 317.846964 -155.779724)
		(end 317.85814 -155.763722)
		(stroke
			(width 0.0635)
			(type default)
		)
		(layer "B.Cu")
	)
	(gr_line
		(start 318.095122 -147.901914)
		(end 318.124078 -148.05787)
		(stroke
			(width 0.08255)
			(type default)
		)
		(layer "B.Cu")
	)
	(gr_line
		(start 318.095122 -147.901914)
		(end 318.375792 -147.49399)
		(stroke
			(width 0.08255)
			(type default)
		)
		(layer "B.Cu")
	)
	(gr_line
		(start 318.098932 -86.278974)
		(end 318.126364 -86.123018)
		(stroke
			(width 0.08255)
			(type default)
		)
		(layer "B.Cu")
	)
	(gr_line
		(start 318.126364 -86.123018)
		(end 318.531748 -85.838792)
		(stroke
			(width 0.08255)
			(type default)
		)
		(layer "B.Cu")
	)
	(gr_line
		(start 318.250062 -55.788052)
		(end 318.314578 -55.627524)
		(stroke
			(width 0.08255)
			(type default)
		)
		(layer "B.Cu")
	)
	(gr_line
		(start 318.29502 -86.501732)
		(end 318.829436 -86.126828)
		(stroke
			(width 0.08255)
			(type default)
		)
		(layer "B.Cu")
	)
	(gr_line
		(start 318.314578 -55.627524)
		(end 318.769746 -55.432452)
		(stroke
			(width 0.08255)
			(type default)
		)
		(layer "B.Cu")
	)
	(gr_line
		(start 318.375792 -147.49399)
		(end 318.531748 -147.465034)
		(stroke
			(width 0.08255)
			(type default)
		)
		(layer "B.Cu")
	)
	(gr_line
		(start 318.385952 -148.197062)
		(end 318.755268 -147.660106)
		(stroke
			(width 0.08255)
			(type default)
		)
		(layer "B.Cu")
	)
	(gr_line
		(start 318.398144 -56.0451)
		(end 319.014094 -55.781448)
		(stroke
			(width 0.08255)
			(type default)
		)
		(layer "B.Cu")
	)
	(gr_line
		(start 318.470026 -287.492694)
		(end 318.477138 -287.481518)
		(stroke
			(width 0.0635)
			(type default)
		)
		(layer "B.Cu")
	)
	(gr_line
		(start 318.477138 -287.481518)
		(end 318.479932 -287.469072)
		(stroke
			(width 0.0635)
			(type default)
		)
		(layer "B.Cu")
	)
	(gr_line
		(start 318.531748 -85.838792)
		(end 318.687704 -85.866224)
		(stroke
			(width 0.08255)
			(type default)
		)
		(layer "B.Cu")
	)
	(gr_line
		(start 318.769746 -55.432452)
		(end 318.930274 -55.496714)
		(stroke
			(width 0.08255)
			(type default)
		)
		(layer "B.Cu")
	)
	(gr_line
		(start 318.786002 -146.897344)
		(end 318.814958 -147.0533)
		(stroke
			(width 0.08255)
			(type default)
		)
		(layer "B.Cu")
	)
	(gr_line
		(start 318.786002 -146.897344)
		(end 319.066672 -146.48942)
		(stroke
			(width 0.08255)
			(type default)
		)
		(layer "B.Cu")
	)
	(gr_line
		(start 319.066672 -146.48942)
		(end 319.222628 -146.460464)
		(stroke
			(width 0.08255)
			(type default)
		)
		(layer "B.Cu")
	)
	(gr_line
		(start 319.076832 -147.192492)
		(end 319.446148 -146.655536)
		(stroke
			(width 0.08255)
			(type default)
		)
		(layer "B.Cu")
	)
	(gr_line
		(start 319.263776 -75.000104)
		(end 319.297812 -74.845672)
		(stroke
			(width 0.08255)
			(type default)
		)
		(layer "B.Cu")
	)
	(gr_line
		(start 319.292732 -156.824172)
		(end 319.29705 -156.804868)
		(stroke
			(width 0.0635)
			(type default)
		)
		(layer "B.Cu")
	)
	(gr_line
		(start 319.29705 -156.804868)
		(end 319.308226 -156.788866)
		(stroke
			(width 0.0635)
			(type default)
		)
		(layer "B.Cu")
	)
	(gr_line
		(start 319.297812 -74.845672)
		(end 319.715642 -74.57948)
		(stroke
			(width 0.08255)
			(type default)
		)
		(layer "B.Cu")
	)
	(gr_line
		(start 319.451228 -75.230228)
		(end 319.999868 -74.880724)
		(stroke
			(width 0.08255)
			(type default)
		)
		(layer "B.Cu")
	)
	(gr_line
		(start 319.715642 -74.57948)
		(end 319.870074 -74.61377)
		(stroke
			(width 0.08255)
			(type default)
		)
		(layer "B.Cu")
	)
	(gr_line
		(start 319.753742 -288.939224)
		(end 319.760854 -288.928048)
		(stroke
			(width 0.0635)
			(type default)
		)
		(layer "B.Cu")
	)
	(gr_line
		(start 319.760854 -288.928048)
		(end 319.763648 -288.915602)
		(stroke
			(width 0.0635)
			(type default)
		)
		(layer "B.Cu")
	)
	(gr_line
		(start 319.993772 -70.550024)
		(end 320.007996 -70.546976)
		(stroke
			(width 0.08255)
			(type default)
		)
		(layer "B.Cu")
	)
	(gr_line
		(start 320.003932 -295.07434)
		(end 320.011044 -295.063164)
		(stroke
			(width 0.0635)
			(type default)
		)
		(layer "B.Cu")
	)
	(gr_line
		(start 320.007996 -70.546976)
		(end 320.01968 -70.53961)
		(stroke
			(width 0.08255)
			(type default)
		)
		(layer "B.Cu")
	)
	(gr_line
		(start 320.011044 -295.063164)
		(end 320.013838 -295.050718)
		(stroke
			(width 0.0635)
			(type default)
		)
		(layer "B.Cu")
	)
	(gr_line
		(start 320.291968 -74.345038)
		(end 320.326258 -74.190352)
		(stroke
			(width 0.08255)
			(type default)
		)
		(layer "B.Cu")
	)
	(gr_line
		(start 320.326258 -74.190352)
		(end 320.743834 -73.924414)
		(stroke
			(width 0.08255)
			(type default)
		)
		(layer "B.Cu")
	)
	(gr_line
		(start 320.478658 -74.57567)
		(end 321.02933 -74.224896)
		(stroke
			(width 0.08255)
			(type default)
		)
		(layer "B.Cu")
	)
	(gr_line
		(start 320.743834 -73.924414)
		(end 320.89852 -73.95845)
		(stroke
			(width 0.08255)
			(type default)
		)
		(layer "B.Cu")
	)
	(gr_line
		(start 321.152774 -76.947522)
		(end 321.188588 -76.778612)
		(stroke
			(width 0.08255)
			(type default)
		)
		(layer "B.Cu")
	)
	(gr_line
		(start 321.188588 -76.778612)
		(end 321.604132 -76.508864)
		(stroke
			(width 0.08255)
			(type default)
		)
		(layer "B.Cu")
	)
	(gr_line
		(start 321.32016 -73.689972)
		(end 321.35445 -73.535286)
		(stroke
			(width 0.08255)
			(type default)
		)
		(layer "B.Cu")
	)
	(gr_line
		(start 321.342512 -77.175614)
		(end 321.903852 -76.811124)
		(stroke
			(width 0.08255)
			(type default)
		)
		(layer "B.Cu")
	)
	(gr_line
		(start 321.35445 -73.535286)
		(end 321.772026 -73.269348)
		(stroke
			(width 0.08255)
			(type default)
		)
		(layer "B.Cu")
	)
	(gr_line
		(start 321.506342 -73.921112)
		(end 322.058284 -73.569322)
		(stroke
			(width 0.08255)
			(type default)
		)
		(layer "B.Cu")
	)
	(gr_line
		(start 321.60337 -272.027142)
		(end 321.606926 -272.011394)
		(stroke
			(width 0.0635)
			(type default)
		)
		(layer "B.Cu")
	)
	(gr_line
		(start 321.604132 -76.508864)
		(end 321.772788 -76.544678)
		(stroke
			(width 0.08255)
			(type default)
		)
		(layer "B.Cu")
	)
	(gr_line
		(start 321.606926 -272.011394)
		(end 321.615816 -271.997932)
		(stroke
			(width 0.0635)
			(type default)
		)
		(layer "B.Cu")
	)
	(gr_line
		(start 321.718178 -156.662374)
		(end 321.72275 -156.642308)
		(stroke
			(width 0.0635)
			(type default)
		)
		(layer "B.Cu")
	)
	(gr_line
		(start 321.72275 -156.642308)
		(end 321.734434 -156.62529)
		(stroke
			(width 0.0635)
			(type default)
		)
		(layer "B.Cu")
	)
	(gr_line
		(start 321.772026 -73.269348)
		(end 321.926712 -73.303384)
		(stroke
			(width 0.08255)
			(type default)
		)
		(layer "B.Cu")
	)
	(gr_line
		(start 322.021708 -277.379684)
		(end 322.025264 -277.363936)
		(stroke
			(width 0.0635)
			(type default)
		)
		(layer "B.Cu")
	)
	(gr_line
		(start 322.025264 -277.363936)
		(end 322.034154 -277.350474)
		(stroke
			(width 0.0635)
			(type default)
		)
		(layer "B.Cu")
	)
	(gr_line
		(start 322.192396 -76.27239)
		(end 322.22821 -76.10348)
		(stroke
			(width 0.08255)
			(type default)
		)
		(layer "B.Cu")
	)
	(gr_line
		(start 322.22821 -76.10348)
		(end 322.6435 -75.833732)
		(stroke
			(width 0.08255)
			(type default)
		)
		(layer "B.Cu")
	)
	(gr_line
		(start 322.348352 -73.034906)
		(end 322.382642 -72.88022)
		(stroke
			(width 0.08255)
			(type default)
		)
		(layer "B.Cu")
	)
	(gr_line
		(start 322.382134 -76.500482)
		(end 322.944236 -76.135484)
		(stroke
			(width 0.08255)
			(type default)
		)
		(layer "B.Cu")
	)
	(gr_line
		(start 322.382642 -72.88022)
		(end 322.800472 -72.614028)
		(stroke
			(width 0.08255)
			(type default)
		)
		(layer "B.Cu")
	)
	(gr_line
		(start 322.392802 -164.156644)
		(end 322.396358 -164.140642)
		(stroke
			(width 0.0635)
			(type default)
		)
		(layer "B.Cu")
	)
	(gr_line
		(start 322.396358 -164.140642)
		(end 322.405248 -164.12718)
		(stroke
			(width 0.0635)
			(type default)
		)
		(layer "B.Cu")
	)
	(gr_line
		(start 322.534026 -73.266554)
		(end 323.088254 -72.913494)
		(stroke
			(width 0.08255)
			(type default)
		)
		(layer "B.Cu")
	)
	(gr_line
		(start 322.6435 -75.833732)
		(end 322.81241 -75.869546)
		(stroke
			(width 0.08255)
			(type default)
		)
		(layer "B.Cu")
	)
	(gr_line
		(start 322.800472 -72.614028)
		(end 322.954904 -72.648318)
		(stroke
			(width 0.08255)
			(type default)
		)
		(layer "B.Cu")
	)
	(gr_line
		(start 322.952872 -130.517392)
		(end 322.981574 -130.673602)
		(stroke
			(width 0.08255)
			(type default)
		)
		(layer "B.Cu")
	)
	(gr_line
		(start 322.952872 -130.517392)
		(end 323.233288 -130.109214)
		(stroke
			(width 0.08255)
			(type default)
		)
		(layer "B.Cu")
	)
	(gr_line
		(start 323.14261 -163.01339)
		(end 323.15404 -162.996118)
		(stroke
			(width 0.0635)
			(type default)
		)
		(layer "B.Cu")
	)
	(gr_line
		(start 323.15404 -162.996118)
		(end 323.171312 -162.984688)
		(stroke
			(width 0.0635)
			(type default)
		)
		(layer "B.Cu")
	)
	(gr_line
		(start 323.232018 -75.597258)
		(end 323.267832 -75.428348)
		(stroke
			(width 0.08255)
			(type default)
		)
		(layer "B.Cu")
	)
	(gr_line
		(start 323.233288 -130.109214)
		(end 323.389498 -130.080258)
		(stroke
			(width 0.08255)
			(type default)
		)
		(layer "B.Cu")
	)
	(gr_line
		(start 323.243702 -130.812032)
		(end 323.612764 -130.27533)
		(stroke
			(width 0.08255)
			(type default)
		)
		(layer "B.Cu")
	)
	(gr_line
		(start 323.267832 -75.428348)
		(end 323.683122 -75.1586)
		(stroke
			(width 0.08255)
			(type default)
		)
		(layer "B.Cu")
	)
	(gr_line
		(start 323.42201 -75.825096)
		(end 323.98335 -75.460606)
		(stroke
			(width 0.08255)
			(type default)
		)
		(layer "B.Cu")
	)
	(gr_line
		(start 323.482462 -278.066754)
		(end 323.50075 -277.984966)
		(stroke
			(width 0.0635)
			(type default)
		)
		(layer "B.Cu")
	)
	(gr_line
		(start 323.50075 -277.984966)
		(end 323.571362 -277.940008)
		(stroke
			(width 0.0635)
			(type default)
		)
		(layer "B.Cu")
	)
	(gr_line
		(start 323.546216 -162.73653)
		(end 323.562218 -162.726116)
		(stroke
			(width 0.0635)
			(type default)
		)
		(layer "B.Cu")
	)
	(gr_line
		(start 323.562218 -162.726116)
		(end 323.581014 -162.722306)
		(stroke
			(width 0.0635)
			(type default)
		)
		(layer "B.Cu")
	)
	(gr_line
		(start 323.643498 -129.512568)
		(end 323.672454 -129.668524)
		(stroke
			(width 0.08255)
			(type default)
		)
		(layer "B.Cu")
	)
	(gr_line
		(start 323.643498 -129.512568)
		(end 323.923914 -129.10439)
		(stroke
			(width 0.08255)
			(type default)
		)
		(layer "B.Cu")
	)
	(gr_line
		(start 323.683122 -75.1586)
		(end 323.852032 -75.194414)
		(stroke
			(width 0.08255)
			(type default)
		)
		(layer "B.Cu")
	)
	(gr_line
		(start 323.823838 -162.67303)
		(end 324.141338 -162.608514)
		(stroke
			(width 0.0635)
			(type default)
		)
		(layer "B.Cu")
	)
	(gr_line
		(start 323.923914 -129.10439)
		(end 324.07987 -129.075688)
		(stroke
			(width 0.08255)
			(type default)
		)
		(layer "B.Cu")
	)
	(gr_line
		(start 323.934582 -129.807208)
		(end 324.303644 -129.270506)
		(stroke
			(width 0.08255)
			(type default)
		)
		(layer "B.Cu")
	)
	(gr_line
		(start 323.99097 -162.93719)
		(end 324.1929 -162.896042)
		(stroke
			(width 0.0635)
			(type default)
		)
		(layer "B.Cu")
	)
	(gr_line
		(start 324.06082 -277.629112)
		(end 324.100444 -277.603966)
		(stroke
			(width 0.0635)
			(type default)
		)
		(layer "B.Cu")
	)
	(gr_line
		(start 324.1929 -162.896042)
		(end 324.193408 -162.896042)
		(stroke
			(width 0.0635)
			(type default)
		)
		(layer "B.Cu")
	)
	(gr_line
		(start 324.271386 -74.922126)
		(end 324.307454 -74.753216)
		(stroke
			(width 0.08255)
			(type default)
		)
		(layer "B.Cu")
	)
	(gr_line
		(start 324.307454 -74.753216)
		(end 324.722744 -74.483468)
		(stroke
			(width 0.08255)
			(type default)
		)
		(layer "B.Cu")
	)
	(gr_line
		(start 324.334124 -128.507998)
		(end 324.36308 -128.663954)
		(stroke
			(width 0.08255)
			(type default)
		)
		(layer "B.Cu")
	)
	(gr_line
		(start 324.334124 -128.507998)
		(end 324.614794 -128.09982)
		(stroke
			(width 0.08255)
			(type default)
		)
		(layer "B.Cu")
	)
	(gr_line
		(start 324.460362 -75.15098)
		(end 325.024242 -74.784966)
		(stroke
			(width 0.08255)
			(type default)
		)
		(layer "B.Cu")
	)
	(gr_line
		(start 324.46849 -131.39166)
		(end 324.497446 -131.547616)
		(stroke
			(width 0.08255)
			(type default)
		)
		(layer "B.Cu")
	)
	(gr_line
		(start 324.46849 -131.39166)
		(end 324.748906 -130.983482)
		(stroke
			(width 0.08255)
			(type default)
		)
		(layer "B.Cu")
	)
	(gr_arc
		(start 324.562216 -277.603966)
		(mid 324.687204 -277.55218)
		(end 324.739 -277.427182)
		(stroke
			(width 0.0635)
			(type default)
		)
		(layer "B.Cu")
	)
	(gr_arc
		(start 324.562216 -162.603942)
		(mid 324.687196 -162.552155)
		(end 324.739 -162.427158)
		(stroke
			(width 0.0635)
			(type default)
		)
		(layer "B.Cu")
	)
	(gr_line
		(start 324.614794 -128.09982)
		(end 324.77075 -128.070864)
		(stroke
			(width 0.08255)
			(type default)
		)
		(layer "B.Cu")
	)
	(gr_line
		(start 324.624954 -128.803146)
		(end 324.99554 -128.264158)
		(stroke
			(width 0.08255)
			(type default)
		)
		(layer "B.Cu")
	)
	(gr_line
		(start 324.722744 -74.483468)
		(end 324.891654 -74.519282)
		(stroke
			(width 0.08255)
			(type default)
		)
		(layer "B.Cu")
	)
	(gr_arc
		(start 324.739 -278.07285)
		(mid 324.687221 -277.947845)
		(end 324.562216 -277.896066)
		(stroke
			(width 0.0635)
			(type default)
		)
		(layer "B.Cu")
	)
	(gr_line
		(start 324.739 -278.07285)
		(end 324.739 -278.321516)
		(stroke
			(width 0.0635)
			(type default)
		)
		(layer "B.Cu")
	)
	(gr_line
		(start 324.739 -277.178516)
		(end 324.739 -277.427182)
		(stroke
			(width 0.0635)
			(type default)
		)
		(layer "B.Cu")
	)
	(gr_arc
		(start 324.739 -163.072826)
		(mid 324.687231 -162.947798)
		(end 324.562216 -162.896042)
		(stroke
			(width 0.0635)
			(type default)
		)
		(layer "B.Cu")
	)
	(gr_line
		(start 324.739 -163.072826)
		(end 324.739 -163.321492)
		(stroke
			(width 0.0635)
			(type default)
		)
		(layer "B.Cu")
	)
	(gr_line
		(start 324.739 -162.178492)
		(end 324.739 -162.427158)
		(stroke
			(width 0.0635)
			(type default)
		)
		(layer "B.Cu")
	)
	(gr_line
		(start 324.748906 -130.983482)
		(end 324.904862 -130.954526)
		(stroke
			(width 0.08255)
			(type default)
		)
		(layer "B.Cu")
	)
	(gr_line
		(start 324.760336 -131.684776)
		(end 325.12762 -131.15036)
		(stroke
			(width 0.08255)
			(type default)
		)
		(layer "B.Cu")
	)
	(gr_line
		(start 325.02475 -127.503174)
		(end 325.053706 -127.659384)
		(stroke
			(width 0.08255)
			(type default)
		)
		(layer "B.Cu")
	)
	(gr_line
		(start 325.02475 -127.503174)
		(end 325.30542 -127.094996)
		(stroke
			(width 0.08255)
			(type default)
		)
		(layer "B.Cu")
	)
	(gr_line
		(start 325.159116 -130.386836)
		(end 325.188072 -130.542538)
		(stroke
			(width 0.08255)
			(type default)
		)
		(layer "B.Cu")
	)
	(gr_line
		(start 325.159116 -130.386836)
		(end 325.439532 -129.978658)
		(stroke
			(width 0.08255)
			(type default)
		)
		(layer "B.Cu")
	)
	(gr_line
		(start 325.30542 -127.094996)
		(end 325.461376 -127.066294)
		(stroke
			(width 0.08255)
			(type default)
		)
		(layer "B.Cu")
	)
	(gr_line
		(start 325.31558 -127.798322)
		(end 325.685404 -127.260604)
		(stroke
			(width 0.08255)
			(type default)
		)
		(layer "B.Cu")
	)
	(gr_line
		(start 325.439532 -129.978658)
		(end 325.595234 -129.949702)
		(stroke
			(width 0.08255)
			(type default)
		)
		(layer "B.Cu")
	)
	(gr_line
		(start 325.451216 -130.67919)
		(end 325.816722 -130.147314)
		(stroke
			(width 0.08255)
			(type default)
		)
		(layer "B.Cu")
	)
	(gr_line
		(start 325.849488 -129.382012)
		(end 325.878444 -129.537968)
		(stroke
			(width 0.08255)
			(type default)
		)
		(layer "B.Cu")
	)
	(gr_line
		(start 325.849488 -129.382012)
		(end 326.129904 -128.973834)
		(stroke
			(width 0.08255)
			(type default)
		)
		(layer "B.Cu")
	)
	(gr_line
		(start 325.91883 -27.658568)
		(end 325.930006 -27.651456)
		(stroke
			(width 0.08255)
			(type default)
		)
		(layer "B.Cu")
	)
	(gr_line
		(start 325.930006 -27.651456)
		(end 325.942452 -27.648662)
		(stroke
			(width 0.08255)
			(type default)
		)
		(layer "B.Cu")
	)
	(gr_line
		(start 326.10171 -132.343906)
		(end 326.130666 -132.499608)
		(stroke
			(width 0.08255)
			(type default)
		)
		(layer "B.Cu")
	)
	(gr_line
		(start 326.10171 -132.343906)
		(end 326.382126 -131.935728)
		(stroke
			(width 0.08255)
			(type default)
		)
		(layer "B.Cu")
	)
	(gr_line
		(start 326.129904 -128.973834)
		(end 326.28586 -128.944878)
		(stroke
			(width 0.08255)
			(type default)
		)
		(layer "B.Cu")
	)
	(gr_line
		(start 326.141588 -129.67462)
		(end 326.50811 -129.141474)
		(stroke
			(width 0.08255)
			(type default)
		)
		(layer "B.Cu")
	)
	(gr_line
		(start 326.382126 -131.935728)
		(end 326.538082 -131.906772)
		(stroke
			(width 0.08255)
			(type default)
		)
		(layer "B.Cu")
	)
	(gr_line
		(start 326.393302 -132.63753)
		(end 326.761602 -132.101844)
		(stroke
			(width 0.08255)
			(type default)
		)
		(layer "B.Cu")
	)
	(gr_line
		(start 326.53986 -128.377188)
		(end 326.56907 -128.53289)
		(stroke
			(width 0.08255)
			(type default)
		)
		(layer "B.Cu")
	)
	(gr_line
		(start 326.53986 -128.377188)
		(end 326.82053 -127.96901)
		(stroke
			(width 0.08255)
			(type default)
		)
		(layer "B.Cu")
	)
	(gr_line
		(start 326.792082 -131.339082)
		(end 326.821038 -131.495292)
		(stroke
			(width 0.08255)
			(type default)
		)
		(layer "B.Cu")
	)
	(gr_line
		(start 326.792082 -131.339082)
		(end 327.072752 -130.930904)
		(stroke
			(width 0.08255)
			(type default)
		)
		(layer "B.Cu")
	)
	(gr_line
		(start 326.82053 -127.96901)
		(end 326.976232 -127.940054)
		(stroke
			(width 0.08255)
			(type default)
		)
		(layer "B.Cu")
	)
	(gr_line
		(start 326.832722 -128.669034)
		(end 327.198736 -128.13665)
		(stroke
			(width 0.08255)
			(type default)
		)
		(layer "B.Cu")
	)
	(gr_line
		(start 327.072752 -130.930904)
		(end 327.228708 -130.901948)
		(stroke
			(width 0.08255)
			(type default)
		)
		(layer "B.Cu")
	)
	(gr_line
		(start 327.082658 -131.634738)
		(end 327.452482 -131.096512)
		(stroke
			(width 0.08255)
			(type default)
		)
		(layer "B.Cu")
	)
	(gr_line
		(start 327.482708 -130.334512)
		(end 327.511664 -130.490468)
		(stroke
			(width 0.08255)
			(type default)
		)
		(layer "B.Cu")
	)
	(gr_line
		(start 327.482708 -130.334512)
		(end 327.763378 -129.926334)
		(stroke
			(width 0.08255)
			(type default)
		)
		(layer "B.Cu")
	)
	(gr_line
		(start 327.763378 -129.926334)
		(end 327.91908 -129.897378)
		(stroke
			(width 0.08255)
			(type default)
		)
		(layer "B.Cu")
	)
	(gr_line
		(start 327.773284 -130.629914)
		(end 328.1426 -130.092704)
		(stroke
			(width 0.08255)
			(type default)
		)
		(layer "B.Cu")
	)
	(gr_line
		(start 327.870566 -133.688836)
		(end 327.899522 -133.844792)
		(stroke
			(width 0.08255)
			(type default)
		)
		(layer "B.Cu")
	)
	(gr_line
		(start 327.870566 -133.688836)
		(end 328.151236 -133.280658)
		(stroke
			(width 0.08255)
			(type default)
		)
		(layer "B.Cu")
	)
	(gr_line
		(start 327.946512 -268.419834)
		(end 327.957942 -268.402562)
		(stroke
			(width 0.0635)
			(type default)
		)
		(layer "B.Cu")
	)
	(gr_line
		(start 327.957942 -268.402562)
		(end 327.975214 -268.391132)
		(stroke
			(width 0.0635)
			(type default)
		)
		(layer "B.Cu")
	)
	(gr_line
		(start 328.151236 -133.280658)
		(end 328.307192 -133.251956)
		(stroke
			(width 0.08255)
			(type default)
		)
		(layer "B.Cu")
	)
	(gr_line
		(start 328.16165 -133.983476)
		(end 328.530712 -133.447028)
		(stroke
			(width 0.08255)
			(type default)
		)
		(layer "B.Cu")
	)
	(gr_line
		(start 328.173334 -129.329688)
		(end 328.20229 -129.485644)
		(stroke
			(width 0.08255)
			(type default)
		)
		(layer "B.Cu")
	)
	(gr_line
		(start 328.173334 -129.329688)
		(end 328.454004 -128.92151)
		(stroke
			(width 0.08255)
			(type default)
		)
		(layer "B.Cu")
	)
	(gr_line
		(start 328.454004 -128.92151)
		(end 328.60996 -128.892554)
		(stroke
			(width 0.08255)
			(type default)
		)
		(layer "B.Cu")
	)
	(gr_line
		(start 328.464418 -129.624074)
		(end 328.832464 -129.088642)
		(stroke
			(width 0.08255)
			(type default)
		)
		(layer "B.Cu")
	)
	(gr_line
		(start 328.561446 -132.684266)
		(end 328.590402 -132.840222)
		(stroke
			(width 0.08255)
			(type default)
		)
		(layer "B.Cu")
	)
	(gr_line
		(start 328.561446 -132.684266)
		(end 328.842116 -132.276342)
		(stroke
			(width 0.08255)
			(type default)
		)
		(layer "B.Cu")
	)
	(gr_line
		(start 328.842116 -132.276342)
		(end 328.998072 -132.247386)
		(stroke
			(width 0.08255)
			(type default)
		)
		(layer "B.Cu")
	)
	(gr_line
		(start 328.85253 -132.978652)
		(end 329.22083 -132.44322)
		(stroke
			(width 0.08255)
			(type default)
		)
		(layer "B.Cu")
	)
	(gr_line
		(start 329.222862 -68.655184)
		(end 329.257152 -68.500752)
		(stroke
			(width 0.08255)
			(type default)
		)
		(layer "B.Cu")
	)
	(gr_line
		(start 329.252326 -131.679696)
		(end 329.281282 -131.835652)
		(stroke
			(width 0.08255)
			(type default)
		)
		(layer "B.Cu")
	)
	(gr_line
		(start 329.252326 -131.679696)
		(end 329.532996 -131.271772)
		(stroke
			(width 0.08255)
			(type default)
		)
		(layer "B.Cu")
	)
	(gr_line
		(start 329.257152 -68.500752)
		(end 329.674728 -68.23456)
		(stroke
			(width 0.08255)
			(type default)
		)
		(layer "B.Cu")
	)
	(gr_line
		(start 329.407774 -68.88734)
		(end 329.960478 -68.535042)
		(stroke
			(width 0.08255)
			(type default)
		)
		(layer "B.Cu")
	)
	(gr_line
		(start 329.532996 -131.271772)
		(end 329.688952 -131.242816)
		(stroke
			(width 0.08255)
			(type default)
		)
		(layer "B.Cu")
	)
	(gr_line
		(start 329.543918 -131.973574)
		(end 329.91171 -131.43865)
		(stroke
			(width 0.08255)
			(type default)
		)
		(layer "B.Cu")
	)
	(gr_line
		(start 329.674728 -68.23456)
		(end 329.829414 -68.26885)
		(stroke
			(width 0.08255)
			(type default)
		)
		(layer "B.Cu")
	)
	(gr_line
		(start 329.943206 -130.675126)
		(end 329.972162 -130.831082)
		(stroke
			(width 0.08255)
			(type default)
		)
		(layer "B.Cu")
	)
	(gr_line
		(start 329.943206 -130.675126)
		(end 330.223876 -130.267202)
		(stroke
			(width 0.08255)
			(type default)
		)
		(layer "B.Cu")
	)
	(gr_line
		(start 330.223876 -130.267202)
		(end 330.379832 -130.238246)
		(stroke
			(width 0.08255)
			(type default)
		)
		(layer "B.Cu")
	)
	(gr_line
		(start 330.234036 -130.970274)
		(end 330.603352 -130.433318)
		(stroke
			(width 0.08255)
			(type default)
		)
		(layer "B.Cu")
	)
	(gr_line
		(start 330.251054 -68.000118)
		(end 330.285344 -67.845686)
		(stroke
			(width 0.08255)
			(type default)
		)
		(layer "B.Cu")
	)
	(gr_line
		(start 330.285344 -67.845686)
		(end 330.70292 -67.579494)
		(stroke
			(width 0.08255)
			(type default)
		)
		(layer "B.Cu")
	)
	(gr_line
		(start 330.435712 -68.232528)
		(end 330.98994 -67.879468)
		(stroke
			(width 0.08255)
			(type default)
		)
		(layer "B.Cu")
	)
	(gr_line
		(start 330.70292 -67.579494)
		(end 330.857606 -67.613784)
		(stroke
			(width 0.08255)
			(type default)
		)
		(layer "B.Cu")
	)
	(gr_line
		(start 331.279246 -67.345052)
		(end 331.313536 -67.19062)
		(stroke
			(width 0.08255)
			(type default)
		)
		(layer "B.Cu")
	)
	(gr_line
		(start 331.313536 -67.19062)
		(end 331.731366 -66.924428)
		(stroke
			(width 0.08255)
			(type default)
		)
		(layer "B.Cu")
	)
	(gr_line
		(start 331.462888 -67.578224)
		(end 332.018894 -67.224148)
		(stroke
			(width 0.08255)
			(type default)
		)
		(layer "B.Cu")
	)
	(gr_line
		(start 331.731366 -66.924428)
		(end 331.885798 -66.958718)
		(stroke
			(width 0.08255)
			(type default)
		)
		(layer "B.Cu")
	)
	(gr_line
		(start 332.926944 -115.990116)
		(end 332.95844 -116.160296)
		(stroke
			(width 0.08255)
			(type default)
		)
		(layer "B.Cu")
	)
	(gr_line
		(start 332.926944 -115.990116)
		(end 333.207614 -115.581938)
		(stroke
			(width 0.08255)
			(type default)
		)
		(layer "B.Cu")
	)
	(gr_line
		(start 333.207614 -115.581938)
		(end 333.377794 -115.550442)
		(stroke
			(width 0.08255)
			(type default)
		)
		(layer "B.Cu")
	)
	(gr_line
		(start 333.219552 -116.300504)
		(end 333.601568 -115.745006)
		(stroke
			(width 0.08255)
			(type default)
		)
		(layer "B.Cu")
	)
	(gr_line
		(start 333.61503 -68.85432)
		(end 333.650844 -68.68541)
		(stroke
			(width 0.08255)
			(type default)
		)
		(layer "B.Cu")
	)
	(gr_line
		(start 333.629254 -114.968782)
		(end 333.66075 -115.138962)
		(stroke
			(width 0.08255)
			(type default)
		)
		(layer "B.Cu")
	)
	(gr_line
		(start 333.629254 -114.968782)
		(end 333.90967 -114.560604)
		(stroke
			(width 0.08255)
			(type default)
		)
		(layer "B.Cu")
	)
	(gr_line
		(start 333.650844 -68.68541)
		(end 334.066388 -68.415662)
		(stroke
			(width 0.08255)
			(type default)
		)
		(layer "B.Cu")
	)
	(gr_line
		(start 333.803752 -69.083428)
		(end 334.368394 -68.716652)
		(stroke
			(width 0.08255)
			(type default)
		)
		(layer "B.Cu")
	)
	(gr_line
		(start 333.90967 -114.560604)
		(end 334.080104 -114.528854)
		(stroke
			(width 0.08255)
			(type default)
		)
		(layer "B.Cu")
	)
	(gr_line
		(start 333.922878 -115.277392)
		(end 334.30337 -114.723926)
		(stroke
			(width 0.08255)
			(type default)
		)
		(layer "B.Cu")
	)
	(gr_line
		(start 334.066388 -68.415662)
		(end 334.235298 -68.451476)
		(stroke
			(width 0.08255)
			(type default)
		)
		(layer "B.Cu")
	)
	(gr_line
		(start 334.320896 -117.05463)
		(end 334.349852 -117.210078)
		(stroke
			(width 0.08255)
			(type default)
		)
		(layer "B.Cu")
	)
	(gr_line
		(start 334.320896 -117.05463)
		(end 334.601312 -116.646198)
		(stroke
			(width 0.08255)
			(type default)
		)
		(layer "B.Cu")
	)
	(gr_line
		(start 334.33131 -113.947194)
		(end 334.36306 -114.11712)
		(stroke
			(width 0.08255)
			(type default)
		)
		(layer "B.Cu")
	)
	(gr_line
		(start 334.33131 -113.947194)
		(end 334.61198 -113.539016)
		(stroke
			(width 0.08255)
			(type default)
		)
		(layer "B.Cu")
	)
	(gr_line
		(start 334.472026 -336.678524)
		(end 334.486758 -336.675222)
		(stroke
			(width 0.0635)
			(type default)
		)
		(layer "B.Cu")
	)
	(gr_line
		(start 334.486758 -336.675222)
		(end 334.499458 -336.667094)
		(stroke
			(width 0.0635)
			(type default)
		)
		(layer "B.Cu")
	)
	(gr_line
		(start 334.601312 -116.646198)
		(end 334.757014 -116.617242)
		(stroke
			(width 0.08255)
			(type default)
		)
		(layer "B.Cu")
	)
	(gr_line
		(start 334.61198 -113.539016)
		(end 334.78216 -113.50752)
		(stroke
			(width 0.08255)
			(type default)
		)
		(layer "B.Cu")
	)
	(gr_line
		(start 334.613504 -117.346222)
		(end 334.979518 -116.813838)
		(stroke
			(width 0.08255)
			(type default)
		)
		(layer "B.Cu")
	)
	(gr_line
		(start 334.624934 -114.256312)
		(end 335.006442 -113.701322)
		(stroke
			(width 0.08255)
			(type default)
		)
		(layer "B.Cu")
	)
	(gr_line
		(start 334.654652 -68.179188)
		(end 334.690466 -68.010278)
		(stroke
			(width 0.08255)
			(type default)
		)
		(layer "B.Cu")
	)
	(gr_line
		(start 334.690466 -68.010278)
		(end 335.105756 -67.74053)
		(stroke
			(width 0.08255)
			(type default)
		)
		(layer "B.Cu")
	)
	(gr_line
		(start 334.842866 -68.40855)
		(end 335.407508 -68.041774)
		(stroke
			(width 0.08255)
			(type default)
		)
		(layer "B.Cu")
	)
	(gr_line
		(start 335.011268 -116.049806)
		(end 335.040224 -116.205508)
		(stroke
			(width 0.08255)
			(type default)
		)
		(layer "B.Cu")
	)
	(gr_line
		(start 335.011268 -116.049806)
		(end 335.291684 -115.641374)
		(stroke
			(width 0.08255)
			(type default)
		)
		(layer "B.Cu")
	)
	(gr_line
		(start 335.105756 -67.74053)
		(end 335.27492 -67.776344)
		(stroke
			(width 0.08255)
			(type default)
		)
		(layer "B.Cu")
	)
	(gr_line
		(start 335.291684 -115.641374)
		(end 335.44764 -115.612418)
		(stroke
			(width 0.08255)
			(type default)
		)
		(layer "B.Cu")
	)
	(gr_line
		(start 335.303368 -116.342414)
		(end 335.670652 -115.807998)
		(stroke
			(width 0.08255)
			(type default)
		)
		(layer "B.Cu")
	)
	(gr_line
		(start 335.69402 -67.50431)
		(end 335.730088 -67.3354)
		(stroke
			(width 0.08255)
			(type default)
		)
		(layer "B.Cu")
	)
	(gr_line
		(start 335.701894 -115.044982)
		(end 335.73085 -115.20043)
		(stroke
			(width 0.08255)
			(type default)
		)
		(layer "B.Cu")
	)
	(gr_line
		(start 335.701894 -115.044982)
		(end 335.98231 -114.63655)
		(stroke
			(width 0.08255)
			(type default)
		)
		(layer "B.Cu")
	)
	(gr_line
		(start 335.730088 -67.3354)
		(end 336.145378 -67.065652)
		(stroke
			(width 0.08255)
			(type default)
		)
		(layer "B.Cu")
	)
	(gr_line
		(start 335.881218 -67.734434)
		(end 336.446876 -67.36715)
		(stroke
			(width 0.08255)
			(type default)
		)
		(layer "B.Cu")
	)
	(gr_line
		(start 335.98231 -114.63655)
		(end 336.138012 -114.607594)
		(stroke
			(width 0.08255)
			(type default)
		)
		(layer "B.Cu")
	)
	(gr_line
		(start 335.99374 -115.33759)
		(end 336.360262 -114.804444)
		(stroke
			(width 0.08255)
			(type default)
		)
		(layer "B.Cu")
	)
	(gr_line
		(start 336.137504 -117.725444)
		(end 336.168746 -117.895116)
		(stroke
			(width 0.08255)
			(type default)
		)
		(layer "B.Cu")
	)
	(gr_line
		(start 336.137504 -117.725444)
		(end 336.41792 -117.317266)
		(stroke
			(width 0.08255)
			(type default)
		)
		(layer "B.Cu")
	)
	(gr_line
		(start 336.145378 -67.065652)
		(end 336.314288 -67.101466)
		(stroke
			(width 0.08255)
			(type default)
		)
		(layer "B.Cu")
	)
	(gr_line
		(start 336.392266 -114.040158)
		(end 336.421222 -114.19586)
		(stroke
			(width 0.08255)
			(type default)
		)
		(layer "B.Cu")
	)
	(gr_line
		(start 336.392266 -114.040158)
		(end 336.672682 -113.631726)
		(stroke
			(width 0.08255)
			(type default)
		)
		(layer "B.Cu")
	)
	(gr_line
		(start 336.41792 -117.317266)
		(end 336.587592 -117.286024)
		(stroke
			(width 0.08255)
			(type default)
		)
		(layer "B.Cu")
	)
	(gr_line
		(start 336.432652 -118.031514)
		(end 336.809588 -117.482874)
		(stroke
			(width 0.08255)
			(type default)
		)
		(layer "B.Cu")
	)
	(gr_line
		(start 336.672682 -113.631726)
		(end 336.828638 -113.60277)
		(stroke
			(width 0.08255)
			(type default)
		)
		(layer "B.Cu")
	)
	(gr_line
		(start 336.684112 -114.33302)
		(end 337.051396 -113.798604)
		(stroke
			(width 0.08255)
			(type default)
		)
		(layer "B.Cu")
	)
	(gr_line
		(start 336.733642 -66.829178)
		(end 336.769456 -66.660268)
		(stroke
			(width 0.08255)
			(type default)
		)
		(layer "B.Cu")
	)
	(gr_line
		(start 336.769456 -66.660268)
		(end 337.185 -66.39052)
		(stroke
			(width 0.08255)
			(type default)
		)
		(layer "B.Cu")
	)
	(gr_line
		(start 336.787236 -337.76539)
		(end 336.799682 -337.762596)
		(stroke
			(width 0.0635)
			(type default)
		)
		(layer "B.Cu")
	)
	(gr_line
		(start 336.799682 -337.762596)
		(end 336.810858 -337.755484)
		(stroke
			(width 0.0635)
			(type default)
		)
		(layer "B.Cu")
	)
	(gr_line
		(start 336.83956 -116.70411)
		(end 336.871056 -116.873782)
		(stroke
			(width 0.08255)
			(type default)
		)
		(layer "B.Cu")
	)
	(gr_line
		(start 336.83956 -116.70411)
		(end 337.119976 -116.295932)
		(stroke
			(width 0.08255)
			(type default)
		)
		(layer "B.Cu")
	)
	(gr_line
		(start 336.921094 -67.059302)
		(end 337.48726 -66.69151)
		(stroke
			(width 0.08255)
			(type default)
		)
		(layer "B.Cu")
	)
	(gr_line
		(start 337.119976 -116.295932)
		(end 337.289902 -116.264182)
		(stroke
			(width 0.08255)
			(type default)
		)
		(layer "B.Cu")
	)
	(gr_line
		(start 337.133692 -117.011704)
		(end 337.512914 -116.460016)
		(stroke
			(width 0.08255)
			(type default)
		)
		(layer "B.Cu")
	)
	(gr_line
		(start 337.185 -66.39052)
		(end 337.35391 -66.426334)
		(stroke
			(width 0.08255)
			(type default)
		)
		(layer "B.Cu")
	)
	(gr_line
		(start 337.541616 -115.682522)
		(end 337.573112 -115.852448)
		(stroke
			(width 0.08255)
			(type default)
		)
		(layer "B.Cu")
	)
	(gr_line
		(start 337.541616 -115.682522)
		(end 337.822286 -115.274344)
		(stroke
			(width 0.08255)
			(type default)
		)
		(layer "B.Cu")
	)
	(gr_line
		(start 337.822286 -115.274344)
		(end 337.991958 -115.242848)
		(stroke
			(width 0.08255)
			(type default)
		)
		(layer "B.Cu")
	)
	(gr_line
		(start 337.834732 -115.992148)
		(end 338.215224 -115.438174)
		(stroke
			(width 0.08255)
			(type default)
		)
		(layer "B.Cu")
	)
	(gr_line
		(start 337.85175 -119.158512)
		(end 337.883246 -119.328692)
		(stroke
			(width 0.08255)
			(type default)
		)
		(layer "B.Cu")
	)
	(gr_line
		(start 337.85175 -119.158512)
		(end 338.13242 -118.750334)
		(stroke
			(width 0.08255)
			(type default)
		)
		(layer "B.Cu")
	)
	(gr_line
		(start 338.13242 -118.750334)
		(end 338.3026 -118.718838)
		(stroke
			(width 0.08255)
			(type default)
		)
		(layer "B.Cu")
	)
	(gr_line
		(start 338.144612 -119.468646)
		(end 338.526374 -118.913402)
		(stroke
			(width 0.08255)
			(type default)
		)
		(layer "B.Cu")
	)
	(gr_line
		(start 338.55406 -118.137178)
		(end 338.58581 -118.307358)
		(stroke
			(width 0.08255)
			(type default)
		)
		(layer "B.Cu")
	)
	(gr_line
		(start 338.55406 -118.137178)
		(end 338.834984 -117.729254)
		(stroke
			(width 0.08255)
			(type default)
		)
		(layer "B.Cu")
	)
	(gr_line
		(start 338.834984 -117.729254)
		(end 339.005164 -117.697504)
		(stroke
			(width 0.08255)
			(type default)
		)
		(layer "B.Cu")
	)
	(gr_line
		(start 338.847684 -118.44655)
		(end 339.229446 -117.891306)
		(stroke
			(width 0.08255)
			(type default)
		)
		(layer "B.Cu")
	)
	(gr_line
		(start 338.962746 -232.997502)
		(end 338.969858 -232.986326)
		(stroke
			(width 0.0635)
			(type default)
		)
		(layer "B.Cu")
	)
	(gr_line
		(start 338.969858 -232.986326)
		(end 338.972652 -232.97388)
		(stroke
			(width 0.0635)
			(type default)
		)
		(layer "B.Cu")
	)
	(gr_line
		(start 339.205824 -295.740074)
		(end 339.225636 -295.726866)
		(stroke
			(width 0.0635)
			(type default)
		)
		(layer "B.Cu")
	)
	(gr_line
		(start 339.225636 -295.726866)
		(end 339.238082 -295.708324)
		(stroke
			(width 0.0635)
			(type default)
		)
		(layer "B.Cu")
	)
	(gr_line
		(start 339.256624 -117.115844)
		(end 339.28812 -117.286024)
		(stroke
			(width 0.08255)
			(type default)
		)
		(layer "B.Cu")
	)
	(gr_line
		(start 339.256624 -117.115844)
		(end 339.537294 -116.70792)
		(stroke
			(width 0.08255)
			(type default)
		)
		(layer "B.Cu")
	)
	(gr_line
		(start 339.537294 -116.70792)
		(end 339.707474 -116.676424)
		(stroke
			(width 0.08255)
			(type default)
		)
		(layer "B.Cu")
	)
	(gr_line
		(start 339.549232 -117.426486)
		(end 339.93201 -116.869972)
		(stroke
			(width 0.08255)
			(type default)
		)
		(layer "B.Cu")
	)
	(gr_line
		(start 341.760302 -106.210354)
		(end 341.791798 -106.38028)
		(stroke
			(width 0.08255)
			(type default)
		)
		(layer "B.Cu")
	)
	(gr_line
		(start 341.760302 -106.210354)
		(end 342.040718 -105.802176)
		(stroke
			(width 0.08255)
			(type default)
		)
		(layer "B.Cu")
	)
	(gr_line
		(start 342.040718 -105.802176)
		(end 342.210898 -105.770426)
		(stroke
			(width 0.08255)
			(type default)
		)
		(layer "B.Cu")
	)
	(gr_line
		(start 342.05418 -106.518202)
		(end 342.433148 -105.966514)
		(stroke
			(width 0.08255)
			(type default)
		)
		(layer "B.Cu")
	)
	(gr_line
		(start 342.462358 -105.188766)
		(end 342.493854 -105.358692)
		(stroke
			(width 0.08255)
			(type default)
		)
		(layer "B.Cu")
	)
	(gr_line
		(start 342.462358 -105.188766)
		(end 342.742774 -104.780588)
		(stroke
			(width 0.08255)
			(type default)
		)
		(layer "B.Cu")
	)
	(gr_line
		(start 342.742774 -104.780588)
		(end 342.9127 -104.749092)
		(stroke
			(width 0.08255)
			(type default)
		)
		(layer "B.Cu")
	)
	(gr_line
		(start 342.756744 -105.495598)
		(end 343.133934 -104.946704)
		(stroke
			(width 0.08255)
			(type default)
		)
		(layer "B.Cu")
	)
	(gr_line
		(start 343.16416 -104.167178)
		(end 343.19591 -104.337104)
		(stroke
			(width 0.08255)
			(type default)
		)
		(layer "B.Cu")
	)
	(gr_line
		(start 343.16416 -104.167178)
		(end 343.44483 -103.759)
		(stroke
			(width 0.08255)
			(type default)
		)
		(layer "B.Cu")
	)
	(gr_line
		(start 343.44483 -103.759)
		(end 343.614756 -103.727504)
		(stroke
			(width 0.08255)
			(type default)
		)
		(layer "B.Cu")
	)
	(gr_line
		(start 343.459308 -104.473502)
		(end 343.837006 -103.9241)
		(stroke
			(width 0.08255)
			(type default)
		)
		(layer "B.Cu")
	)
	(gr_line
		(start 343.658952 -55.131208)
		(end 343.69629 -54.962806)
		(stroke
			(width 0.08255)
			(type default)
		)
		(layer "B.Cu")
	)
	(gr_line
		(start 343.69629 -54.962806)
		(end 344.11412 -54.696868)
		(stroke
			(width 0.08255)
			(type default)
		)
		(layer "B.Cu")
	)
	(gr_line
		(start 343.847674 -55.36057)
		(end 344.411046 -55.001668)
		(stroke
			(width 0.08255)
			(type default)
		)
		(layer "B.Cu")
	)
	(gr_line
		(start 344.11412 -54.696868)
		(end 344.282268 -54.734206)
		(stroke
			(width 0.08255)
			(type default)
		)
		(layer "B.Cu")
	)
	(gr_line
		(start 344.704416 -54.46522)
		(end 344.741754 -54.297072)
		(stroke
			(width 0.08255)
			(type default)
		)
		(layer "B.Cu")
	)
	(gr_line
		(start 344.741754 -54.297072)
		(end 345.15933 -54.03088)
		(stroke
			(width 0.08255)
			(type default)
		)
		(layer "B.Cu")
	)
	(gr_line
		(start 344.892122 -54.695344)
		(end 345.456764 -54.335426)
		(stroke
			(width 0.08255)
			(type default)
		)
		(layer "B.Cu")
	)
	(gr_line
		(start 345.111578 -303.527968)
		(end 345.12504 -303.519078)
		(stroke
			(width 0.0635)
			(type default)
		)
		(layer "B.Cu")
	)
	(gr_line
		(start 345.12504 -303.519078)
		(end 345.140788 -303.515522)
		(stroke
			(width 0.0635)
			(type default)
		)
		(layer "B.Cu")
	)
	(gr_line
		(start 345.15933 -54.03088)
		(end 345.327732 -54.068218)
		(stroke
			(width 0.08255)
			(type default)
		)
		(layer "B.Cu")
	)
	(gr_line
		(start 345.74988 -53.799232)
		(end 345.787218 -53.631084)
		(stroke
			(width 0.08255)
			(type default)
		)
		(layer "B.Cu")
	)
	(gr_line
		(start 345.787218 -53.631084)
		(end 346.204794 -53.364892)
		(stroke
			(width 0.08255)
			(type default)
		)
		(layer "B.Cu")
	)
	(gr_line
		(start 345.93784 -54.029102)
		(end 346.501974 -53.669692)
		(stroke
			(width 0.08255)
			(type default)
		)
		(layer "B.Cu")
	)
	(gr_line
		(start 346.204794 -53.364892)
		(end 346.373196 -53.40223)
		(stroke
			(width 0.08255)
			(type default)
		)
		(layer "B.Cu")
	)
	(gr_line
		(start 346.79509 -53.133498)
		(end 346.832428 -52.965096)
		(stroke
			(width 0.08255)
			(type default)
		)
		(layer "B.Cu")
	)
	(gr_line
		(start 346.832428 -52.965096)
		(end 347.250258 -52.698904)
		(stroke
			(width 0.08255)
			(type default)
		)
		(layer "B.Cu")
	)
	(gr_line
		(start 346.982288 -53.363876)
		(end 347.547692 -53.00345)
		(stroke
			(width 0.08255)
			(type default)
		)
		(layer "B.Cu")
	)
	(gr_line
		(start 347.250258 -52.698904)
		(end 347.41866 -52.736242)
		(stroke
			(width 0.08255)
			(type default)
		)
		(layer "B.Cu")
	)
	(gr_line
		(start 347.29293 -303.03597)
		(end 347.406722 -302.857154)
		(stroke
			(width 0.0635)
			(type default)
		)
		(layer "B.Cu")
	)
	(gr_line
		(start 347.390974 -303.316132)
		(end 347.988128 -303.183798)
		(stroke
			(width 0.0635)
			(type default)
		)
		(layer "B.Cu")
	)
	(gr_line
		(start 347.406722 -302.857154)
		(end 347.778578 -302.774604)
		(stroke
			(width 0.0635)
			(type default)
		)
		(layer "B.Cu")
	)
	(gr_line
		(start 347.601032 -282.544012)
		(end 347.612462 -282.52674)
		(stroke
			(width 0.0635)
			(type default)
		)
		(layer "B.Cu")
	)
	(gr_line
		(start 347.612462 -282.52674)
		(end 347.629734 -282.51531)
		(stroke
			(width 0.0635)
			(type default)
		)
		(layer "B.Cu")
	)
	(gr_line
		(start 347.746574 -327.78954)
		(end 347.791532 -327.582276)
		(stroke
			(width 0.0635)
			(type default)
		)
		(layer "B.Cu")
	)
	(gr_line
		(start 347.778578 -302.774604)
		(end 347.957648 -302.88865)
		(stroke
			(width 0.0635)
			(type default)
		)
		(layer "B.Cu")
	)
	(gr_line
		(start 347.791532 -327.582276)
		(end 348.111826 -327.376028)
		(stroke
			(width 0.0635)
			(type default)
		)
		(layer "B.Cu")
	)
	(gr_line
		(start 347.935804 -328.01814)
		(end 348.447868 -327.688448)
		(stroke
			(width 0.0635)
			(type default)
		)
		(layer "B.Cu")
	)
	(gr_line
		(start 348.111826 -327.376028)
		(end 348.31909 -327.420986)
		(stroke
			(width 0.0635)
			(type default)
		)
		(layer "B.Cu")
	)
	(gr_line
		(start 348.33433 -302.805084)
		(end 348.448122 -302.626268)
		(stroke
			(width 0.0635)
			(type default)
		)
		(layer "B.Cu")
	)
	(gr_line
		(start 348.431866 -303.0855)
		(end 349.029782 -302.952912)
		(stroke
			(width 0.0635)
			(type default)
		)
		(layer "B.Cu")
	)
	(gr_line
		(start 348.448122 -302.626268)
		(end 348.820232 -302.543718)
		(stroke
			(width 0.0635)
			(type default)
		)
		(layer "B.Cu")
	)
	(gr_line
		(start 348.643702 -327.212198)
		(end 348.68866 -327.00468)
		(stroke
			(width 0.0635)
			(type default)
		)
		(layer "B.Cu")
	)
	(gr_line
		(start 348.68866 -327.00468)
		(end 349.008954 -326.798686)
		(stroke
			(width 0.0635)
			(type default)
		)
		(layer "B.Cu")
	)
	(gr_line
		(start 348.820232 -302.543718)
		(end 348.999048 -302.657764)
		(stroke
			(width 0.0635)
			(type default)
		)
		(layer "B.Cu")
	)
	(gr_line
		(start 348.83344 -327.44029)
		(end 349.346774 -327.109836)
		(stroke
			(width 0.0635)
			(type default)
		)
		(layer "B.Cu")
	)
	(gr_line
		(start 349.008954 -326.798686)
		(end 349.216472 -326.84339)
		(stroke
			(width 0.0635)
			(type default)
		)
		(layer "B.Cu")
	)
	(gr_line
		(start 349.321628 -302.58893)
		(end 349.373952 -302.577246)
		(stroke
			(width 0.0635)
			(type default)
		)
		(layer "B.Cu")
	)
	(gr_line
		(start 349.328994 -51.868832)
		(end 349.351092 -51.854608)
		(stroke
			(width 0.08255)
			(type default)
		)
		(layer "B.Cu")
	)
	(gr_line
		(start 349.351092 -51.854608)
		(end 349.365316 -51.83251)
		(stroke
			(width 0.08255)
			(type default)
		)
		(layer "B.Cu")
	)
	(gr_line
		(start 349.375984 -302.574198)
		(end 349.489776 -302.395382)
		(stroke
			(width 0.0635)
			(type default)
		)
		(layer "B.Cu")
	)
	(gr_line
		(start 349.415608 -302.867314)
		(end 349.444564 -302.86071)
		(stroke
			(width 0.0635)
			(type default)
		)
		(layer "B.Cu")
	)
	(gr_line
		(start 349.47479 -302.854106)
		(end 350.069404 -302.72228)
		(stroke
			(width 0.0635)
			(type default)
		)
		(layer "B.Cu")
	)
	(gr_line
		(start 349.489776 -302.395382)
		(end 349.861632 -302.312832)
		(stroke
			(width 0.0635)
			(type default)
		)
		(layer "B.Cu")
	)
	(gr_line
		(start 349.540576 -326.634856)
		(end 349.585534 -326.427338)
		(stroke
			(width 0.0635)
			(type default)
		)
		(layer "B.Cu")
	)
	(gr_line
		(start 349.585534 -326.427338)
		(end 349.905828 -326.22109)
		(stroke
			(width 0.0635)
			(type default)
		)
		(layer "B.Cu")
	)
	(gr_line
		(start 349.728282 -326.864472)
		(end 350.243648 -326.532748)
		(stroke
			(width 0.0635)
			(type default)
		)
		(layer "B.Cu")
	)
	(gr_line
		(start 349.861632 -302.312832)
		(end 350.040702 -302.426878)
		(stroke
			(width 0.0635)
			(type default)
		)
		(layer "B.Cu")
	)
	(gr_line
		(start 349.905828 -326.22109)
		(end 350.113346 -326.266048)
		(stroke
			(width 0.0635)
			(type default)
		)
		(layer "B.Cu")
	)
	(gr_line
		(start 350.631252 -297.793918)
		(end 350.647762 -297.782996)
		(stroke
			(width 0.0635)
			(type default)
		)
		(layer "B.Cu")
	)
	(gr_line
		(start 350.637856 -52.944522)
		(end 350.659954 -52.930298)
		(stroke
			(width 0.08255)
			(type default)
		)
		(layer "B.Cu")
	)
	(gr_line
		(start 350.647762 -297.782996)
		(end 350.66732 -297.778932)
		(stroke
			(width 0.0635)
			(type default)
		)
		(layer "B.Cu")
	)
	(gr_line
		(start 350.659954 -52.930298)
		(end 350.674178 -52.9082)
		(stroke
			(width 0.08255)
			(type default)
		)
		(layer "B.Cu")
	)
	(gr_line
		(start 352.61423 -43.82643)
		(end 352.626676 -43.823636)
		(stroke
			(width 0.08255)
			(type default)
		)
		(layer "B.Cu")
	)
	(gr_line
		(start 352.626676 -43.823636)
		(end 352.637852 -43.816524)
		(stroke
			(width 0.08255)
			(type default)
		)
		(layer "B.Cu")
	)
	(gr_line
		(start 353.01047 -45.56633)
		(end 353.021646 -45.548804)
		(stroke
			(width 0.08255)
			(type default)
		)
		(layer "B.Cu")
	)
	(gr_line
		(start 353.021646 -45.548804)
		(end 353.038664 -45.53712)
		(stroke
			(width 0.08255)
			(type default)
		)
		(layer "B.Cu")
	)
	(gr_line
		(start 353.795838 -164.774372)
		(end 353.799648 -164.7571)
		(stroke
			(width 0.0635)
			(type default)
		)
		(layer "B.Cu")
	)
	(gr_line
		(start 353.799648 -164.7571)
		(end 353.809554 -164.742368)
		(stroke
			(width 0.0635)
			(type default)
		)
		(layer "B.Cu")
	)
	(gr_line
		(start 353.92741 -106.456988)
		(end 353.94011 -106.4387)
		(stroke
			(width 0.0635)
			(type default)
		)
		(layer "B.Cu")
	)
	(gr_line
		(start 353.94011 -106.4387)
		(end 353.958652 -106.426508)
		(stroke
			(width 0.0635)
			(type default)
		)
		(layer "B.Cu")
	)
	(gr_line
		(start 354.376736 -46.552358)
		(end 354.387912 -46.534832)
		(stroke
			(width 0.08255)
			(type default)
		)
		(layer "B.Cu")
	)
	(gr_line
		(start 354.387912 -46.534832)
		(end 354.405184 -46.52264)
		(stroke
			(width 0.08255)
			(type default)
		)
		(layer "B.Cu")
	)
	(gr_line
		(start 354.659438 -147.269962)
		(end 355.14788 -146.78152)
		(stroke
			(width 0.127)
			(type default)
		)
		(layer "B.Cu")
	)
	(gr_line
		(start 354.659438 -145.642838)
		(end 355.14788 -146.13128)
		(stroke
			(width 0.127)
			(type default)
		)
		(layer "B.Cu")
	)
	(gr_line
		(start 354.68052 -222.03791)
		(end 354.69576 -222.01505)
		(stroke
			(width 0.0635)
			(type default)
		)
		(layer "B.Cu")
	)
	(gr_line
		(start 354.69576 -222.01505)
		(end 354.719128 -222.000318)
		(stroke
			(width 0.0635)
			(type default)
		)
		(layer "B.Cu")
	)
	(gr_line
		(start 354.807774 -277.763986)
		(end 354.823776 -277.753572)
		(stroke
			(width 0.0635)
			(type default)
		)
		(layer "B.Cu")
	)
	(gr_line
		(start 354.823776 -277.753572)
		(end 354.842318 -277.749762)
		(stroke
			(width 0.0635)
			(type default)
		)
		(layer "B.Cu")
	)
	(gr_line
		(start 354.964238 -108.324396)
		(end 354.975922 -108.307378)
		(stroke
			(width 0.0635)
			(type default)
		)
		(layer "B.Cu")
	)
	(gr_line
		(start 354.975922 -108.307378)
		(end 354.993448 -108.295948)
		(stroke
			(width 0.0635)
			(type default)
		)
		(layer "B.Cu")
	)
	(gr_arc
		(start 354.983542 -21.504148)
		(mid 355.101183 -21.455419)
		(end 355.149912 -21.337778)
		(stroke
			(width 0.08255)
			(type default)
		)
		(layer "B.Cu")
	)
	(gr_line
		(start 355.048312 -162.905186)
		(end 355.061266 -162.886136)
		(stroke
			(width 0.0635)
			(type default)
		)
		(layer "B.Cu")
	)
	(gr_line
		(start 355.061266 -162.886136)
		(end 355.080316 -162.874198)
		(stroke
			(width 0.0635)
			(type default)
		)
		(layer "B.Cu")
	)
	(gr_arc
		(start 355.149912 -21.962618)
		(mid 355.101183 -21.844977)
		(end 354.983542 -21.796248)
		(stroke
			(width 0.08255)
			(type default)
		)
		(layer "B.Cu")
	)
	(gr_line
		(start 355.149912 -21.962618)
		(end 355.149912 -22.350222)
		(stroke
			(width 0.08255)
			(type default)
		)
		(layer "B.Cu")
	)
	(gr_line
		(start 355.149912 -20.950174)
		(end 355.149912 -21.337778)
		(stroke
			(width 0.08255)
			(type default)
		)
		(layer "B.Cu")
	)
	(gr_line
		(start 355.358446 -162.698938)
		(end 355.369368 -162.69208)
		(stroke
			(width 0.0635)
			(type default)
		)
		(layer "B.Cu")
	)
	(gr_line
		(start 355.369368 -162.69208)
		(end 355.38156 -162.689286)
		(stroke
			(width 0.0635)
			(type default)
		)
		(layer "B.Cu")
	)
	(gr_line
		(start 355.714046 -162.913822)
		(end 355.792532 -162.896042)
		(stroke
			(width 0.0635)
			(type default)
		)
		(layer "B.Cu")
	)
	(gr_line
		(start 355.722682 -162.612324)
		(end 355.733858 -162.609784)
		(stroke
			(width 0.0635)
			(type default)
		)
		(layer "B.Cu")
	)
	(gr_line
		(start 355.792532 -162.896042)
		(end 355.792786 -162.896042)
		(stroke
			(width 0.0635)
			(type default)
		)
		(layer "B.Cu")
	)
	(gr_line
		(start 355.814884 -31.42869)
		(end 355.856794 -31.41218)
		(stroke
			(width 0.08255)
			(type default)
		)
		(layer "B.Cu")
	)
	(gr_line
		(start 355.856794 -31.41218)
		(end 355.883972 -31.376112)
		(stroke
			(width 0.08255)
			(type default)
		)
		(layer "B.Cu")
	)
	(gr_arc
		(start 356.112318 -277.603966)
		(mid 356.237305 -277.55218)
		(end 356.289102 -277.427182)
		(stroke
			(width 0.0635)
			(type default)
		)
		(layer "B.Cu")
	)
	(gr_arc
		(start 356.112318 -162.603942)
		(mid 356.237297 -162.552154)
		(end 356.289102 -162.427158)
		(stroke
			(width 0.0635)
			(type default)
		)
		(layer "B.Cu")
	)
	(gr_line
		(start 356.160578 -31.00705)
		(end 356.196138 -30.959552)
		(stroke
			(width 0.08255)
			(type default)
		)
		(layer "B.Cu")
	)
	(gr_arc
		(start 356.289102 -278.07285)
		(mid 356.237323 -277.947845)
		(end 356.112318 -277.896066)
		(stroke
			(width 0.0635)
			(type default)
		)
		(layer "B.Cu")
	)
	(gr_line
		(start 356.289102 -278.07285)
		(end 356.289102 -278.321516)
		(stroke
			(width 0.0635)
			(type default)
		)
		(layer "B.Cu")
	)
	(gr_line
		(start 356.289102 -277.178516)
		(end 356.289102 -277.427182)
		(stroke
			(width 0.0635)
			(type default)
		)
		(layer "B.Cu")
	)
	(gr_arc
		(start 356.289102 -163.072826)
		(mid 356.237333 -162.947798)
		(end 356.112318 -162.896042)
		(stroke
			(width 0.0635)
			(type default)
		)
		(layer "B.Cu")
	)
	(gr_line
		(start 356.289102 -163.072826)
		(end 356.289102 -163.321492)
		(stroke
			(width 0.0635)
			(type default)
		)
		(layer "B.Cu")
	)
	(gr_line
		(start 356.289102 -162.178492)
		(end 356.289102 -162.427158)
		(stroke
			(width 0.0635)
			(type default)
		)
		(layer "B.Cu")
	)
	(gr_arc
		(start 356.78364 -22.504146)
		(mid 356.901281 -22.455417)
		(end 356.95001 -22.337776)
		(stroke
			(width 0.08255)
			(type default)
		)
		(layer "B.Cu")
	)
	(gr_arc
		(start 356.95001 -22.962616)
		(mid 356.901289 -22.84495)
		(end 356.78364 -22.796246)
		(stroke
			(width 0.08255)
			(type default)
		)
		(layer "B.Cu")
	)
	(gr_line
		(start 356.95001 -22.962616)
		(end 356.95001 -23.35022)
		(stroke
			(width 0.08255)
			(type default)
		)
		(layer "B.Cu")
	)
	(gr_line
		(start 356.95001 -21.950172)
		(end 356.95001 -22.337776)
		(stroke
			(width 0.08255)
			(type default)
		)
		(layer "B.Cu")
	)
	(gr_line
		(start 357.105712 -32.45104)
		(end 357.12908 -32.436054)
		(stroke
			(width 0.08255)
			(type default)
		)
		(layer "B.Cu")
	)
	(gr_line
		(start 357.12908 -32.436054)
		(end 357.143558 -32.413194)
		(stroke
			(width 0.08255)
			(type default)
		)
		(layer "B.Cu")
	)
	(gr_line
		(start 357.2383 -51.156362)
		(end 357.260398 -51.142138)
		(stroke
			(width 0.08255)
			(type default)
		)
		(layer "B.Cu")
	)
	(gr_line
		(start 357.260398 -51.142138)
		(end 357.274622 -51.12004)
		(stroke
			(width 0.08255)
			(type default)
		)
		(layer "B.Cu")
	)
	(gr_line
		(start 357.971598 -31.110174)
		(end 357.996236 -31.071312)
		(stroke
			(width 0.08255)
			(type default)
		)
		(layer "B.Cu")
	)
	(gr_line
		(start 358.031542 -53.349652)
		(end 358.052116 -53.33619)
		(stroke
			(width 0.08255)
			(type default)
		)
		(layer "B.Cu")
	)
	(gr_line
		(start 358.052116 -53.33619)
		(end 358.065324 -53.316124)
		(stroke
			(width 0.08255)
			(type default)
		)
		(layer "B.Cu")
	)
	(gr_line
		(start 358.411526 -33.536382)
		(end 358.433624 -33.522158)
		(stroke
			(width 0.08255)
			(type default)
		)
		(layer "B.Cu")
	)
	(gr_line
		(start 358.433624 -33.522158)
		(end 358.447848 -33.50006)
		(stroke
			(width 0.08255)
			(type default)
		)
		(layer "B.Cu")
	)
	(gr_arc
		(start 358.583738 -21.504148)
		(mid 358.701379 -21.455419)
		(end 358.750108 -21.337778)
		(stroke
			(width 0.08255)
			(type default)
		)
		(layer "B.Cu")
	)
	(gr_arc
		(start 358.750108 -21.962618)
		(mid 358.701388 -21.844952)
		(end 358.583738 -21.796248)
		(stroke
			(width 0.08255)
			(type default)
		)
		(layer "B.Cu")
	)
	(gr_line
		(start 358.750108 -21.962618)
		(end 358.750108 -22.350222)
		(stroke
			(width 0.08255)
			(type default)
		)
		(layer "B.Cu")
	)
	(gr_line
		(start 358.750108 -20.950174)
		(end 358.750108 -21.337778)
		(stroke
			(width 0.08255)
			(type default)
		)
		(layer "B.Cu")
	)
	(gr_line
		(start 359.164128 -296.348404)
		(end 359.183686 -296.34434)
		(stroke
			(width 0.0635)
			(type default)
		)
		(layer "B.Cu")
	)
	(gr_line
		(start 359.183686 -296.34434)
		(end 359.200196 -296.333418)
		(stroke
			(width 0.0635)
			(type default)
		)
		(layer "B.Cu")
	)
	(gr_line
		(start 359.286302 -39.581328)
		(end 359.31729 -39.561516)
		(stroke
			(width 0.08255)
			(type default)
		)
		(layer "B.Cu")
	)
	(gr_line
		(start 359.31729 -39.561516)
		(end 359.335324 -39.529258)
		(stroke
			(width 0.08255)
			(type default)
		)
		(layer "B.Cu")
	)
	(gr_line
		(start 359.5624 -34.71926)
		(end 359.585768 -34.704274)
		(stroke
			(width 0.08255)
			(type default)
		)
		(layer "B.Cu")
	)
	(gr_line
		(start 359.585768 -34.704274)
		(end 359.600754 -34.680906)
		(stroke
			(width 0.08255)
			(type default)
		)
		(layer "B.Cu")
	)
	(gr_line
		(start 359.77068 -31.423356)
		(end 359.79608 -31.383478)
		(stroke
			(width 0.08255)
			(type default)
		)
		(layer "B.Cu")
	)
	(gr_arc
		(start 360.383582 -22.504146)
		(mid 360.501223 -22.455417)
		(end 360.549952 -22.337776)
		(stroke
			(width 0.08255)
			(type default)
		)
		(layer "B.Cu")
	)
	(gr_line
		(start 360.523028 -40.642286)
		(end 360.546904 -40.625522)
		(stroke
			(width 0.08255)
			(type default)
		)
		(layer "B.Cu")
	)
	(gr_line
		(start 360.546904 -40.625522)
		(end 360.560874 -40.600122)
		(stroke
			(width 0.08255)
			(type default)
		)
		(layer "B.Cu")
	)
	(gr_arc
		(start 360.549952 -22.962616)
		(mid 360.501228 -22.844971)
		(end 360.383582 -22.796246)
		(stroke
			(width 0.08255)
			(type default)
		)
		(layer "B.Cu")
	)
	(gr_line
		(start 360.549952 -22.962616)
		(end 360.549952 -23.35022)
		(stroke
			(width 0.08255)
			(type default)
		)
		(layer "B.Cu")
	)
	(gr_line
		(start 360.549952 -21.950172)
		(end 360.549952 -22.337776)
		(stroke
			(width 0.08255)
			(type default)
		)
		(layer "B.Cu")
	)
	(gr_line
		(start 360.786426 -142.597886)
		(end 360.994706 -142.806166)
		(stroke
			(width 0.127)
			(type default)
		)
		(layer "B.Cu")
	)
	(gr_line
		(start 360.786426 -141.947646)
		(end 360.994706 -141.739366)
		(stroke
			(width 0.127)
			(type default)
		)
		(layer "B.Cu")
	)
	(gr_line
		(start 361.570778 -31.58871)
		(end 361.596178 -31.548832)
		(stroke
			(width 0.08255)
			(type default)
		)
		(layer "B.Cu")
	)
	(gr_line
		(start 361.580176 -43.824144)
		(end 361.5944 -43.802046)
		(stroke
			(width 0.08255)
			(type default)
		)
		(layer "B.Cu")
	)
	(gr_line
		(start 361.5944 -43.802046)
		(end 361.616498 -43.787822)
		(stroke
			(width 0.08255)
			(type default)
		)
		(layer "B.Cu")
	)
	(gr_line
		(start 361.747308 -41.729152)
		(end 361.76458 -41.71696)
		(stroke
			(width 0.08255)
			(type default)
		)
		(layer "B.Cu")
	)
	(gr_line
		(start 361.76458 -41.71696)
		(end 361.775756 -41.699434)
		(stroke
			(width 0.08255)
			(type default)
		)
		(layer "B.Cu")
	)
	(gr_arc
		(start 362.18368 -21.504148)
		(mid 362.301321 -21.455419)
		(end 362.35005 -21.337778)
		(stroke
			(width 0.08255)
			(type default)
		)
		(layer "B.Cu")
	)
	(gr_arc
		(start 362.35005 -21.962618)
		(mid 362.301327 -21.844972)
		(end 362.18368 -21.796248)
		(stroke
			(width 0.08255)
			(type default)
		)
		(layer "B.Cu")
	)
	(gr_line
		(start 362.35005 -21.962618)
		(end 362.35005 -22.350222)
		(stroke
			(width 0.08255)
			(type default)
		)
		(layer "B.Cu")
	)
	(gr_line
		(start 362.35005 -20.950174)
		(end 362.35005 -21.337778)
		(stroke
			(width 0.08255)
			(type default)
		)
		(layer "B.Cu")
	)
	(gr_line
		(start 363.0803 -142.7734)
		(end 363.26318 -142.59052)
		(stroke
			(width 0.127)
			(type default)
		)
		(layer "B.Cu")
	)
	(gr_line
		(start 363.0803 -141.7574)
		(end 363.26318 -141.94028)
		(stroke
			(width 0.127)
			(type default)
		)
		(layer "B.Cu")
	)
	(gr_line
		(start 363.345222 -44.763436)
		(end 363.35843 -44.743624)
		(stroke
			(width 0.08255)
			(type default)
		)
		(layer "B.Cu")
	)
	(gr_line
		(start 363.35843 -44.743624)
		(end 363.378242 -44.73067)
		(stroke
			(width 0.08255)
			(type default)
		)
		(layer "B.Cu")
	)
	(gr_line
		(start 363.377734 -32.262572)
		(end 363.396022 -32.229552)
		(stroke
			(width 0.08255)
			(type default)
		)
		(layer "B.Cu")
	)
	(gr_arc
		(start 363.983524 -22.504146)
		(mid 364.101165 -22.455417)
		(end 364.149894 -22.337776)
		(stroke
			(width 0.08255)
			(type default)
		)
		(layer "B.Cu")
	)
	(gr_arc
		(start 364.149894 -22.962616)
		(mid 364.101172 -22.844956)
		(end 363.983524 -22.796246)
		(stroke
			(width 0.08255)
			(type default)
		)
		(layer "B.Cu")
	)
	(gr_line
		(start 364.149894 -22.962616)
		(end 364.149894 -23.35022)
		(stroke
			(width 0.08255)
			(type default)
		)
		(layer "B.Cu")
	)
	(gr_line
		(start 364.149894 -21.950172)
		(end 364.149894 -22.337776)
		(stroke
			(width 0.08255)
			(type default)
		)
		(layer "B.Cu")
	)
	(gr_line
		(start 364.67542 -142.59052)
		(end 364.7948 -142.7099)
		(stroke
			(width 0.127)
			(type default)
		)
		(layer "B.Cu")
	)
	(gr_line
		(start 364.67542 -141.94028)
		(end 364.7948 -141.8209)
		(stroke
			(width 0.127)
			(type default)
		)
		(layer "B.Cu")
	)
	(gr_line
		(start 364.7948 -142.7099)
		(end 364.91418 -142.59052)
		(stroke
			(width 0.127)
			(type default)
		)
		(layer "B.Cu")
	)
	(gr_line
		(start 364.7948 -141.8209)
		(end 364.91418 -141.94028)
		(stroke
			(width 0.127)
			(type default)
		)
		(layer "B.Cu")
	)
	(gr_line
		(start 365.178086 -32.301434)
		(end 365.19612 -32.268922)
		(stroke
			(width 0.08255)
			(type default)
		)
		(layer "B.Cu")
	)
	(gr_arc
		(start 365.783622 -21.504148)
		(mid 365.901263 -21.455419)
		(end 365.949992 -21.337778)
		(stroke
			(width 0.08255)
			(type default)
		)
		(layer "B.Cu")
	)
	(gr_arc
		(start 365.949992 -21.962618)
		(mid 365.901271 -21.844957)
		(end 365.783622 -21.796248)
		(stroke
			(width 0.08255)
			(type default)
		)
		(layer "B.Cu")
	)
	(gr_line
		(start 365.949992 -21.962618)
		(end 365.949992 -22.350222)
		(stroke
			(width 0.08255)
			(type default)
		)
		(layer "B.Cu")
	)
	(gr_line
		(start 365.949992 -20.950174)
		(end 365.949992 -21.337778)
		(stroke
			(width 0.08255)
			(type default)
		)
		(layer "B.Cu")
	)
	(gr_line
		(start 366.395 -140.352272)
		(end 366.395 -140.8938)
		(stroke
			(width 0.127)
			(type default)
		)
		(layer "B.Cu")
	)
	(gr_line
		(start 366.395 -140.352272)
		(end 366.46358 -140.283692)
		(stroke
			(width 0.127)
			(type default)
		)
		(layer "B.Cu")
	)
	(gr_line
		(start 366.395 -139.564872)
		(end 366.46358 -139.633452)
		(stroke
			(width 0.127)
			(type default)
		)
		(layer "B.Cu")
	)
	(gr_line
		(start 366.395 -139.2936)
		(end 366.395 -139.564872)
		(stroke
			(width 0.127)
			(type default)
		)
		(layer "B.Cu")
	)
	(gr_line
		(start 366.970818 -33.547304)
		(end 366.996218 -33.507426)
		(stroke
			(width 0.08255)
			(type default)
		)
		(layer "B.Cu")
	)
	(gr_line
		(start 367.283238 -83.91144)
		(end 367.291366 -83.899248)
		(stroke
			(width 0.0635)
			(type default)
		)
		(layer "B.Cu")
	)
	(gr_line
		(start 367.291366 -83.899248)
		(end 367.303812 -83.890358)
		(stroke
			(width 0.0635)
			(type default)
		)
		(layer "B.Cu")
	)
	(gr_arc
		(start 367.58372 -22.504146)
		(mid 367.701361 -22.455417)
		(end 367.75009 -22.337776)
		(stroke
			(width 0.08255)
			(type default)
		)
		(layer "B.Cu")
	)
	(gr_arc
		(start 367.75009 -22.962616)
		(mid 367.701368 -22.844957)
		(end 367.58372 -22.796246)
		(stroke
			(width 0.08255)
			(type default)
		)
		(layer "B.Cu")
	)
	(gr_line
		(start 367.75009 -22.962616)
		(end 367.75009 -23.35022)
		(stroke
			(width 0.08255)
			(type default)
		)
		(layer "B.Cu")
	)
	(gr_line
		(start 367.75009 -21.950172)
		(end 367.75009 -22.337776)
		(stroke
			(width 0.08255)
			(type default)
		)
		(layer "B.Cu")
	)
	(gr_line
		(start 369.441984 -193.41084)
		(end 369.457986 -193.385948)
		(stroke
			(width 0.0635)
			(type default)
		)
		(layer "B.Cu")
	)
	(gr_line
		(start 369.457986 -193.385948)
		(end 369.483132 -193.3702)
		(stroke
			(width 0.0635)
			(type default)
		)
		(layer "B.Cu")
	)
	(gr_line
		(start 371.324886 -312.615326)
		(end 371.338856 -312.606436)
		(stroke
			(width 0.0635)
			(type default)
		)
		(layer "B.Cu")
	)
	(gr_line
		(start 371.338856 -312.606436)
		(end 371.355112 -312.603134)
		(stroke
			(width 0.0635)
			(type default)
		)
		(layer "B.Cu")
	)
	(gr_line
		(start 372.34876 -45.96892)
		(end 372.365016 -45.95749)
		(stroke
			(width 0.08255)
			(type default)
		)
		(layer "B.Cu")
	)
	(gr_line
		(start 372.365016 -45.95749)
		(end 372.375684 -45.94098)
		(stroke
			(width 0.08255)
			(type default)
		)
		(layer "B.Cu")
	)
	(gr_line
		(start 372.366286 -314.754006)
		(end 372.381272 -314.744608)
		(stroke
			(width 0.0635)
			(type default)
		)
		(layer "B.Cu")
	)
	(gr_line
		(start 372.381272 -314.744608)
		(end 372.397274 -314.74156)
		(stroke
			(width 0.0635)
			(type default)
		)
		(layer "B.Cu")
	)
	(gr_line
		(start 372.75643 -314.665868)
		(end 372.881398 -314.476892)
		(stroke
			(width 0.0635)
			(type default)
		)
		(layer "B.Cu")
	)
	(gr_line
		(start 372.803166 -48.264318)
		(end 372.819422 -48.252888)
		(stroke
			(width 0.08255)
			(type default)
		)
		(layer "B.Cu")
	)
	(gr_line
		(start 372.819422 -48.252888)
		(end 372.83009 -48.236378)
		(stroke
			(width 0.08255)
			(type default)
		)
		(layer "B.Cu")
	)
	(gr_line
		(start 372.848378 -314.948062)
		(end 373.469154 -314.821824)
		(stroke
			(width 0.0635)
			(type default)
		)
		(layer "B.Cu")
	)
	(gr_line
		(start 372.881398 -314.476892)
		(end 373.254778 -314.400946)
		(stroke
			(width 0.0635)
			(type default)
		)
		(layer "B.Cu")
	)
	(gr_line
		(start 373.254778 -314.400946)
		(end 373.443754 -314.526168)
		(stroke
			(width 0.0635)
			(type default)
		)
		(layer "B.Cu")
	)
	(gr_line
		(start 373.821706 -314.449206)
		(end 373.946928 -314.26023)
		(stroke
			(width 0.0635)
			(type default)
		)
		(layer "B.Cu")
	)
	(gr_line
		(start 373.914416 -314.731146)
		(end 374.534684 -314.604908)
		(stroke
			(width 0.0635)
			(type default)
		)
		(layer "B.Cu")
	)
	(gr_line
		(start 373.946928 -314.26023)
		(end 374.320054 -314.184284)
		(stroke
			(width 0.0635)
			(type default)
		)
		(layer "B.Cu")
	)
	(gr_line
		(start 374.320054 -314.184284)
		(end 374.509284 -314.309252)
		(stroke
			(width 0.0635)
			(type default)
		)
		(layer "B.Cu")
	)
	(gr_line
		(start 374.886982 -314.232544)
		(end 375.012204 -314.043568)
		(stroke
			(width 0.0635)
			(type default)
		)
		(layer "B.Cu")
	)
	(gr_line
		(start 374.979184 -314.51423)
		(end 375.599452 -314.388246)
		(stroke
			(width 0.0635)
			(type default)
		)
		(layer "B.Cu")
	)
	(gr_line
		(start 375.012204 -314.043568)
		(end 375.38533 -313.967622)
		(stroke
			(width 0.0635)
			(type default)
		)
		(layer "B.Cu")
	)
	(gr_line
		(start 375.18467 -35.489642)
		(end 375.206768 -35.475418)
		(stroke
			(width 0.08255)
			(type default)
		)
		(layer "B.Cu")
	)
	(gr_line
		(start 375.206768 -35.475418)
		(end 375.220992 -35.45332)
		(stroke
			(width 0.08255)
			(type default)
		)
		(layer "B.Cu")
	)
	(gr_line
		(start 375.38533 -313.967622)
		(end 375.574306 -314.09259)
		(stroke
			(width 0.0635)
			(type default)
		)
		(layer "B.Cu")
	)
	(gr_line
		(start 376.477784 -36.548822)
		(end 376.499628 -36.534598)
		(stroke
			(width 0.08255)
			(type default)
		)
		(layer "B.Cu")
	)
	(gr_line
		(start 376.499628 -36.534598)
		(end 376.513598 -36.512754)
		(stroke
			(width 0.08255)
			(type default)
		)
		(layer "B.Cu")
	)
	(gr_line
		(start 376.750072 -21.962618)
		(end 376.750072 -22.350222)
		(stroke
			(width 0.08255)
			(type default)
		)
		(layer "B.Cu")
	)
	(gr_arc
		(start 376.750072 -21.337778)
		(mid 376.798795 -21.455419)
		(end 376.916442 -21.504148)
		(stroke
			(width 0.08255)
			(type default)
		)
		(layer "B.Cu")
	)
	(gr_line
		(start 376.750072 -20.950174)
		(end 376.750072 -21.337778)
		(stroke
			(width 0.08255)
			(type default)
		)
		(layer "B.Cu")
	)
	(gr_arc
		(start 376.916442 -21.796248)
		(mid 376.798801 -21.844977)
		(end 376.750072 -21.962618)
		(stroke
			(width 0.08255)
			(type default)
		)
		(layer "B.Cu")
	)
	(gr_line
		(start 377.685554 -235.488226)
		(end 377.699016 -235.479336)
		(stroke
			(width 0.0635)
			(type default)
		)
		(layer "B.Cu")
	)
	(gr_line
		(start 377.699016 -235.479336)
		(end 377.70181 -235.477558)
		(stroke
			(width 0.0635)
			(type default)
		)
		(layer "B.Cu")
	)
	(gr_line
		(start 377.70181 -235.477558)
		(end 377.720606 -235.473748)
		(stroke
			(width 0.0635)
			(type default)
		)
		(layer "B.Cu")
	)
	(gr_line
		(start 377.771152 -31.453074)
		(end 377.796044 -31.414212)
		(stroke
			(width 0.08255)
			(type default)
		)
		(layer "B.Cu")
	)
	(gr_line
		(start 378.549916 -22.962616)
		(end 378.549916 -23.35022)
		(stroke
			(width 0.08255)
			(type default)
		)
		(layer "B.Cu")
	)
	(gr_arc
		(start 378.549916 -22.337776)
		(mid 378.598635 -22.455438)
		(end 378.716286 -22.504146)
		(stroke
			(width 0.08255)
			(type default)
		)
		(layer "B.Cu")
	)
	(gr_line
		(start 378.549916 -21.950172)
		(end 378.549916 -22.337776)
		(stroke
			(width 0.08255)
			(type default)
		)
		(layer "B.Cu")
	)
	(gr_arc
		(start 378.716286 -22.796246)
		(mid 378.598659 -22.844981)
		(end 378.549916 -22.962616)
		(stroke
			(width 0.08255)
			(type default)
		)
		(layer "B.Cu")
	)
	(gr_line
		(start 379.570996 -31.707328)
		(end 379.595888 -31.668212)
		(stroke
			(width 0.08255)
			(type default)
		)
		(layer "B.Cu")
	)
	(gr_line
		(start 380.350014 -21.962618)
		(end 380.350014 -22.350222)
		(stroke
			(width 0.08255)
			(type default)
		)
		(layer "B.Cu")
	)
	(gr_arc
		(start 380.350014 -21.337778)
		(mid 380.398743 -21.455419)
		(end 380.516384 -21.504148)
		(stroke
			(width 0.08255)
			(type default)
		)
		(layer "B.Cu")
	)
	(gr_line
		(start 380.350014 -20.950174)
		(end 380.350014 -21.337778)
		(stroke
			(width 0.08255)
			(type default)
		)
		(layer "B.Cu")
	)
	(gr_arc
		(start 380.516384 -21.796248)
		(mid 380.398759 -21.844983)
		(end 380.350014 -21.962618)
		(stroke
			(width 0.08255)
			(type default)
		)
		(layer "B.Cu")
	)
	(gr_line
		(start 381.371094 -31.832042)
		(end 381.395986 -31.79318)
		(stroke
			(width 0.08255)
			(type default)
		)
		(layer "B.Cu")
	)
	(gr_line
		(start 381.526796 -60.016898)
		(end 381.547878 -59.986164)
		(stroke
			(width 0.0635)
			(type default)
		)
		(layer "B.Cu")
	)
	(gr_line
		(start 381.75057 -60.211462)
		(end 381.776478 -60.201048)
		(stroke
			(width 0.0635)
			(type default)
		)
		(layer "B.Cu")
	)
	(gr_line
		(start 381.776478 -60.201048)
		(end 381.808736 -60.125864)
		(stroke
			(width 0.0635)
			(type default)
		)
		(layer "B.Cu")
	)
	(gr_line
		(start 382.150112 -22.962616)
		(end 382.150112 -23.35022)
		(stroke
			(width 0.08255)
			(type default)
		)
		(layer "B.Cu")
	)
	(gr_arc
		(start 382.150112 -22.337776)
		(mid 382.198831 -22.455439)
		(end 382.316482 -22.504146)
		(stroke
			(width 0.08255)
			(type default)
		)
		(layer "B.Cu")
	)
	(gr_line
		(start 382.150112 -21.950172)
		(end 382.150112 -22.337776)
		(stroke
			(width 0.08255)
			(type default)
		)
		(layer "B.Cu")
	)
	(gr_arc
		(start 382.316482 -22.796246)
		(mid 382.198858 -22.844982)
		(end 382.150112 -22.962616)
		(stroke
			(width 0.08255)
			(type default)
		)
		(layer "B.Cu")
	)
	(gr_line
		(start 383.171192 -32.0167)
		(end 383.196084 -31.977838)
		(stroke
			(width 0.08255)
			(type default)
		)
		(layer "B.Cu")
	)
	(gr_line
		(start 383.949956 -21.962618)
		(end 383.949956 -22.350222)
		(stroke
			(width 0.08255)
			(type default)
		)
		(layer "B.Cu")
	)
	(gr_arc
		(start 383.949956 -21.337778)
		(mid 383.998685 -21.455419)
		(end 384.116326 -21.504148)
		(stroke
			(width 0.08255)
			(type default)
		)
		(layer "B.Cu")
	)
	(gr_line
		(start 383.949956 -20.950174)
		(end 383.949956 -21.337778)
		(stroke
			(width 0.08255)
			(type default)
		)
		(layer "B.Cu")
	)
	(gr_arc
		(start 384.116326 -21.796248)
		(mid 383.998674 -21.844969)
		(end 383.949956 -21.962618)
		(stroke
			(width 0.08255)
			(type default)
		)
		(layer "B.Cu")
	)
	(gr_line
		(start 384.965702 -34.24809)
		(end 384.995928 -34.204656)
		(stroke
			(width 0.08255)
			(type default)
		)
		(layer "B.Cu")
	)
	(gr_line
		(start 385.750054 -22.962616)
		(end 385.750054 -23.35022)
		(stroke
			(width 0.08255)
			(type default)
		)
		(layer "B.Cu")
	)
	(gr_arc
		(start 385.750054 -22.337776)
		(mid 385.798783 -22.455417)
		(end 385.916424 -22.504146)
		(stroke
			(width 0.08255)
			(type default)
		)
		(layer "B.Cu")
	)
	(gr_line
		(start 385.750054 -21.950172)
		(end 385.750054 -22.337776)
		(stroke
			(width 0.08255)
			(type default)
		)
		(layer "B.Cu")
	)
	(gr_arc
		(start 385.916424 -22.796246)
		(mid 385.798773 -22.844967)
		(end 385.750054 -22.962616)
		(stroke
			(width 0.08255)
			(type default)
		)
		(layer "B.Cu")
	)
	(gr_line
		(start 386.275326 -162.965384)
		(end 386.290566 -162.941508)
		(stroke
			(width 0.0635)
			(type default)
		)
		(layer "B.Cu")
	)
	(gr_line
		(start 386.290566 -162.941508)
		(end 386.313934 -162.92703)
		(stroke
			(width 0.0635)
			(type default)
		)
		(layer "B.Cu")
	)
	(gr_line
		(start 386.73024 -47.878492)
		(end 386.73786 -47.860458)
		(stroke
			(width 0.0635)
			(type default)
		)
		(layer "B.Cu")
	)
	(gr_line
		(start 386.73786 -47.860458)
		(end 386.751322 -47.84725)
		(stroke
			(width 0.0635)
			(type default)
		)
		(layer "B.Cu")
	)
	(gr_line
		(start 386.7658 -34.45891)
		(end 386.796026 -34.415476)
		(stroke
			(width 0.08255)
			(type default)
		)
		(layer "B.Cu")
	)
	(gr_line
		(start 386.790184 -162.628072)
		(end 386.828792 -162.603942)
		(stroke
			(width 0.0635)
			(type default)
		)
		(layer "B.Cu")
	)
	(gr_line
		(start 386.92709 -277.631398)
		(end 386.968238 -277.603966)
		(stroke
			(width 0.0635)
			(type default)
		)
		(layer "B.Cu")
	)
	(gr_line
		(start 387.549898 -21.962618)
		(end 387.549898 -22.350222)
		(stroke
			(width 0.08255)
			(type default)
		)
		(layer "B.Cu")
	)
	(gr_arc
		(start 387.549898 -21.337778)
		(mid 387.598627 -21.455419)
		(end 387.716268 -21.504148)
		(stroke
			(width 0.08255)
			(type default)
		)
		(layer "B.Cu")
	)
	(gr_line
		(start 387.549898 -20.950174)
		(end 387.549898 -21.337778)
		(stroke
			(width 0.08255)
			(type default)
		)
		(layer "B.Cu")
	)
	(gr_arc
		(start 387.662166 -277.603966)
		(mid 387.787187 -277.552198)
		(end 387.83895 -277.427182)
		(stroke
			(width 0.0635)
			(type default)
		)
		(layer "B.Cu")
	)
	(gr_arc
		(start 387.662166 -162.603942)
		(mid 387.787171 -162.552163)
		(end 387.83895 -162.427158)
		(stroke
			(width 0.0635)
			(type default)
		)
		(layer "B.Cu")
	)
	(gr_arc
		(start 387.662166 -47.603918)
		(mid 387.787205 -47.552153)
		(end 387.83895 -47.427134)
		(stroke
			(width 0.0635)
			(type default)
		)
		(layer "B.Cu")
	)
	(gr_arc
		(start 387.716268 -21.796248)
		(mid 387.598654 -21.844989)
		(end 387.549898 -21.962618)
		(stroke
			(width 0.08255)
			(type default)
		)
		(layer "B.Cu")
	)
	(gr_arc
		(start 387.83895 -278.07285)
		(mid 387.787171 -277.947845)
		(end 387.662166 -277.896066)
		(stroke
			(width 0.0635)
			(type default)
		)
		(layer "B.Cu")
	)
	(gr_line
		(start 387.83895 -278.07285)
		(end 387.83895 -278.321516)
		(stroke
			(width 0.0635)
			(type default)
		)
		(layer "B.Cu")
	)
	(gr_line
		(start 387.83895 -277.178516)
		(end 387.83895 -277.427182)
		(stroke
			(width 0.0635)
			(type default)
		)
		(layer "B.Cu")
	)
	(gr_arc
		(start 387.83895 -163.072826)
		(mid 387.787171 -162.947821)
		(end 387.662166 -162.896042)
		(stroke
			(width 0.0635)
			(type default)
		)
		(layer "B.Cu")
	)
	(gr_line
		(start 387.83895 -163.072826)
		(end 387.83895 -163.321492)
		(stroke
			(width 0.0635)
			(type default)
		)
		(layer "B.Cu")
	)
	(gr_line
		(start 387.83895 -162.178492)
		(end 387.83895 -162.427158)
		(stroke
			(width 0.0635)
			(type default)
		)
		(layer "B.Cu")
	)
	(gr_arc
		(start 387.83895 -48.072802)
		(mid 387.787171 -47.947797)
		(end 387.662166 -47.896018)
		(stroke
			(width 0.0635)
			(type default)
		)
		(layer "B.Cu")
	)
	(gr_line
		(start 387.83895 -48.072802)
		(end 387.83895 -48.321468)
		(stroke
			(width 0.0635)
			(type default)
		)
		(layer "B.Cu")
	)
	(gr_line
		(start 387.83895 -47.178468)
		(end 387.83895 -47.427134)
		(stroke
			(width 0.0635)
			(type default)
		)
		(layer "B.Cu")
	)
	(gr_line
		(start 388.565644 -34.63925)
		(end 388.59587 -34.595562)
		(stroke
			(width 0.08255)
			(type default)
		)
		(layer "B.Cu")
	)
	(gr_line
		(start 389.349996 -22.962616)
		(end 389.349996 -23.35022)
		(stroke
			(width 0.08255)
			(type default)
		)
		(layer "B.Cu")
	)
	(gr_arc
		(start 389.349996 -22.337776)
		(mid 389.398725 -22.455417)
		(end 389.516366 -22.504146)
		(stroke
			(width 0.08255)
			(type default)
		)
		(layer "B.Cu")
	)
	(gr_line
		(start 389.349996 -21.950172)
		(end 389.349996 -22.337776)
		(stroke
			(width 0.08255)
			(type default)
		)
		(layer "B.Cu")
	)
	(gr_arc
		(start 389.516366 -22.796246)
		(mid 389.398752 -22.844988)
		(end 389.349996 -22.962616)
		(stroke
			(width 0.08255)
			(type default)
		)
		(layer "B.Cu")
	)
	(gr_line
		(start 390.162034 -39.692834)
		(end 390.172956 -39.676324)
		(stroke
			(width 0.08255)
			(type default)
		)
		(layer "B.Cu")
	)
	(gr_line
		(start 390.172956 -39.676324)
		(end 390.176512 -39.657782)
		(stroke
			(width 0.08255)
			(type default)
		)
		(layer "B.Cu")
	)
	(gr_line
		(start 408.489912 -305.346354)
		(end 408.509216 -305.34229)
		(stroke
			(width 0.0635)
			(type default)
		)
		(layer "B.Cu")
	)
	(gr_line
		(start 408.509216 -305.34229)
		(end 408.525726 -305.331368)
		(stroke
			(width 0.0635)
			(type default)
		)
		(layer "B.Cu")
	)
	(gr_line
		(start 417.661598 -47.874428)
		(end 417.674044 -47.865538)
		(stroke
			(width 0.0635)
			(type default)
		)
		(layer "B.Cu")
	)
	(gr_line
		(start 417.674044 -47.865538)
		(end 417.688776 -47.861474)
		(stroke
			(width 0.0635)
			(type default)
		)
		(layer "B.Cu")
	)
	(gr_line
		(start 418.33546 -277.612094)
		(end 418.354764 -277.603966)
		(stroke
			(width 0.0635)
			(type default)
		)
		(layer "B.Cu")
	)
	(gr_line
		(start 418.49802 -64.517524)
		(end 418.511482 -64.508634)
		(stroke
			(width 0.0635)
			(type default)
		)
		(layer "B.Cu")
	)
	(gr_line
		(start 418.511482 -64.508634)
		(end 418.527738 -64.505078)
		(stroke
			(width 0.0635)
			(type default)
		)
		(layer "B.Cu")
	)
	(gr_line
		(start 418.671502 -162.627564)
		(end 418.709094 -162.603942)
		(stroke
			(width 0.0635)
			(type default)
		)
		(layer "B.Cu")
	)
	(gr_line
		(start 418.968174 -66.839592)
		(end 418.981636 -66.830956)
		(stroke
			(width 0.0635)
			(type default)
		)
		(layer "B.Cu")
	)
	(gr_line
		(start 418.981636 -66.830956)
		(end 418.99713 -66.827654)
		(stroke
			(width 0.0635)
			(type default)
		)
		(layer "B.Cu")
	)
	(gr_arc
		(start 419.212268 -277.603966)
		(mid 419.337287 -277.552197)
		(end 419.389052 -277.427182)
		(stroke
			(width 0.0635)
			(type default)
		)
		(layer "B.Cu")
	)
	(gr_arc
		(start 419.212268 -162.603942)
		(mid 419.337279 -162.552172)
		(end 419.389052 -162.427158)
		(stroke
			(width 0.0635)
			(type default)
		)
		(layer "B.Cu")
	)
	(gr_arc
		(start 419.212268 -47.603918)
		(mid 419.337306 -47.552153)
		(end 419.389052 -47.427134)
		(stroke
			(width 0.0635)
			(type default)
		)
		(layer "B.Cu")
	)
	(gr_arc
		(start 419.389052 -278.07285)
		(mid 419.337273 -277.947845)
		(end 419.212268 -277.896066)
		(stroke
			(width 0.0635)
			(type default)
		)
		(layer "B.Cu")
	)
	(gr_line
		(start 419.389052 -278.07285)
		(end 419.389052 -278.321516)
		(stroke
			(width 0.0635)
			(type default)
		)
		(layer "B.Cu")
	)
	(gr_line
		(start 419.389052 -277.178516)
		(end 419.389052 -277.427182)
		(stroke
			(width 0.0635)
			(type default)
		)
		(layer "B.Cu")
	)
	(gr_arc
		(start 419.389052 -163.072826)
		(mid 419.337273 -162.947821)
		(end 419.212268 -162.896042)
		(stroke
			(width 0.0635)
			(type default)
		)
		(layer "B.Cu")
	)
	(gr_line
		(start 419.389052 -163.072826)
		(end 419.389052 -163.321492)
		(stroke
			(width 0.0635)
			(type default)
		)
		(layer "B.Cu")
	)
	(gr_line
		(start 419.389052 -162.178492)
		(end 419.389052 -162.427158)
		(stroke
			(width 0.0635)
			(type default)
		)
		(layer "B.Cu")
	)
	(gr_arc
		(start 419.389052 -48.072802)
		(mid 419.337272 -47.947807)
		(end 419.212268 -47.896018)
		(stroke
			(width 0.0635)
			(type default)
		)
		(layer "B.Cu")
	)
	(gr_line
		(start 419.389052 -48.072802)
		(end 419.389052 -48.321468)
		(stroke
			(width 0.0635)
			(type default)
		)
		(layer "B.Cu")
	)
	(gr_line
		(start 419.389052 -47.178468)
		(end 419.389052 -47.427134)
		(stroke
			(width 0.0635)
			(type default)
		)
		(layer "B.Cu")
	)
	(gr_line
		(start 422.752774 -169.503852)
		(end 422.76014 -169.496486)
		(stroke
			(width 0.0635)
			(type default)
		)
		(layer "B.Cu")
	)
	(gr_line
		(start 422.76014 -169.496486)
		(end 422.769792 -169.49166)
		(stroke
			(width 0.0635)
			(type default)
		)
		(layer "B.Cu")
	)
	(gr_line
		(start 429.375316 -62.497716)
		(end 429.396398 -62.493398)
		(stroke
			(width 0.0635)
			(type default)
		)
		(layer "B.Cu")
	)
	(gr_line
		(start 429.396398 -62.493398)
		(end 429.414178 -62.480698)
		(stroke
			(width 0.0635)
			(type default)
		)
		(layer "B.Cu")
	)
	(gr_line
		(start 430.271174 -225.304604)
		(end 430.3014 -225.298508)
		(stroke
			(width 0.0635)
			(type default)
		)
		(layer "B.Cu")
	)
	(gr_line
		(start 430.3014 -225.298508)
		(end 430.325784 -225.279712)
		(stroke
			(width 0.0635)
			(type default)
		)
		(layer "B.Cu")
	)
	(gr_line
		(start 430.958244 -64.285876)
		(end 430.959514 -64.285622)
		(stroke
			(width 0.0635)
			(type default)
		)
		(layer "B.Cu")
	)
	(gr_line
		(start 430.959514 -64.285114)
		(end 430.959514 -64.285622)
		(stroke
			(width 0.0635)
			(type default)
		)
		(layer "B.Cu")
	)
	(gr_line
		(start 431.05197 -64.56426)
		(end 431.05197 -64.564768)
		(stroke
			(width 0.0635)
			(type default)
		)
		(layer "B.Cu")
	)
	(gr_line
		(start 431.069242 -64.556386)
		(end 431.09388 -64.544956)
		(stroke
			(width 0.0635)
			(type default)
		)
		(layer "B.Cu")
	)
	(gr_line
		(start 436.857902 -162.616642)
		(end 436.884064 -162.603942)
		(stroke
			(width 0.0635)
			(type default)
		)
		(layer "B.Cu")
	)
	(gr_line
		(start 436.903876 -220.174566)
		(end 436.905146 -220.17355)
		(stroke
			(width 0.0635)
			(type default)
		)
		(layer "B.Cu")
	)
	(gr_line
		(start 436.905146 -220.17355)
		(end 436.906162 -220.172026)
		(stroke
			(width 0.0635)
			(type default)
		)
		(layer "B.Cu")
	)
	(gr_arc
		(start 438.062116 -162.603942)
		(mid 438.187121 -162.552163)
		(end 438.2389 -162.427158)
		(stroke
			(width 0.0635)
			(type default)
		)
		(layer "B.Cu")
	)
	(gr_arc
		(start 438.2389 -163.072826)
		(mid 438.187131 -162.947798)
		(end 438.062116 -162.896042)
		(stroke
			(width 0.0635)
			(type default)
		)
		(layer "B.Cu")
	)
	(gr_line
		(start 438.2389 -163.072826)
		(end 438.2389 -163.321492)
		(stroke
			(width 0.0635)
			(type default)
		)
		(layer "B.Cu")
	)
	(gr_line
		(start 438.2389 -162.178492)
		(end 438.2389 -162.427158)
		(stroke
			(width 0.0635)
			(type default)
		)
		(layer "B.Cu")
	)
	(gr_line
		(start 449.358258 -47.856648)
		(end 449.371466 -47.846996)
		(stroke
			(width 0.0635)
			(type default)
		)
		(layer "B.Cu")
	)
	(gr_line
		(start 449.371466 -47.846996)
		(end 449.388484 -47.842424)
		(stroke
			(width 0.0635)
			(type default)
		)
		(layer "B.Cu")
	)
	(gr_line
		(start 449.84543 -277.631398)
		(end 449.886578 -277.603966)
		(stroke
			(width 0.0635)
			(type default)
		)
		(layer "B.Cu")
	)
	(gr_line
		(start 450.374512 -201.51217)
		(end 450.375528 -201.510646)
		(stroke
			(width 0.0635)
			(type default)
		)
		(layer "B.Cu")
	)
	(gr_line
		(start 450.375528 -201.510646)
		(end 450.376798 -201.50963)
		(stroke
			(width 0.0635)
			(type default)
		)
		(layer "B.Cu")
	)
	(gr_arc
		(start 450.762116 -277.603966)
		(mid 450.887104 -277.55218)
		(end 450.9389 -277.427182)
		(stroke
			(width 0.0635)
			(type default)
		)
		(layer "B.Cu")
	)
	(gr_arc
		(start 450.762116 -47.603918)
		(mid 450.887121 -47.552139)
		(end 450.9389 -47.427134)
		(stroke
			(width 0.0635)
			(type default)
		)
		(layer "B.Cu")
	)
	(gr_arc
		(start 450.9389 -278.07285)
		(mid 450.887121 -277.947845)
		(end 450.762116 -277.896066)
		(stroke
			(width 0.0635)
			(type default)
		)
		(layer "B.Cu")
	)
	(gr_line
		(start 450.9389 -278.07285)
		(end 450.9389 -278.321516)
		(stroke
			(width 0.0635)
			(type default)
		)
		(layer "B.Cu")
	)
	(gr_line
		(start 450.9389 -277.178516)
		(end 450.9389 -277.427182)
		(stroke
			(width 0.0635)
			(type default)
		)
		(layer "B.Cu")
	)
	(gr_arc
		(start 450.9389 -48.072802)
		(mid 450.887123 -47.94779)
		(end 450.762116 -47.896018)
		(stroke
			(width 0.0635)
			(type default)
		)
		(layer "B.Cu")
	)
	(gr_line
		(start 450.9389 -48.072802)
		(end 450.9389 -48.321468)
		(stroke
			(width 0.0635)
			(type default)
		)
		(layer "B.Cu")
	)
	(gr_line
		(start 450.9389 -47.178468)
		(end 450.9389 -47.427134)
		(stroke
			(width 0.0635)
			(type default)
		)
		(layer "B.Cu")
	)
	(gr_line
		(start 451.510908 -298.943014)
		(end 451.530466 -298.93895)
		(stroke
			(width 0.0635)
			(type default)
		)
		(layer "B.Cu")
	)
	(gr_line
		(start 451.530466 -298.93895)
		(end 451.546976 -298.928028)
		(stroke
			(width 0.0635)
			(type default)
		)
		(layer "B.Cu")
	)
	(gr_line
		(start 461.71612 -193.129662)
		(end 461.723994 -193.123566)
		(stroke
			(width 0.0635)
			(type default)
		)
		(layer "B.Cu")
	)
	(gr_line
		(start 461.723994 -193.123566)
		(end 461.729582 -193.11493)
		(stroke
			(width 0.0635)
			(type default)
		)
		(layer "B.Cu")
	)
	(gr_line
		(start 463.61477 -49.291494)
		(end 463.624422 -49.286922)
		(stroke
			(width 0.0635)
			(type default)
		)
		(layer "B.Cu")
	)
	(gr_line
		(start 463.624422 -49.286922)
		(end 463.63509 -49.285906)
		(stroke
			(width 0.0635)
			(type default)
		)
		(layer "B.Cu")
	)
	(gr_line
		(start 478.360994 -281.179778)
		(end 478.378266 -281.168348)
		(stroke
			(width 0.0635)
			(type default)
		)
		(layer "B.Cu")
	)
	(gr_line
		(start 478.378266 -281.168348)
		(end 478.389696 -281.151076)
		(stroke
			(width 0.0635)
			(type default)
		)
		(layer "B.Cu")
	)
	(gr_line
		(start 479.679762 -278.673814)
		(end 479.691192 -278.656542)
		(stroke
			(width 0.0635)
			(type default)
		)
		(layer "B.Cu")
	)
	(gr_line
		(start 479.691192 -278.656542)
		(end 479.708464 -278.645112)
		(stroke
			(width 0.0635)
			(type default)
		)
		(layer "B.Cu")
	)
	(gr_line
		(start 481.038662 -277.764494)
		(end 481.055172 -277.753572)
		(stroke
			(width 0.0635)
			(type default)
		)
		(layer "B.Cu")
	)
	(gr_line
		(start 481.055172 -277.753572)
		(end 481.073206 -277.750016)
		(stroke
			(width 0.0635)
			(type default)
		)
		(layer "B.Cu")
	)
	(gr_arc
		(start 482.312218 -277.603966)
		(mid 482.437223 -277.552187)
		(end 482.489002 -277.427182)
		(stroke
			(width 0.0635)
			(type default)
		)
		(layer "B.Cu")
	)
	(gr_arc
		(start 482.312218 -162.603942)
		(mid 482.437197 -162.552154)
		(end 482.489002 -162.427158)
		(stroke
			(width 0.0635)
			(type default)
		)
		(layer "B.Cu")
	)
	(gr_arc
		(start 482.312218 -47.603918)
		(mid 482.437224 -47.552135)
		(end 482.489002 -47.427134)
		(stroke
			(width 0.0635)
			(type default)
		)
		(layer "B.Cu")
	)
	(gr_arc
		(start 482.489002 -278.07285)
		(mid 482.437223 -277.947845)
		(end 482.312218 -277.896066)
		(stroke
			(width 0.0635)
			(type default)
		)
		(layer "B.Cu")
	)
	(gr_line
		(start 482.489002 -278.07285)
		(end 482.489002 -278.321516)
		(stroke
			(width 0.0635)
			(type default)
		)
		(layer "B.Cu")
	)
	(gr_line
		(start 482.489002 -277.178516)
		(end 482.489002 -277.427182)
		(stroke
			(width 0.0635)
			(type default)
		)
		(layer "B.Cu")
	)
	(gr_arc
		(start 482.489002 -163.072826)
		(mid 482.437223 -162.947821)
		(end 482.312218 -162.896042)
		(stroke
			(width 0.0635)
			(type default)
		)
		(layer "B.Cu")
	)
	(gr_line
		(start 482.489002 -163.072826)
		(end 482.489002 -163.321492)
		(stroke
			(width 0.0635)
			(type default)
		)
		(layer "B.Cu")
	)
	(gr_line
		(start 482.489002 -162.178492)
		(end 482.489002 -162.427158)
		(stroke
			(width 0.0635)
			(type default)
		)
		(layer "B.Cu")
	)
	(gr_arc
		(start 482.489002 -48.072802)
		(mid 482.437225 -47.947789)
		(end 482.312218 -47.896018)
		(stroke
			(width 0.0635)
			(type default)
		)
		(layer "B.Cu")
	)
	(gr_line
		(start 482.489002 -48.072802)
		(end 482.489002 -48.321468)
		(stroke
			(width 0.0635)
			(type default)
		)
		(layer "B.Cu")
	)
	(gr_line
		(start 482.489002 -47.178468)
		(end 482.489002 -47.427134)
		(stroke
			(width 0.0635)
			(type default)
		)
		(layer "B.Cu")
	)
	(gr_line
		(start 0 -348.199964)
		(end 0 -0.999998)
		(stroke
			(width 1.524)
			(type default)
		)
		(layer "In1.Cu")
	)
	(gr_arc
		(start 0 -348.199964)
		(mid 0.292894 -348.907067)
		(end 0.999998 -349.199962)
		(stroke
			(width 1.524)
			(type default)
		)
		(layer "In1.Cu")
	)
	(gr_arc
		(start 0.999998 0)
		(mid 0.292893 -0.292893)
		(end 0 -0.999998)
		(stroke
			(width 1.524)
			(type default)
		)
		(layer "In1.Cu")
	)
	(gr_line
		(start 0.999998 0)
		(end 101.000052 0)
		(stroke
			(width 1.524)
			(type default)
		)
		(layer "In1.Cu")
	)
	(gr_line
		(start 28.843986 -279.350216)
		(end 28.843986 -276.149816)
		(stroke
			(width 0.2)
			(type default)
		)
		(layer "In1.Cu")
	)
	(gr_rect
		(start 28.843986 -276.810216)
		(end 31.206186 -278.689816)
		(stroke
			(width 0)
			(type default)
		)
		(fill no)
		(layer "In1.Cu")
	)
	(gr_line
		(start 28.843986 -276.149816)
		(end 31.206186 -276.149816)
		(stroke
			(width 0.2)
			(type default)
		)
		(layer "In1.Cu")
	)
	(gr_line
		(start 28.843986 -275.540216)
		(end 28.843986 -272.339816)
		(stroke
			(width 0.2)
			(type default)
		)
		(layer "In1.Cu")
	)
	(gr_rect
		(start 28.843986 -273.000216)
		(end 31.206186 -274.879816)
		(stroke
			(width 0)
			(type default)
		)
		(fill no)
		(layer "In1.Cu")
	)
	(gr_line
		(start 28.843986 -272.339816)
		(end 31.206186 -272.340578)
		(stroke
			(width 0.2)
			(type default)
		)
		(layer "In1.Cu")
	)
	(gr_line
		(start 28.843986 -164.350192)
		(end 28.843986 -161.149792)
		(stroke
			(width 0.2)
			(type default)
		)
		(layer "In1.Cu")
	)
	(gr_rect
		(start 28.843986 -161.810192)
		(end 31.206186 -163.689792)
		(stroke
			(width 0)
			(type default)
		)
		(fill no)
		(layer "In1.Cu")
	)
	(gr_line
		(start 28.843986 -161.149792)
		(end 31.206186 -161.149792)
		(stroke
			(width 0.2)
			(type default)
		)
		(layer "In1.Cu")
	)
	(gr_line
		(start 28.843986 -160.540192)
		(end 28.843986 -157.339792)
		(stroke
			(width 0.2)
			(type default)
		)
		(layer "In1.Cu")
	)
	(gr_rect
		(start 28.843986 -158.000192)
		(end 31.206186 -159.879792)
		(stroke
			(width 0)
			(type default)
		)
		(fill no)
		(layer "In1.Cu")
	)
	(gr_line
		(start 28.843986 -157.339792)
		(end 31.206186 -157.340554)
		(stroke
			(width 0.2)
			(type default)
		)
		(layer "In1.Cu")
	)
	(gr_line
		(start 28.843986 -49.350168)
		(end 28.843986 -46.149768)
		(stroke
			(width 0.2)
			(type default)
		)
		(layer "In1.Cu")
	)
	(gr_line
		(start 28.843986 -46.149768)
		(end 31.206186 -46.149768)
		(stroke
			(width 0.2)
			(type default)
		)
		(layer "In1.Cu")
	)
	(gr_line
		(start 28.843986 -45.540168)
		(end 28.843986 -42.339768)
		(stroke
			(width 0.2)
			(type default)
		)
		(layer "In1.Cu")
	)
	(gr_line
		(start 28.843986 -42.339768)
		(end 31.206186 -42.34053)
		(stroke
			(width 0.2)
			(type default)
		)
		(layer "In1.Cu")
	)
	(gr_line
		(start 31.206186 -279.350216)
		(end 28.843986 -279.350216)
		(stroke
			(width 0.2)
			(type default)
		)
		(layer "In1.Cu")
	)
	(gr_line
		(start 31.206186 -276.149816)
		(end 31.206186 -279.350216)
		(stroke
			(width 0.2)
			(type default)
		)
		(layer "In1.Cu")
	)
	(gr_line
		(start 31.206186 -275.540216)
		(end 28.843986 -275.540216)
		(stroke
			(width 0.2)
			(type default)
		)
		(layer "In1.Cu")
	)
	(gr_line
		(start 31.206186 -272.340578)
		(end 31.206186 -275.540216)
		(stroke
			(width 0.2)
			(type default)
		)
		(layer "In1.Cu")
	)
	(gr_line
		(start 31.206186 -164.350192)
		(end 28.843986 -164.350192)
		(stroke
			(width 0.2)
			(type default)
		)
		(layer "In1.Cu")
	)
	(gr_line
		(start 31.206186 -161.149792)
		(end 31.206186 -164.350192)
		(stroke
			(width 0.2)
			(type default)
		)
		(layer "In1.Cu")
	)
	(gr_line
		(start 31.206186 -160.540192)
		(end 28.843986 -160.540192)
		(stroke
			(width 0.2)
			(type default)
		)
		(layer "In1.Cu")
	)
	(gr_line
		(start 31.206186 -157.340554)
		(end 31.206186 -160.540192)
		(stroke
			(width 0.2)
			(type default)
		)
		(layer "In1.Cu")
	)
	(gr_line
		(start 31.206186 -49.350168)
		(end 28.843986 -49.350168)
		(stroke
			(width 0.2)
			(type default)
		)
		(layer "In1.Cu")
	)
	(gr_line
		(start 31.206186 -46.149768)
		(end 31.206186 -49.350168)
		(stroke
			(width 0.2)
			(type default)
		)
		(layer "In1.Cu")
	)
	(gr_line
		(start 31.206186 -45.540168)
		(end 28.843986 -45.540168)
		(stroke
			(width 0.2)
			(type default)
		)
		(layer "In1.Cu")
	)
	(gr_line
		(start 31.206186 -42.34053)
		(end 31.206186 -45.540168)
		(stroke
			(width 0.2)
			(type default)
		)
		(layer "In1.Cu")
	)
	(gr_arc
		(start 32.006286 -274.321016)
		(mid 32.021165 -274.356937)
		(end 32.057086 -274.371816)
		(stroke
			(width 0.2)
			(type default)
		)
		(layer "In1.Cu")
	)
	(gr_line
		(start 32.006286 -274.117816)
		(end 32.006286 -274.321016)
		(stroke
			(width 0.2)
			(type default)
		)
		(layer "In1.Cu")
	)
	(gr_arc
		(start 32.006286 -273.762216)
		(mid 32.021165 -273.798137)
		(end 32.057086 -273.813016)
		(stroke
			(width 0.2)
			(type default)
		)
		(layer "In1.Cu")
	)
	(gr_line
		(start 32.006286 -273.559016)
		(end 32.006286 -273.762216)
		(stroke
			(width 0.2)
			(type default)
		)
		(layer "In1.Cu")
	)
	(gr_arc
		(start 32.006286 -159.320992)
		(mid 32.021165 -159.356913)
		(end 32.057086 -159.371792)
		(stroke
			(width 0.2)
			(type default)
		)
		(layer "In1.Cu")
	)
	(gr_line
		(start 32.006286 -159.117792)
		(end 32.006286 -159.320992)
		(stroke
			(width 0.2)
			(type default)
		)
		(layer "In1.Cu")
	)
	(gr_arc
		(start 32.006286 -158.762192)
		(mid 32.021165 -158.798113)
		(end 32.057086 -158.812992)
		(stroke
			(width 0.2)
			(type default)
		)
		(layer "In1.Cu")
	)
	(gr_line
		(start 32.006286 -158.558992)
		(end 32.006286 -158.762192)
		(stroke
			(width 0.2)
			(type default)
		)
		(layer "In1.Cu")
	)
	(gr_arc
		(start 32.006286 -44.320968)
		(mid 32.021165 -44.356889)
		(end 32.057086 -44.371768)
		(stroke
			(width 0.2)
			(type default)
		)
		(layer "In1.Cu")
	)
	(gr_line
		(start 32.006286 -44.117768)
		(end 32.006286 -44.320968)
		(stroke
			(width 0.2)
			(type default)
		)
		(layer "In1.Cu")
	)
	(gr_arc
		(start 32.006286 -43.762168)
		(mid 32.021165 -43.798089)
		(end 32.057086 -43.812968)
		(stroke
			(width 0.2)
			(type default)
		)
		(layer "In1.Cu")
	)
	(gr_line
		(start 32.006286 -43.558968)
		(end 32.006286 -43.762168)
		(stroke
			(width 0.2)
			(type default)
		)
		(layer "In1.Cu")
	)
	(gr_line
		(start 32.057086 -274.371816)
		(end 32.869886 -274.371816)
		(stroke
			(width 0.2)
			(type default)
		)
		(layer "In1.Cu")
	)
	(gr_arc
		(start 32.057086 -274.067016)
		(mid 32.021165 -274.081895)
		(end 32.006286 -274.117816)
		(stroke
			(width 0.2)
			(type default)
		)
		(layer "In1.Cu")
	)
	(gr_line
		(start 32.057086 -273.813016)
		(end 32.869886 -273.813016)
		(stroke
			(width 0.2)
			(type default)
		)
		(layer "In1.Cu")
	)
	(gr_arc
		(start 32.057086 -273.508216)
		(mid 32.021165 -273.523095)
		(end 32.006286 -273.559016)
		(stroke
			(width 0.2)
			(type default)
		)
		(layer "In1.Cu")
	)
	(gr_line
		(start 32.057086 -159.371792)
		(end 32.869886 -159.371792)
		(stroke
			(width 0.2)
			(type default)
		)
		(layer "In1.Cu")
	)
	(gr_arc
		(start 32.057086 -159.066992)
		(mid 32.021165 -159.081871)
		(end 32.006286 -159.117792)
		(stroke
			(width 0.2)
			(type default)
		)
		(layer "In1.Cu")
	)
	(gr_line
		(start 32.057086 -158.812992)
		(end 32.869886 -158.812992)
		(stroke
			(width 0.2)
			(type default)
		)
		(layer "In1.Cu")
	)
	(gr_arc
		(start 32.057086 -158.508192)
		(mid 32.021165 -158.523071)
		(end 32.006286 -158.558992)
		(stroke
			(width 0.2)
			(type default)
		)
		(layer "In1.Cu")
	)
	(gr_line
		(start 32.057086 -44.371768)
		(end 32.869886 -44.371768)
		(stroke
			(width 0.2)
			(type default)
		)
		(layer "In1.Cu")
	)
	(gr_arc
		(start 32.057086 -44.066968)
		(mid 32.021165 -44.081847)
		(end 32.006286 -44.117768)
		(stroke
			(width 0.2)
			(type default)
		)
		(layer "In1.Cu")
	)
	(gr_line
		(start 32.057086 -43.812968)
		(end 32.869886 -43.812968)
		(stroke
			(width 0.2)
			(type default)
		)
		(layer "In1.Cu")
	)
	(gr_arc
		(start 32.057086 -43.508168)
		(mid 32.021165 -43.523047)
		(end 32.006286 -43.558968)
		(stroke
			(width 0.2)
			(type default)
		)
		(layer "In1.Cu")
	)
	(gr_arc
		(start 32.127952 -278.321516)
		(mid 32.508952 -278.702516)
		(end 32.889952 -278.321516)
		(stroke
			(width 0.2)
			(type default)
		)
		(layer "In1.Cu")
	)
	(gr_line
		(start 32.127952 -277.178516)
		(end 32.127952 -278.321516)
		(stroke
			(width 0.2)
			(type default)
		)
		(layer "In1.Cu")
	)
	(gr_arc
		(start 32.127952 -163.321492)
		(mid 32.508952 -163.702492)
		(end 32.889952 -163.321492)
		(stroke
			(width 0.2)
			(type default)
		)
		(layer "In1.Cu")
	)
	(gr_line
		(start 32.127952 -162.178492)
		(end 32.127952 -163.321492)
		(stroke
			(width 0.2)
			(type default)
		)
		(layer "In1.Cu")
	)
	(gr_arc
		(start 32.127952 -48.321468)
		(mid 32.508952 -48.702468)
		(end 32.889952 -48.321468)
		(stroke
			(width 0.2)
			(type default)
		)
		(layer "In1.Cu")
	)
	(gr_line
		(start 32.127952 -47.178468)
		(end 32.127952 -48.321468)
		(stroke
			(width 0.2)
			(type default)
		)
		(layer "In1.Cu")
	)
	(gr_arc
		(start 32.869886 -274.371816)
		(mid 32.905807 -274.356937)
		(end 32.920686 -274.321016)
		(stroke
			(width 0.2)
			(type default)
		)
		(layer "In1.Cu")
	)
	(gr_line
		(start 32.869886 -274.067016)
		(end 32.057086 -274.067016)
		(stroke
			(width 0.2)
			(type default)
		)
		(layer "In1.Cu")
	)
	(gr_arc
		(start 32.869886 -273.813016)
		(mid 32.905807 -273.798137)
		(end 32.920686 -273.762216)
		(stroke
			(width 0.2)
			(type default)
		)
		(layer "In1.Cu")
	)
	(gr_line
		(start 32.869886 -273.508216)
		(end 32.057086 -273.508216)
		(stroke
			(width 0.2)
			(type default)
		)
		(layer "In1.Cu")
	)
	(gr_arc
		(start 32.869886 -159.371792)
		(mid 32.905807 -159.356913)
		(end 32.920686 -159.320992)
		(stroke
			(width 0.2)
			(type default)
		)
		(layer "In1.Cu")
	)
	(gr_line
		(start 32.869886 -159.066992)
		(end 32.057086 -159.066992)
		(stroke
			(width 0.2)
			(type default)
		)
		(layer "In1.Cu")
	)
	(gr_arc
		(start 32.869886 -158.812992)
		(mid 32.905807 -158.798113)
		(end 32.920686 -158.762192)
		(stroke
			(width 0.2)
			(type default)
		)
		(layer "In1.Cu")
	)
	(gr_line
		(start 32.869886 -158.508192)
		(end 32.057086 -158.508192)
		(stroke
			(width 0.2)
			(type default)
		)
		(layer "In1.Cu")
	)
	(gr_arc
		(start 32.869886 -44.371768)
		(mid 32.905807 -44.356889)
		(end 32.920686 -44.320968)
		(stroke
			(width 0.2)
			(type default)
		)
		(layer "In1.Cu")
	)
	(gr_line
		(start 32.869886 -44.066968)
		(end 32.057086 -44.066968)
		(stroke
			(width 0.2)
			(type default)
		)
		(layer "In1.Cu")
	)
	(gr_arc
		(start 32.869886 -43.812968)
		(mid 32.905807 -43.798089)
		(end 32.920686 -43.762168)
		(stroke
			(width 0.2)
			(type default)
		)
		(layer "In1.Cu")
	)
	(gr_line
		(start 32.869886 -43.508168)
		(end 32.057086 -43.508168)
		(stroke
			(width 0.2)
			(type default)
		)
		(layer "In1.Cu")
	)
	(gr_line
		(start 32.889952 -278.321516)
		(end 32.889952 -277.17877)
		(stroke
			(width 0.2)
			(type default)
		)
		(layer "In1.Cu")
	)
	(gr_arc
		(start 32.889952 -277.17877)
		(mid 32.509079 -276.797516)
		(end 32.127952 -277.178516)
		(stroke
			(width 0.2)
			(type default)
		)
		(layer "In1.Cu")
	)
	(gr_line
		(start 32.889952 -163.321492)
		(end 32.889952 -162.178746)
		(stroke
			(width 0.2)
			(type default)
		)
		(layer "In1.Cu")
	)
	(gr_arc
		(start 32.889952 -162.178746)
		(mid 32.509079 -161.797492)
		(end 32.127952 -162.178492)
		(stroke
			(width 0.2)
			(type default)
		)
		(layer "In1.Cu")
	)
	(gr_line
		(start 32.889952 -48.321468)
		(end 32.889952 -47.178722)
		(stroke
			(width 0.2)
			(type default)
		)
		(layer "In1.Cu")
	)
	(gr_arc
		(start 32.889952 -47.178722)
		(mid 32.509079 -46.797468)
		(end 32.127952 -47.178468)
		(stroke
			(width 0.2)
			(type default)
		)
		(layer "In1.Cu")
	)
	(gr_line
		(start 32.920686 -274.321016)
		(end 32.920686 -274.117816)
		(stroke
			(width 0.2)
			(type default)
		)
		(layer "In1.Cu")
	)
	(gr_arc
		(start 32.920686 -274.117816)
		(mid 32.905807 -274.081895)
		(end 32.869886 -274.067016)
		(stroke
			(width 0.2)
			(type default)
		)
		(layer "In1.Cu")
	)
	(gr_line
		(start 32.920686 -273.762216)
		(end 32.920686 -273.559016)
		(stroke
			(width 0.2)
			(type default)
		)
		(layer "In1.Cu")
	)
	(gr_arc
		(start 32.920686 -273.559016)
		(mid 32.905807 -273.523095)
		(end 32.869886 -273.508216)
		(stroke
			(width 0.2)
			(type default)
		)
		(layer "In1.Cu")
	)
	(gr_line
		(start 32.920686 -159.320992)
		(end 32.920686 -159.117792)
		(stroke
			(width 0.2)
			(type default)
		)
		(layer "In1.Cu")
	)
	(gr_arc
		(start 32.920686 -159.117792)
		(mid 32.905807 -159.081871)
		(end 32.869886 -159.066992)
		(stroke
			(width 0.2)
			(type default)
		)
		(layer "In1.Cu")
	)
	(gr_line
		(start 32.920686 -158.762192)
		(end 32.920686 -158.558992)
		(stroke
			(width 0.2)
			(type default)
		)
		(layer "In1.Cu")
	)
	(gr_arc
		(start 32.920686 -158.558992)
		(mid 32.905807 -158.523071)
		(end 32.869886 -158.508192)
		(stroke
			(width 0.2)
			(type default)
		)
		(layer "In1.Cu")
	)
	(gr_line
		(start 32.920686 -44.320968)
		(end 32.920686 -44.117768)
		(stroke
			(width 0.2)
			(type default)
		)
		(layer "In1.Cu")
	)
	(gr_arc
		(start 32.920686 -44.117768)
		(mid 32.905807 -44.081847)
		(end 32.869886 -44.066968)
		(stroke
			(width 0.2)
			(type default)
		)
		(layer "In1.Cu")
	)
	(gr_line
		(start 32.920686 -43.762168)
		(end 32.920686 -43.558968)
		(stroke
			(width 0.2)
			(type default)
		)
		(layer "In1.Cu")
	)
	(gr_arc
		(start 32.920686 -43.558968)
		(mid 32.905807 -43.523047)
		(end 32.869886 -43.508168)
		(stroke
			(width 0.2)
			(type default)
		)
		(layer "In1.Cu")
	)
	(gr_line
		(start 60.393834 -279.350216)
		(end 60.393834 -276.149816)
		(stroke
			(width 0.2)
			(type default)
		)
		(layer "In1.Cu")
	)
	(gr_rect
		(start 60.393834 -276.810216)
		(end 62.756034 -278.689816)
		(stroke
			(width 0)
			(type default)
		)
		(fill no)
		(layer "In1.Cu")
	)
	(gr_line
		(start 60.393834 -276.149816)
		(end 62.756034 -276.149816)
		(stroke
			(width 0.2)
			(type default)
		)
		(layer "In1.Cu")
	)
	(gr_line
		(start 60.393834 -275.540216)
		(end 60.393834 -272.339816)
		(stroke
			(width 0.2)
			(type default)
		)
		(layer "In1.Cu")
	)
	(gr_rect
		(start 60.393834 -273.000216)
		(end 62.756034 -274.879816)
		(stroke
			(width 0)
			(type default)
		)
		(fill no)
		(layer "In1.Cu")
	)
	(gr_line
		(start 60.393834 -272.339816)
		(end 62.756034 -272.340578)
		(stroke
			(width 0.2)
			(type default)
		)
		(layer "In1.Cu")
	)
	(gr_line
		(start 60.393834 -164.350192)
		(end 60.393834 -161.149792)
		(stroke
			(width 0.2)
			(type default)
		)
		(layer "In1.Cu")
	)
	(gr_rect
		(start 60.393834 -161.810192)
		(end 62.756034 -163.689792)
		(stroke
			(width 0)
			(type default)
		)
		(fill no)
		(layer "In1.Cu")
	)
	(gr_line
		(start 60.393834 -161.149792)
		(end 62.756034 -161.149792)
		(stroke
			(width 0.2)
			(type default)
		)
		(layer "In1.Cu")
	)
	(gr_line
		(start 60.393834 -160.540192)
		(end 60.393834 -157.339792)
		(stroke
			(width 0.2)
			(type default)
		)
		(layer "In1.Cu")
	)
	(gr_rect
		(start 60.393834 -158.000192)
		(end 62.756034 -159.879792)
		(stroke
			(width 0)
			(type default)
		)
		(fill no)
		(layer "In1.Cu")
	)
	(gr_line
		(start 60.393834 -157.339792)
		(end 62.756034 -157.340554)
		(stroke
			(width 0.2)
			(type default)
		)
		(layer "In1.Cu")
	)
	(gr_line
		(start 60.393834 -49.350168)
		(end 60.393834 -46.149768)
		(stroke
			(width 0.2)
			(type default)
		)
		(layer "In1.Cu")
	)
	(gr_rect
		(start 60.393834 -46.810168)
		(end 62.756034 -48.689768)
		(stroke
			(width 0)
			(type default)
		)
		(fill no)
		(layer "In1.Cu")
	)
	(gr_line
		(start 60.393834 -46.149768)
		(end 62.756034 -46.149768)
		(stroke
			(width 0.2)
			(type default)
		)
		(layer "In1.Cu")
	)
	(gr_line
		(start 60.393834 -45.540168)
		(end 60.393834 -42.339768)
		(stroke
			(width 0.2)
			(type default)
		)
		(layer "In1.Cu")
	)
	(gr_rect
		(start 60.393834 -43.000168)
		(end 62.756034 -44.879768)
		(stroke
			(width 0)
			(type default)
		)
		(fill no)
		(layer "In1.Cu")
	)
	(gr_line
		(start 60.393834 -42.339768)
		(end 62.756034 -42.34053)
		(stroke
			(width 0.2)
			(type default)
		)
		(layer "In1.Cu")
	)
	(gr_line
		(start 62.756034 -279.350216)
		(end 60.393834 -279.350216)
		(stroke
			(width 0.2)
			(type default)
		)
		(layer "In1.Cu")
	)
	(gr_line
		(start 62.756034 -276.149816)
		(end 62.756034 -279.350216)
		(stroke
			(width 0.2)
			(type default)
		)
		(layer "In1.Cu")
	)
	(gr_line
		(start 62.756034 -275.540216)
		(end 60.393834 -275.540216)
		(stroke
			(width 0.2)
			(type default)
		)
		(layer "In1.Cu")
	)
	(gr_line
		(start 62.756034 -272.340578)
		(end 62.756034 -275.540216)
		(stroke
			(width 0.2)
			(type default)
		)
		(layer "In1.Cu")
	)
	(gr_line
		(start 62.756034 -164.350192)
		(end 60.393834 -164.350192)
		(stroke
			(width 0.2)
			(type default)
		)
		(layer "In1.Cu")
	)
	(gr_line
		(start 62.756034 -161.149792)
		(end 62.756034 -164.350192)
		(stroke
			(width 0.2)
			(type default)
		)
		(layer "In1.Cu")
	)
	(gr_line
		(start 62.756034 -160.540192)
		(end 60.393834 -160.540192)
		(stroke
			(width 0.2)
			(type default)
		)
		(layer "In1.Cu")
	)
	(gr_line
		(start 62.756034 -157.340554)
		(end 62.756034 -160.540192)
		(stroke
			(width 0.2)
			(type default)
		)
		(layer "In1.Cu")
	)
	(gr_line
		(start 62.756034 -49.350168)
		(end 60.393834 -49.350168)
		(stroke
			(width 0.2)
			(type default)
		)
		(layer "In1.Cu")
	)
	(gr_line
		(start 62.756034 -46.149768)
		(end 62.756034 -49.350168)
		(stroke
			(width 0.2)
			(type default)
		)
		(layer "In1.Cu")
	)
	(gr_line
		(start 62.756034 -45.540168)
		(end 60.393834 -45.540168)
		(stroke
			(width 0.2)
			(type default)
		)
		(layer "In1.Cu")
	)
	(gr_line
		(start 62.756034 -42.34053)
		(end 62.756034 -45.540168)
		(stroke
			(width 0.2)
			(type default)
		)
		(layer "In1.Cu")
	)
	(gr_arc
		(start 63.556134 -274.321016)
		(mid 63.571013 -274.356937)
		(end 63.606934 -274.371816)
		(stroke
			(width 0.2)
			(type default)
		)
		(layer "In1.Cu")
	)
	(gr_line
		(start 63.556134 -274.117816)
		(end 63.556134 -274.321016)
		(stroke
			(width 0.2)
			(type default)
		)
		(layer "In1.Cu")
	)
	(gr_arc
		(start 63.556134 -273.762216)
		(mid 63.571013 -273.798137)
		(end 63.606934 -273.813016)
		(stroke
			(width 0.2)
			(type default)
		)
		(layer "In1.Cu")
	)
	(gr_line
		(start 63.556134 -273.559016)
		(end 63.556134 -273.762216)
		(stroke
			(width 0.2)
			(type default)
		)
		(layer "In1.Cu")
	)
	(gr_arc
		(start 63.556134 -159.320992)
		(mid 63.571013 -159.356913)
		(end 63.606934 -159.371792)
		(stroke
			(width 0.2)
			(type default)
		)
		(layer "In1.Cu")
	)
	(gr_line
		(start 63.556134 -159.117792)
		(end 63.556134 -159.320992)
		(stroke
			(width 0.2)
			(type default)
		)
		(layer "In1.Cu")
	)
	(gr_arc
		(start 63.556134 -158.762192)
		(mid 63.571013 -158.798113)
		(end 63.606934 -158.812992)
		(stroke
			(width 0.2)
			(type default)
		)
		(layer "In1.Cu")
	)
	(gr_line
		(start 63.556134 -158.558992)
		(end 63.556134 -158.762192)
		(stroke
			(width 0.2)
			(type default)
		)
		(layer "In1.Cu")
	)
	(gr_arc
		(start 63.556134 -44.320968)
		(mid 63.571013 -44.356889)
		(end 63.606934 -44.371768)
		(stroke
			(width 0.2)
			(type default)
		)
		(layer "In1.Cu")
	)
	(gr_line
		(start 63.556134 -44.117768)
		(end 63.556134 -44.320968)
		(stroke
			(width 0.2)
			(type default)
		)
		(layer "In1.Cu")
	)
	(gr_arc
		(start 63.556134 -43.762168)
		(mid 63.571013 -43.798089)
		(end 63.606934 -43.812968)
		(stroke
			(width 0.2)
			(type default)
		)
		(layer "In1.Cu")
	)
	(gr_line
		(start 63.556134 -43.558968)
		(end 63.556134 -43.762168)
		(stroke
			(width 0.2)
			(type default)
		)
		(layer "In1.Cu")
	)
	(gr_line
		(start 63.606934 -274.371816)
		(end 64.419734 -274.371816)
		(stroke
			(width 0.2)
			(type default)
		)
		(layer "In1.Cu")
	)
	(gr_arc
		(start 63.606934 -274.067016)
		(mid 63.571013 -274.081895)
		(end 63.556134 -274.117816)
		(stroke
			(width 0.2)
			(type default)
		)
		(layer "In1.Cu")
	)
	(gr_line
		(start 63.606934 -273.813016)
		(end 64.419734 -273.813016)
		(stroke
			(width 0.2)
			(type default)
		)
		(layer "In1.Cu")
	)
	(gr_arc
		(start 63.606934 -273.508216)
		(mid 63.571013 -273.523095)
		(end 63.556134 -273.559016)
		(stroke
			(width 0.2)
			(type default)
		)
		(layer "In1.Cu")
	)
	(gr_line
		(start 63.606934 -159.371792)
		(end 64.419734 -159.371792)
		(stroke
			(width 0.2)
			(type default)
		)
		(layer "In1.Cu")
	)
	(gr_arc
		(start 63.606934 -159.066992)
		(mid 63.571013 -159.081871)
		(end 63.556134 -159.117792)
		(stroke
			(width 0.2)
			(type default)
		)
		(layer "In1.Cu")
	)
	(gr_line
		(start 63.606934 -158.812992)
		(end 64.419734 -158.812992)
		(stroke
			(width 0.2)
			(type default)
		)
		(layer "In1.Cu")
	)
	(gr_arc
		(start 63.606934 -158.508192)
		(mid 63.571013 -158.523071)
		(end 63.556134 -158.558992)
		(stroke
			(width 0.2)
			(type default)
		)
		(layer "In1.Cu")
	)
	(gr_line
		(start 63.606934 -44.371768)
		(end 64.419734 -44.371768)
		(stroke
			(width 0.2)
			(type default)
		)
		(layer "In1.Cu")
	)
	(gr_arc
		(start 63.606934 -44.066968)
		(mid 63.571013 -44.081847)
		(end 63.556134 -44.117768)
		(stroke
			(width 0.2)
			(type default)
		)
		(layer "In1.Cu")
	)
	(gr_line
		(start 63.606934 -43.812968)
		(end 64.419734 -43.812968)
		(stroke
			(width 0.2)
			(type default)
		)
		(layer "In1.Cu")
	)
	(gr_arc
		(start 63.606934 -43.508168)
		(mid 63.571013 -43.523047)
		(end 63.556134 -43.558968)
		(stroke
			(width 0.2)
			(type default)
		)
		(layer "In1.Cu")
	)
	(gr_arc
		(start 63.6778 -278.321516)
		(mid 64.0588 -278.702516)
		(end 64.4398 -278.321516)
		(stroke
			(width 0.2)
			(type default)
		)
		(layer "In1.Cu")
	)
	(gr_line
		(start 63.6778 -277.178516)
		(end 63.6778 -278.321516)
		(stroke
			(width 0.2)
			(type default)
		)
		(layer "In1.Cu")
	)
	(gr_arc
		(start 63.6778 -163.321492)
		(mid 64.0588 -163.702492)
		(end 64.4398 -163.321492)
		(stroke
			(width 0.2)
			(type default)
		)
		(layer "In1.Cu")
	)
	(gr_line
		(start 63.6778 -162.178492)
		(end 63.6778 -163.321492)
		(stroke
			(width 0.2)
			(type default)
		)
		(layer "In1.Cu")
	)
	(gr_arc
		(start 63.6778 -48.321468)
		(mid 64.0588 -48.702468)
		(end 64.4398 -48.321468)
		(stroke
			(width 0.2)
			(type default)
		)
		(layer "In1.Cu")
	)
	(gr_line
		(start 63.6778 -47.178468)
		(end 63.6778 -48.321468)
		(stroke
			(width 0.2)
			(type default)
		)
		(layer "In1.Cu")
	)
	(gr_arc
		(start 64.419734 -274.371816)
		(mid 64.455655 -274.356937)
		(end 64.470534 -274.321016)
		(stroke
			(width 0.2)
			(type default)
		)
		(layer "In1.Cu")
	)
	(gr_line
		(start 64.419734 -274.067016)
		(end 63.606934 -274.067016)
		(stroke
			(width 0.2)
			(type default)
		)
		(layer "In1.Cu")
	)
	(gr_arc
		(start 64.419734 -273.813016)
		(mid 64.455655 -273.798137)
		(end 64.470534 -273.762216)
		(stroke
			(width 0.2)
			(type default)
		)
		(layer "In1.Cu")
	)
	(gr_line
		(start 64.419734 -273.508216)
		(end 63.606934 -273.508216)
		(stroke
			(width 0.2)
			(type default)
		)
		(layer "In1.Cu")
	)
	(gr_arc
		(start 64.419734 -159.371792)
		(mid 64.455655 -159.356913)
		(end 64.470534 -159.320992)
		(stroke
			(width 0.2)
			(type default)
		)
		(layer "In1.Cu")
	)
	(gr_line
		(start 64.419734 -159.066992)
		(end 63.606934 -159.066992)
		(stroke
			(width 0.2)
			(type default)
		)
		(layer "In1.Cu")
	)
	(gr_arc
		(start 64.419734 -158.812992)
		(mid 64.455655 -158.798113)
		(end 64.470534 -158.762192)
		(stroke
			(width 0.2)
			(type default)
		)
		(layer "In1.Cu")
	)
	(gr_line
		(start 64.419734 -158.508192)
		(end 63.606934 -158.508192)
		(stroke
			(width 0.2)
			(type default)
		)
		(layer "In1.Cu")
	)
	(gr_arc
		(start 64.419734 -44.371768)
		(mid 64.455655 -44.356889)
		(end 64.470534 -44.320968)
		(stroke
			(width 0.2)
			(type default)
		)
		(layer "In1.Cu")
	)
	(gr_line
		(start 64.419734 -44.066968)
		(end 63.606934 -44.066968)
		(stroke
			(width 0.2)
			(type default)
		)
		(layer "In1.Cu")
	)
	(gr_arc
		(start 64.419734 -43.812968)
		(mid 64.455655 -43.798089)
		(end 64.470534 -43.762168)
		(stroke
			(width 0.2)
			(type default)
		)
		(layer "In1.Cu")
	)
	(gr_line
		(start 64.419734 -43.508168)
		(end 63.606934 -43.508168)
		(stroke
			(width 0.2)
			(type default)
		)
		(layer "In1.Cu")
	)
	(gr_line
		(start 64.4398 -278.321516)
		(end 64.4398 -277.17877)
		(stroke
			(width 0.2)
			(type default)
		)
		(layer "In1.Cu")
	)
	(gr_arc
		(start 64.4398 -277.17877)
		(mid 64.058927 -276.797516)
		(end 63.6778 -277.178516)
		(stroke
			(width 0.2)
			(type default)
		)
		(layer "In1.Cu")
	)
	(gr_line
		(start 64.4398 -163.321492)
		(end 64.4398 -162.178746)
		(stroke
			(width 0.2)
			(type default)
		)
		(layer "In1.Cu")
	)
	(gr_arc
		(start 64.4398 -162.178746)
		(mid 64.058927 -161.797492)
		(end 63.6778 -162.178492)
		(stroke
			(width 0.2)
			(type default)
		)
		(layer "In1.Cu")
	)
	(gr_line
		(start 64.4398 -48.321468)
		(end 64.4398 -47.178722)
		(stroke
			(width 0.2)
			(type default)
		)
		(layer "In1.Cu")
	)
	(gr_arc
		(start 64.4398 -47.178722)
		(mid 64.058927 -46.797468)
		(end 63.6778 -47.178468)
		(stroke
			(width 0.2)
			(type default)
		)
		(layer "In1.Cu")
	)
	(gr_line
		(start 64.470534 -274.321016)
		(end 64.470534 -274.117816)
		(stroke
			(width 0.2)
			(type default)
		)
		(layer "In1.Cu")
	)
	(gr_arc
		(start 64.470534 -274.117816)
		(mid 64.455655 -274.081895)
		(end 64.419734 -274.067016)
		(stroke
			(width 0.2)
			(type default)
		)
		(layer "In1.Cu")
	)
	(gr_line
		(start 64.470534 -273.762216)
		(end 64.470534 -273.559016)
		(stroke
			(width 0.2)
			(type default)
		)
		(layer "In1.Cu")
	)
	(gr_arc
		(start 64.470534 -273.559016)
		(mid 64.455655 -273.523095)
		(end 64.419734 -273.508216)
		(stroke
			(width 0.2)
			(type default)
		)
		(layer "In1.Cu")
	)
	(gr_line
		(start 64.470534 -159.320992)
		(end 64.470534 -159.117792)
		(stroke
			(width 0.2)
			(type default)
		)
		(layer "In1.Cu")
	)
	(gr_arc
		(start 64.470534 -159.117792)
		(mid 64.455655 -159.081871)
		(end 64.419734 -159.066992)
		(stroke
			(width 0.2)
			(type default)
		)
		(layer "In1.Cu")
	)
	(gr_line
		(start 64.470534 -158.762192)
		(end 64.470534 -158.558992)
		(stroke
			(width 0.2)
			(type default)
		)
		(layer "In1.Cu")
	)
	(gr_arc
		(start 64.470534 -158.558992)
		(mid 64.455655 -158.523071)
		(end 64.419734 -158.508192)
		(stroke
			(width 0.2)
			(type default)
		)
		(layer "In1.Cu")
	)
	(gr_line
		(start 64.470534 -44.320968)
		(end 64.470534 -44.117768)
		(stroke
			(width 0.2)
			(type default)
		)
		(layer "In1.Cu")
	)
	(gr_arc
		(start 64.470534 -44.117768)
		(mid 64.455655 -44.081847)
		(end 64.419734 -44.066968)
		(stroke
			(width 0.2)
			(type default)
		)
		(layer "In1.Cu")
	)
	(gr_line
		(start 64.470534 -43.762168)
		(end 64.470534 -43.558968)
		(stroke
			(width 0.2)
			(type default)
		)
		(layer "In1.Cu")
	)
	(gr_arc
		(start 64.470534 -43.558968)
		(mid 64.455655 -43.523047)
		(end 64.419734 -43.508168)
		(stroke
			(width 0.2)
			(type default)
		)
		(layer "In1.Cu")
	)
	(gr_line
		(start 91.943936 -279.350216)
		(end 91.943936 -276.149816)
		(stroke
			(width 0.2)
			(type default)
		)
		(layer "In1.Cu")
	)
	(gr_rect
		(start 91.943936 -276.810216)
		(end 94.306136 -278.689816)
		(stroke
			(width 0)
			(type default)
		)
		(fill no)
		(layer "In1.Cu")
	)
	(gr_line
		(start 91.943936 -276.149816)
		(end 94.306136 -276.149816)
		(stroke
			(width 0.2)
			(type default)
		)
		(layer "In1.Cu")
	)
	(gr_line
		(start 91.943936 -275.540216)
		(end 91.943936 -272.339816)
		(stroke
			(width 0.2)
			(type default)
		)
		(layer "In1.Cu")
	)
	(gr_rect
		(start 91.943936 -273.000216)
		(end 94.306136 -274.879816)
		(stroke
			(width 0)
			(type default)
		)
		(fill no)
		(layer "In1.Cu")
	)
	(gr_line
		(start 91.943936 -272.339816)
		(end 94.306136 -272.340578)
		(stroke
			(width 0.2)
			(type default)
		)
		(layer "In1.Cu")
	)
	(gr_line
		(start 91.943936 -164.350192)
		(end 91.943936 -161.149792)
		(stroke
			(width 0.2)
			(type default)
		)
		(layer "In1.Cu")
	)
	(gr_rect
		(start 91.943936 -161.810192)
		(end 94.306136 -163.689792)
		(stroke
			(width 0)
			(type default)
		)
		(fill no)
		(layer "In1.Cu")
	)
	(gr_line
		(start 91.943936 -161.149792)
		(end 94.306136 -161.149792)
		(stroke
			(width 0.2)
			(type default)
		)
		(layer "In1.Cu")
	)
	(gr_line
		(start 91.943936 -160.540192)
		(end 91.943936 -157.339792)
		(stroke
			(width 0.2)
			(type default)
		)
		(layer "In1.Cu")
	)
	(gr_rect
		(start 91.943936 -158.000192)
		(end 94.306136 -159.879792)
		(stroke
			(width 0)
			(type default)
		)
		(fill no)
		(layer "In1.Cu")
	)
	(gr_line
		(start 91.943936 -157.339792)
		(end 94.306136 -157.340554)
		(stroke
			(width 0.2)
			(type default)
		)
		(layer "In1.Cu")
	)
	(gr_line
		(start 91.943936 -49.350168)
		(end 91.943936 -46.149768)
		(stroke
			(width 0.2)
			(type default)
		)
		(layer "In1.Cu")
	)
	(gr_rect
		(start 91.943936 -46.810168)
		(end 94.306136 -48.689768)
		(stroke
			(width 0)
			(type default)
		)
		(fill no)
		(layer "In1.Cu")
	)
	(gr_line
		(start 91.943936 -46.149768)
		(end 94.306136 -46.149768)
		(stroke
			(width 0.2)
			(type default)
		)
		(layer "In1.Cu")
	)
	(gr_line
		(start 91.943936 -45.540168)
		(end 91.943936 -42.339768)
		(stroke
			(width 0.2)
			(type default)
		)
		(layer "In1.Cu")
	)
	(gr_rect
		(start 91.943936 -43.000168)
		(end 94.306136 -44.879768)
		(stroke
			(width 0)
			(type default)
		)
		(fill no)
		(layer "In1.Cu")
	)
	(gr_line
		(start 91.943936 -42.339768)
		(end 94.306136 -42.34053)
		(stroke
			(width 0.2)
			(type default)
		)
		(layer "In1.Cu")
	)
	(gr_line
		(start 94.306136 -279.350216)
		(end 91.943936 -279.350216)
		(stroke
			(width 0.2)
			(type default)
		)
		(layer "In1.Cu")
	)
	(gr_line
		(start 94.306136 -276.149816)
		(end 94.306136 -279.350216)
		(stroke
			(width 0.2)
			(type default)
		)
		(layer "In1.Cu")
	)
	(gr_line
		(start 94.306136 -275.540216)
		(end 91.943936 -275.540216)
		(stroke
			(width 0.2)
			(type default)
		)
		(layer "In1.Cu")
	)
	(gr_line
		(start 94.306136 -272.340578)
		(end 94.306136 -275.540216)
		(stroke
			(width 0.2)
			(type default)
		)
		(layer "In1.Cu")
	)
	(gr_line
		(start 94.306136 -164.350192)
		(end 91.943936 -164.350192)
		(stroke
			(width 0.2)
			(type default)
		)
		(layer "In1.Cu")
	)
	(gr_line
		(start 94.306136 -161.149792)
		(end 94.306136 -164.350192)
		(stroke
			(width 0.2)
			(type default)
		)
		(layer "In1.Cu")
	)
	(gr_line
		(start 94.306136 -160.540192)
		(end 91.943936 -160.540192)
		(stroke
			(width 0.2)
			(type default)
		)
		(layer "In1.Cu")
	)
	(gr_line
		(start 94.306136 -157.340554)
		(end 94.306136 -160.540192)
		(stroke
			(width 0.2)
			(type default)
		)
		(layer "In1.Cu")
	)
	(gr_line
		(start 94.306136 -49.350168)
		(end 91.943936 -49.350168)
		(stroke
			(width 0.2)
			(type default)
		)
		(layer "In1.Cu")
	)
	(gr_line
		(start 94.306136 -46.149768)
		(end 94.306136 -49.350168)
		(stroke
			(width 0.2)
			(type default)
		)
		(layer "In1.Cu")
	)
	(gr_line
		(start 94.306136 -45.540168)
		(end 91.943936 -45.540168)
		(stroke
			(width 0.2)
			(type default)
		)
		(layer "In1.Cu")
	)
	(gr_line
		(start 94.306136 -42.34053)
		(end 94.306136 -45.540168)
		(stroke
			(width 0.2)
			(type default)
		)
		(layer "In1.Cu")
	)
	(gr_arc
		(start 95.106236 -274.321016)
		(mid 95.121115 -274.356937)
		(end 95.157036 -274.371816)
		(stroke
			(width 0.2)
			(type default)
		)
		(layer "In1.Cu")
	)
	(gr_line
		(start 95.106236 -274.117816)
		(end 95.106236 -274.321016)
		(stroke
			(width 0.2)
			(type default)
		)
		(layer "In1.Cu")
	)
	(gr_arc
		(start 95.106236 -273.762216)
		(mid 95.121115 -273.798137)
		(end 95.157036 -273.813016)
		(stroke
			(width 0.2)
			(type default)
		)
		(layer "In1.Cu")
	)
	(gr_line
		(start 95.106236 -273.559016)
		(end 95.106236 -273.762216)
		(stroke
			(width 0.2)
			(type default)
		)
		(layer "In1.Cu")
	)
	(gr_arc
		(start 95.106236 -159.320992)
		(mid 95.121115 -159.356913)
		(end 95.157036 -159.371792)
		(stroke
			(width 0.2)
			(type default)
		)
		(layer "In1.Cu")
	)
	(gr_line
		(start 95.106236 -159.117792)
		(end 95.106236 -159.320992)
		(stroke
			(width 0.2)
			(type default)
		)
		(layer "In1.Cu")
	)
	(gr_arc
		(start 95.106236 -158.762192)
		(mid 95.121115 -158.798113)
		(end 95.157036 -158.812992)
		(stroke
			(width 0.2)
			(type default)
		)
		(layer "In1.Cu")
	)
	(gr_line
		(start 95.106236 -158.558992)
		(end 95.106236 -158.762192)
		(stroke
			(width 0.2)
			(type default)
		)
		(layer "In1.Cu")
	)
	(gr_arc
		(start 95.106236 -44.320968)
		(mid 95.121115 -44.356889)
		(end 95.157036 -44.371768)
		(stroke
			(width 0.2)
			(type default)
		)
		(layer "In1.Cu")
	)
	(gr_line
		(start 95.106236 -44.117768)
		(end 95.106236 -44.320968)
		(stroke
			(width 0.2)
			(type default)
		)
		(layer "In1.Cu")
	)
	(gr_arc
		(start 95.106236 -43.762168)
		(mid 95.121115 -43.798089)
		(end 95.157036 -43.812968)
		(stroke
			(width 0.2)
			(type default)
		)
		(layer "In1.Cu")
	)
	(gr_line
		(start 95.106236 -43.558968)
		(end 95.106236 -43.762168)
		(stroke
			(width 0.2)
			(type default)
		)
		(layer "In1.Cu")
	)
	(gr_line
		(start 95.157036 -274.371816)
		(end 95.969836 -274.371816)
		(stroke
			(width 0.2)
			(type default)
		)
		(layer "In1.Cu")
	)
	(gr_arc
		(start 95.157036 -274.067016)
		(mid 95.121115 -274.081895)
		(end 95.106236 -274.117816)
		(stroke
			(width 0.2)
			(type default)
		)
		(layer "In1.Cu")
	)
	(gr_line
		(start 95.157036 -273.813016)
		(end 95.969836 -273.813016)
		(stroke
			(width 0.2)
			(type default)
		)
		(layer "In1.Cu")
	)
	(gr_arc
		(start 95.157036 -273.508216)
		(mid 95.121115 -273.523095)
		(end 95.106236 -273.559016)
		(stroke
			(width 0.2)
			(type default)
		)
		(layer "In1.Cu")
	)
	(gr_line
		(start 95.157036 -159.371792)
		(end 95.969836 -159.371792)
		(stroke
			(width 0.2)
			(type default)
		)
		(layer "In1.Cu")
	)
	(gr_arc
		(start 95.157036 -159.066992)
		(mid 95.121115 -159.081871)
		(end 95.106236 -159.117792)
		(stroke
			(width 0.2)
			(type default)
		)
		(layer "In1.Cu")
	)
	(gr_line
		(start 95.157036 -158.812992)
		(end 95.969836 -158.812992)
		(stroke
			(width 0.2)
			(type default)
		)
		(layer "In1.Cu")
	)
	(gr_arc
		(start 95.157036 -158.508192)
		(mid 95.121115 -158.523071)
		(end 95.106236 -158.558992)
		(stroke
			(width 0.2)
			(type default)
		)
		(layer "In1.Cu")
	)
	(gr_line
		(start 95.157036 -44.371768)
		(end 95.969836 -44.371768)
		(stroke
			(width 0.2)
			(type default)
		)
		(layer "In1.Cu")
	)
	(gr_arc
		(start 95.157036 -44.066968)
		(mid 95.121115 -44.081847)
		(end 95.106236 -44.117768)
		(stroke
			(width 0.2)
			(type default)
		)
		(layer "In1.Cu")
	)
	(gr_line
		(start 95.157036 -43.812968)
		(end 95.969836 -43.812968)
		(stroke
			(width 0.2)
			(type default)
		)
		(layer "In1.Cu")
	)
	(gr_arc
		(start 95.157036 -43.508168)
		(mid 95.121115 -43.523047)
		(end 95.106236 -43.558968)
		(stroke
			(width 0.2)
			(type default)
		)
		(layer "In1.Cu")
	)
	(gr_arc
		(start 95.227902 -278.321516)
		(mid 95.608902 -278.702516)
		(end 95.989902 -278.321516)
		(stroke
			(width 0.2)
			(type default)
		)
		(layer "In1.Cu")
	)
	(gr_line
		(start 95.227902 -277.178516)
		(end 95.227902 -278.321516)
		(stroke
			(width 0.2)
			(type default)
		)
		(layer "In1.Cu")
	)
	(gr_arc
		(start 95.227902 -163.321492)
		(mid 95.608902 -163.702492)
		(end 95.989902 -163.321492)
		(stroke
			(width 0.2)
			(type default)
		)
		(layer "In1.Cu")
	)
	(gr_line
		(start 95.227902 -162.178492)
		(end 95.227902 -163.321492)
		(stroke
			(width 0.2)
			(type default)
		)
		(layer "In1.Cu")
	)
	(gr_arc
		(start 95.227902 -48.321468)
		(mid 95.608902 -48.702468)
		(end 95.989902 -48.321468)
		(stroke
			(width 0.2)
			(type default)
		)
		(layer "In1.Cu")
	)
	(gr_line
		(start 95.227902 -47.178468)
		(end 95.227902 -48.321468)
		(stroke
			(width 0.2)
			(type default)
		)
		(layer "In1.Cu")
	)
	(gr_arc
		(start 95.969836 -274.371816)
		(mid 96.005757 -274.356937)
		(end 96.020636 -274.321016)
		(stroke
			(width 0.2)
			(type default)
		)
		(layer "In1.Cu")
	)
	(gr_line
		(start 95.969836 -274.067016)
		(end 95.157036 -274.067016)
		(stroke
			(width 0.2)
			(type default)
		)
		(layer "In1.Cu")
	)
	(gr_arc
		(start 95.969836 -273.813016)
		(mid 96.005757 -273.798137)
		(end 96.020636 -273.762216)
		(stroke
			(width 0.2)
			(type default)
		)
		(layer "In1.Cu")
	)
	(gr_line
		(start 95.969836 -273.508216)
		(end 95.157036 -273.508216)
		(stroke
			(width 0.2)
			(type default)
		)
		(layer "In1.Cu")
	)
	(gr_arc
		(start 95.969836 -159.371792)
		(mid 96.005757 -159.356913)
		(end 96.020636 -159.320992)
		(stroke
			(width 0.2)
			(type default)
		)
		(layer "In1.Cu")
	)
	(gr_line
		(start 95.969836 -159.066992)
		(end 95.157036 -159.066992)
		(stroke
			(width 0.2)
			(type default)
		)
		(layer "In1.Cu")
	)
	(gr_arc
		(start 95.969836 -158.812992)
		(mid 96.005757 -158.798113)
		(end 96.020636 -158.762192)
		(stroke
			(width 0.2)
			(type default)
		)
		(layer "In1.Cu")
	)
	(gr_line
		(start 95.969836 -158.508192)
		(end 95.157036 -158.508192)
		(stroke
			(width 0.2)
			(type default)
		)
		(layer "In1.Cu")
	)
	(gr_arc
		(start 95.969836 -44.371768)
		(mid 96.005757 -44.356889)
		(end 96.020636 -44.320968)
		(stroke
			(width 0.2)
			(type default)
		)
		(layer "In1.Cu")
	)
	(gr_line
		(start 95.969836 -44.066968)
		(end 95.157036 -44.066968)
		(stroke
			(width 0.2)
			(type default)
		)
		(layer "In1.Cu")
	)
	(gr_arc
		(start 95.969836 -43.812968)
		(mid 96.005757 -43.798089)
		(end 96.020636 -43.762168)
		(stroke
			(width 0.2)
			(type default)
		)
		(layer "In1.Cu")
	)
	(gr_line
		(start 95.969836 -43.508168)
		(end 95.157036 -43.508168)
		(stroke
			(width 0.2)
			(type default)
		)
		(layer "In1.Cu")
	)
	(gr_line
		(start 95.989902 -278.321516)
		(end 95.989902 -277.17877)
		(stroke
			(width 0.2)
			(type default)
		)
		(layer "In1.Cu")
	)
	(gr_arc
		(start 95.989902 -277.17877)
		(mid 95.609029 -276.797516)
		(end 95.227902 -277.178516)
		(stroke
			(width 0.2)
			(type default)
		)
		(layer "In1.Cu")
	)
	(gr_line
		(start 95.989902 -163.321492)
		(end 95.989902 -162.178746)
		(stroke
			(width 0.2)
			(type default)
		)
		(layer "In1.Cu")
	)
	(gr_arc
		(start 95.989902 -162.178746)
		(mid 95.609029 -161.797492)
		(end 95.227902 -162.178492)
		(stroke
			(width 0.2)
			(type default)
		)
		(layer "In1.Cu")
	)
	(gr_line
		(start 95.989902 -48.321468)
		(end 95.989902 -47.178722)
		(stroke
			(width 0.2)
			(type default)
		)
		(layer "In1.Cu")
	)
	(gr_arc
		(start 95.989902 -47.178722)
		(mid 95.609029 -46.797468)
		(end 95.227902 -47.178468)
		(stroke
			(width 0.2)
			(type default)
		)
		(layer "In1.Cu")
	)
	(gr_line
		(start 96.020636 -274.321016)
		(end 96.020636 -274.117816)
		(stroke
			(width 0.2)
			(type default)
		)
		(layer "In1.Cu")
	)
	(gr_arc
		(start 96.020636 -274.117816)
		(mid 96.005757 -274.081895)
		(end 95.969836 -274.067016)
		(stroke
			(width 0.2)
			(type default)
		)
		(layer "In1.Cu")
	)
	(gr_line
		(start 96.020636 -273.762216)
		(end 96.020636 -273.559016)
		(stroke
			(width 0.2)
			(type default)
		)
		(layer "In1.Cu")
	)
	(gr_arc
		(start 96.020636 -273.559016)
		(mid 96.005757 -273.523095)
		(end 95.969836 -273.508216)
		(stroke
			(width 0.2)
			(type default)
		)
		(layer "In1.Cu")
	)
	(gr_line
		(start 96.020636 -159.320992)
		(end 96.020636 -159.117792)
		(stroke
			(width 0.2)
			(type default)
		)
		(layer "In1.Cu")
	)
	(gr_arc
		(start 96.020636 -159.117792)
		(mid 96.005757 -159.081871)
		(end 95.969836 -159.066992)
		(stroke
			(width 0.2)
			(type default)
		)
		(layer "In1.Cu")
	)
	(gr_line
		(start 96.020636 -158.762192)
		(end 96.020636 -158.558992)
		(stroke
			(width 0.2)
			(type default)
		)
		(layer "In1.Cu")
	)
	(gr_arc
		(start 96.020636 -158.558992)
		(mid 96.005757 -158.523071)
		(end 95.969836 -158.508192)
		(stroke
			(width 0.2)
			(type default)
		)
		(layer "In1.Cu")
	)
	(gr_line
		(start 96.020636 -44.320968)
		(end 96.020636 -44.117768)
		(stroke
			(width 0.2)
			(type default)
		)
		(layer "In1.Cu")
	)
	(gr_arc
		(start 96.020636 -44.117768)
		(mid 96.005757 -44.081847)
		(end 95.969836 -44.066968)
		(stroke
			(width 0.2)
			(type default)
		)
		(layer "In1.Cu")
	)
	(gr_line
		(start 96.020636 -43.762168)
		(end 96.020636 -43.558968)
		(stroke
			(width 0.2)
			(type default)
		)
		(layer "In1.Cu")
	)
	(gr_arc
		(start 96.020636 -43.558968)
		(mid 96.005757 -43.523047)
		(end 95.969836 -43.508168)
		(stroke
			(width 0.2)
			(type default)
		)
		(layer "In1.Cu")
	)
	(gr_arc
		(start 102.00005 -13.999972)
		(mid 102.292943 -14.707077)
		(end 103.000048 -14.99997)
		(stroke
			(width 1.524)
			(type default)
		)
		(layer "In1.Cu")
	)
	(gr_arc
		(start 102.00005 -0.999998)
		(mid 101.707154 -0.292911)
		(end 101.000052 0)
		(stroke
			(width 1.524)
			(type default)
		)
		(layer "In1.Cu")
	)
	(gr_line
		(start 102.00005 -0.999998)
		(end 102.00005 -13.999972)
		(stroke
			(width 1.524)
			(type default)
		)
		(layer "In1.Cu")
	)
	(gr_line
		(start 103.000048 -14.99997)
		(end 148.999956 -14.99997)
		(stroke
			(width 1.524)
			(type default)
		)
		(layer "In1.Cu")
	)
	(gr_arc
		(start 108.601256 -22.350222)
		(mid 109.149896 -22.898862)
		(end 109.698536 -22.350222)
		(stroke
			(width 0.2)
			(type default)
		)
		(layer "In1.Cu")
	)
	(gr_line
		(start 108.601256 -20.950174)
		(end 108.601256 -22.350222)
		(stroke
			(width 0.2)
			(type default)
		)
		(layer "In1.Cu")
	)
	(gr_arc
		(start 108.601256 -18.750026)
		(mid 109.149896 -19.298666)
		(end 109.698536 -18.750026)
		(stroke
			(width 0.2)
			(type default)
		)
		(layer "In1.Cu")
	)
	(gr_line
		(start 108.601256 -17.349978)
		(end 108.601256 -18.750026)
		(stroke
			(width 0.2)
			(type default)
		)
		(layer "In1.Cu")
	)
	(gr_line
		(start 109.698536 -22.350222)
		(end 109.698536 -20.950428)
		(stroke
			(width 0.2)
			(type default)
		)
		(layer "In1.Cu")
	)
	(gr_arc
		(start 109.698536 -20.950428)
		(mid 109.150023 -20.401534)
		(end 108.601256 -20.950174)
		(stroke
			(width 0.2)
			(type default)
		)
		(layer "In1.Cu")
	)
	(gr_line
		(start 109.698536 -18.750026)
		(end 109.698536 -17.350232)
		(stroke
			(width 0.2)
			(type default)
		)
		(layer "In1.Cu")
	)
	(gr_arc
		(start 109.698536 -17.350232)
		(mid 109.150023 -16.801338)
		(end 108.601256 -17.349978)
		(stroke
			(width 0.2)
			(type default)
		)
		(layer "In1.Cu")
	)
	(gr_arc
		(start 110.401354 -23.35022)
		(mid 110.949994 -23.89886)
		(end 111.498634 -23.35022)
		(stroke
			(width 0.2)
			(type default)
		)
		(layer "In1.Cu")
	)
	(gr_line
		(start 110.401354 -21.950172)
		(end 110.401354 -23.35022)
		(stroke
			(width 0.2)
			(type default)
		)
		(layer "In1.Cu")
	)
	(gr_arc
		(start 110.401354 -19.750024)
		(mid 110.949994 -20.298664)
		(end 111.498634 -19.750024)
		(stroke
			(width 0.2)
			(type default)
		)
		(layer "In1.Cu")
	)
	(gr_line
		(start 110.401354 -18.35023)
		(end 110.401354 -19.750024)
		(stroke
			(width 0.2)
			(type default)
		)
		(layer "In1.Cu")
	)
	(gr_line
		(start 111.498634 -23.35022)
		(end 111.498634 -21.950426)
		(stroke
			(width 0.2)
			(type default)
		)
		(layer "In1.Cu")
	)
	(gr_arc
		(start 111.498634 -21.950426)
		(mid 110.950121 -21.401532)
		(end 110.401354 -21.950172)
		(stroke
			(width 0.2)
			(type default)
		)
		(layer "In1.Cu")
	)
	(gr_line
		(start 111.498634 -19.750024)
		(end 111.498634 -18.350484)
		(stroke
			(width 0.2)
			(type default)
		)
		(layer "In1.Cu")
	)
	(gr_arc
		(start 111.498634 -18.350484)
		(mid 110.950121 -17.80159)
		(end 110.401354 -18.35023)
		(stroke
			(width 0.2)
			(type default)
		)
		(layer "In1.Cu")
	)
	(gr_arc
		(start 112.201452 -22.350222)
		(mid 112.750092 -22.898862)
		(end 113.298732 -22.350222)
		(stroke
			(width 0.2)
			(type default)
		)
		(layer "In1.Cu")
	)
	(gr_line
		(start 112.201452 -20.950174)
		(end 112.201452 -22.350222)
		(stroke
			(width 0.2)
			(type default)
		)
		(layer "In1.Cu")
	)
	(gr_arc
		(start 112.201452 -18.750026)
		(mid 112.750092 -19.298666)
		(end 113.298732 -18.750026)
		(stroke
			(width 0.2)
			(type default)
		)
		(layer "In1.Cu")
	)
	(gr_line
		(start 112.201452 -17.349978)
		(end 112.201452 -18.750026)
		(stroke
			(width 0.2)
			(type default)
		)
		(layer "In1.Cu")
	)
	(gr_line
		(start 113.298732 -22.350222)
		(end 113.298732 -20.950428)
		(stroke
			(width 0.2)
			(type default)
		)
		(layer "In1.Cu")
	)
	(gr_arc
		(start 113.298732 -20.950428)
		(mid 112.750219 -20.401534)
		(end 112.201452 -20.950174)
		(stroke
			(width 0.2)
			(type default)
		)
		(layer "In1.Cu")
	)
	(gr_line
		(start 113.298732 -18.750026)
		(end 113.298732 -17.350232)
		(stroke
			(width 0.2)
			(type default)
		)
		(layer "In1.Cu")
	)
	(gr_arc
		(start 113.298732 -17.350232)
		(mid 112.750219 -16.801338)
		(end 112.201452 -17.349978)
		(stroke
			(width 0.2)
			(type default)
		)
		(layer "In1.Cu")
	)
	(gr_arc
		(start 114.001296 -23.35022)
		(mid 114.549936 -23.89886)
		(end 115.098576 -23.35022)
		(stroke
			(width 0.2)
			(type default)
		)
		(layer "In1.Cu")
	)
	(gr_line
		(start 114.001296 -21.950172)
		(end 114.001296 -23.35022)
		(stroke
			(width 0.2)
			(type default)
		)
		(layer "In1.Cu")
	)
	(gr_arc
		(start 114.001296 -19.750024)
		(mid 114.549936 -20.298664)
		(end 115.098576 -19.750024)
		(stroke
			(width 0.2)
			(type default)
		)
		(layer "In1.Cu")
	)
	(gr_line
		(start 114.001296 -18.35023)
		(end 114.001296 -19.750024)
		(stroke
			(width 0.2)
			(type default)
		)
		(layer "In1.Cu")
	)
	(gr_line
		(start 115.098576 -23.35022)
		(end 115.098576 -21.950426)
		(stroke
			(width 0.2)
			(type default)
		)
		(layer "In1.Cu")
	)
	(gr_arc
		(start 115.098576 -21.950426)
		(mid 114.550063 -21.401532)
		(end 114.001296 -21.950172)
		(stroke
			(width 0.2)
			(type default)
		)
		(layer "In1.Cu")
	)
	(gr_line
		(start 115.098576 -19.750024)
		(end 115.098576 -18.350484)
		(stroke
			(width 0.2)
			(type default)
		)
		(layer "In1.Cu")
	)
	(gr_arc
		(start 115.098576 -18.350484)
		(mid 114.550063 -17.80159)
		(end 114.001296 -18.35023)
		(stroke
			(width 0.2)
			(type default)
		)
		(layer "In1.Cu")
	)
	(gr_arc
		(start 115.801394 -29.550106)
		(mid 116.350034 -30.098746)
		(end 116.898674 -29.550106)
		(stroke
			(width 0.2)
			(type default)
		)
		(layer "In1.Cu")
	)
	(gr_line
		(start 115.801394 -28.150058)
		(end 115.801394 -29.550106)
		(stroke
			(width 0.2)
			(type default)
		)
		(layer "In1.Cu")
	)
	(gr_arc
		(start 115.801394 -22.350222)
		(mid 116.350034 -22.898862)
		(end 116.898674 -22.350222)
		(stroke
			(width 0.2)
			(type default)
		)
		(layer "In1.Cu")
	)
	(gr_line
		(start 115.801394 -20.950174)
		(end 115.801394 -22.350222)
		(stroke
			(width 0.2)
			(type default)
		)
		(layer "In1.Cu")
	)
	(gr_arc
		(start 115.801394 -18.750026)
		(mid 116.350034 -19.298666)
		(end 116.898674 -18.750026)
		(stroke
			(width 0.2)
			(type default)
		)
		(layer "In1.Cu")
	)
	(gr_line
		(start 115.801394 -17.349978)
		(end 115.801394 -18.750026)
		(stroke
			(width 0.2)
			(type default)
		)
		(layer "In1.Cu")
	)
	(gr_line
		(start 116.898674 -29.550106)
		(end 116.898674 -28.150312)
		(stroke
			(width 0.2)
			(type default)
		)
		(layer "In1.Cu")
	)
	(gr_arc
		(start 116.898674 -28.150312)
		(mid 116.350161 -27.601418)
		(end 115.801394 -28.150058)
		(stroke
			(width 0.2)
			(type default)
		)
		(layer "In1.Cu")
	)
	(gr_line
		(start 116.898674 -22.350222)
		(end 116.898674 -20.950428)
		(stroke
			(width 0.2)
			(type default)
		)
		(layer "In1.Cu")
	)
	(gr_arc
		(start 116.898674 -20.950428)
		(mid 116.350161 -20.401534)
		(end 115.801394 -20.950174)
		(stroke
			(width 0.2)
			(type default)
		)
		(layer "In1.Cu")
	)
	(gr_line
		(start 116.898674 -18.750026)
		(end 116.898674 -17.350232)
		(stroke
			(width 0.2)
			(type default)
		)
		(layer "In1.Cu")
	)
	(gr_arc
		(start 116.898674 -17.350232)
		(mid 116.350161 -16.801338)
		(end 115.801394 -17.349978)
		(stroke
			(width 0.2)
			(type default)
		)
		(layer "In1.Cu")
	)
	(gr_arc
		(start 117.601238 -23.35022)
		(mid 118.149878 -23.89886)
		(end 118.698518 -23.35022)
		(stroke
			(width 0.2)
			(type default)
		)
		(layer "In1.Cu")
	)
	(gr_line
		(start 117.601238 -21.950172)
		(end 117.601238 -23.35022)
		(stroke
			(width 0.2)
			(type default)
		)
		(layer "In1.Cu")
	)
	(gr_arc
		(start 117.601238 -19.750024)
		(mid 118.149878 -20.298664)
		(end 118.698518 -19.750024)
		(stroke
			(width 0.2)
			(type default)
		)
		(layer "In1.Cu")
	)
	(gr_line
		(start 117.601238 -18.35023)
		(end 117.601238 -19.750024)
		(stroke
			(width 0.2)
			(type default)
		)
		(layer "In1.Cu")
	)
	(gr_line
		(start 118.698518 -23.35022)
		(end 118.698518 -21.950426)
		(stroke
			(width 0.2)
			(type default)
		)
		(layer "In1.Cu")
	)
	(gr_arc
		(start 118.698518 -21.950426)
		(mid 118.150005 -21.401532)
		(end 117.601238 -21.950172)
		(stroke
			(width 0.2)
			(type default)
		)
		(layer "In1.Cu")
	)
	(gr_line
		(start 118.698518 -19.750024)
		(end 118.698518 -18.350484)
		(stroke
			(width 0.2)
			(type default)
		)
		(layer "In1.Cu")
	)
	(gr_arc
		(start 118.698518 -18.350484)
		(mid 118.150005 -17.80159)
		(end 117.601238 -18.35023)
		(stroke
			(width 0.2)
			(type default)
		)
		(layer "In1.Cu")
	)
	(gr_arc
		(start 119.401336 -22.350222)
		(mid 119.949976 -22.898862)
		(end 120.498616 -22.350222)
		(stroke
			(width 0.2)
			(type default)
		)
		(layer "In1.Cu")
	)
	(gr_line
		(start 119.401336 -20.950174)
		(end 119.401336 -22.350222)
		(stroke
			(width 0.2)
			(type default)
		)
		(layer "In1.Cu")
	)
	(gr_arc
		(start 119.401336 -18.750026)
		(mid 119.949976 -19.298666)
		(end 120.498616 -18.750026)
		(stroke
			(width 0.2)
			(type default)
		)
		(layer "In1.Cu")
	)
	(gr_line
		(start 119.401336 -17.349978)
		(end 119.401336 -18.750026)
		(stroke
			(width 0.2)
			(type default)
		)
		(layer "In1.Cu")
	)
	(gr_line
		(start 120.498616 -22.350222)
		(end 120.498616 -20.950428)
		(stroke
			(width 0.2)
			(type default)
		)
		(layer "In1.Cu")
	)
	(gr_arc
		(start 120.498616 -20.950428)
		(mid 119.950103 -20.401534)
		(end 119.401336 -20.950174)
		(stroke
			(width 0.2)
			(type default)
		)
		(layer "In1.Cu")
	)
	(gr_line
		(start 120.498616 -18.750026)
		(end 120.498616 -17.350232)
		(stroke
			(width 0.2)
			(type default)
		)
		(layer "In1.Cu")
	)
	(gr_arc
		(start 120.498616 -17.350232)
		(mid 119.950103 -16.801338)
		(end 119.401336 -17.349978)
		(stroke
			(width 0.2)
			(type default)
		)
		(layer "In1.Cu")
	)
	(gr_arc
		(start 121.198894 -30.54985)
		(mid 121.749947 -31.101284)
		(end 122.301254 -30.550104)
		(stroke
			(width 0.2)
			(type default)
		)
		(layer "In1.Cu")
	)
	(gr_line
		(start 121.198894 -29.150056)
		(end 121.198894 -30.54985)
		(stroke
			(width 0.2)
			(type default)
		)
		(layer "In1.Cu")
	)
	(gr_arc
		(start 121.201434 -23.35022)
		(mid 121.750074 -23.89886)
		(end 122.298714 -23.35022)
		(stroke
			(width 0.2)
			(type default)
		)
		(layer "In1.Cu")
	)
	(gr_line
		(start 121.201434 -21.950172)
		(end 121.201434 -23.35022)
		(stroke
			(width 0.2)
			(type default)
		)
		(layer "In1.Cu")
	)
	(gr_arc
		(start 121.201434 -19.750024)
		(mid 121.750074 -20.298664)
		(end 122.298714 -19.750024)
		(stroke
			(width 0.2)
			(type default)
		)
		(layer "In1.Cu")
	)
	(gr_line
		(start 121.201434 -18.35023)
		(end 121.201434 -19.750024)
		(stroke
			(width 0.2)
			(type default)
		)
		(layer "In1.Cu")
	)
	(gr_line
		(start 122.298714 -23.35022)
		(end 122.298714 -21.950426)
		(stroke
			(width 0.2)
			(type default)
		)
		(layer "In1.Cu")
	)
	(gr_arc
		(start 122.298714 -21.950426)
		(mid 121.750201 -21.401532)
		(end 121.201434 -21.950172)
		(stroke
			(width 0.2)
			(type default)
		)
		(layer "In1.Cu")
	)
	(gr_line
		(start 122.298714 -19.750024)
		(end 122.298714 -18.350484)
		(stroke
			(width 0.2)
			(type default)
		)
		(layer "In1.Cu")
	)
	(gr_arc
		(start 122.298714 -18.350484)
		(mid 121.750201 -17.80159)
		(end 121.201434 -18.35023)
		(stroke
			(width 0.2)
			(type default)
		)
		(layer "In1.Cu")
	)
	(gr_line
		(start 122.301254 -30.550104)
		(end 122.301254 -29.150056)
		(stroke
			(width 0.2)
			(type default)
		)
		(layer "In1.Cu")
	)
	(gr_arc
		(start 122.301254 -29.150056)
		(mid 121.750074 -28.598876)
		(end 121.198894 -29.150056)
		(stroke
			(width 0.2)
			(type default)
		)
		(layer "In1.Cu")
	)
	(gr_line
		(start 123.493784 -279.350216)
		(end 123.493784 -276.149816)
		(stroke
			(width 0.2)
			(type default)
		)
		(layer "In1.Cu")
	)
	(gr_rect
		(start 123.493784 -276.810216)
		(end 125.855984 -278.689816)
		(stroke
			(width 0)
			(type default)
		)
		(fill no)
		(layer "In1.Cu")
	)
	(gr_line
		(start 123.493784 -276.149816)
		(end 125.855984 -276.149816)
		(stroke
			(width 0.2)
			(type default)
		)
		(layer "In1.Cu")
	)
	(gr_line
		(start 123.493784 -275.540216)
		(end 123.493784 -272.339816)
		(stroke
			(width 0.2)
			(type default)
		)
		(layer "In1.Cu")
	)
	(gr_rect
		(start 123.493784 -273.000216)
		(end 125.855984 -274.879816)
		(stroke
			(width 0)
			(type default)
		)
		(fill no)
		(layer "In1.Cu")
	)
	(gr_line
		(start 123.493784 -272.339816)
		(end 125.855984 -272.340578)
		(stroke
			(width 0.2)
			(type default)
		)
		(layer "In1.Cu")
	)
	(gr_line
		(start 123.493784 -164.350192)
		(end 123.493784 -161.149792)
		(stroke
			(width 0.2)
			(type default)
		)
		(layer "In1.Cu")
	)
	(gr_rect
		(start 123.493784 -161.810192)
		(end 125.855984 -163.689792)
		(stroke
			(width 0)
			(type default)
		)
		(fill no)
		(layer "In1.Cu")
	)
	(gr_line
		(start 123.493784 -161.149792)
		(end 125.855984 -161.149792)
		(stroke
			(width 0.2)
			(type default)
		)
		(layer "In1.Cu")
	)
	(gr_line
		(start 123.493784 -160.540192)
		(end 123.493784 -157.339792)
		(stroke
			(width 0.2)
			(type default)
		)
		(layer "In1.Cu")
	)
	(gr_rect
		(start 123.493784 -158.000192)
		(end 125.855984 -159.879792)
		(stroke
			(width 0)
			(type default)
		)
		(fill no)
		(layer "In1.Cu")
	)
	(gr_line
		(start 123.493784 -157.339792)
		(end 125.855984 -157.340554)
		(stroke
			(width 0.2)
			(type default)
		)
		(layer "In1.Cu")
	)
	(gr_line
		(start 123.493784 -49.350168)
		(end 123.493784 -46.149768)
		(stroke
			(width 0.2)
			(type default)
		)
		(layer "In1.Cu")
	)
	(gr_rect
		(start 123.493784 -46.810168)
		(end 125.855984 -48.689768)
		(stroke
			(width 0)
			(type default)
		)
		(fill no)
		(layer "In1.Cu")
	)
	(gr_line
		(start 123.493784 -46.149768)
		(end 125.855984 -46.149768)
		(stroke
			(width 0.2)
			(type default)
		)
		(layer "In1.Cu")
	)
	(gr_line
		(start 123.493784 -45.540168)
		(end 123.493784 -42.339768)
		(stroke
			(width 0.2)
			(type default)
		)
		(layer "In1.Cu")
	)
	(gr_rect
		(start 123.493784 -43.000168)
		(end 125.855984 -44.879768)
		(stroke
			(width 0)
			(type default)
		)
		(fill no)
		(layer "In1.Cu")
	)
	(gr_line
		(start 123.493784 -42.339768)
		(end 125.855984 -42.34053)
		(stroke
			(width 0.2)
			(type default)
		)
		(layer "In1.Cu")
	)
	(gr_line
		(start 125.855984 -279.350216)
		(end 123.493784 -279.350216)
		(stroke
			(width 0.2)
			(type default)
		)
		(layer "In1.Cu")
	)
	(gr_line
		(start 125.855984 -276.149816)
		(end 125.855984 -279.350216)
		(stroke
			(width 0.2)
			(type default)
		)
		(layer "In1.Cu")
	)
	(gr_line
		(start 125.855984 -275.540216)
		(end 123.493784 -275.540216)
		(stroke
			(width 0.2)
			(type default)
		)
		(layer "In1.Cu")
	)
	(gr_line
		(start 125.855984 -272.340578)
		(end 125.855984 -275.540216)
		(stroke
			(width 0.2)
			(type default)
		)
		(layer "In1.Cu")
	)
	(gr_line
		(start 125.855984 -164.350192)
		(end 123.493784 -164.350192)
		(stroke
			(width 0.2)
			(type default)
		)
		(layer "In1.Cu")
	)
	(gr_line
		(start 125.855984 -161.149792)
		(end 125.855984 -164.350192)
		(stroke
			(width 0.2)
			(type default)
		)
		(layer "In1.Cu")
	)
	(gr_line
		(start 125.855984 -160.540192)
		(end 123.493784 -160.540192)
		(stroke
			(width 0.2)
			(type default)
		)
		(layer "In1.Cu")
	)
	(gr_line
		(start 125.855984 -157.340554)
		(end 125.855984 -160.540192)
		(stroke
			(width 0.2)
			(type default)
		)
		(layer "In1.Cu")
	)
	(gr_line
		(start 125.855984 -49.350168)
		(end 123.493784 -49.350168)
		(stroke
			(width 0.2)
			(type default)
		)
		(layer "In1.Cu")
	)
	(gr_line
		(start 125.855984 -46.149768)
		(end 125.855984 -49.350168)
		(stroke
			(width 0.2)
			(type default)
		)
		(layer "In1.Cu")
	)
	(gr_line
		(start 125.855984 -45.540168)
		(end 123.493784 -45.540168)
		(stroke
			(width 0.2)
			(type default)
		)
		(layer "In1.Cu")
	)
	(gr_line
		(start 125.855984 -42.34053)
		(end 125.855984 -45.540168)
		(stroke
			(width 0.2)
			(type default)
		)
		(layer "In1.Cu")
	)
	(gr_arc
		(start 126.656084 -274.321016)
		(mid 126.670963 -274.356937)
		(end 126.706884 -274.371816)
		(stroke
			(width 0.2)
			(type default)
		)
		(layer "In1.Cu")
	)
	(gr_line
		(start 126.656084 -274.117816)
		(end 126.656084 -274.321016)
		(stroke
			(width 0.2)
			(type default)
		)
		(layer "In1.Cu")
	)
	(gr_arc
		(start 126.656084 -273.762216)
		(mid 126.670963 -273.798137)
		(end 126.706884 -273.813016)
		(stroke
			(width 0.2)
			(type default)
		)
		(layer "In1.Cu")
	)
	(gr_line
		(start 126.656084 -273.559016)
		(end 126.656084 -273.762216)
		(stroke
			(width 0.2)
			(type default)
		)
		(layer "In1.Cu")
	)
	(gr_arc
		(start 126.656084 -159.320992)
		(mid 126.670963 -159.356913)
		(end 126.706884 -159.371792)
		(stroke
			(width 0.2)
			(type default)
		)
		(layer "In1.Cu")
	)
	(gr_line
		(start 126.656084 -159.117792)
		(end 126.656084 -159.320992)
		(stroke
			(width 0.2)
			(type default)
		)
		(layer "In1.Cu")
	)
	(gr_arc
		(start 126.656084 -158.762192)
		(mid 126.670963 -158.798113)
		(end 126.706884 -158.812992)
		(stroke
			(width 0.2)
			(type default)
		)
		(layer "In1.Cu")
	)
	(gr_line
		(start 126.656084 -158.558992)
		(end 126.656084 -158.762192)
		(stroke
			(width 0.2)
			(type default)
		)
		(layer "In1.Cu")
	)
	(gr_arc
		(start 126.656084 -44.320968)
		(mid 126.670963 -44.356889)
		(end 126.706884 -44.371768)
		(stroke
			(width 0.2)
			(type default)
		)
		(layer "In1.Cu")
	)
	(gr_line
		(start 126.656084 -44.117768)
		(end 126.656084 -44.320968)
		(stroke
			(width 0.2)
			(type default)
		)
		(layer "In1.Cu")
	)
	(gr_arc
		(start 126.656084 -43.762168)
		(mid 126.670963 -43.798089)
		(end 126.706884 -43.812968)
		(stroke
			(width 0.2)
			(type default)
		)
		(layer "In1.Cu")
	)
	(gr_line
		(start 126.656084 -43.558968)
		(end 126.656084 -43.762168)
		(stroke
			(width 0.2)
			(type default)
		)
		(layer "In1.Cu")
	)
	(gr_line
		(start 126.706884 -274.371816)
		(end 127.519684 -274.371816)
		(stroke
			(width 0.2)
			(type default)
		)
		(layer "In1.Cu")
	)
	(gr_arc
		(start 126.706884 -274.067016)
		(mid 126.670963 -274.081895)
		(end 126.656084 -274.117816)
		(stroke
			(width 0.2)
			(type default)
		)
		(layer "In1.Cu")
	)
	(gr_line
		(start 126.706884 -273.813016)
		(end 127.519684 -273.813016)
		(stroke
			(width 0.2)
			(type default)
		)
		(layer "In1.Cu")
	)
	(gr_arc
		(start 126.706884 -273.508216)
		(mid 126.670963 -273.523095)
		(end 126.656084 -273.559016)
		(stroke
			(width 0.2)
			(type default)
		)
		(layer "In1.Cu")
	)
	(gr_line
		(start 126.706884 -159.371792)
		(end 127.519684 -159.371792)
		(stroke
			(width 0.2)
			(type default)
		)
		(layer "In1.Cu")
	)
	(gr_arc
		(start 126.706884 -159.066992)
		(mid 126.670963 -159.081871)
		(end 126.656084 -159.117792)
		(stroke
			(width 0.2)
			(type default)
		)
		(layer "In1.Cu")
	)
	(gr_line
		(start 126.706884 -158.812992)
		(end 127.519684 -158.812992)
		(stroke
			(width 0.2)
			(type default)
		)
		(layer "In1.Cu")
	)
	(gr_arc
		(start 126.706884 -158.508192)
		(mid 126.670963 -158.523071)
		(end 126.656084 -158.558992)
		(stroke
			(width 0.2)
			(type default)
		)
		(layer "In1.Cu")
	)
	(gr_line
		(start 126.706884 -44.371768)
		(end 127.519684 -44.371768)
		(stroke
			(width 0.2)
			(type default)
		)
		(layer "In1.Cu")
	)
	(gr_arc
		(start 126.706884 -44.066968)
		(mid 126.670963 -44.081847)
		(end 126.656084 -44.117768)
		(stroke
			(width 0.2)
			(type default)
		)
		(layer "In1.Cu")
	)
	(gr_line
		(start 126.706884 -43.812968)
		(end 127.519684 -43.812968)
		(stroke
			(width 0.2)
			(type default)
		)
		(layer "In1.Cu")
	)
	(gr_arc
		(start 126.706884 -43.508168)
		(mid 126.670963 -43.523047)
		(end 126.656084 -43.558968)
		(stroke
			(width 0.2)
			(type default)
		)
		(layer "In1.Cu")
	)
	(gr_arc
		(start 126.77775 -278.321516)
		(mid 127.15875 -278.702516)
		(end 127.53975 -278.321516)
		(stroke
			(width 0.2)
			(type default)
		)
		(layer "In1.Cu")
	)
	(gr_line
		(start 126.77775 -277.178516)
		(end 126.77775 -278.321516)
		(stroke
			(width 0.2)
			(type default)
		)
		(layer "In1.Cu")
	)
	(gr_arc
		(start 126.77775 -163.321492)
		(mid 127.15875 -163.702492)
		(end 127.53975 -163.321492)
		(stroke
			(width 0.2)
			(type default)
		)
		(layer "In1.Cu")
	)
	(gr_line
		(start 126.77775 -162.178492)
		(end 126.77775 -163.321492)
		(stroke
			(width 0.2)
			(type default)
		)
		(layer "In1.Cu")
	)
	(gr_arc
		(start 126.77775 -48.321468)
		(mid 127.15875 -48.702468)
		(end 127.53975 -48.321468)
		(stroke
			(width 0.2)
			(type default)
		)
		(layer "In1.Cu")
	)
	(gr_line
		(start 126.77775 -47.178468)
		(end 126.77775 -48.321468)
		(stroke
			(width 0.2)
			(type default)
		)
		(layer "In1.Cu")
	)
	(gr_arc
		(start 127.519684 -274.371816)
		(mid 127.555605 -274.356937)
		(end 127.570484 -274.321016)
		(stroke
			(width 0.2)
			(type default)
		)
		(layer "In1.Cu")
	)
	(gr_line
		(start 127.519684 -274.067016)
		(end 126.706884 -274.067016)
		(stroke
			(width 0.2)
			(type default)
		)
		(layer "In1.Cu")
	)
	(gr_arc
		(start 127.519684 -273.813016)
		(mid 127.555605 -273.798137)
		(end 127.570484 -273.762216)
		(stroke
			(width 0.2)
			(type default)
		)
		(layer "In1.Cu")
	)
	(gr_line
		(start 127.519684 -273.508216)
		(end 126.706884 -273.508216)
		(stroke
			(width 0.2)
			(type default)
		)
		(layer "In1.Cu")
	)
	(gr_arc
		(start 127.519684 -159.371792)
		(mid 127.555605 -159.356913)
		(end 127.570484 -159.320992)
		(stroke
			(width 0.2)
			(type default)
		)
		(layer "In1.Cu")
	)
	(gr_line
		(start 127.519684 -159.066992)
		(end 126.706884 -159.066992)
		(stroke
			(width 0.2)
			(type default)
		)
		(layer "In1.Cu")
	)
	(gr_arc
		(start 127.519684 -158.812992)
		(mid 127.555605 -158.798113)
		(end 127.570484 -158.762192)
		(stroke
			(width 0.2)
			(type default)
		)
		(layer "In1.Cu")
	)
	(gr_line
		(start 127.519684 -158.508192)
		(end 126.706884 -158.508192)
		(stroke
			(width 0.2)
			(type default)
		)
		(layer "In1.Cu")
	)
	(gr_arc
		(start 127.519684 -44.371768)
		(mid 127.555605 -44.356889)
		(end 127.570484 -44.320968)
		(stroke
			(width 0.2)
			(type default)
		)
		(layer "In1.Cu")
	)
	(gr_line
		(start 127.519684 -44.066968)
		(end 126.706884 -44.066968)
		(stroke
			(width 0.2)
			(type default)
		)
		(layer "In1.Cu")
	)
	(gr_arc
		(start 127.519684 -43.812968)
		(mid 127.555605 -43.798089)
		(end 127.570484 -43.762168)
		(stroke
			(width 0.2)
			(type default)
		)
		(layer "In1.Cu")
	)
	(gr_line
		(start 127.519684 -43.508168)
		(end 126.706884 -43.508168)
		(stroke
			(width 0.2)
			(type default)
		)
		(layer "In1.Cu")
	)
	(gr_line
		(start 127.53975 -278.321516)
		(end 127.53975 -277.17877)
		(stroke
			(width 0.2)
			(type default)
		)
		(layer "In1.Cu")
	)
	(gr_arc
		(start 127.53975 -277.17877)
		(mid 127.158877 -276.797516)
		(end 126.77775 -277.178516)
		(stroke
			(width 0.2)
			(type default)
		)
		(layer "In1.Cu")
	)
	(gr_line
		(start 127.53975 -163.321492)
		(end 127.53975 -162.178746)
		(stroke
			(width 0.2)
			(type default)
		)
		(layer "In1.Cu")
	)
	(gr_arc
		(start 127.53975 -162.178746)
		(mid 127.158877 -161.797492)
		(end 126.77775 -162.178492)
		(stroke
			(width 0.2)
			(type default)
		)
		(layer "In1.Cu")
	)
	(gr_line
		(start 127.53975 -48.321468)
		(end 127.53975 -47.178722)
		(stroke
			(width 0.2)
			(type default)
		)
		(layer "In1.Cu")
	)
	(gr_arc
		(start 127.53975 -47.178722)
		(mid 127.158877 -46.797468)
		(end 126.77775 -47.178468)
		(stroke
			(width 0.2)
			(type default)
		)
		(layer "In1.Cu")
	)
	(gr_line
		(start 127.570484 -274.321016)
		(end 127.570484 -274.117816)
		(stroke
			(width 0.2)
			(type default)
		)
		(layer "In1.Cu")
	)
	(gr_arc
		(start 127.570484 -274.117816)
		(mid 127.555605 -274.081895)
		(end 127.519684 -274.067016)
		(stroke
			(width 0.2)
			(type default)
		)
		(layer "In1.Cu")
	)
	(gr_line
		(start 127.570484 -273.762216)
		(end 127.570484 -273.559016)
		(stroke
			(width 0.2)
			(type default)
		)
		(layer "In1.Cu")
	)
	(gr_arc
		(start 127.570484 -273.559016)
		(mid 127.555605 -273.523095)
		(end 127.519684 -273.508216)
		(stroke
			(width 0.2)
			(type default)
		)
		(layer "In1.Cu")
	)
	(gr_line
		(start 127.570484 -159.320992)
		(end 127.570484 -159.117792)
		(stroke
			(width 0.2)
			(type default)
		)
		(layer "In1.Cu")
	)
	(gr_arc
		(start 127.570484 -159.117792)
		(mid 127.555605 -159.081871)
		(end 127.519684 -159.066992)
		(stroke
			(width 0.2)
			(type default)
		)
		(layer "In1.Cu")
	)
	(gr_line
		(start 127.570484 -158.762192)
		(end 127.570484 -158.558992)
		(stroke
			(width 0.2)
			(type default)
		)
		(layer "In1.Cu")
	)
	(gr_arc
		(start 127.570484 -158.558992)
		(mid 127.555605 -158.523071)
		(end 127.519684 -158.508192)
		(stroke
			(width 0.2)
			(type default)
		)
		(layer "In1.Cu")
	)
	(gr_line
		(start 127.570484 -44.320968)
		(end 127.570484 -44.117768)
		(stroke
			(width 0.2)
			(type default)
		)
		(layer "In1.Cu")
	)
	(gr_arc
		(start 127.570484 -44.117768)
		(mid 127.555605 -44.081847)
		(end 127.519684 -44.066968)
		(stroke
			(width 0.2)
			(type default)
		)
		(layer "In1.Cu")
	)
	(gr_line
		(start 127.570484 -43.762168)
		(end 127.570484 -43.558968)
		(stroke
			(width 0.2)
			(type default)
		)
		(layer "In1.Cu")
	)
	(gr_arc
		(start 127.570484 -43.558968)
		(mid 127.555605 -43.523047)
		(end 127.519684 -43.508168)
		(stroke
			(width 0.2)
			(type default)
		)
		(layer "In1.Cu")
	)
	(gr_line
		(start 129.1336 -147.5486)
		(end 129.558796 -147.973796)
		(stroke
			(width 0.381)
			(type default)
		)
		(layer "In1.Cu")
	)
	(gr_line
		(start 129.1336 -140.3096)
		(end 129.1336 -147.5486)
		(stroke
			(width 0.381)
			(type default)
		)
		(layer "In1.Cu")
	)
	(gr_line
		(start 129.558796 -147.973796)
		(end 139.836398 -147.973796)
		(stroke
			(width 0.381)
			(type default)
		)
		(layer "In1.Cu")
	)
	(gr_arc
		(start 130.201416 -22.350222)
		(mid 130.750056 -22.898862)
		(end 131.298696 -22.350222)
		(stroke
			(width 0.2)
			(type default)
		)
		(layer "In1.Cu")
	)
	(gr_line
		(start 130.201416 -20.950174)
		(end 130.201416 -22.350222)
		(stroke
			(width 0.2)
			(type default)
		)
		(layer "In1.Cu")
	)
	(gr_arc
		(start 130.201416 -18.750026)
		(mid 130.750056 -19.298666)
		(end 131.298696 -18.750026)
		(stroke
			(width 0.2)
			(type default)
		)
		(layer "In1.Cu")
	)
	(gr_line
		(start 130.201416 -17.349978)
		(end 130.201416 -18.750026)
		(stroke
			(width 0.2)
			(type default)
		)
		(layer "In1.Cu")
	)
	(gr_line
		(start 131.298696 -22.350222)
		(end 131.298696 -20.950428)
		(stroke
			(width 0.2)
			(type default)
		)
		(layer "In1.Cu")
	)
	(gr_arc
		(start 131.298696 -20.950428)
		(mid 130.750183 -20.401534)
		(end 130.201416 -20.950174)
		(stroke
			(width 0.2)
			(type default)
		)
		(layer "In1.Cu")
	)
	(gr_line
		(start 131.298696 -18.750026)
		(end 131.298696 -17.350232)
		(stroke
			(width 0.2)
			(type default)
		)
		(layer "In1.Cu")
	)
	(gr_arc
		(start 131.298696 -17.350232)
		(mid 130.750183 -16.801338)
		(end 130.201416 -17.349978)
		(stroke
			(width 0.2)
			(type default)
		)
		(layer "In1.Cu")
	)
	(gr_arc
		(start 132.00126 -23.35022)
		(mid 132.5499 -23.89886)
		(end 133.09854 -23.35022)
		(stroke
			(width 0.2)
			(type default)
		)
		(layer "In1.Cu")
	)
	(gr_line
		(start 132.00126 -21.950172)
		(end 132.00126 -23.35022)
		(stroke
			(width 0.2)
			(type default)
		)
		(layer "In1.Cu")
	)
	(gr_arc
		(start 132.00126 -19.74977)
		(mid 132.549773 -20.298664)
		(end 133.09854 -19.750024)
		(stroke
			(width 0.2)
			(type default)
		)
		(layer "In1.Cu")
	)
	(gr_line
		(start 132.00126 -18.35023)
		(end 132.00126 -19.74977)
		(stroke
			(width 0.2)
			(type default)
		)
		(layer "In1.Cu")
	)
	(gr_line
		(start 133.09854 -23.35022)
		(end 133.09854 -21.950426)
		(stroke
			(width 0.2)
			(type default)
		)
		(layer "In1.Cu")
	)
	(gr_arc
		(start 133.09854 -21.950426)
		(mid 132.550027 -21.401532)
		(end 132.00126 -21.950172)
		(stroke
			(width 0.2)
			(type default)
		)
		(layer "In1.Cu")
	)
	(gr_line
		(start 133.09854 -19.750024)
		(end 133.09854 -18.35023)
		(stroke
			(width 0.2)
			(type default)
		)
		(layer "In1.Cu")
	)
	(gr_arc
		(start 133.09854 -18.35023)
		(mid 132.5499 -17.80159)
		(end 132.00126 -18.35023)
		(stroke
			(width 0.2)
			(type default)
		)
		(layer "In1.Cu")
	)
	(gr_line
		(start 133.2738 -136.1694)
		(end 129.1336 -140.3096)
		(stroke
			(width 0.381)
			(type default)
		)
		(layer "In1.Cu")
	)
	(gr_arc
		(start 133.801358 -22.350222)
		(mid 134.349998 -22.898862)
		(end 134.898638 -22.350222)
		(stroke
			(width 0.2)
			(type default)
		)
		(layer "In1.Cu")
	)
	(gr_line
		(start 133.801358 -20.950174)
		(end 133.801358 -22.350222)
		(stroke
			(width 0.2)
			(type default)
		)
		(layer "In1.Cu")
	)
	(gr_arc
		(start 133.801358 -18.750026)
		(mid 134.349998 -19.298666)
		(end 134.898638 -18.750026)
		(stroke
			(width 0.2)
			(type default)
		)
		(layer "In1.Cu")
	)
	(gr_line
		(start 133.801358 -17.349978)
		(end 133.801358 -18.750026)
		(stroke
			(width 0.2)
			(type default)
		)
		(layer "In1.Cu")
	)
	(gr_line
		(start 134.898638 -22.350222)
		(end 134.898638 -20.950428)
		(stroke
			(width 0.2)
			(type default)
		)
		(layer "In1.Cu")
	)
	(gr_arc
		(start 134.898638 -20.950428)
		(mid 134.350125 -20.401534)
		(end 133.801358 -20.950174)
		(stroke
			(width 0.2)
			(type default)
		)
		(layer "In1.Cu")
	)
	(gr_line
		(start 134.898638 -18.750026)
		(end 134.898638 -17.350232)
		(stroke
			(width 0.2)
			(type default)
		)
		(layer "In1.Cu")
	)
	(gr_arc
		(start 134.898638 -17.350232)
		(mid 134.350125 -16.801338)
		(end 133.801358 -17.349978)
		(stroke
			(width 0.2)
			(type default)
		)
		(layer "In1.Cu")
	)
	(gr_arc
		(start 135.601456 -30.550104)
		(mid 136.150096 -31.098744)
		(end 136.698736 -30.550104)
		(stroke
			(width 0.2)
			(type default)
		)
		(layer "In1.Cu")
	)
	(gr_line
		(start 135.601456 -29.150056)
		(end 135.601456 -30.550104)
		(stroke
			(width 0.2)
			(type default)
		)
		(layer "In1.Cu")
	)
	(gr_arc
		(start 135.601456 -23.35022)
		(mid 136.150096 -23.89886)
		(end 136.698736 -23.35022)
		(stroke
			(width 0.2)
			(type default)
		)
		(layer "In1.Cu")
	)
	(gr_line
		(start 135.601456 -21.950172)
		(end 135.601456 -23.35022)
		(stroke
			(width 0.2)
			(type default)
		)
		(layer "In1.Cu")
	)
	(gr_arc
		(start 135.601456 -19.750024)
		(mid 136.150096 -20.298664)
		(end 136.698736 -19.750024)
		(stroke
			(width 0.2)
			(type default)
		)
		(layer "In1.Cu")
	)
	(gr_line
		(start 135.601456 -18.35023)
		(end 135.601456 -19.750024)
		(stroke
			(width 0.2)
			(type default)
		)
		(layer "In1.Cu")
	)
	(gr_line
		(start 136.698736 -30.550104)
		(end 136.698736 -29.15031)
		(stroke
			(width 0.2)
			(type default)
		)
		(layer "In1.Cu")
	)
	(gr_arc
		(start 136.698736 -29.15031)
		(mid 136.150223 -28.601416)
		(end 135.601456 -29.150056)
		(stroke
			(width 0.2)
			(type default)
		)
		(layer "In1.Cu")
	)
	(gr_line
		(start 136.698736 -23.35022)
		(end 136.698736 -21.950426)
		(stroke
			(width 0.2)
			(type default)
		)
		(layer "In1.Cu")
	)
	(gr_arc
		(start 136.698736 -21.950426)
		(mid 136.150223 -21.401532)
		(end 135.601456 -21.950172)
		(stroke
			(width 0.2)
			(type default)
		)
		(layer "In1.Cu")
	)
	(gr_line
		(start 136.698736 -19.750024)
		(end 136.698736 -18.350484)
		(stroke
			(width 0.2)
			(type default)
		)
		(layer "In1.Cu")
	)
	(gr_arc
		(start 136.698736 -18.350484)
		(mid 136.150223 -17.80159)
		(end 135.601456 -18.35023)
		(stroke
			(width 0.2)
			(type default)
		)
		(layer "In1.Cu")
	)
	(gr_arc
		(start 137.4013 -22.350222)
		(mid 137.94994 -22.898862)
		(end 138.49858 -22.350222)
		(stroke
			(width 0.2)
			(type default)
		)
		(layer "In1.Cu")
	)
	(gr_line
		(start 137.4013 -20.950174)
		(end 137.4013 -22.350222)
		(stroke
			(width 0.2)
			(type default)
		)
		(layer "In1.Cu")
	)
	(gr_arc
		(start 137.4013 -18.750026)
		(mid 137.94994 -19.298666)
		(end 138.49858 -18.750026)
		(stroke
			(width 0.2)
			(type default)
		)
		(layer "In1.Cu")
	)
	(gr_line
		(start 137.4013 -17.349978)
		(end 137.4013 -18.750026)
		(stroke
			(width 0.2)
			(type default)
		)
		(layer "In1.Cu")
	)
	(gr_line
		(start 137.7442 -136.1694)
		(end 133.2738 -136.1694)
		(stroke
			(width 0.381)
			(type default)
		)
		(layer "In1.Cu")
	)
	(gr_line
		(start 137.9728 -135.9408)
		(end 137.7442 -136.1694)
		(stroke
			(width 0.381)
			(type default)
		)
		(layer "In1.Cu")
	)
	(gr_line
		(start 137.9728 -130.007106)
		(end 137.9728 -135.9408)
		(stroke
			(width 0.381)
			(type default)
		)
		(layer "In1.Cu")
	)
	(gr_line
		(start 138.49858 -22.350222)
		(end 138.49858 -20.950428)
		(stroke
			(width 0.2)
			(type default)
		)
		(layer "In1.Cu")
	)
	(gr_arc
		(start 138.49858 -20.950428)
		(mid 137.950067 -20.401534)
		(end 137.4013 -20.950174)
		(stroke
			(width 0.2)
			(type default)
		)
		(layer "In1.Cu")
	)
	(gr_line
		(start 138.49858 -18.750026)
		(end 138.49858 -17.350232)
		(stroke
			(width 0.2)
			(type default)
		)
		(layer "In1.Cu")
	)
	(gr_arc
		(start 138.49858 -17.350232)
		(mid 137.950067 -16.801338)
		(end 137.4013 -17.349978)
		(stroke
			(width 0.2)
			(type default)
		)
		(layer "In1.Cu")
	)
	(gr_arc
		(start 139.201398 -23.35022)
		(mid 139.750038 -23.89886)
		(end 140.298678 -23.35022)
		(stroke
			(width 0.2)
			(type default)
		)
		(layer "In1.Cu")
	)
	(gr_line
		(start 139.201398 -21.950172)
		(end 139.201398 -23.35022)
		(stroke
			(width 0.2)
			(type default)
		)
		(layer "In1.Cu")
	)
	(gr_arc
		(start 139.201398 -19.750024)
		(mid 139.750038 -20.298664)
		(end 140.298678 -19.750024)
		(stroke
			(width 0.2)
			(type default)
		)
		(layer "In1.Cu")
	)
	(gr_line
		(start 139.201398 -18.35023)
		(end 139.201398 -19.750024)
		(stroke
			(width 0.2)
			(type default)
		)
		(layer "In1.Cu")
	)
	(gr_line
		(start 139.836398 -147.973796)
		(end 155.63088 -147.973796)
		(stroke
			(width 0.381)
			(type default)
		)
		(layer "In1.Cu")
	)
	(gr_line
		(start 140.298678 -23.35022)
		(end 140.298678 -21.950426)
		(stroke
			(width 0.2)
			(type default)
		)
		(layer "In1.Cu")
	)
	(gr_arc
		(start 140.298678 -21.950426)
		(mid 139.750165 -21.401532)
		(end 139.201398 -21.950172)
		(stroke
			(width 0.2)
			(type default)
		)
		(layer "In1.Cu")
	)
	(gr_line
		(start 140.298678 -19.750024)
		(end 140.298678 -18.350484)
		(stroke
			(width 0.2)
			(type default)
		)
		(layer "In1.Cu")
	)
	(gr_arc
		(start 140.298678 -18.350484)
		(mid 139.750165 -17.80159)
		(end 139.201398 -18.35023)
		(stroke
			(width 0.2)
			(type default)
		)
		(layer "In1.Cu")
	)
	(gr_arc
		(start 141.001242 -22.350222)
		(mid 141.549882 -22.898862)
		(end 142.098522 -22.350222)
		(stroke
			(width 0.2)
			(type default)
		)
		(layer "In1.Cu")
	)
	(gr_line
		(start 141.001242 -20.950174)
		(end 141.001242 -22.350222)
		(stroke
			(width 0.2)
			(type default)
		)
		(layer "In1.Cu")
	)
	(gr_arc
		(start 141.001242 -18.750026)
		(mid 141.549882 -19.298666)
		(end 142.098522 -18.750026)
		(stroke
			(width 0.2)
			(type default)
		)
		(layer "In1.Cu")
	)
	(gr_line
		(start 141.001242 -17.349978)
		(end 141.001242 -18.750026)
		(stroke
			(width 0.2)
			(type default)
		)
		(layer "In1.Cu")
	)
	(gr_line
		(start 141.589506 -126.3904)
		(end 137.9728 -130.007106)
		(stroke
			(width 0.381)
			(type default)
		)
		(layer "In1.Cu")
	)
	(gr_line
		(start 142.098522 -22.350222)
		(end 142.098522 -20.950428)
		(stroke
			(width 0.2)
			(type default)
		)
		(layer "In1.Cu")
	)
	(gr_arc
		(start 142.098522 -20.950428)
		(mid 141.550009 -20.401534)
		(end 141.001242 -20.950174)
		(stroke
			(width 0.2)
			(type default)
		)
		(layer "In1.Cu")
	)
	(gr_line
		(start 142.098522 -18.750026)
		(end 142.098522 -17.350232)
		(stroke
			(width 0.2)
			(type default)
		)
		(layer "In1.Cu")
	)
	(gr_arc
		(start 142.098522 -17.350232)
		(mid 141.550009 -16.801338)
		(end 141.001242 -17.349978)
		(stroke
			(width 0.2)
			(type default)
		)
		(layer "In1.Cu")
	)
	(gr_arc
		(start 142.80134 -30.550104)
		(mid 143.34998 -31.098744)
		(end 143.89862 -30.550104)
		(stroke
			(width 0.2)
			(type default)
		)
		(layer "In1.Cu")
	)
	(gr_line
		(start 142.80134 -29.150056)
		(end 142.80134 -30.550104)
		(stroke
			(width 0.2)
			(type default)
		)
		(layer "In1.Cu")
	)
	(gr_arc
		(start 142.80134 -23.35022)
		(mid 143.34998 -23.89886)
		(end 143.89862 -23.35022)
		(stroke
			(width 0.2)
			(type default)
		)
		(layer "In1.Cu")
	)
	(gr_line
		(start 142.80134 -21.950172)
		(end 142.80134 -23.35022)
		(stroke
			(width 0.2)
			(type default)
		)
		(layer "In1.Cu")
	)
	(gr_arc
		(start 142.80134 -19.750024)
		(mid 143.34998 -20.298664)
		(end 143.89862 -19.750024)
		(stroke
			(width 0.2)
			(type default)
		)
		(layer "In1.Cu")
	)
	(gr_line
		(start 142.80134 -18.35023)
		(end 142.80134 -19.750024)
		(stroke
			(width 0.2)
			(type default)
		)
		(layer "In1.Cu")
	)
	(gr_line
		(start 143.89862 -30.550104)
		(end 143.89862 -29.15031)
		(stroke
			(width 0.2)
			(type default)
		)
		(layer "In1.Cu")
	)
	(gr_arc
		(start 143.89862 -29.15031)
		(mid 143.350107 -28.601416)
		(end 142.80134 -29.150056)
		(stroke
			(width 0.2)
			(type default)
		)
		(layer "In1.Cu")
	)
	(gr_line
		(start 143.89862 -23.35022)
		(end 143.89862 -21.950426)
		(stroke
			(width 0.2)
			(type default)
		)
		(layer "In1.Cu")
	)
	(gr_arc
		(start 143.89862 -21.950426)
		(mid 143.350107 -21.401532)
		(end 142.80134 -21.950172)
		(stroke
			(width 0.2)
			(type default)
		)
		(layer "In1.Cu")
	)
	(gr_line
		(start 143.89862 -19.750024)
		(end 143.89862 -18.350484)
		(stroke
			(width 0.2)
			(type default)
		)
		(layer "In1.Cu")
	)
	(gr_arc
		(start 143.89862 -18.350484)
		(mid 143.350107 -17.80159)
		(end 142.80134 -18.35023)
		(stroke
			(width 0.2)
			(type default)
		)
		(layer "In1.Cu")
	)
	(gr_arc
		(start 148.999956 -14.99997)
		(mid 149.707061 -14.707077)
		(end 149.999954 -13.999972)
		(stroke
			(width 1.524)
			(type default)
		)
		(layer "In1.Cu")
	)
	(gr_line
		(start 149.999954 -13.999972)
		(end 149.999954 -0.999998)
		(stroke
			(width 1.524)
			(type default)
		)
		(layer "In1.Cu")
	)
	(gr_arc
		(start 150.999952 0)
		(mid 150.292877 -0.292909)
		(end 149.999954 -0.999998)
		(stroke
			(width 1.524)
			(type default)
		)
		(layer "In1.Cu")
	)
	(gr_line
		(start 150.999952 0)
		(end 199.00011 0)
		(stroke
			(width 1.524)
			(type default)
		)
		(layer "In1.Cu")
	)
	(gr_line
		(start 153.0858 -126.3904)
		(end 141.589506 -126.3904)
		(stroke
			(width 0.381)
			(type default)
		)
		(layer "In1.Cu")
	)
	(gr_line
		(start 155.043886 -279.350216)
		(end 155.043886 -276.149816)
		(stroke
			(width 0.2)
			(type default)
		)
		(layer "In1.Cu")
	)
	(gr_rect
		(start 155.043886 -276.810216)
		(end 157.406086 -278.689816)
		(stroke
			(width 0)
			(type default)
		)
		(fill no)
		(layer "In1.Cu")
	)
	(gr_line
		(start 155.043886 -276.149816)
		(end 157.406086 -276.149816)
		(stroke
			(width 0.2)
			(type default)
		)
		(layer "In1.Cu")
	)
	(gr_line
		(start 155.043886 -275.540216)
		(end 155.043886 -272.339816)
		(stroke
			(width 0.2)
			(type default)
		)
		(layer "In1.Cu")
	)
	(gr_rect
		(start 155.043886 -273.000216)
		(end 157.406086 -274.879816)
		(stroke
			(width 0)
			(type default)
		)
		(fill no)
		(layer "In1.Cu")
	)
	(gr_line
		(start 155.043886 -272.339816)
		(end 157.406086 -272.340578)
		(stroke
			(width 0.2)
			(type default)
		)
		(layer "In1.Cu")
	)
	(gr_line
		(start 155.043886 -164.350192)
		(end 155.043886 -161.149792)
		(stroke
			(width 0.2)
			(type default)
		)
		(layer "In1.Cu")
	)
	(gr_rect
		(start 155.043886 -161.810192)
		(end 157.406086 -163.689792)
		(stroke
			(width 0)
			(type default)
		)
		(fill no)
		(layer "In1.Cu")
	)
	(gr_line
		(start 155.043886 -161.149792)
		(end 157.406086 -161.149792)
		(stroke
			(width 0.2)
			(type default)
		)
		(layer "In1.Cu")
	)
	(gr_line
		(start 155.043886 -160.540192)
		(end 155.043886 -157.339792)
		(stroke
			(width 0.2)
			(type default)
		)
		(layer "In1.Cu")
	)
	(gr_rect
		(start 155.043886 -158.000192)
		(end 157.406086 -159.879792)
		(stroke
			(width 0)
			(type default)
		)
		(fill no)
		(layer "In1.Cu")
	)
	(gr_line
		(start 155.043886 -157.339792)
		(end 157.406086 -157.340554)
		(stroke
			(width 0.2)
			(type default)
		)
		(layer "In1.Cu")
	)
	(gr_line
		(start 155.043886 -49.350168)
		(end 155.043886 -46.149768)
		(stroke
			(width 0.2)
			(type default)
		)
		(layer "In1.Cu")
	)
	(gr_rect
		(start 155.043886 -46.810168)
		(end 157.406086 -48.689768)
		(stroke
			(width 0)
			(type default)
		)
		(fill no)
		(layer "In1.Cu")
	)
	(gr_line
		(start 155.043886 -46.149768)
		(end 157.406086 -46.149768)
		(stroke
			(width 0.2)
			(type default)
		)
		(layer "In1.Cu")
	)
	(gr_line
		(start 155.043886 -45.540168)
		(end 155.043886 -42.339768)
		(stroke
			(width 0.2)
			(type default)
		)
		(layer "In1.Cu")
	)
	(gr_rect
		(start 155.043886 -43.000168)
		(end 157.406086 -44.879768)
		(stroke
			(width 0)
			(type default)
		)
		(fill no)
		(layer "In1.Cu")
	)
	(gr_line
		(start 155.043886 -42.339768)
		(end 157.406086 -42.34053)
		(stroke
			(width 0.2)
			(type default)
		)
		(layer "In1.Cu")
	)
	(gr_line
		(start 155.63088 -147.973796)
		(end 159.893 -143.711676)
		(stroke
			(width 0.381)
			(type default)
		)
		(layer "In1.Cu")
	)
	(gr_line
		(start 156.8958 -131.826)
		(end 156.8958 -130.2004)
		(stroke
			(width 0.381)
			(type default)
		)
		(layer "In1.Cu")
	)
	(gr_line
		(start 156.8958 -130.2004)
		(end 153.0858 -126.3904)
		(stroke
			(width 0.381)
			(type default)
		)
		(layer "In1.Cu")
	)
	(gr_line
		(start 157.406086 -279.350216)
		(end 155.043886 -279.350216)
		(stroke
			(width 0.2)
			(type default)
		)
		(layer "In1.Cu")
	)
	(gr_line
		(start 157.406086 -276.149816)
		(end 157.406086 -279.350216)
		(stroke
			(width 0.2)
			(type default)
		)
		(layer "In1.Cu")
	)
	(gr_line
		(start 157.406086 -275.540216)
		(end 155.043886 -275.540216)
		(stroke
			(width 0.2)
			(type default)
		)
		(layer "In1.Cu")
	)
	(gr_line
		(start 157.406086 -272.340578)
		(end 157.406086 -275.540216)
		(stroke
			(width 0.2)
			(type default)
		)
		(layer "In1.Cu")
	)
	(gr_line
		(start 157.406086 -164.350192)
		(end 155.043886 -164.350192)
		(stroke
			(width 0.2)
			(type default)
		)
		(layer "In1.Cu")
	)
	(gr_line
		(start 157.406086 -161.149792)
		(end 157.406086 -164.350192)
		(stroke
			(width 0.2)
			(type default)
		)
		(layer "In1.Cu")
	)
	(gr_line
		(start 157.406086 -160.540192)
		(end 155.043886 -160.540192)
		(stroke
			(width 0.2)
			(type default)
		)
		(layer "In1.Cu")
	)
	(gr_line
		(start 157.406086 -157.340554)
		(end 157.406086 -160.540192)
		(stroke
			(width 0.2)
			(type default)
		)
		(layer "In1.Cu")
	)
	(gr_line
		(start 157.406086 -49.350168)
		(end 155.043886 -49.350168)
		(stroke
			(width 0.2)
			(type default)
		)
		(layer "In1.Cu")
	)
	(gr_line
		(start 157.406086 -46.149768)
		(end 157.406086 -49.350168)
		(stroke
			(width 0.2)
			(type default)
		)
		(layer "In1.Cu")
	)
	(gr_line
		(start 157.406086 -45.540168)
		(end 155.043886 -45.540168)
		(stroke
			(width 0.2)
			(type default)
		)
		(layer "In1.Cu")
	)
	(gr_line
		(start 157.406086 -42.34053)
		(end 157.406086 -45.540168)
		(stroke
			(width 0.2)
			(type default)
		)
		(layer "In1.Cu")
	)
	(gr_arc
		(start 158.206186 -274.321016)
		(mid 158.221065 -274.356937)
		(end 158.256986 -274.371816)
		(stroke
			(width 0.2)
			(type default)
		)
		(layer "In1.Cu")
	)
	(gr_line
		(start 158.206186 -274.117816)
		(end 158.206186 -274.321016)
		(stroke
			(width 0.2)
			(type default)
		)
		(layer "In1.Cu")
	)
	(gr_arc
		(start 158.206186 -273.762216)
		(mid 158.221065 -273.798137)
		(end 158.256986 -273.813016)
		(stroke
			(width 0.2)
			(type default)
		)
		(layer "In1.Cu")
	)
	(gr_line
		(start 158.206186 -273.559016)
		(end 158.206186 -273.762216)
		(stroke
			(width 0.2)
			(type default)
		)
		(layer "In1.Cu")
	)
	(gr_arc
		(start 158.206186 -159.320992)
		(mid 158.221065 -159.356913)
		(end 158.256986 -159.371792)
		(stroke
			(width 0.2)
			(type default)
		)
		(layer "In1.Cu")
	)
	(gr_line
		(start 158.206186 -159.117792)
		(end 158.206186 -159.320992)
		(stroke
			(width 0.2)
			(type default)
		)
		(layer "In1.Cu")
	)
	(gr_arc
		(start 158.206186 -158.762192)
		(mid 158.221065 -158.798113)
		(end 158.256986 -158.812992)
		(stroke
			(width 0.2)
			(type default)
		)
		(layer "In1.Cu")
	)
	(gr_line
		(start 158.206186 -158.558992)
		(end 158.206186 -158.762192)
		(stroke
			(width 0.2)
			(type default)
		)
		(layer "In1.Cu")
	)
	(gr_arc
		(start 158.206186 -44.320968)
		(mid 158.221065 -44.356889)
		(end 158.256986 -44.371768)
		(stroke
			(width 0.2)
			(type default)
		)
		(layer "In1.Cu")
	)
	(gr_line
		(start 158.206186 -44.117768)
		(end 158.206186 -44.320968)
		(stroke
			(width 0.2)
			(type default)
		)
		(layer "In1.Cu")
	)
	(gr_arc
		(start 158.206186 -43.762168)
		(mid 158.221065 -43.798089)
		(end 158.256986 -43.812968)
		(stroke
			(width 0.2)
			(type default)
		)
		(layer "In1.Cu")
	)
	(gr_line
		(start 158.206186 -43.558968)
		(end 158.206186 -43.762168)
		(stroke
			(width 0.2)
			(type default)
		)
		(layer "In1.Cu")
	)
	(gr_line
		(start 158.256986 -274.371816)
		(end 159.069786 -274.371816)
		(stroke
			(width 0.2)
			(type default)
		)
		(layer "In1.Cu")
	)
	(gr_arc
		(start 158.256986 -274.067016)
		(mid 158.221065 -274.081895)
		(end 158.206186 -274.117816)
		(stroke
			(width 0.2)
			(type default)
		)
		(layer "In1.Cu")
	)
	(gr_line
		(start 158.256986 -273.813016)
		(end 159.069786 -273.813016)
		(stroke
			(width 0.2)
			(type default)
		)
		(layer "In1.Cu")
	)
	(gr_arc
		(start 158.256986 -273.508216)
		(mid 158.221065 -273.523095)
		(end 158.206186 -273.559016)
		(stroke
			(width 0.2)
			(type default)
		)
		(layer "In1.Cu")
	)
	(gr_line
		(start 158.256986 -159.371792)
		(end 159.069786 -159.371792)
		(stroke
			(width 0.2)
			(type default)
		)
		(layer "In1.Cu")
	)
	(gr_arc
		(start 158.256986 -159.066992)
		(mid 158.221065 -159.081871)
		(end 158.206186 -159.117792)
		(stroke
			(width 0.2)
			(type default)
		)
		(layer "In1.Cu")
	)
	(gr_line
		(start 158.256986 -158.812992)
		(end 159.069786 -158.812992)
		(stroke
			(width 0.2)
			(type default)
		)
		(layer "In1.Cu")
	)
	(gr_arc
		(start 158.256986 -158.508192)
		(mid 158.221065 -158.523071)
		(end 158.206186 -158.558992)
		(stroke
			(width 0.2)
			(type default)
		)
		(layer "In1.Cu")
	)
	(gr_line
		(start 158.256986 -44.371768)
		(end 159.069786 -44.371768)
		(stroke
			(width 0.2)
			(type default)
		)
		(layer "In1.Cu")
	)
	(gr_arc
		(start 158.256986 -44.066968)
		(mid 158.221065 -44.081847)
		(end 158.206186 -44.117768)
		(stroke
			(width 0.2)
			(type default)
		)
		(layer "In1.Cu")
	)
	(gr_line
		(start 158.256986 -43.812968)
		(end 159.069786 -43.812968)
		(stroke
			(width 0.2)
			(type default)
		)
		(layer "In1.Cu")
	)
	(gr_arc
		(start 158.256986 -43.508168)
		(mid 158.221065 -43.523047)
		(end 158.206186 -43.558968)
		(stroke
			(width 0.2)
			(type default)
		)
		(layer "In1.Cu")
	)
	(gr_arc
		(start 158.327852 -278.321516)
		(mid 158.708852 -278.702516)
		(end 159.089852 -278.321516)
		(stroke
			(width 0.2)
			(type default)
		)
		(layer "In1.Cu")
	)
	(gr_line
		(start 158.327852 -277.178516)
		(end 158.327852 -278.321516)
		(stroke
			(width 0.2)
			(type default)
		)
		(layer "In1.Cu")
	)
	(gr_arc
		(start 158.327852 -163.321492)
		(mid 158.708852 -163.702492)
		(end 159.089852 -163.321492)
		(stroke
			(width 0.2)
			(type default)
		)
		(layer "In1.Cu")
	)
	(gr_line
		(start 158.327852 -162.178492)
		(end 158.327852 -163.321492)
		(stroke
			(width 0.2)
			(type default)
		)
		(layer "In1.Cu")
	)
	(gr_arc
		(start 158.327852 -48.321468)
		(mid 158.708852 -48.702468)
		(end 159.089852 -48.321468)
		(stroke
			(width 0.2)
			(type default)
		)
		(layer "In1.Cu")
	)
	(gr_line
		(start 158.327852 -47.178468)
		(end 158.327852 -48.321468)
		(stroke
			(width 0.2)
			(type default)
		)
		(layer "In1.Cu")
	)
	(gr_arc
		(start 159.069786 -274.371816)
		(mid 159.105707 -274.356937)
		(end 159.120586 -274.321016)
		(stroke
			(width 0.2)
			(type default)
		)
		(layer "In1.Cu")
	)
	(gr_line
		(start 159.069786 -274.067016)
		(end 158.256986 -274.067016)
		(stroke
			(width 0.2)
			(type default)
		)
		(layer "In1.Cu")
	)
	(gr_arc
		(start 159.069786 -273.813016)
		(mid 159.105707 -273.798137)
		(end 159.120586 -273.762216)
		(stroke
			(width 0.2)
			(type default)
		)
		(layer "In1.Cu")
	)
	(gr_line
		(start 159.069786 -273.508216)
		(end 158.256986 -273.508216)
		(stroke
			(width 0.2)
			(type default)
		)
		(layer "In1.Cu")
	)
	(gr_arc
		(start 159.069786 -159.371792)
		(mid 159.105707 -159.356913)
		(end 159.120586 -159.320992)
		(stroke
			(width 0.2)
			(type default)
		)
		(layer "In1.Cu")
	)
	(gr_line
		(start 159.069786 -159.066992)
		(end 158.256986 -159.066992)
		(stroke
			(width 0.2)
			(type default)
		)
		(layer "In1.Cu")
	)
	(gr_arc
		(start 159.069786 -158.812992)
		(mid 159.105707 -158.798113)
		(end 159.120586 -158.762192)
		(stroke
			(width 0.2)
			(type default)
		)
		(layer "In1.Cu")
	)
	(gr_line
		(start 159.069786 -158.508192)
		(end 158.256986 -158.508192)
		(stroke
			(width 0.2)
			(type default)
		)
		(layer "In1.Cu")
	)
	(gr_arc
		(start 159.069786 -44.371768)
		(mid 159.105707 -44.356889)
		(end 159.120586 -44.320968)
		(stroke
			(width 0.2)
			(type default)
		)
		(layer "In1.Cu")
	)
	(gr_line
		(start 159.069786 -44.066968)
		(end 158.256986 -44.066968)
		(stroke
			(width 0.2)
			(type default)
		)
		(layer "In1.Cu")
	)
	(gr_arc
		(start 159.069786 -43.812968)
		(mid 159.105707 -43.798089)
		(end 159.120586 -43.762168)
		(stroke
			(width 0.2)
			(type default)
		)
		(layer "In1.Cu")
	)
	(gr_line
		(start 159.069786 -43.508168)
		(end 158.256986 -43.508168)
		(stroke
			(width 0.2)
			(type default)
		)
		(layer "In1.Cu")
	)
	(gr_line
		(start 159.089852 -278.321516)
		(end 159.089852 -277.17877)
		(stroke
			(width 0.2)
			(type default)
		)
		(layer "In1.Cu")
	)
	(gr_arc
		(start 159.089852 -277.17877)
		(mid 158.708979 -276.797516)
		(end 158.327852 -277.178516)
		(stroke
			(width 0.2)
			(type default)
		)
		(layer "In1.Cu")
	)
	(gr_line
		(start 159.089852 -163.321492)
		(end 159.089852 -162.178746)
		(stroke
			(width 0.2)
			(type default)
		)
		(layer "In1.Cu")
	)
	(gr_arc
		(start 159.089852 -162.178746)
		(mid 158.708979 -161.797492)
		(end 158.327852 -162.178492)
		(stroke
			(width 0.2)
			(type default)
		)
		(layer "In1.Cu")
	)
	(gr_line
		(start 159.089852 -48.321468)
		(end 159.089852 -47.178722)
		(stroke
			(width 0.2)
			(type default)
		)
		(layer "In1.Cu")
	)
	(gr_arc
		(start 159.089852 -47.178722)
		(mid 158.708979 -46.797468)
		(end 158.327852 -47.178468)
		(stroke
			(width 0.2)
			(type default)
		)
		(layer "In1.Cu")
	)
	(gr_line
		(start 159.120586 -274.321016)
		(end 159.120586 -274.117816)
		(stroke
			(width 0.2)
			(type default)
		)
		(layer "In1.Cu")
	)
	(gr_arc
		(start 159.120586 -274.117816)
		(mid 159.105707 -274.081895)
		(end 159.069786 -274.067016)
		(stroke
			(width 0.2)
			(type default)
		)
		(layer "In1.Cu")
	)
	(gr_line
		(start 159.120586 -273.762216)
		(end 159.120586 -273.559016)
		(stroke
			(width 0.2)
			(type default)
		)
		(layer "In1.Cu")
	)
	(gr_arc
		(start 159.120586 -273.559016)
		(mid 159.105707 -273.523095)
		(end 159.069786 -273.508216)
		(stroke
			(width 0.2)
			(type default)
		)
		(layer "In1.Cu")
	)
	(gr_line
		(start 159.120586 -159.320992)
		(end 159.120586 -159.117792)
		(stroke
			(width 0.2)
			(type default)
		)
		(layer "In1.Cu")
	)
	(gr_arc
		(start 159.120586 -159.117792)
		(mid 159.105707 -159.081871)
		(end 159.069786 -159.066992)
		(stroke
			(width 0.2)
			(type default)
		)
		(layer "In1.Cu")
	)
	(gr_line
		(start 159.120586 -158.762192)
		(end 159.120586 -158.558992)
		(stroke
			(width 0.2)
			(type default)
		)
		(layer "In1.Cu")
	)
	(gr_arc
		(start 159.120586 -158.558992)
		(mid 159.105707 -158.523071)
		(end 159.069786 -158.508192)
		(stroke
			(width 0.2)
			(type default)
		)
		(layer "In1.Cu")
	)
	(gr_line
		(start 159.120586 -44.320968)
		(end 159.120586 -44.117768)
		(stroke
			(width 0.2)
			(type default)
		)
		(layer "In1.Cu")
	)
	(gr_arc
		(start 159.120586 -44.117768)
		(mid 159.105707 -44.081847)
		(end 159.069786 -44.066968)
		(stroke
			(width 0.2)
			(type default)
		)
		(layer "In1.Cu")
	)
	(gr_line
		(start 159.120586 -43.762168)
		(end 159.120586 -43.558968)
		(stroke
			(width 0.2)
			(type default)
		)
		(layer "In1.Cu")
	)
	(gr_arc
		(start 159.120586 -43.558968)
		(mid 159.105707 -43.523047)
		(end 159.069786 -43.508168)
		(stroke
			(width 0.2)
			(type default)
		)
		(layer "In1.Cu")
	)
	(gr_line
		(start 159.893 -143.711676)
		(end 159.893 -134.8232)
		(stroke
			(width 0.381)
			(type default)
		)
		(layer "In1.Cu")
	)
	(gr_line
		(start 159.893 -134.8232)
		(end 156.8958 -131.826)
		(stroke
			(width 0.381)
			(type default)
		)
		(layer "In1.Cu")
	)
	(gr_line
		(start 186.593988 -279.350216)
		(end 186.593988 -276.149816)
		(stroke
			(width 0.2)
			(type default)
		)
		(layer "In1.Cu")
	)
	(gr_rect
		(start 186.593988 -276.810216)
		(end 188.956188 -278.689816)
		(stroke
			(width 0)
			(type default)
		)
		(fill no)
		(layer "In1.Cu")
	)
	(gr_line
		(start 186.593988 -276.149816)
		(end 188.956188 -276.149816)
		(stroke
			(width 0.2)
			(type default)
		)
		(layer "In1.Cu")
	)
	(gr_line
		(start 186.593988 -275.540216)
		(end 186.593988 -272.339816)
		(stroke
			(width 0.2)
			(type default)
		)
		(layer "In1.Cu")
	)
	(gr_rect
		(start 186.593988 -273.000216)
		(end 188.956188 -274.879816)
		(stroke
			(width 0)
			(type default)
		)
		(fill no)
		(layer "In1.Cu")
	)
	(gr_line
		(start 186.593988 -272.339816)
		(end 188.956188 -272.340578)
		(stroke
			(width 0.2)
			(type default)
		)
		(layer "In1.Cu")
	)
	(gr_line
		(start 186.593988 -164.350192)
		(end 186.593988 -161.149792)
		(stroke
			(width 0.2)
			(type default)
		)
		(layer "In1.Cu")
	)
	(gr_rect
		(start 186.593988 -161.810192)
		(end 188.956188 -163.689792)
		(stroke
			(width 0)
			(type default)
		)
		(fill no)
		(layer "In1.Cu")
	)
	(gr_line
		(start 186.593988 -161.149792)
		(end 188.956188 -161.149792)
		(stroke
			(width 0.2)
			(type default)
		)
		(layer "In1.Cu")
	)
	(gr_line
		(start 186.593988 -160.540192)
		(end 186.593988 -157.339792)
		(stroke
			(width 0.2)
			(type default)
		)
		(layer "In1.Cu")
	)
	(gr_rect
		(start 186.593988 -158.000192)
		(end 188.956188 -159.879792)
		(stroke
			(width 0)
			(type default)
		)
		(fill no)
		(layer "In1.Cu")
	)
	(gr_line
		(start 186.593988 -157.339792)
		(end 188.956188 -157.340554)
		(stroke
			(width 0.2)
			(type default)
		)
		(layer "In1.Cu")
	)
	(gr_line
		(start 186.593988 -49.350168)
		(end 186.593988 -46.149768)
		(stroke
			(width 0.2)
			(type default)
		)
		(layer "In1.Cu")
	)
	(gr_rect
		(start 186.593988 -46.810168)
		(end 188.956188 -48.689768)
		(stroke
			(width 0)
			(type default)
		)
		(fill no)
		(layer "In1.Cu")
	)
	(gr_line
		(start 186.593988 -46.149768)
		(end 188.956188 -46.149768)
		(stroke
			(width 0.2)
			(type default)
		)
		(layer "In1.Cu")
	)
	(gr_line
		(start 186.593988 -45.540168)
		(end 186.593988 -42.339768)
		(stroke
			(width 0.2)
			(type default)
		)
		(layer "In1.Cu")
	)
	(gr_rect
		(start 186.593988 -43.000168)
		(end 188.956188 -44.879768)
		(stroke
			(width 0)
			(type default)
		)
		(fill no)
		(layer "In1.Cu")
	)
	(gr_line
		(start 186.593988 -42.339768)
		(end 188.956188 -42.34053)
		(stroke
			(width 0.2)
			(type default)
		)
		(layer "In1.Cu")
	)
	(gr_line
		(start 188.956188 -279.350216)
		(end 186.593988 -279.350216)
		(stroke
			(width 0.2)
			(type default)
		)
		(layer "In1.Cu")
	)
	(gr_line
		(start 188.956188 -276.149816)
		(end 188.956188 -279.350216)
		(stroke
			(width 0.2)
			(type default)
		)
		(layer "In1.Cu")
	)
	(gr_line
		(start 188.956188 -275.540216)
		(end 186.593988 -275.540216)
		(stroke
			(width 0.2)
			(type default)
		)
		(layer "In1.Cu")
	)
	(gr_line
		(start 188.956188 -272.340578)
		(end 188.956188 -275.540216)
		(stroke
			(width 0.2)
			(type default)
		)
		(layer "In1.Cu")
	)
	(gr_line
		(start 188.956188 -164.350192)
		(end 186.593988 -164.350192)
		(stroke
			(width 0.2)
			(type default)
		)
		(layer "In1.Cu")
	)
	(gr_line
		(start 188.956188 -161.149792)
		(end 188.956188 -164.350192)
		(stroke
			(width 0.2)
			(type default)
		)
		(layer "In1.Cu")
	)
	(gr_line
		(start 188.956188 -160.540192)
		(end 186.593988 -160.540192)
		(stroke
			(width 0.2)
			(type default)
		)
		(layer "In1.Cu")
	)
	(gr_line
		(start 188.956188 -157.340554)
		(end 188.956188 -160.540192)
		(stroke
			(width 0.2)
			(type default)
		)
		(layer "In1.Cu")
	)
	(gr_line
		(start 188.956188 -49.350168)
		(end 186.593988 -49.350168)
		(stroke
			(width 0.2)
			(type default)
		)
		(layer "In1.Cu")
	)
	(gr_line
		(start 188.956188 -46.149768)
		(end 188.956188 -49.350168)
		(stroke
			(width 0.2)
			(type default)
		)
		(layer "In1.Cu")
	)
	(gr_line
		(start 188.956188 -45.540168)
		(end 186.593988 -45.540168)
		(stroke
			(width 0.2)
			(type default)
		)
		(layer "In1.Cu")
	)
	(gr_line
		(start 188.956188 -42.34053)
		(end 188.956188 -45.540168)
		(stroke
			(width 0.2)
			(type default)
		)
		(layer "In1.Cu")
	)
	(gr_line
		(start 189.6999 -349.199962)
		(end 0.999998 -349.199962)
		(stroke
			(width 1.524)
			(type default)
		)
		(layer "In1.Cu")
	)
	(gr_arc
		(start 189.756288 -274.321016)
		(mid 189.771167 -274.356937)
		(end 189.807088 -274.371816)
		(stroke
			(width 0.2)
			(type default)
		)
		(layer "In1.Cu")
	)
	(gr_line
		(start 189.756288 -274.117816)
		(end 189.756288 -274.321016)
		(stroke
			(width 0.2)
			(type default)
		)
		(layer "In1.Cu")
	)
	(gr_arc
		(start 189.756288 -273.762216)
		(mid 189.771167 -273.798137)
		(end 189.807088 -273.813016)
		(stroke
			(width 0.2)
			(type default)
		)
		(layer "In1.Cu")
	)
	(gr_line
		(start 189.756288 -273.559016)
		(end 189.756288 -273.762216)
		(stroke
			(width 0.2)
			(type default)
		)
		(layer "In1.Cu")
	)
	(gr_arc
		(start 189.756288 -159.320992)
		(mid 189.771167 -159.356913)
		(end 189.807088 -159.371792)
		(stroke
			(width 0.2)
			(type default)
		)
		(layer "In1.Cu")
	)
	(gr_line
		(start 189.756288 -159.117792)
		(end 189.756288 -159.320992)
		(stroke
			(width 0.2)
			(type default)
		)
		(layer "In1.Cu")
	)
	(gr_arc
		(start 189.756288 -158.762192)
		(mid 189.771167 -158.798113)
		(end 189.807088 -158.812992)
		(stroke
			(width 0.2)
			(type default)
		)
		(layer "In1.Cu")
	)
	(gr_line
		(start 189.756288 -158.558992)
		(end 189.756288 -158.762192)
		(stroke
			(width 0.2)
			(type default)
		)
		(layer "In1.Cu")
	)
	(gr_arc
		(start 189.756288 -44.320968)
		(mid 189.771167 -44.356889)
		(end 189.807088 -44.371768)
		(stroke
			(width 0.2)
			(type default)
		)
		(layer "In1.Cu")
	)
	(gr_line
		(start 189.756288 -44.117768)
		(end 189.756288 -44.320968)
		(stroke
			(width 0.2)
			(type default)
		)
		(layer "In1.Cu")
	)
	(gr_arc
		(start 189.756288 -43.762168)
		(mid 189.771167 -43.798089)
		(end 189.807088 -43.812968)
		(stroke
			(width 0.2)
			(type default)
		)
		(layer "In1.Cu")
	)
	(gr_line
		(start 189.756288 -43.558968)
		(end 189.756288 -43.762168)
		(stroke
			(width 0.2)
			(type default)
		)
		(layer "In1.Cu")
	)
	(gr_line
		(start 189.807088 -274.371816)
		(end 190.619888 -274.371816)
		(stroke
			(width 0.2)
			(type default)
		)
		(layer "In1.Cu")
	)
	(gr_arc
		(start 189.807088 -274.067016)
		(mid 189.771167 -274.081895)
		(end 189.756288 -274.117816)
		(stroke
			(width 0.2)
			(type default)
		)
		(layer "In1.Cu")
	)
	(gr_line
		(start 189.807088 -273.813016)
		(end 190.619888 -273.813016)
		(stroke
			(width 0.2)
			(type default)
		)
		(layer "In1.Cu")
	)
	(gr_arc
		(start 189.807088 -273.508216)
		(mid 189.771167 -273.523095)
		(end 189.756288 -273.559016)
		(stroke
			(width 0.2)
			(type default)
		)
		(layer "In1.Cu")
	)
	(gr_line
		(start 189.807088 -159.371792)
		(end 190.619888 -159.371792)
		(stroke
			(width 0.2)
			(type default)
		)
		(layer "In1.Cu")
	)
	(gr_arc
		(start 189.807088 -159.066992)
		(mid 189.771167 -159.081871)
		(end 189.756288 -159.117792)
		(stroke
			(width 0.2)
			(type default)
		)
		(layer "In1.Cu")
	)
	(gr_line
		(start 189.807088 -158.812992)
		(end 190.619888 -158.812992)
		(stroke
			(width 0.2)
			(type default)
		)
		(layer "In1.Cu")
	)
	(gr_arc
		(start 189.807088 -158.508192)
		(mid 189.771167 -158.523071)
		(end 189.756288 -158.558992)
		(stroke
			(width 0.2)
			(type default)
		)
		(layer "In1.Cu")
	)
	(gr_line
		(start 189.807088 -44.371768)
		(end 190.619888 -44.371768)
		(stroke
			(width 0.2)
			(type default)
		)
		(layer "In1.Cu")
	)
	(gr_arc
		(start 189.807088 -44.066968)
		(mid 189.771167 -44.081847)
		(end 189.756288 -44.117768)
		(stroke
			(width 0.2)
			(type default)
		)
		(layer "In1.Cu")
	)
	(gr_line
		(start 189.807088 -43.812968)
		(end 190.619888 -43.812968)
		(stroke
			(width 0.2)
			(type default)
		)
		(layer "In1.Cu")
	)
	(gr_arc
		(start 189.807088 -43.508168)
		(mid 189.771167 -43.523047)
		(end 189.756288 -43.558968)
		(stroke
			(width 0.2)
			(type default)
		)
		(layer "In1.Cu")
	)
	(gr_arc
		(start 189.877954 -278.321516)
		(mid 190.258954 -278.702516)
		(end 190.639954 -278.321516)
		(stroke
			(width 0.2)
			(type default)
		)
		(layer "In1.Cu")
	)
	(gr_line
		(start 189.877954 -277.178516)
		(end 189.877954 -278.321516)
		(stroke
			(width 0.2)
			(type default)
		)
		(layer "In1.Cu")
	)
	(gr_arc
		(start 189.877954 -163.321492)
		(mid 190.258954 -163.702492)
		(end 190.639954 -163.321492)
		(stroke
			(width 0.2)
			(type default)
		)
		(layer "In1.Cu")
	)
	(gr_line
		(start 189.877954 -162.178492)
		(end 189.877954 -163.321492)
		(stroke
			(width 0.2)
			(type default)
		)
		(layer "In1.Cu")
	)
	(gr_arc
		(start 189.877954 -48.321468)
		(mid 190.258954 -48.702468)
		(end 190.639954 -48.321468)
		(stroke
			(width 0.2)
			(type default)
		)
		(layer "In1.Cu")
	)
	(gr_line
		(start 189.877954 -47.178468)
		(end 189.877954 -48.321468)
		(stroke
			(width 0.2)
			(type default)
		)
		(layer "In1.Cu")
	)
	(gr_arc
		(start 190.619888 -274.371816)
		(mid 190.655809 -274.356937)
		(end 190.670688 -274.321016)
		(stroke
			(width 0.2)
			(type default)
		)
		(layer "In1.Cu")
	)
	(gr_line
		(start 190.619888 -274.067016)
		(end 189.807088 -274.067016)
		(stroke
			(width 0.2)
			(type default)
		)
		(layer "In1.Cu")
	)
	(gr_arc
		(start 190.619888 -273.813016)
		(mid 190.655809 -273.798137)
		(end 190.670688 -273.762216)
		(stroke
			(width 0.2)
			(type default)
		)
		(layer "In1.Cu")
	)
	(gr_line
		(start 190.619888 -273.508216)
		(end 189.807088 -273.508216)
		(stroke
			(width 0.2)
			(type default)
		)
		(layer "In1.Cu")
	)
	(gr_arc
		(start 190.619888 -159.371792)
		(mid 190.655809 -159.356913)
		(end 190.670688 -159.320992)
		(stroke
			(width 0.2)
			(type default)
		)
		(layer "In1.Cu")
	)
	(gr_line
		(start 190.619888 -159.066992)
		(end 189.807088 -159.066992)
		(stroke
			(width 0.2)
			(type default)
		)
		(layer "In1.Cu")
	)
	(gr_arc
		(start 190.619888 -158.812992)
		(mid 190.655809 -158.798113)
		(end 190.670688 -158.762192)
		(stroke
			(width 0.2)
			(type default)
		)
		(layer "In1.Cu")
	)
	(gr_line
		(start 190.619888 -158.508192)
		(end 189.807088 -158.508192)
		(stroke
			(width 0.2)
			(type default)
		)
		(layer "In1.Cu")
	)
	(gr_arc
		(start 190.619888 -44.371768)
		(mid 190.655809 -44.356889)
		(end 190.670688 -44.320968)
		(stroke
			(width 0.2)
			(type default)
		)
		(layer "In1.Cu")
	)
	(gr_line
		(start 190.619888 -44.066968)
		(end 189.807088 -44.066968)
		(stroke
			(width 0.2)
			(type default)
		)
		(layer "In1.Cu")
	)
	(gr_arc
		(start 190.619888 -43.812968)
		(mid 190.655809 -43.798089)
		(end 190.670688 -43.762168)
		(stroke
			(width 0.2)
			(type default)
		)
		(layer "In1.Cu")
	)
	(gr_line
		(start 190.619888 -43.508168)
		(end 189.807088 -43.508168)
		(stroke
			(width 0.2)
			(type default)
		)
		(layer "In1.Cu")
	)
	(gr_line
		(start 190.639954 -278.321516)
		(end 190.639954 -277.17877)
		(stroke
			(width 0.2)
			(type default)
		)
		(layer "In1.Cu")
	)
	(gr_arc
		(start 190.639954 -277.17877)
		(mid 190.259081 -276.797516)
		(end 189.877954 -277.178516)
		(stroke
			(width 0.2)
			(type default)
		)
		(layer "In1.Cu")
	)
	(gr_line
		(start 190.639954 -163.321492)
		(end 190.639954 -162.178746)
		(stroke
			(width 0.2)
			(type default)
		)
		(layer "In1.Cu")
	)
	(gr_arc
		(start 190.639954 -162.178746)
		(mid 190.259081 -161.797492)
		(end 189.877954 -162.178492)
		(stroke
			(width 0.2)
			(type default)
		)
		(layer "In1.Cu")
	)
	(gr_line
		(start 190.639954 -48.321468)
		(end 190.639954 -47.178722)
		(stroke
			(width 0.2)
			(type default)
		)
		(layer "In1.Cu")
	)
	(gr_arc
		(start 190.639954 -47.178722)
		(mid 190.259081 -46.797468)
		(end 189.877954 -47.178468)
		(stroke
			(width 0.2)
			(type default)
		)
		(layer "In1.Cu")
	)
	(gr_line
		(start 190.670688 -274.321016)
		(end 190.670688 -274.117816)
		(stroke
			(width 0.2)
			(type default)
		)
		(layer "In1.Cu")
	)
	(gr_arc
		(start 190.670688 -274.117816)
		(mid 190.655809 -274.081895)
		(end 190.619888 -274.067016)
		(stroke
			(width 0.2)
			(type default)
		)
		(layer "In1.Cu")
	)
	(gr_line
		(start 190.670688 -273.762216)
		(end 190.670688 -273.559016)
		(stroke
			(width 0.2)
			(type default)
		)
		(layer "In1.Cu")
	)
	(gr_arc
		(start 190.670688 -273.559016)
		(mid 190.655809 -273.523095)
		(end 190.619888 -273.508216)
		(stroke
			(width 0.2)
			(type default)
		)
		(layer "In1.Cu")
	)
	(gr_line
		(start 190.670688 -159.320992)
		(end 190.670688 -159.117792)
		(stroke
			(width 0.2)
			(type default)
		)
		(layer "In1.Cu")
	)
	(gr_arc
		(start 190.670688 -159.117792)
		(mid 190.655809 -159.081871)
		(end 190.619888 -159.066992)
		(stroke
			(width 0.2)
			(type default)
		)
		(layer "In1.Cu")
	)
	(gr_line
		(start 190.670688 -158.762192)
		(end 190.670688 -158.558992)
		(stroke
			(width 0.2)
			(type default)
		)
		(layer "In1.Cu")
	)
	(gr_arc
		(start 190.670688 -158.558992)
		(mid 190.655809 -158.523071)
		(end 190.619888 -158.508192)
		(stroke
			(width 0.2)
			(type default)
		)
		(layer "In1.Cu")
	)
	(gr_line
		(start 190.670688 -44.320968)
		(end 190.670688 -44.117768)
		(stroke
			(width 0.2)
			(type default)
		)
		(layer "In1.Cu")
	)
	(gr_arc
		(start 190.670688 -44.117768)
		(mid 190.655809 -44.081847)
		(end 190.619888 -44.066968)
		(stroke
			(width 0.2)
			(type default)
		)
		(layer "In1.Cu")
	)
	(gr_line
		(start 190.670688 -43.762168)
		(end 190.670688 -43.558968)
		(stroke
			(width 0.2)
			(type default)
		)
		(layer "In1.Cu")
	)
	(gr_arc
		(start 190.670688 -43.558968)
		(mid 190.655809 -43.523047)
		(end 190.619888 -43.508168)
		(stroke
			(width 0.2)
			(type default)
		)
		(layer "In1.Cu")
	)
	(gr_line
		(start 190.699898 -372.000018)
		(end 190.699898 -350.19996)
		(stroke
			(width 1.524)
			(type default)
		)
		(layer "In1.Cu")
	)
	(gr_arc
		(start 190.699898 -372.000018)
		(mid 190.992797 -372.707113)
		(end 191.699896 -373.000016)
		(stroke
			(width 1.524)
			(type default)
		)
		(layer "In1.Cu")
	)
	(gr_arc
		(start 190.699898 -350.19996)
		(mid 190.407005 -349.492855)
		(end 189.6999 -349.199962)
		(stroke
			(width 1.524)
			(type default)
		)
		(layer "In1.Cu")
	)
	(gr_line
		(start 199.00011 -373.000016)
		(end 191.699896 -373.000016)
		(stroke
			(width 1.524)
			(type default)
		)
		(layer "In1.Cu")
	)
	(gr_arc
		(start 199.00011 0)
		(mid 199.707215 0.292893)
		(end 200.000108 0.999998)
		(stroke
			(width 1.524)
			(type default)
		)
		(layer "In1.Cu")
	)
	(gr_line
		(start 200.000108 -420.200074)
		(end 200.000108 -374.000014)
		(stroke
			(width 1.524)
			(type default)
		)
		(layer "In1.Cu")
	)
	(gr_arc
		(start 200.000108 -420.200074)
		(mid 200.292992 -420.907194)
		(end 201.000106 -421.200072)
		(stroke
			(width 1.524)
			(type default)
		)
		(layer "In1.Cu")
	)
	(gr_arc
		(start 200.000108 -374.000014)
		(mid 199.707215 -373.292909)
		(end 199.00011 -373.000016)
		(stroke
			(width 1.524)
			(type default)
		)
		(layer "In1.Cu")
	)
	(gr_arc
		(start 201.000106 1.999996)
		(mid 200.292997 1.707105)
		(end 200.000108 0.999998)
		(stroke
			(width 1.524)
			(type default)
		)
		(layer "In1.Cu")
	)
	(gr_line
		(start 201.000106 1.999996)
		(end 219.00007 1.999996)
		(stroke
			(width 1.524)
			(type default)
		)
		(layer "In1.Cu")
	)
	(gr_arc
		(start 209.451448 -415.600134)
		(mid 210.000088 -416.148774)
		(end 210.548728 -415.600134)
		(stroke
			(width 0.2)
			(type default)
		)
		(layer "In1.Cu")
	)
	(gr_line
		(start 209.451448 -414.200086)
		(end 209.451448 -415.600134)
		(stroke
			(width 0.2)
			(type default)
		)
		(layer "In1.Cu")
	)
	(gr_arc
		(start 209.451448 -412.000192)
		(mid 210.000088 -412.548832)
		(end 210.548728 -412.000192)
		(stroke
			(width 0.2)
			(type default)
		)
		(layer "In1.Cu")
	)
	(gr_line
		(start 209.451448 -410.600144)
		(end 209.451448 -412.000192)
		(stroke
			(width 0.2)
			(type default)
		)
		(layer "In1.Cu")
	)
	(gr_arc
		(start 209.451448 -408.399996)
		(mid 210.000088 -408.948636)
		(end 210.548728 -408.399996)
		(stroke
			(width 0.2)
			(type default)
		)
		(layer "In1.Cu")
	)
	(gr_line
		(start 209.451448 -407.000202)
		(end 209.451448 -408.399996)
		(stroke
			(width 0.2)
			(type default)
		)
		(layer "In1.Cu")
	)
	(gr_line
		(start 210.548728 -415.600134)
		(end 210.548728 -414.20034)
		(stroke
			(width 0.2)
			(type default)
		)
		(layer "In1.Cu")
	)
	(gr_arc
		(start 210.548728 -414.20034)
		(mid 210.000215 -413.651446)
		(end 209.451448 -414.200086)
		(stroke
			(width 0.2)
			(type default)
		)
		(layer "In1.Cu")
	)
	(gr_line
		(start 210.548728 -412.000192)
		(end 210.548728 -410.600398)
		(stroke
			(width 0.2)
			(type default)
		)
		(layer "In1.Cu")
	)
	(gr_arc
		(start 210.548728 -410.600398)
		(mid 210.000215 -410.051504)
		(end 209.451448 -410.600144)
		(stroke
			(width 0.2)
			(type default)
		)
		(layer "In1.Cu")
	)
	(gr_line
		(start 210.548728 -408.399996)
		(end 210.548728 -407.000456)
		(stroke
			(width 0.2)
			(type default)
		)
		(layer "In1.Cu")
	)
	(gr_arc
		(start 210.548728 -407.000456)
		(mid 210.000215 -406.451562)
		(end 209.451448 -407.000202)
		(stroke
			(width 0.2)
			(type default)
		)
		(layer "In1.Cu")
	)
	(gr_arc
		(start 211.251546 -418.200078)
		(mid 211.800186 -418.748718)
		(end 212.348826 -418.200078)
		(stroke
			(width 0.2)
			(type default)
		)
		(layer "In1.Cu")
	)
	(gr_line
		(start 211.251546 -416.80003)
		(end 211.251546 -418.200078)
		(stroke
			(width 0.2)
			(type default)
		)
		(layer "In1.Cu")
	)
	(gr_arc
		(start 211.251546 -407.399998)
		(mid 211.800186 -407.948638)
		(end 212.348826 -407.399998)
		(stroke
			(width 0.2)
			(type default)
		)
		(layer "In1.Cu")
	)
	(gr_line
		(start 211.251546 -405.99995)
		(end 211.251546 -407.399998)
		(stroke
			(width 0.2)
			(type default)
		)
		(layer "In1.Cu")
	)
	(gr_line
		(start 212.348826 -418.200078)
		(end 212.348826 -416.800284)
		(stroke
			(width 0.2)
			(type default)
		)
		(layer "In1.Cu")
	)
	(gr_arc
		(start 212.348826 -416.800284)
		(mid 211.800313 -416.25139)
		(end 211.251546 -416.80003)
		(stroke
			(width 0.2)
			(type default)
		)
		(layer "In1.Cu")
	)
	(gr_line
		(start 212.348826 -407.399998)
		(end 212.348826 -406.000204)
		(stroke
			(width 0.2)
			(type default)
		)
		(layer "In1.Cu")
	)
	(gr_arc
		(start 212.348826 -406.000204)
		(mid 211.800313 -405.45131)
		(end 211.251546 -405.99995)
		(stroke
			(width 0.2)
			(type default)
		)
		(layer "In1.Cu")
	)
	(gr_arc
		(start 213.05139 -415.600134)
		(mid 213.60003 -416.148774)
		(end 214.14867 -415.600134)
		(stroke
			(width 0.2)
			(type default)
		)
		(layer "In1.Cu")
	)
	(gr_line
		(start 213.05139 -414.200086)
		(end 213.05139 -415.600134)
		(stroke
			(width 0.2)
			(type default)
		)
		(layer "In1.Cu")
	)
	(gr_arc
		(start 213.05139 -408.399996)
		(mid 213.60003 -408.948636)
		(end 214.14867 -408.399996)
		(stroke
			(width 0.2)
			(type default)
		)
		(layer "In1.Cu")
	)
	(gr_line
		(start 213.05139 -407.000202)
		(end 213.05139 -408.399996)
		(stroke
			(width 0.2)
			(type default)
		)
		(layer "In1.Cu")
	)
	(gr_line
		(start 214.14867 -415.600134)
		(end 214.14867 -414.20034)
		(stroke
			(width 0.2)
			(type default)
		)
		(layer "In1.Cu")
	)
	(gr_arc
		(start 214.14867 -414.20034)
		(mid 213.600157 -413.651446)
		(end 213.05139 -414.200086)
		(stroke
			(width 0.2)
			(type default)
		)
		(layer "In1.Cu")
	)
	(gr_line
		(start 214.14867 -408.399996)
		(end 214.14867 -407.000456)
		(stroke
			(width 0.2)
			(type default)
		)
		(layer "In1.Cu")
	)
	(gr_arc
		(start 214.14867 -407.000456)
		(mid 213.600157 -406.451562)
		(end 213.05139 -407.000202)
		(stroke
			(width 0.2)
			(type default)
		)
		(layer "In1.Cu")
	)
	(gr_arc
		(start 214.851488 -418.200078)
		(mid 215.400128 -418.748718)
		(end 215.948768 -418.200078)
		(stroke
			(width 0.2)
			(type default)
		)
		(layer "In1.Cu")
	)
	(gr_line
		(start 214.851488 -416.80003)
		(end 214.851488 -418.200078)
		(stroke
			(width 0.2)
			(type default)
		)
		(layer "In1.Cu")
	)
	(gr_arc
		(start 214.851488 -407.399998)
		(mid 215.400128 -407.948638)
		(end 215.948768 -407.399998)
		(stroke
			(width 0.2)
			(type default)
		)
		(layer "In1.Cu")
	)
	(gr_line
		(start 214.851488 -405.99995)
		(end 214.851488 -407.399998)
		(stroke
			(width 0.2)
			(type default)
		)
		(layer "In1.Cu")
	)
	(gr_line
		(start 215.948768 -418.200078)
		(end 215.948768 -416.800284)
		(stroke
			(width 0.2)
			(type default)
		)
		(layer "In1.Cu")
	)
	(gr_arc
		(start 215.948768 -416.800284)
		(mid 215.400255 -416.25139)
		(end 214.851488 -416.80003)
		(stroke
			(width 0.2)
			(type default)
		)
		(layer "In1.Cu")
	)
	(gr_line
		(start 215.948768 -407.399998)
		(end 215.948768 -406.000204)
		(stroke
			(width 0.2)
			(type default)
		)
		(layer "In1.Cu")
	)
	(gr_arc
		(start 215.948768 -406.000204)
		(mid 215.400255 -405.45131)
		(end 214.851488 -405.99995)
		(stroke
			(width 0.2)
			(type default)
		)
		(layer "In1.Cu")
	)
	(gr_arc
		(start 216.651332 -415.600134)
		(mid 217.199972 -416.148774)
		(end 217.748612 -415.600134)
		(stroke
			(width 0.2)
			(type default)
		)
		(layer "In1.Cu")
	)
	(gr_line
		(start 216.651332 -414.200086)
		(end 216.651332 -415.600134)
		(stroke
			(width 0.2)
			(type default)
		)
		(layer "In1.Cu")
	)
	(gr_arc
		(start 216.651332 -408.399996)
		(mid 217.199972 -408.948636)
		(end 217.748612 -408.399996)
		(stroke
			(width 0.2)
			(type default)
		)
		(layer "In1.Cu")
	)
	(gr_line
		(start 216.651332 -407.000202)
		(end 216.651332 -408.399996)
		(stroke
			(width 0.2)
			(type default)
		)
		(layer "In1.Cu")
	)
	(gr_line
		(start 217.748612 -415.600134)
		(end 217.748612 -414.20034)
		(stroke
			(width 0.2)
			(type default)
		)
		(layer "In1.Cu")
	)
	(gr_arc
		(start 217.748612 -414.20034)
		(mid 217.200099 -413.651446)
		(end 216.651332 -414.200086)
		(stroke
			(width 0.2)
			(type default)
		)
		(layer "In1.Cu")
	)
	(gr_line
		(start 217.748612 -408.399996)
		(end 217.748612 -407.000456)
		(stroke
			(width 0.2)
			(type default)
		)
		(layer "In1.Cu")
	)
	(gr_arc
		(start 217.748612 -407.000456)
		(mid 217.200099 -406.451562)
		(end 216.651332 -407.000202)
		(stroke
			(width 0.2)
			(type default)
		)
		(layer "In1.Cu")
	)
	(gr_arc
		(start 218.45143 -418.200078)
		(mid 219.00007 -418.748718)
		(end 219.54871 -418.200078)
		(stroke
			(width 0.2)
			(type default)
		)
		(layer "In1.Cu")
	)
	(gr_line
		(start 218.45143 -416.80003)
		(end 218.45143 -418.200078)
		(stroke
			(width 0.2)
			(type default)
		)
		(layer "In1.Cu")
	)
	(gr_arc
		(start 218.45143 -407.399998)
		(mid 219.00007 -407.948638)
		(end 219.54871 -407.399998)
		(stroke
			(width 0.2)
			(type default)
		)
		(layer "In1.Cu")
	)
	(gr_line
		(start 218.45143 -405.99995)
		(end 218.45143 -407.399998)
		(stroke
			(width 0.2)
			(type default)
		)
		(layer "In1.Cu")
	)
	(gr_arc
		(start 219.00007 1.999996)
		(mid 219.707175 2.292889)
		(end 220.000068 2.999994)
		(stroke
			(width 1.524)
			(type default)
		)
		(layer "In1.Cu")
	)
	(gr_line
		(start 219.54871 -418.200078)
		(end 219.54871 -416.800284)
		(stroke
			(width 0.2)
			(type default)
		)
		(layer "In1.Cu")
	)
	(gr_arc
		(start 219.54871 -416.800284)
		(mid 219.000197 -416.25139)
		(end 218.45143 -416.80003)
		(stroke
			(width 0.2)
			(type default)
		)
		(layer "In1.Cu")
	)
	(gr_line
		(start 219.54871 -407.399998)
		(end 219.54871 -406.000204)
		(stroke
			(width 0.2)
			(type default)
		)
		(layer "In1.Cu")
	)
	(gr_arc
		(start 219.54871 -406.000204)
		(mid 219.000197 -405.45131)
		(end 218.45143 -405.99995)
		(stroke
			(width 0.2)
			(type default)
		)
		(layer "In1.Cu")
	)
	(gr_line
		(start 220.000068 2.999994)
		(end 220.000068 37.800026)
		(stroke
			(width 1.524)
			(type default)
		)
		(layer "In1.Cu")
	)
	(gr_arc
		(start 220.251528 -415.600134)
		(mid 220.800168 -416.148774)
		(end 221.348808 -415.600134)
		(stroke
			(width 0.2)
			(type default)
		)
		(layer "In1.Cu")
	)
	(gr_line
		(start 220.251528 -414.200086)
		(end 220.251528 -415.600134)
		(stroke
			(width 0.2)
			(type default)
		)
		(layer "In1.Cu")
	)
	(gr_arc
		(start 220.251528 -408.399996)
		(mid 220.800168 -408.948636)
		(end 221.348808 -408.399996)
		(stroke
			(width 0.2)
			(type default)
		)
		(layer "In1.Cu")
	)
	(gr_line
		(start 220.251528 -407.000202)
		(end 220.251528 -408.399996)
		(stroke
			(width 0.2)
			(type default)
		)
		(layer "In1.Cu")
	)
	(gr_arc
		(start 221.000066 38.800024)
		(mid 220.292973 38.507121)
		(end 220.000068 37.800026)
		(stroke
			(width 1.524)
			(type default)
		)
		(layer "In1.Cu")
	)
	(gr_line
		(start 221.000066 38.800024)
		(end 298.99991 38.800024)
		(stroke
			(width 1.524)
			(type default)
		)
		(layer "In1.Cu")
	)
	(gr_line
		(start 221.348808 -415.600134)
		(end 221.348808 -414.20034)
		(stroke
			(width 0.2)
			(type default)
		)
		(layer "In1.Cu")
	)
	(gr_arc
		(start 221.348808 -414.20034)
		(mid 220.800295 -413.651446)
		(end 220.251528 -414.200086)
		(stroke
			(width 0.2)
			(type default)
		)
		(layer "In1.Cu")
	)
	(gr_line
		(start 221.348808 -408.399996)
		(end 221.348808 -407.000456)
		(stroke
			(width 0.2)
			(type default)
		)
		(layer "In1.Cu")
	)
	(gr_arc
		(start 221.348808 -407.000456)
		(mid 220.800295 -406.451562)
		(end 220.251528 -407.000202)
		(stroke
			(width 0.2)
			(type default)
		)
		(layer "In1.Cu")
	)
	(gr_arc
		(start 222.051372 -418.200078)
		(mid 222.600012 -418.748718)
		(end 223.148652 -418.200078)
		(stroke
			(width 0.2)
			(type default)
		)
		(layer "In1.Cu")
	)
	(gr_line
		(start 222.051372 -416.80003)
		(end 222.051372 -418.200078)
		(stroke
			(width 0.2)
			(type default)
		)
		(layer "In1.Cu")
	)
	(gr_arc
		(start 222.051372 -407.399998)
		(mid 222.600012 -407.948638)
		(end 223.148652 -407.399998)
		(stroke
			(width 0.2)
			(type default)
		)
		(layer "In1.Cu")
	)
	(gr_line
		(start 222.051372 -405.99995)
		(end 222.051372 -407.399998)
		(stroke
			(width 0.2)
			(type default)
		)
		(layer "In1.Cu")
	)
	(gr_line
		(start 222.758 -389.9408)
		(end 225.6028 -392.7856)
		(stroke
			(width 0.381)
			(type default)
		)
		(layer "In1.Cu")
	)
	(gr_line
		(start 222.758 -385.9276)
		(end 222.758 -389.9408)
		(stroke
			(width 0.381)
			(type default)
		)
		(layer "In1.Cu")
	)
	(gr_line
		(start 223.0628 -385.6228)
		(end 222.758 -385.9276)
		(stroke
			(width 0.381)
			(type default)
		)
		(layer "In1.Cu")
	)
	(gr_line
		(start 223.148652 -418.200078)
		(end 223.148652 -416.800284)
		(stroke
			(width 0.2)
			(type default)
		)
		(layer "In1.Cu")
	)
	(gr_arc
		(start 223.148652 -416.800284)
		(mid 222.600139 -416.25139)
		(end 222.051372 -416.80003)
		(stroke
			(width 0.2)
			(type default)
		)
		(layer "In1.Cu")
	)
	(gr_line
		(start 223.148652 -407.399998)
		(end 223.148652 -406.000204)
		(stroke
			(width 0.2)
			(type default)
		)
		(layer "In1.Cu")
	)
	(gr_arc
		(start 223.148652 -406.000204)
		(mid 222.600139 -405.45131)
		(end 222.051372 -405.99995)
		(stroke
			(width 0.2)
			(type default)
		)
		(layer "In1.Cu")
	)
	(gr_line
		(start 225.6028 -392.7856)
		(end 228.14915 -392.7856)
		(stroke
			(width 0.381)
			(type default)
		)
		(layer "In1.Cu")
	)
	(gr_line
		(start 225.7044 -385.6228)
		(end 223.0628 -385.6228)
		(stroke
			(width 0.381)
			(type default)
		)
		(layer "In1.Cu")
	)
	(gr_line
		(start 226.5934 -384.7338)
		(end 225.7044 -385.6228)
		(stroke
			(width 0.381)
			(type default)
		)
		(layer "In1.Cu")
	)
	(gr_line
		(start 228.14915 -392.7856)
		(end 233.939334 -398.575784)
		(stroke
			(width 0.381)
			(type default)
		)
		(layer "In1.Cu")
	)
	(gr_line
		(start 230.632 -384.7338)
		(end 226.5934 -384.7338)
		(stroke
			(width 0.381)
			(type default)
		)
		(layer "In1.Cu")
	)
	(gr_line
		(start 230.82885 -384.53695)
		(end 230.632 -384.7338)
		(stroke
			(width 0.381)
			(type default)
		)
		(layer "In1.Cu")
	)
	(gr_line
		(start 230.82885 -381.85598)
		(end 230.82885 -384.53695)
		(stroke
			(width 0.381)
			(type default)
		)
		(layer "In1.Cu")
	)
	(gr_line
		(start 233.939334 -398.575784)
		(end 247.681496 -398.575784)
		(stroke
			(width 0.381)
			(type default)
		)
		(layer "In1.Cu")
	)
	(gr_line
		(start 234.19943 -378.4854)
		(end 230.82885 -381.85598)
		(stroke
			(width 0.381)
			(type default)
		)
		(layer "In1.Cu")
	)
	(gr_arc
		(start 235.722922 -121.845578)
		(mid 235.39577 -122.827034)
		(end 236.377226 -123.154186)
		(stroke
			(width 0.2)
			(type default)
		)
		(layer "In1.Cu")
	)
	(gr_line
		(start 235.723938 -65.548002)
		(end 235.725208 -65.550288)
		(stroke
			(width 0.2)
			(type default)
		)
		(layer "In1.Cu")
	)
	(gr_line
		(start 235.724192 -177.848006)
		(end 235.725208 -177.850038)
		(stroke
			(width 0.2)
			(type default)
		)
		(layer "In1.Cu")
	)
	(gr_line
		(start 235.724192 -177.847752)
		(end 235.724192 -177.848006)
		(stroke
			(width 0.2)
			(type default)
		)
		(layer "In1.Cu")
	)
	(gr_line
		(start 235.724192 -173.848014)
		(end 235.725208 -173.850046)
		(stroke
			(width 0.2)
			(type default)
		)
		(layer "In1.Cu")
	)
	(gr_line
		(start 235.724192 -173.84776)
		(end 235.724192 -173.848014)
		(stroke
			(width 0.2)
			(type default)
		)
		(layer "In1.Cu")
	)
	(gr_line
		(start 235.724192 -169.848022)
		(end 235.725208 -169.850054)
		(stroke
			(width 0.2)
			(type default)
		)
		(layer "In1.Cu")
	)
	(gr_line
		(start 235.724192 -169.847768)
		(end 235.724192 -169.848022)
		(stroke
			(width 0.2)
			(type default)
		)
		(layer "In1.Cu")
	)
	(gr_line
		(start 235.724192 -165.84803)
		(end 235.725208 -165.850062)
		(stroke
			(width 0.2)
			(type default)
		)
		(layer "In1.Cu")
	)
	(gr_line
		(start 235.724192 -165.847776)
		(end 235.724192 -165.84803)
		(stroke
			(width 0.2)
			(type default)
		)
		(layer "In1.Cu")
	)
	(gr_line
		(start 235.724192 -137.848086)
		(end 235.725208 -137.850118)
		(stroke
			(width 0.2)
			(type default)
		)
		(layer "In1.Cu")
	)
	(gr_line
		(start 235.724192 -137.847832)
		(end 235.724192 -137.848086)
		(stroke
			(width 0.2)
			(type default)
		)
		(layer "In1.Cu")
	)
	(gr_line
		(start 235.724192 -81.548224)
		(end 235.725208 -81.550256)
		(stroke
			(width 0.2)
			(type default)
		)
		(layer "In1.Cu")
	)
	(gr_line
		(start 235.724192 -81.54797)
		(end 235.724192 -81.548224)
		(stroke
			(width 0.2)
			(type default)
		)
		(layer "In1.Cu")
	)
	(gr_line
		(start 235.724192 -77.548232)
		(end 235.725208 -77.550264)
		(stroke
			(width 0.2)
			(type default)
		)
		(layer "In1.Cu")
	)
	(gr_line
		(start 235.724192 -77.547978)
		(end 235.724192 -77.548232)
		(stroke
			(width 0.2)
			(type default)
		)
		(layer "In1.Cu")
	)
	(gr_line
		(start 235.724192 -73.54824)
		(end 235.725208 -73.550272)
		(stroke
			(width 0.2)
			(type default)
		)
		(layer "In1.Cu")
	)
	(gr_line
		(start 235.724192 -73.547986)
		(end 235.724192 -73.54824)
		(stroke
			(width 0.2)
			(type default)
		)
		(layer "In1.Cu")
	)
	(gr_line
		(start 235.724192 -69.548248)
		(end 235.725208 -69.55028)
		(stroke
			(width 0.2)
			(type default)
		)
		(layer "In1.Cu")
	)
	(gr_line
		(start 235.724192 -69.547994)
		(end 235.724192 -69.548248)
		(stroke
			(width 0.2)
			(type default)
		)
		(layer "In1.Cu")
	)
	(gr_line
		(start 235.724192 -61.548264)
		(end 235.725208 -61.550296)
		(stroke
			(width 0.2)
			(type default)
		)
		(layer "In1.Cu")
	)
	(gr_line
		(start 235.724192 -61.54801)
		(end 235.724192 -61.548264)
		(stroke
			(width 0.2)
			(type default)
		)
		(layer "In1.Cu")
	)
	(gr_line
		(start 235.724192 -57.548272)
		(end 235.725208 -57.550304)
		(stroke
			(width 0.2)
			(type default)
		)
		(layer "In1.Cu")
	)
	(gr_line
		(start 235.724192 -57.548018)
		(end 235.724192 -57.548272)
		(stroke
			(width 0.2)
			(type default)
		)
		(layer "In1.Cu")
	)
	(gr_line
		(start 235.724192 -53.54828)
		(end 235.725208 -53.550312)
		(stroke
			(width 0.2)
			(type default)
		)
		(layer "In1.Cu")
	)
	(gr_line
		(start 235.724192 -53.548026)
		(end 235.724192 -53.54828)
		(stroke
			(width 0.2)
			(type default)
		)
		(layer "In1.Cu")
	)
	(gr_line
		(start 235.724192 -49.548288)
		(end 235.725208 -49.55032)
		(stroke
			(width 0.2)
			(type default)
		)
		(layer "In1.Cu")
	)
	(gr_line
		(start 235.724192 -49.548034)
		(end 235.724192 -49.548288)
		(stroke
			(width 0.2)
			(type default)
		)
		(layer "In1.Cu")
	)
	(gr_line
		(start 235.724192 -45.548296)
		(end 235.725208 -45.550328)
		(stroke
			(width 0.2)
			(type default)
		)
		(layer "In1.Cu")
	)
	(gr_line
		(start 235.724192 -45.548042)
		(end 235.724192 -45.548296)
		(stroke
			(width 0.2)
			(type default)
		)
		(layer "In1.Cu")
	)
	(gr_line
		(start 235.724192 -41.548304)
		(end 235.725208 -41.550336)
		(stroke
			(width 0.2)
			(type default)
		)
		(layer "In1.Cu")
	)
	(gr_line
		(start 235.724192 -41.54805)
		(end 235.724192 -41.548304)
		(stroke
			(width 0.2)
			(type default)
		)
		(layer "In1.Cu")
	)
	(gr_line
		(start 235.724192 -37.548312)
		(end 235.725208 -37.550344)
		(stroke
			(width 0.2)
			(type default)
		)
		(layer "In1.Cu")
	)
	(gr_line
		(start 235.724192 -37.548058)
		(end 235.724192 -37.548312)
		(stroke
			(width 0.2)
			(type default)
		)
		(layer "In1.Cu")
	)
	(gr_line
		(start 235.724192 -17.548352)
		(end 235.725208 -17.550384)
		(stroke
			(width 0.2)
			(type default)
		)
		(layer "In1.Cu")
	)
	(gr_line
		(start 235.724192 -17.548098)
		(end 235.724192 -17.548352)
		(stroke
			(width 0.2)
			(type default)
		)
		(layer "In1.Cu")
	)
	(gr_arc
		(start 235.725208 -177.850038)
		(mid 235.400342 -178.824636)
		(end 236.37494 -179.149502)
		(stroke
			(width 0.2)
			(type default)
		)
		(layer "In1.Cu")
	)
	(gr_arc
		(start 235.725208 -173.850046)
		(mid 235.400342 -174.824644)
		(end 236.37494 -175.14951)
		(stroke
			(width 0.2)
			(type default)
		)
		(layer "In1.Cu")
	)
	(gr_arc
		(start 235.725208 -169.850054)
		(mid 235.400342 -170.824652)
		(end 236.37494 -171.149518)
		(stroke
			(width 0.2)
			(type default)
		)
		(layer "In1.Cu")
	)
	(gr_arc
		(start 235.725208 -165.850062)
		(mid 235.400342 -166.82466)
		(end 236.37494 -167.149526)
		(stroke
			(width 0.2)
			(type default)
		)
		(layer "In1.Cu")
	)
	(gr_arc
		(start 235.725208 -137.850118)
		(mid 235.400342 -138.824716)
		(end 236.37494 -139.149582)
		(stroke
			(width 0.2)
			(type default)
		)
		(layer "In1.Cu")
	)
	(gr_arc
		(start 235.725208 -81.550256)
		(mid 235.400342 -82.524854)
		(end 236.37494 -82.84972)
		(stroke
			(width 0.2)
			(type default)
		)
		(layer "In1.Cu")
	)
	(gr_arc
		(start 235.725208 -77.550264)
		(mid 235.400342 -78.524862)
		(end 236.37494 -78.849728)
		(stroke
			(width 0.2)
			(type default)
		)
		(layer "In1.Cu")
	)
	(gr_arc
		(start 235.725208 -73.550272)
		(mid 235.400342 -74.52487)
		(end 236.37494 -74.849736)
		(stroke
			(width 0.2)
			(type default)
		)
		(layer "In1.Cu")
	)
	(gr_arc
		(start 235.725208 -69.55028)
		(mid 235.400342 -70.524878)
		(end 236.37494 -70.849744)
		(stroke
			(width 0.2)
			(type default)
		)
		(layer "In1.Cu")
	)
	(gr_arc
		(start 235.725208 -65.550288)
		(mid 235.400342 -66.524886)
		(end 236.37494 -66.849752)
		(stroke
			(width 0.2)
			(type default)
		)
		(layer "In1.Cu")
	)
	(gr_arc
		(start 235.725208 -61.550296)
		(mid 235.400342 -62.524894)
		(end 236.37494 -62.84976)
		(stroke
			(width 0.2)
			(type default)
		)
		(layer "In1.Cu")
	)
	(gr_arc
		(start 235.725208 -57.550304)
		(mid 235.400342 -58.524902)
		(end 236.37494 -58.849768)
		(stroke
			(width 0.2)
			(type default)
		)
		(layer "In1.Cu")
	)
	(gr_arc
		(start 235.725208 -53.550312)
		(mid 235.400342 -54.52491)
		(end 236.37494 -54.849776)
		(stroke
			(width 0.2)
			(type default)
		)
		(layer "In1.Cu")
	)
	(gr_arc
		(start 235.725208 -49.55032)
		(mid 235.400342 -50.524918)
		(end 236.37494 -50.849784)
		(stroke
			(width 0.2)
			(type default)
		)
		(layer "In1.Cu")
	)
	(gr_arc
		(start 235.725208 -45.550328)
		(mid 235.400342 -46.524926)
		(end 236.37494 -46.849792)
		(stroke
			(width 0.2)
			(type default)
		)
		(layer "In1.Cu")
	)
	(gr_arc
		(start 235.725208 -41.550336)
		(mid 235.400342 -42.524934)
		(end 236.37494 -42.8498)
		(stroke
			(width 0.2)
			(type default)
		)
		(layer "In1.Cu")
	)
	(gr_arc
		(start 235.725208 -37.550344)
		(mid 235.400342 -38.524942)
		(end 236.37494 -38.849808)
		(stroke
			(width 0.2)
			(type default)
		)
		(layer "In1.Cu")
	)
	(gr_arc
		(start 235.725208 -17.550384)
		(mid 235.400342 -18.524982)
		(end 236.37494 -18.849848)
		(stroke
			(width 0.2)
			(type default)
		)
		(layer "In1.Cu")
	)
	(gr_arc
		(start 235.733844 -161.840164)
		(mid 235.393447 -162.821194)
		(end 236.377226 -163.154106)
		(stroke
			(width 0.2)
			(type default)
		)
		(layer "In1.Cu")
	)
	(gr_arc
		(start 235.733844 -157.840172)
		(mid 235.393447 -158.821202)
		(end 236.377226 -159.154114)
		(stroke
			(width 0.2)
			(type default)
		)
		(layer "In1.Cu")
	)
	(gr_arc
		(start 235.733844 -153.84018)
		(mid 235.393447 -154.82121)
		(end 236.377226 -155.154122)
		(stroke
			(width 0.2)
			(type default)
		)
		(layer "In1.Cu")
	)
	(gr_arc
		(start 235.733844 -149.840188)
		(mid 235.393447 -150.821218)
		(end 236.377226 -151.15413)
		(stroke
			(width 0.2)
			(type default)
		)
		(layer "In1.Cu")
	)
	(gr_arc
		(start 235.733844 -129.840228)
		(mid 235.393447 -130.821258)
		(end 236.377226 -131.15417)
		(stroke
			(width 0.2)
			(type default)
		)
		(layer "In1.Cu")
	)
	(gr_arc
		(start 235.733844 -125.840236)
		(mid 235.393447 -126.821266)
		(end 236.377226 -127.154178)
		(stroke
			(width 0.2)
			(type default)
		)
		(layer "In1.Cu")
	)
	(gr_arc
		(start 235.733844 -117.840252)
		(mid 235.393447 -118.821282)
		(end 236.377226 -119.154194)
		(stroke
			(width 0.2)
			(type default)
		)
		(layer "In1.Cu")
	)
	(gr_arc
		(start 235.733844 -113.84026)
		(mid 235.393447 -114.82129)
		(end 236.377226 -115.154202)
		(stroke
			(width 0.2)
			(type default)
		)
		(layer "In1.Cu")
	)
	(gr_arc
		(start 235.733844 -11.54049)
		(mid 235.393447 -12.52152)
		(end 236.377226 -12.854432)
		(stroke
			(width 0.2)
			(type default)
		)
		(layer "In1.Cu")
	)
	(gr_line
		(start 236.37494 -179.149502)
		(end 236.37621 -179.151788)
		(stroke
			(width 0.2)
			(type default)
		)
		(layer "In1.Cu")
	)
	(gr_line
		(start 236.37494 -175.14951)
		(end 236.37621 -175.151796)
		(stroke
			(width 0.2)
			(type default)
		)
		(layer "In1.Cu")
	)
	(gr_line
		(start 236.37494 -171.149518)
		(end 236.37621 -171.151804)
		(stroke
			(width 0.2)
			(type default)
		)
		(layer "In1.Cu")
	)
	(gr_line
		(start 236.37494 -167.149526)
		(end 236.37621 -167.151812)
		(stroke
			(width 0.2)
			(type default)
		)
		(layer "In1.Cu")
	)
	(gr_line
		(start 236.37494 -139.149582)
		(end 236.37621 -139.151868)
		(stroke
			(width 0.2)
			(type default)
		)
		(layer "In1.Cu")
	)
	(gr_line
		(start 236.37494 -82.84972)
		(end 236.37621 -82.852006)
		(stroke
			(width 0.2)
			(type default)
		)
		(layer "In1.Cu")
	)
	(gr_line
		(start 236.37494 -78.849728)
		(end 236.37621 -78.852014)
		(stroke
			(width 0.2)
			(type default)
		)
		(layer "In1.Cu")
	)
	(gr_line
		(start 236.37494 -74.849736)
		(end 236.37621 -74.852022)
		(stroke
			(width 0.2)
			(type default)
		)
		(layer "In1.Cu")
	)
	(gr_line
		(start 236.37494 -70.849744)
		(end 236.37621 -70.85203)
		(stroke
			(width 0.2)
			(type default)
		)
		(layer "In1.Cu")
	)
	(gr_line
		(start 236.37494 -66.849752)
		(end 236.37621 -66.852038)
		(stroke
			(width 0.2)
			(type default)
		)
		(layer "In1.Cu")
	)
	(gr_line
		(start 236.37494 -62.84976)
		(end 236.37621 -62.852046)
		(stroke
			(width 0.2)
			(type default)
		)
		(layer "In1.Cu")
	)
	(gr_line
		(start 236.37494 -58.849768)
		(end 236.37621 -58.852054)
		(stroke
			(width 0.2)
			(type default)
		)
		(layer "In1.Cu")
	)
	(gr_line
		(start 236.37494 -54.849776)
		(end 236.37621 -54.852062)
		(stroke
			(width 0.2)
			(type default)
		)
		(layer "In1.Cu")
	)
	(gr_line
		(start 236.37494 -50.849784)
		(end 236.37621 -50.85207)
		(stroke
			(width 0.2)
			(type default)
		)
		(layer "In1.Cu")
	)
	(gr_line
		(start 236.37494 -46.849792)
		(end 236.37621 -46.852078)
		(stroke
			(width 0.2)
			(type default)
		)
		(layer "In1.Cu")
	)
	(gr_line
		(start 236.37494 -42.8498)
		(end 236.37621 -42.852086)
		(stroke
			(width 0.2)
			(type default)
		)
		(layer "In1.Cu")
	)
	(gr_line
		(start 236.37494 -38.849808)
		(end 236.37621 -38.852094)
		(stroke
			(width 0.2)
			(type default)
		)
		(layer "In1.Cu")
	)
	(gr_line
		(start 236.37494 -18.849848)
		(end 236.37621 -18.852134)
		(stroke
			(width 0.2)
			(type default)
		)
		(layer "In1.Cu")
	)
	(gr_line
		(start 236.37621 -179.151788)
		(end 238.376206 -178.15179)
		(stroke
			(width 0.2)
			(type default)
		)
		(layer "In1.Cu")
	)
	(gr_line
		(start 236.37621 -175.151796)
		(end 238.376206 -174.151798)
		(stroke
			(width 0.2)
			(type default)
		)
		(layer "In1.Cu")
	)
	(gr_line
		(start 236.37621 -171.151804)
		(end 238.376206 -170.151806)
		(stroke
			(width 0.2)
			(type default)
		)
		(layer "In1.Cu")
	)
	(gr_line
		(start 236.37621 -167.151812)
		(end 238.376206 -166.151814)
		(stroke
			(width 0.2)
			(type default)
		)
		(layer "In1.Cu")
	)
	(gr_line
		(start 236.37621 -139.151868)
		(end 238.376206 -138.15187)
		(stroke
			(width 0.2)
			(type default)
		)
		(layer "In1.Cu")
	)
	(gr_line
		(start 236.37621 -82.852006)
		(end 238.376206 -81.852008)
		(stroke
			(width 0.2)
			(type default)
		)
		(layer "In1.Cu")
	)
	(gr_line
		(start 236.37621 -78.852014)
		(end 238.376206 -77.852016)
		(stroke
			(width 0.2)
			(type default)
		)
		(layer "In1.Cu")
	)
	(gr_line
		(start 236.37621 -74.852022)
		(end 238.376206 -73.852024)
		(stroke
			(width 0.2)
			(type default)
		)
		(layer "In1.Cu")
	)
	(gr_line
		(start 236.37621 -70.85203)
		(end 238.376206 -69.852032)
		(stroke
			(width 0.2)
			(type default)
		)
		(layer "In1.Cu")
	)
	(gr_line
		(start 236.37621 -66.852038)
		(end 238.375952 -65.85204)
		(stroke
			(width 0.2)
			(type default)
		)
		(layer "In1.Cu")
	)
	(gr_line
		(start 236.37621 -62.852046)
		(end 238.376206 -61.852048)
		(stroke
			(width 0.2)
			(type default)
		)
		(layer "In1.Cu")
	)
	(gr_line
		(start 236.37621 -58.852054)
		(end 238.376206 -57.852056)
		(stroke
			(width 0.2)
			(type default)
		)
		(layer "In1.Cu")
	)
	(gr_line
		(start 236.37621 -54.852062)
		(end 238.376206 -53.852064)
		(stroke
			(width 0.2)
			(type default)
		)
		(layer "In1.Cu")
	)
	(gr_line
		(start 236.37621 -50.85207)
		(end 238.376206 -49.852072)
		(stroke
			(width 0.2)
			(type default)
		)
		(layer "In1.Cu")
	)
	(gr_line
		(start 236.37621 -46.852078)
		(end 238.376206 -45.85208)
		(stroke
			(width 0.2)
			(type default)
		)
		(layer "In1.Cu")
	)
	(gr_line
		(start 236.37621 -42.852086)
		(end 238.376206 -41.852088)
		(stroke
			(width 0.2)
			(type default)
		)
		(layer "In1.Cu")
	)
	(gr_line
		(start 236.37621 -38.852094)
		(end 238.376206 -37.852096)
		(stroke
			(width 0.2)
			(type default)
		)
		(layer "In1.Cu")
	)
	(gr_line
		(start 236.37621 -18.852134)
		(end 238.376206 -17.852136)
		(stroke
			(width 0.2)
			(type default)
		)
		(layer "In1.Cu")
	)
	(gr_line
		(start 236.377226 -163.154106)
		(end 238.377222 -162.154108)
		(stroke
			(width 0.2)
			(type default)
		)
		(layer "In1.Cu")
	)
	(gr_line
		(start 236.377226 -159.154114)
		(end 238.377222 -158.154116)
		(stroke
			(width 0.2)
			(type default)
		)
		(layer "In1.Cu")
	)
	(gr_line
		(start 236.377226 -155.154122)
		(end 238.377222 -154.154124)
		(stroke
			(width 0.2)
			(type default)
		)
		(layer "In1.Cu")
	)
	(gr_line
		(start 236.377226 -151.15413)
		(end 238.377222 -150.154132)
		(stroke
			(width 0.2)
			(type default)
		)
		(layer "In1.Cu")
	)
	(gr_line
		(start 236.377226 -131.15417)
		(end 238.377222 -130.154172)
		(stroke
			(width 0.2)
			(type default)
		)
		(layer "In1.Cu")
	)
	(gr_line
		(start 236.377226 -127.154178)
		(end 238.377222 -126.15418)
		(stroke
			(width 0.2)
			(type default)
		)
		(layer "In1.Cu")
	)
	(gr_line
		(start 236.377226 -123.154186)
		(end 238.3663 -122.159522)
		(stroke
			(width 0.2)
			(type default)
		)
		(layer "In1.Cu")
	)
	(gr_line
		(start 236.377226 -119.154194)
		(end 238.377222 -118.154196)
		(stroke
			(width 0.2)
			(type default)
		)
		(layer "In1.Cu")
	)
	(gr_line
		(start 236.377226 -115.154202)
		(end 238.377222 -114.154204)
		(stroke
			(width 0.2)
			(type default)
		)
		(layer "In1.Cu")
	)
	(gr_line
		(start 236.377226 -12.854432)
		(end 238.377222 -11.854434)
		(stroke
			(width 0.2)
			(type default)
		)
		(layer "In1.Cu")
	)
	(gr_line
		(start 237.722918 -160.8455)
		(end 235.733844 -161.840164)
		(stroke
			(width 0.2)
			(type default)
		)
		(layer "In1.Cu")
	)
	(gr_line
		(start 237.722918 -156.845508)
		(end 235.733844 -157.840172)
		(stroke
			(width 0.2)
			(type default)
		)
		(layer "In1.Cu")
	)
	(gr_line
		(start 237.722918 -152.845516)
		(end 235.733844 -153.84018)
		(stroke
			(width 0.2)
			(type default)
		)
		(layer "In1.Cu")
	)
	(gr_line
		(start 237.722918 -148.845524)
		(end 235.733844 -149.840188)
		(stroke
			(width 0.2)
			(type default)
		)
		(layer "In1.Cu")
	)
	(gr_line
		(start 237.722918 -128.845564)
		(end 235.733844 -129.840228)
		(stroke
			(width 0.2)
			(type default)
		)
		(layer "In1.Cu")
	)
	(gr_line
		(start 237.722918 -124.845572)
		(end 235.733844 -125.840236)
		(stroke
			(width 0.2)
			(type default)
		)
		(layer "In1.Cu")
	)
	(gr_line
		(start 237.722918 -120.84558)
		(end 235.722922 -121.845578)
		(stroke
			(width 0.2)
			(type default)
		)
		(layer "In1.Cu")
	)
	(gr_line
		(start 237.722918 -116.845588)
		(end 235.733844 -117.840252)
		(stroke
			(width 0.2)
			(type default)
		)
		(layer "In1.Cu")
	)
	(gr_line
		(start 237.722918 -112.845596)
		(end 235.733844 -113.84026)
		(stroke
			(width 0.2)
			(type default)
		)
		(layer "In1.Cu")
	)
	(gr_line
		(start 237.722918 -10.545826)
		(end 235.733844 -11.54049)
		(stroke
			(width 0.2)
			(type default)
		)
		(layer "In1.Cu")
	)
	(gr_line
		(start 237.723934 -176.847754)
		(end 235.724192 -177.847752)
		(stroke
			(width 0.2)
			(type default)
		)
		(layer "In1.Cu")
	)
	(gr_line
		(start 237.723934 -172.847762)
		(end 235.724192 -173.84776)
		(stroke
			(width 0.2)
			(type default)
		)
		(layer "In1.Cu")
	)
	(gr_line
		(start 237.723934 -168.84777)
		(end 235.724192 -169.847768)
		(stroke
			(width 0.2)
			(type default)
		)
		(layer "In1.Cu")
	)
	(gr_line
		(start 237.723934 -164.847778)
		(end 235.724192 -165.847776)
		(stroke
			(width 0.2)
			(type default)
		)
		(layer "In1.Cu")
	)
	(gr_line
		(start 237.723934 -136.847834)
		(end 235.724192 -137.847832)
		(stroke
			(width 0.2)
			(type default)
		)
		(layer "In1.Cu")
	)
	(gr_line
		(start 237.723934 -80.547972)
		(end 235.724192 -81.54797)
		(stroke
			(width 0.2)
			(type default)
		)
		(layer "In1.Cu")
	)
	(gr_line
		(start 237.723934 -76.54798)
		(end 235.724192 -77.547978)
		(stroke
			(width 0.2)
			(type default)
		)
		(layer "In1.Cu")
	)
	(gr_line
		(start 237.723934 -72.547988)
		(end 235.724192 -73.547986)
		(stroke
			(width 0.2)
			(type default)
		)
		(layer "In1.Cu")
	)
	(gr_line
		(start 237.723934 -68.547996)
		(end 235.724192 -69.547994)
		(stroke
			(width 0.2)
			(type default)
		)
		(layer "In1.Cu")
	)
	(gr_line
		(start 237.723934 -64.548004)
		(end 235.723938 -65.548002)
		(stroke
			(width 0.2)
			(type default)
		)
		(layer "In1.Cu")
	)
	(gr_line
		(start 237.723934 -60.548012)
		(end 235.724192 -61.54801)
		(stroke
			(width 0.2)
			(type default)
		)
		(layer "In1.Cu")
	)
	(gr_line
		(start 237.723934 -56.54802)
		(end 235.724192 -57.548018)
		(stroke
			(width 0.2)
			(type default)
		)
		(layer "In1.Cu")
	)
	(gr_line
		(start 237.723934 -52.548028)
		(end 235.724192 -53.548026)
		(stroke
			(width 0.2)
			(type default)
		)
		(layer "In1.Cu")
	)
	(gr_line
		(start 237.723934 -48.548036)
		(end 235.724192 -49.548034)
		(stroke
			(width 0.2)
			(type default)
		)
		(layer "In1.Cu")
	)
	(gr_line
		(start 237.723934 -44.548044)
		(end 235.724192 -45.548042)
		(stroke
			(width 0.2)
			(type default)
		)
		(layer "In1.Cu")
	)
	(gr_line
		(start 237.723934 -40.548052)
		(end 235.724192 -41.54805)
		(stroke
			(width 0.2)
			(type default)
		)
		(layer "In1.Cu")
	)
	(gr_line
		(start 237.723934 -36.54806)
		(end 235.724192 -37.548058)
		(stroke
			(width 0.2)
			(type default)
		)
		(layer "In1.Cu")
	)
	(gr_line
		(start 237.723934 -16.5481)
		(end 235.724192 -17.548098)
		(stroke
			(width 0.2)
			(type default)
		)
		(layer "In1.Cu")
	)
	(gr_line
		(start 237.725204 -176.85004)
		(end 237.723934 -176.847754)
		(stroke
			(width 0.2)
			(type default)
		)
		(layer "In1.Cu")
	)
	(gr_line
		(start 237.725204 -172.850048)
		(end 237.723934 -172.847762)
		(stroke
			(width 0.2)
			(type default)
		)
		(layer "In1.Cu")
	)
	(gr_line
		(start 237.725204 -168.850056)
		(end 237.723934 -168.84777)
		(stroke
			(width 0.2)
			(type default)
		)
		(layer "In1.Cu")
	)
	(gr_line
		(start 237.725204 -164.850064)
		(end 237.723934 -164.847778)
		(stroke
			(width 0.2)
			(type default)
		)
		(layer "In1.Cu")
	)
	(gr_line
		(start 237.725204 -136.85012)
		(end 237.723934 -136.847834)
		(stroke
			(width 0.2)
			(type default)
		)
		(layer "In1.Cu")
	)
	(gr_line
		(start 237.725204 -80.550258)
		(end 237.723934 -80.547972)
		(stroke
			(width 0.2)
			(type default)
		)
		(layer "In1.Cu")
	)
	(gr_line
		(start 237.725204 -76.550266)
		(end 237.723934 -76.54798)
		(stroke
			(width 0.2)
			(type default)
		)
		(layer "In1.Cu")
	)
	(gr_line
		(start 237.725204 -72.550274)
		(end 237.723934 -72.547988)
		(stroke
			(width 0.2)
			(type default)
		)
		(layer "In1.Cu")
	)
	(gr_line
		(start 237.725204 -68.550282)
		(end 237.723934 -68.547996)
		(stroke
			(width 0.2)
			(type default)
		)
		(layer "In1.Cu")
	)
	(gr_line
		(start 237.725204 -64.55029)
		(end 237.723934 -64.548004)
		(stroke
			(width 0.2)
			(type default)
		)
		(layer "In1.Cu")
	)
	(gr_line
		(start 237.725204 -60.550298)
		(end 237.723934 -60.548012)
		(stroke
			(width 0.2)
			(type default)
		)
		(layer "In1.Cu")
	)
	(gr_line
		(start 237.725204 -56.550306)
		(end 237.723934 -56.54802)
		(stroke
			(width 0.2)
			(type default)
		)
		(layer "In1.Cu")
	)
	(gr_line
		(start 237.725204 -52.550314)
		(end 237.723934 -52.548028)
		(stroke
			(width 0.2)
			(type default)
		)
		(layer "In1.Cu")
	)
	(gr_line
		(start 237.725204 -48.550322)
		(end 237.723934 -48.548036)
		(stroke
			(width 0.2)
			(type default)
		)
		(layer "In1.Cu")
	)
	(gr_line
		(start 237.725204 -44.55033)
		(end 237.723934 -44.548044)
		(stroke
			(width 0.2)
			(type default)
		)
		(layer "In1.Cu")
	)
	(gr_line
		(start 237.725204 -40.550338)
		(end 237.723934 -40.548052)
		(stroke
			(width 0.2)
			(type default)
		)
		(layer "In1.Cu")
	)
	(gr_line
		(start 237.725204 -36.550346)
		(end 237.723934 -36.54806)
		(stroke
			(width 0.2)
			(type default)
		)
		(layer "In1.Cu")
	)
	(gr_line
		(start 237.725204 -16.550386)
		(end 237.723934 -16.5481)
		(stroke
			(width 0.2)
			(type default)
		)
		(layer "In1.Cu")
	)
	(gr_arc
		(start 238.3663 -122.159522)
		(mid 238.706697 -121.178492)
		(end 237.722918 -120.84558)
		(stroke
			(width 0.2)
			(type default)
		)
		(layer "In1.Cu")
	)
	(gr_arc
		(start 238.374936 -178.149504)
		(mid 238.699802 -177.174906)
		(end 237.725204 -176.85004)
		(stroke
			(width 0.2)
			(type default)
		)
		(layer "In1.Cu")
	)
	(gr_arc
		(start 238.374936 -174.149512)
		(mid 238.699802 -173.174914)
		(end 237.725204 -172.850048)
		(stroke
			(width 0.2)
			(type default)
		)
		(layer "In1.Cu")
	)
	(gr_arc
		(start 238.374936 -170.14952)
		(mid 238.699802 -169.174922)
		(end 237.725204 -168.850056)
		(stroke
			(width 0.2)
			(type default)
		)
		(layer "In1.Cu")
	)
	(gr_arc
		(start 238.374936 -166.149528)
		(mid 238.699802 -165.17493)
		(end 237.725204 -164.850064)
		(stroke
			(width 0.2)
			(type default)
		)
		(layer "In1.Cu")
	)
	(gr_arc
		(start 238.374936 -138.149584)
		(mid 238.699802 -137.174986)
		(end 237.725204 -136.85012)
		(stroke
			(width 0.2)
			(type default)
		)
		(layer "In1.Cu")
	)
	(gr_arc
		(start 238.374936 -81.849722)
		(mid 238.699802 -80.875124)
		(end 237.725204 -80.550258)
		(stroke
			(width 0.2)
			(type default)
		)
		(layer "In1.Cu")
	)
	(gr_arc
		(start 238.374936 -77.84973)
		(mid 238.699802 -76.875132)
		(end 237.725204 -76.550266)
		(stroke
			(width 0.2)
			(type default)
		)
		(layer "In1.Cu")
	)
	(gr_arc
		(start 238.374936 -73.849738)
		(mid 238.699802 -72.87514)
		(end 237.725204 -72.550274)
		(stroke
			(width 0.2)
			(type default)
		)
		(layer "In1.Cu")
	)
	(gr_arc
		(start 238.374936 -69.849746)
		(mid 238.699802 -68.875148)
		(end 237.725204 -68.550282)
		(stroke
			(width 0.2)
			(type default)
		)
		(layer "In1.Cu")
	)
	(gr_arc
		(start 238.374936 -65.849754)
		(mid 238.699802 -64.875156)
		(end 237.725204 -64.55029)
		(stroke
			(width 0.2)
			(type default)
		)
		(layer "In1.Cu")
	)
	(gr_arc
		(start 238.374936 -61.849762)
		(mid 238.699802 -60.875164)
		(end 237.725204 -60.550298)
		(stroke
			(width 0.2)
			(type default)
		)
		(layer "In1.Cu")
	)
	(gr_arc
		(start 238.374936 -57.84977)
		(mid 238.699802 -56.875172)
		(end 237.725204 -56.550306)
		(stroke
			(width 0.2)
			(type default)
		)
		(layer "In1.Cu")
	)
	(gr_arc
		(start 238.374936 -53.849778)
		(mid 238.699802 -52.87518)
		(end 237.725204 -52.550314)
		(stroke
			(width 0.2)
			(type default)
		)
		(layer "In1.Cu")
	)
	(gr_arc
		(start 238.374936 -49.849786)
		(mid 238.699802 -48.875188)
		(end 237.725204 -48.550322)
		(stroke
			(width 0.2)
			(type default)
		)
		(layer "In1.Cu")
	)
	(gr_arc
		(start 238.374936 -45.849794)
		(mid 238.699802 -44.875196)
		(end 237.725204 -44.55033)
		(stroke
			(width 0.2)
			(type default)
		)
		(layer "In1.Cu")
	)
	(gr_arc
		(start 238.374936 -41.849802)
		(mid 238.699802 -40.875204)
		(end 237.725204 -40.550338)
		(stroke
			(width 0.2)
			(type default)
		)
		(layer "In1.Cu")
	)
	(gr_arc
		(start 238.374936 -37.84981)
		(mid 238.699802 -36.875212)
		(end 237.725204 -36.550346)
		(stroke
			(width 0.2)
			(type default)
		)
		(layer "In1.Cu")
	)
	(gr_arc
		(start 238.374936 -17.84985)
		(mid 238.699802 -16.875252)
		(end 237.725204 -16.550386)
		(stroke
			(width 0.2)
			(type default)
		)
		(layer "In1.Cu")
	)
	(gr_line
		(start 238.375952 -65.85204)
		(end 238.375952 -65.851786)
		(stroke
			(width 0.2)
			(type default)
		)
		(layer "In1.Cu")
	)
	(gr_line
		(start 238.375952 -65.851786)
		(end 238.374936 -65.849754)
		(stroke
			(width 0.2)
			(type default)
		)
		(layer "In1.Cu")
	)
	(gr_line
		(start 238.376206 -178.15179)
		(end 238.374936 -178.149504)
		(stroke
			(width 0.2)
			(type default)
		)
		(layer "In1.Cu")
	)
	(gr_line
		(start 238.376206 -174.151798)
		(end 238.374936 -174.149512)
		(stroke
			(width 0.2)
			(type default)
		)
		(layer "In1.Cu")
	)
	(gr_line
		(start 238.376206 -170.151806)
		(end 238.374936 -170.14952)
		(stroke
			(width 0.2)
			(type default)
		)
		(layer "In1.Cu")
	)
	(gr_line
		(start 238.376206 -166.151814)
		(end 238.374936 -166.149528)
		(stroke
			(width 0.2)
			(type default)
		)
		(layer "In1.Cu")
	)
	(gr_line
		(start 238.376206 -138.15187)
		(end 238.374936 -138.149584)
		(stroke
			(width 0.2)
			(type default)
		)
		(layer "In1.Cu")
	)
	(gr_line
		(start 238.376206 -81.852008)
		(end 238.374936 -81.849722)
		(stroke
			(width 0.2)
			(type default)
		)
		(layer "In1.Cu")
	)
	(gr_line
		(start 238.376206 -77.852016)
		(end 238.374936 -77.84973)
		(stroke
			(width 0.2)
			(type default)
		)
		(layer "In1.Cu")
	)
	(gr_line
		(start 238.376206 -73.852024)
		(end 238.374936 -73.849738)
		(stroke
			(width 0.2)
			(type default)
		)
		(layer "In1.Cu")
	)
	(gr_line
		(start 238.376206 -69.852032)
		(end 238.374936 -69.849746)
		(stroke
			(width 0.2)
			(type default)
		)
		(layer "In1.Cu")
	)
	(gr_line
		(start 238.376206 -61.852048)
		(end 238.374936 -61.849762)
		(stroke
			(width 0.2)
			(type default)
		)
		(layer "In1.Cu")
	)
	(gr_line
		(start 238.376206 -57.852056)
		(end 238.374936 -57.84977)
		(stroke
			(width 0.2)
			(type default)
		)
		(layer "In1.Cu")
	)
	(gr_line
		(start 238.376206 -53.852064)
		(end 238.374936 -53.849778)
		(stroke
			(width 0.2)
			(type default)
		)
		(layer "In1.Cu")
	)
	(gr_line
		(start 238.376206 -49.852072)
		(end 238.374936 -49.849786)
		(stroke
			(width 0.2)
			(type default)
		)
		(layer "In1.Cu")
	)
	(gr_line
		(start 238.376206 -45.85208)
		(end 238.374936 -45.849794)
		(stroke
			(width 0.2)
			(type default)
		)
		(layer "In1.Cu")
	)
	(gr_line
		(start 238.376206 -41.852088)
		(end 238.374936 -41.849802)
		(stroke
			(width 0.2)
			(type default)
		)
		(layer "In1.Cu")
	)
	(gr_line
		(start 238.376206 -37.852096)
		(end 238.374936 -37.84981)
		(stroke
			(width 0.2)
			(type default)
		)
		(layer "In1.Cu")
	)
	(gr_line
		(start 238.376206 -17.852136)
		(end 238.374936 -17.84985)
		(stroke
			(width 0.2)
			(type default)
		)
		(layer "In1.Cu")
	)
	(gr_arc
		(start 238.377222 -162.154108)
		(mid 238.704374 -161.172652)
		(end 237.722918 -160.8455)
		(stroke
			(width 0.2)
			(type default)
		)
		(layer "In1.Cu")
	)
	(gr_arc
		(start 238.377222 -158.154116)
		(mid 238.704374 -157.17266)
		(end 237.722918 -156.845508)
		(stroke
			(width 0.2)
			(type default)
		)
		(layer "In1.Cu")
	)
	(gr_arc
		(start 238.377222 -154.154124)
		(mid 238.704374 -153.172668)
		(end 237.722918 -152.845516)
		(stroke
			(width 0.2)
			(type default)
		)
		(layer "In1.Cu")
	)
	(gr_arc
		(start 238.377222 -150.154132)
		(mid 238.704374 -149.172676)
		(end 237.722918 -148.845524)
		(stroke
			(width 0.2)
			(type default)
		)
		(layer "In1.Cu")
	)
	(gr_arc
		(start 238.377222 -130.154172)
		(mid 238.704374 -129.172716)
		(end 237.722918 -128.845564)
		(stroke
			(width 0.2)
			(type default)
		)
		(layer "In1.Cu")
	)
	(gr_arc
		(start 238.377222 -126.15418)
		(mid 238.704374 -125.172724)
		(end 237.722918 -124.845572)
		(stroke
			(width 0.2)
			(type default)
		)
		(layer "In1.Cu")
	)
	(gr_arc
		(start 238.377222 -118.154196)
		(mid 238.704374 -117.17274)
		(end 237.722918 -116.845588)
		(stroke
			(width 0.2)
			(type default)
		)
		(layer "In1.Cu")
	)
	(gr_arc
		(start 238.377222 -114.154204)
		(mid 238.704374 -113.172748)
		(end 237.722918 -112.845596)
		(stroke
			(width 0.2)
			(type default)
		)
		(layer "In1.Cu")
	)
	(gr_arc
		(start 238.377222 -11.854434)
		(mid 238.704374 -10.872978)
		(end 237.722918 -10.545826)
		(stroke
			(width 0.2)
			(type default)
		)
		(layer "In1.Cu")
	)
	(gr_line
		(start 240.219484 -128.161034)
		(end 242.21948 -129.161032)
		(stroke
			(width 0.2)
			(type default)
		)
		(layer "In1.Cu")
	)
	(gr_line
		(start 240.219484 -124.161042)
		(end 242.20805 -125.155198)
		(stroke
			(width 0.2)
			(type default)
		)
		(layer "In1.Cu")
	)
	(gr_line
		(start 240.222786 -164.154104)
		(end 242.222782 -165.154102)
		(stroke
			(width 0.2)
			(type default)
		)
		(layer "In1.Cu")
	)
	(gr_line
		(start 240.222786 -160.154112)
		(end 242.222528 -161.15411)
		(stroke
			(width 0.2)
			(type default)
		)
		(layer "In1.Cu")
	)
	(gr_line
		(start 240.222786 -156.15412)
		(end 242.222528 -157.154118)
		(stroke
			(width 0.2)
			(type default)
		)
		(layer "In1.Cu")
	)
	(gr_line
		(start 240.222786 -152.154128)
		(end 242.222782 -153.154126)
		(stroke
			(width 0.2)
			(type default)
		)
		(layer "In1.Cu")
	)
	(gr_line
		(start 240.222786 -120.154192)
		(end 242.222528 -121.15419)
		(stroke
			(width 0.2)
			(type default)
		)
		(layer "In1.Cu")
	)
	(gr_line
		(start 240.222786 -116.1542)
		(end 242.222782 -117.154198)
		(stroke
			(width 0.2)
			(type default)
		)
		(layer "In1.Cu")
	)
	(gr_line
		(start 240.223802 -136.151874)
		(end 242.223798 -137.151872)
		(stroke
			(width 0.2)
			(type default)
		)
		(layer "In1.Cu")
	)
	(gr_line
		(start 240.223802 -108.15193)
		(end 242.223798 -109.151928)
		(stroke
			(width 0.2)
			(type default)
		)
		(layer "In1.Cu")
	)
	(gr_line
		(start 240.223802 -35.8521)
		(end 242.223798 -36.852098)
		(stroke
			(width 0.2)
			(type default)
		)
		(layer "In1.Cu")
	)
	(gr_line
		(start 240.225072 -136.149588)
		(end 240.223802 -136.151874)
		(stroke
			(width 0.2)
			(type default)
		)
		(layer "In1.Cu")
	)
	(gr_line
		(start 240.225072 -108.149644)
		(end 240.223802 -108.15193)
		(stroke
			(width 0.2)
			(type default)
		)
		(layer "In1.Cu")
	)
	(gr_line
		(start 240.236502 -180.126894)
		(end 242.236498 -181.126892)
		(stroke
			(width 0.2)
			(type default)
		)
		(layer "In1.Cu")
	)
	(gr_line
		(start 240.236502 -176.126902)
		(end 242.236498 -177.1269)
		(stroke
			(width 0.2)
			(type default)
		)
		(layer "In1.Cu")
	)
	(gr_line
		(start 240.236502 -172.12691)
		(end 242.236498 -173.126908)
		(stroke
			(width 0.2)
			(type default)
		)
		(layer "In1.Cu")
	)
	(gr_line
		(start 240.236502 -168.126918)
		(end 242.236498 -169.126916)
		(stroke
			(width 0.2)
			(type default)
		)
		(layer "In1.Cu")
	)
	(gr_line
		(start 240.236502 -83.827112)
		(end 242.236498 -84.82711)
		(stroke
			(width 0.2)
			(type default)
		)
		(layer "In1.Cu")
	)
	(gr_line
		(start 240.236502 -79.82712)
		(end 242.228116 -80.8228)
		(stroke
			(width 0.2)
			(type default)
		)
		(layer "In1.Cu")
	)
	(gr_line
		(start 240.236502 -75.827128)
		(end 242.228116 -76.822808)
		(stroke
			(width 0.2)
			(type default)
		)
		(layer "In1.Cu")
	)
	(gr_line
		(start 240.236502 -71.827136)
		(end 242.228116 -72.822816)
		(stroke
			(width 0.2)
			(type default)
		)
		(layer "In1.Cu")
	)
	(gr_line
		(start 240.236502 -67.827144)
		(end 242.236498 -68.827142)
		(stroke
			(width 0.2)
			(type default)
		)
		(layer "In1.Cu")
	)
	(gr_line
		(start 240.236502 -63.827152)
		(end 242.236498 -64.82715)
		(stroke
			(width 0.2)
			(type default)
		)
		(layer "In1.Cu")
	)
	(gr_line
		(start 240.236502 -59.82716)
		(end 242.236498 -60.827158)
		(stroke
			(width 0.2)
			(type default)
		)
		(layer "In1.Cu")
	)
	(gr_line
		(start 240.236502 -55.827168)
		(end 242.236498 -56.827166)
		(stroke
			(width 0.2)
			(type default)
		)
		(layer "In1.Cu")
	)
	(gr_line
		(start 240.236502 -51.827176)
		(end 242.228116 -52.822856)
		(stroke
			(width 0.2)
			(type default)
		)
		(layer "In1.Cu")
	)
	(gr_line
		(start 240.236502 -47.827184)
		(end 242.236498 -48.827182)
		(stroke
			(width 0.2)
			(type default)
		)
		(layer "In1.Cu")
	)
	(gr_line
		(start 240.236502 -43.827192)
		(end 242.236498 -44.82719)
		(stroke
			(width 0.2)
			(type default)
		)
		(layer "In1.Cu")
	)
	(gr_line
		(start 240.236502 -39.8272)
		(end 242.236498 -40.827198)
		(stroke
			(width 0.2)
			(type default)
		)
		(layer "In1.Cu")
	)
	(gr_arc
		(start 240.863374 -78.572868)
		(mid 239.922812 -78.886558)
		(end 240.236502 -79.82712)
		(stroke
			(width 0.2)
			(type default)
		)
		(layer "In1.Cu")
	)
	(gr_arc
		(start 240.863374 -74.572876)
		(mid 239.922812 -74.886566)
		(end 240.236502 -75.827128)
		(stroke
			(width 0.2)
			(type default)
		)
		(layer "In1.Cu")
	)
	(gr_arc
		(start 240.863374 -70.572884)
		(mid 239.922812 -70.886574)
		(end 240.236502 -71.827136)
		(stroke
			(width 0.2)
			(type default)
		)
		(layer "In1.Cu")
	)
	(gr_arc
		(start 240.863374 -50.572924)
		(mid 239.922812 -50.886614)
		(end 240.236502 -51.827176)
		(stroke
			(width 0.2)
			(type default)
		)
		(layer "In1.Cu")
	)
	(gr_arc
		(start 240.871756 -178.87696)
		(mid 239.92498 -179.182145)
		(end 240.236502 -180.126894)
		(stroke
			(width 0.2)
			(type default)
		)
		(layer "In1.Cu")
	)
	(gr_arc
		(start 240.871756 -174.876968)
		(mid 239.92498 -175.182153)
		(end 240.236502 -176.126902)
		(stroke
			(width 0.2)
			(type default)
		)
		(layer "In1.Cu")
	)
	(gr_arc
		(start 240.871756 -170.876976)
		(mid 239.92498 -171.182161)
		(end 240.236502 -172.12691)
		(stroke
			(width 0.2)
			(type default)
		)
		(layer "In1.Cu")
	)
	(gr_arc
		(start 240.871756 -166.876984)
		(mid 239.92498 -167.182169)
		(end 240.236502 -168.126918)
		(stroke
			(width 0.2)
			(type default)
		)
		(layer "In1.Cu")
	)
	(gr_arc
		(start 240.871756 -82.577178)
		(mid 239.92498 -82.882363)
		(end 240.236502 -83.827112)
		(stroke
			(width 0.2)
			(type default)
		)
		(layer "In1.Cu")
	)
	(gr_arc
		(start 240.871756 -66.57721)
		(mid 239.92498 -66.882395)
		(end 240.236502 -67.827144)
		(stroke
			(width 0.2)
			(type default)
		)
		(layer "In1.Cu")
	)
	(gr_arc
		(start 240.871756 -62.577218)
		(mid 239.92498 -62.882403)
		(end 240.236502 -63.827152)
		(stroke
			(width 0.2)
			(type default)
		)
		(layer "In1.Cu")
	)
	(gr_arc
		(start 240.871756 -58.577226)
		(mid 239.92498 -58.882411)
		(end 240.236502 -59.82716)
		(stroke
			(width 0.2)
			(type default)
		)
		(layer "In1.Cu")
	)
	(gr_arc
		(start 240.871756 -54.577234)
		(mid 239.92498 -54.882419)
		(end 240.236502 -55.827168)
		(stroke
			(width 0.2)
			(type default)
		)
		(layer "In1.Cu")
	)
	(gr_arc
		(start 240.871756 -46.57725)
		(mid 239.92498 -46.882435)
		(end 240.236502 -47.827184)
		(stroke
			(width 0.2)
			(type default)
		)
		(layer "In1.Cu")
	)
	(gr_arc
		(start 240.871756 -42.577258)
		(mid 239.92498 -42.882443)
		(end 240.236502 -43.827192)
		(stroke
			(width 0.2)
			(type default)
		)
		(layer "In1.Cu")
	)
	(gr_arc
		(start 240.871756 -38.577266)
		(mid 239.92498 -38.882451)
		(end 240.236502 -39.8272)
		(stroke
			(width 0.2)
			(type default)
		)
		(layer "In1.Cu")
	)
	(gr_arc
		(start 240.874804 -134.850124)
		(mid 239.900206 -135.17499)
		(end 240.225072 -136.149588)
		(stroke
			(width 0.2)
			(type default)
		)
		(layer "In1.Cu")
	)
	(gr_arc
		(start 240.874804 -106.85018)
		(mid 239.900206 -107.175046)
		(end 240.225072 -108.149644)
		(stroke
			(width 0.2)
			(type default)
		)
		(layer "In1.Cu")
	)
	(gr_line
		(start 240.87582 -134.848092)
		(end 240.874804 -134.850124)
		(stroke
			(width 0.2)
			(type default)
		)
		(layer "In1.Cu")
	)
	(gr_line
		(start 240.87582 -106.848148)
		(end 240.874804 -106.85018)
		(stroke
			(width 0.2)
			(type default)
		)
		(layer "In1.Cu")
	)
	(gr_line
		(start 240.876074 -134.847838)
		(end 240.87582 -134.848092)
		(stroke
			(width 0.2)
			(type default)
		)
		(layer "In1.Cu")
	)
	(gr_line
		(start 240.876074 -106.847894)
		(end 240.87582 -106.848148)
		(stroke
			(width 0.2)
			(type default)
		)
		(layer "In1.Cu")
	)
	(gr_arc
		(start 240.876074 -34.548064)
		(mid 239.89792 -34.873946)
		(end 240.223802 -35.8521)
		(stroke
			(width 0.2)
			(type default)
		)
		(layer "In1.Cu")
	)
	(gr_arc
		(start 240.87709 -158.845504)
		(mid 239.895634 -159.172656)
		(end 240.222786 -160.154112)
		(stroke
			(width 0.2)
			(type default)
		)
		(layer "In1.Cu")
	)
	(gr_arc
		(start 240.87709 -154.845512)
		(mid 239.895634 -155.172664)
		(end 240.222786 -156.15412)
		(stroke
			(width 0.2)
			(type default)
		)
		(layer "In1.Cu")
	)
	(gr_arc
		(start 240.87709 -118.845584)
		(mid 239.895634 -119.172736)
		(end 240.222786 -120.154192)
		(stroke
			(width 0.2)
			(type default)
		)
		(layer "In1.Cu")
	)
	(gr_arc
		(start 240.877344 -162.845496)
		(mid 239.895939 -163.172546)
		(end 240.222786 -164.154104)
		(stroke
			(width 0.2)
			(type default)
		)
		(layer "In1.Cu")
	)
	(gr_arc
		(start 240.877344 -150.84552)
		(mid 239.895939 -151.17257)
		(end 240.222786 -152.154128)
		(stroke
			(width 0.2)
			(type default)
		)
		(layer "In1.Cu")
	)
	(gr_arc
		(start 240.877344 -114.845592)
		(mid 239.895939 -115.172642)
		(end 240.222786 -116.1542)
		(stroke
			(width 0.2)
			(type default)
		)
		(layer "In1.Cu")
	)
	(gr_arc
		(start 240.880392 -122.838718)
		(mid 239.888776 -123.169426)
		(end 240.219484 -124.161042)
		(stroke
			(width 0.2)
			(type default)
		)
		(layer "In1.Cu")
	)
	(gr_arc
		(start 240.891822 -126.844552)
		(mid 239.891674 -127.163691)
		(end 240.219484 -128.161034)
		(stroke
			(width 0.2)
			(type default)
		)
		(layer "In1.Cu")
	)
	(gr_arc
		(start 242.20805 -125.155198)
		(mid 243.208198 -124.836059)
		(end 242.880388 -123.838716)
		(stroke
			(width 0.2)
			(type default)
		)
		(layer "In1.Cu")
	)
	(gr_arc
		(start 242.21948 -129.161032)
		(mid 243.211096 -128.830324)
		(end 242.880388 -127.838708)
		(stroke
			(width 0.2)
			(type default)
		)
		(layer "In1.Cu")
	)
	(gr_arc
		(start 242.222528 -161.15411)
		(mid 243.204289 -160.82711)
		(end 242.877086 -159.845502)
		(stroke
			(width 0.2)
			(type default)
		)
		(layer "In1.Cu")
	)
	(gr_arc
		(start 242.222528 -157.154118)
		(mid 243.204289 -156.827118)
		(end 242.877086 -155.84551)
		(stroke
			(width 0.2)
			(type default)
		)
		(layer "In1.Cu")
	)
	(gr_arc
		(start 242.222528 -121.15419)
		(mid 243.204289 -120.82719)
		(end 242.877086 -119.845582)
		(stroke
			(width 0.2)
			(type default)
		)
		(layer "In1.Cu")
	)
	(gr_arc
		(start 242.222782 -165.154102)
		(mid 243.204238 -164.82695)
		(end 242.877086 -163.845494)
		(stroke
			(width 0.2)
			(type default)
		)
		(layer "In1.Cu")
	)
	(gr_arc
		(start 242.222782 -153.154126)
		(mid 243.204238 -152.826974)
		(end 242.877086 -151.845518)
		(stroke
			(width 0.2)
			(type default)
		)
		(layer "In1.Cu")
	)
	(gr_arc
		(start 242.222782 -117.154198)
		(mid 243.204238 -116.827046)
		(end 242.877086 -115.84559)
		(stroke
			(width 0.2)
			(type default)
		)
		(layer "In1.Cu")
	)
	(gr_line
		(start 242.223798 -137.151872)
		(end 242.225068 -137.149586)
		(stroke
			(width 0.2)
			(type default)
		)
		(layer "In1.Cu")
	)
	(gr_line
		(start 242.223798 -109.151928)
		(end 242.225068 -109.149642)
		(stroke
			(width 0.2)
			(type default)
		)
		(layer "In1.Cu")
	)
	(gr_arc
		(start 242.223798 -36.852098)
		(mid 243.201952 -36.526216)
		(end 242.87607 -35.548062)
		(stroke
			(width 0.2)
			(type default)
		)
		(layer "In1.Cu")
	)
	(gr_arc
		(start 242.225068 -137.149586)
		(mid 243.199666 -136.82472)
		(end 242.8748 -135.850122)
		(stroke
			(width 0.2)
			(type default)
		)
		(layer "In1.Cu")
	)
	(gr_arc
		(start 242.225068 -109.149642)
		(mid 243.199666 -108.824776)
		(end 242.8748 -107.850178)
		(stroke
			(width 0.2)
			(type default)
		)
		(layer "In1.Cu")
	)
	(gr_arc
		(start 242.228116 -80.8228)
		(mid 243.174892 -80.517615)
		(end 242.86337 -79.572866)
		(stroke
			(width 0.2)
			(type default)
		)
		(layer "In1.Cu")
	)
	(gr_arc
		(start 242.228116 -76.822808)
		(mid 243.174892 -76.517623)
		(end 242.86337 -75.572874)
		(stroke
			(width 0.2)
			(type default)
		)
		(layer "In1.Cu")
	)
	(gr_arc
		(start 242.228116 -72.822816)
		(mid 243.174892 -72.517631)
		(end 242.86337 -71.572882)
		(stroke
			(width 0.2)
			(type default)
		)
		(layer "In1.Cu")
	)
	(gr_arc
		(start 242.228116 -52.822856)
		(mid 243.174892 -52.517671)
		(end 242.86337 -51.572922)
		(stroke
			(width 0.2)
			(type default)
		)
		(layer "In1.Cu")
	)
	(gr_arc
		(start 242.236498 -181.126892)
		(mid 243.17706 -180.813202)
		(end 242.86337 -179.87264)
		(stroke
			(width 0.2)
			(type default)
		)
		(layer "In1.Cu")
	)
	(gr_arc
		(start 242.236498 -177.1269)
		(mid 243.17706 -176.81321)
		(end 242.86337 -175.872648)
		(stroke
			(width 0.2)
			(type default)
		)
		(layer "In1.Cu")
	)
	(gr_arc
		(start 242.236498 -173.126908)
		(mid 243.17706 -172.813218)
		(end 242.86337 -171.872656)
		(stroke
			(width 0.2)
			(type default)
		)
		(layer "In1.Cu")
	)
	(gr_arc
		(start 242.236498 -169.126916)
		(mid 243.17706 -168.813226)
		(end 242.86337 -167.872664)
		(stroke
			(width 0.2)
			(type default)
		)
		(layer "In1.Cu")
	)
	(gr_arc
		(start 242.236498 -84.82711)
		(mid 243.17706 -84.51342)
		(end 242.86337 -83.572858)
		(stroke
			(width 0.2)
			(type default)
		)
		(layer "In1.Cu")
	)
	(gr_arc
		(start 242.236498 -68.827142)
		(mid 243.17706 -68.513452)
		(end 242.86337 -67.57289)
		(stroke
			(width 0.2)
			(type default)
		)
		(layer "In1.Cu")
	)
	(gr_arc
		(start 242.236498 -64.82715)
		(mid 243.17706 -64.51346)
		(end 242.86337 -63.572898)
		(stroke
			(width 0.2)
			(type default)
		)
		(layer "In1.Cu")
	)
	(gr_arc
		(start 242.236498 -60.827158)
		(mid 243.17706 -60.513468)
		(end 242.86337 -59.572906)
		(stroke
			(width 0.2)
			(type default)
		)
		(layer "In1.Cu")
	)
	(gr_arc
		(start 242.236498 -56.827166)
		(mid 243.17706 -56.513476)
		(end 242.86337 -55.572914)
		(stroke
			(width 0.2)
			(type default)
		)
		(layer "In1.Cu")
	)
	(gr_arc
		(start 242.236498 -48.827182)
		(mid 243.17706 -48.513492)
		(end 242.86337 -47.57293)
		(stroke
			(width 0.2)
			(type default)
		)
		(layer "In1.Cu")
	)
	(gr_arc
		(start 242.236498 -44.82719)
		(mid 243.17706 -44.5135)
		(end 242.86337 -43.572938)
		(stroke
			(width 0.2)
			(type default)
		)
		(layer "In1.Cu")
	)
	(gr_arc
		(start 242.236498 -40.827198)
		(mid 243.17706 -40.513508)
		(end 242.86337 -39.572946)
		(stroke
			(width 0.2)
			(type default)
		)
		(layer "In1.Cu")
	)
	(gr_line
		(start 242.86337 -179.87264)
		(end 240.871756 -178.87696)
		(stroke
			(width 0.2)
			(type default)
		)
		(layer "In1.Cu")
	)
	(gr_line
		(start 242.86337 -175.872648)
		(end 240.871756 -174.876968)
		(stroke
			(width 0.2)
			(type default)
		)
		(layer "In1.Cu")
	)
	(gr_line
		(start 242.86337 -171.872656)
		(end 240.871756 -170.876976)
		(stroke
			(width 0.2)
			(type default)
		)
		(layer "In1.Cu")
	)
	(gr_line
		(start 242.86337 -167.872664)
		(end 240.871756 -166.876984)
		(stroke
			(width 0.2)
			(type default)
		)
		(layer "In1.Cu")
	)
	(gr_line
		(start 242.86337 -83.572858)
		(end 240.871756 -82.577178)
		(stroke
			(width 0.2)
			(type default)
		)
		(layer "In1.Cu")
	)
	(gr_line
		(start 242.86337 -79.572866)
		(end 240.863374 -78.572868)
		(stroke
			(width 0.2)
			(type default)
		)
		(layer "In1.Cu")
	)
	(gr_line
		(start 242.86337 -75.572874)
		(end 240.863374 -74.572876)
		(stroke
			(width 0.2)
			(type default)
		)
		(layer "In1.Cu")
	)
	(gr_line
		(start 242.86337 -71.572882)
		(end 240.863374 -70.572884)
		(stroke
			(width 0.2)
			(type default)
		)
		(layer "In1.Cu")
	)
	(gr_line
		(start 242.86337 -67.57289)
		(end 240.871756 -66.57721)
		(stroke
			(width 0.2)
			(type default)
		)
		(layer "In1.Cu")
	)
	(gr_line
		(start 242.86337 -63.572898)
		(end 240.871756 -62.577218)
		(stroke
			(width 0.2)
			(type default)
		)
		(layer "In1.Cu")
	)
	(gr_line
		(start 242.86337 -59.572906)
		(end 240.871756 -58.577226)
		(stroke
			(width 0.2)
			(type default)
		)
		(layer "In1.Cu")
	)
	(gr_line
		(start 242.86337 -55.572914)
		(end 240.871756 -54.577234)
		(stroke
			(width 0.2)
			(type default)
		)
		(layer "In1.Cu")
	)
	(gr_line
		(start 242.86337 -51.572922)
		(end 240.863374 -50.572924)
		(stroke
			(width 0.2)
			(type default)
		)
		(layer "In1.Cu")
	)
	(gr_line
		(start 242.86337 -47.57293)
		(end 240.871756 -46.57725)
		(stroke
			(width 0.2)
			(type default)
		)
		(layer "In1.Cu")
	)
	(gr_line
		(start 242.86337 -43.572938)
		(end 240.871756 -42.577258)
		(stroke
			(width 0.2)
			(type default)
		)
		(layer "In1.Cu")
	)
	(gr_line
		(start 242.86337 -39.572946)
		(end 240.871756 -38.577266)
		(stroke
			(width 0.2)
			(type default)
		)
		(layer "In1.Cu")
	)
	(gr_line
		(start 242.8748 -135.850122)
		(end 242.87607 -135.847836)
		(stroke
			(width 0.2)
			(type default)
		)
		(layer "In1.Cu")
	)
	(gr_line
		(start 242.8748 -107.850178)
		(end 242.87607 -107.847892)
		(stroke
			(width 0.2)
			(type default)
		)
		(layer "In1.Cu")
	)
	(gr_line
		(start 242.87607 -135.847836)
		(end 240.876074 -134.847838)
		(stroke
			(width 0.2)
			(type default)
		)
		(layer "In1.Cu")
	)
	(gr_line
		(start 242.87607 -107.847892)
		(end 240.876074 -106.847894)
		(stroke
			(width 0.2)
			(type default)
		)
		(layer "In1.Cu")
	)
	(gr_line
		(start 242.87607 -35.548062)
		(end 240.876074 -34.548064)
		(stroke
			(width 0.2)
			(type default)
		)
		(layer "In1.Cu")
	)
	(gr_line
		(start 242.877086 -163.845494)
		(end 240.877344 -162.845496)
		(stroke
			(width 0.2)
			(type default)
		)
		(layer "In1.Cu")
	)
	(gr_line
		(start 242.877086 -159.845502)
		(end 240.87709 -158.845504)
		(stroke
			(width 0.2)
			(type default)
		)
		(layer "In1.Cu")
	)
	(gr_line
		(start 242.877086 -155.84551)
		(end 240.87709 -154.845512)
		(stroke
			(width 0.2)
			(type default)
		)
		(layer "In1.Cu")
	)
	(gr_line
		(start 242.877086 -151.845518)
		(end 240.877344 -150.84552)
		(stroke
			(width 0.2)
			(type default)
		)
		(layer "In1.Cu")
	)
	(gr_line
		(start 242.877086 -119.845582)
		(end 240.87709 -118.845584)
		(stroke
			(width 0.2)
			(type default)
		)
		(layer "In1.Cu")
	)
	(gr_line
		(start 242.877086 -115.84559)
		(end 240.877344 -114.845592)
		(stroke
			(width 0.2)
			(type default)
		)
		(layer "In1.Cu")
	)
	(gr_line
		(start 242.880388 -127.838708)
		(end 240.891822 -126.844552)
		(stroke
			(width 0.2)
			(type default)
		)
		(layer "In1.Cu")
	)
	(gr_line
		(start 242.880388 -123.838716)
		(end 240.880392 -122.838718)
		(stroke
			(width 0.2)
			(type default)
		)
		(layer "In1.Cu")
	)
	(gr_line
		(start 247.681496 -398.575784)
		(end 249.6312 -396.62608)
		(stroke
			(width 0.381)
			(type default)
		)
		(layer "In1.Cu")
	)
	(gr_line
		(start 248.7168 -378.4854)
		(end 234.19943 -378.4854)
		(stroke
			(width 0.381)
			(type default)
		)
		(layer "In1.Cu")
	)
	(gr_line
		(start 249.6312 -396.62608)
		(end 249.6312 -388.8994)
		(stroke
			(width 0.381)
			(type default)
		)
		(layer "In1.Cu")
	)
	(gr_line
		(start 249.6312 -388.8994)
		(end 251.8918 -386.6388)
		(stroke
			(width 0.381)
			(type default)
		)
		(layer "In1.Cu")
	)
	(gr_line
		(start 251.8918 -386.6388)
		(end 251.8918 -381.6604)
		(stroke
			(width 0.381)
			(type default)
		)
		(layer "In1.Cu")
	)
	(gr_line
		(start 251.8918 -381.6604)
		(end 248.7168 -378.4854)
		(stroke
			(width 0.381)
			(type default)
		)
		(layer "In1.Cu")
	)
	(gr_line
		(start 271.9705 -359.885996)
		(end 273.1135 -359.885996)
		(stroke
			(width 0.2)
			(type default)
		)
		(layer "In1.Cu")
	)
	(gr_line
		(start 271.9705 -358.085898)
		(end 273.1135 -358.085898)
		(stroke
			(width 0.2)
			(type default)
		)
		(layer "In1.Cu")
	)
	(gr_line
		(start 271.9705 -356.286054)
		(end 273.1135 -356.286054)
		(stroke
			(width 0.2)
			(type default)
		)
		(layer "In1.Cu")
	)
	(gr_line
		(start 271.9705 -354.485956)
		(end 273.1135 -354.485956)
		(stroke
			(width 0.2)
			(type default)
		)
		(layer "In1.Cu")
	)
	(gr_line
		(start 271.9705 -352.686112)
		(end 273.1135 -352.686112)
		(stroke
			(width 0.2)
			(type default)
		)
		(layer "In1.Cu")
	)
	(gr_line
		(start 271.9705 -350.886014)
		(end 273.1135 -350.886014)
		(stroke
			(width 0.2)
			(type default)
		)
		(layer "In1.Cu")
	)
	(gr_line
		(start 271.9705 -338.28863)
		(end 273.1135 -338.28863)
		(stroke
			(width 0.2)
			(type default)
		)
		(layer "In1.Cu")
	)
	(gr_line
		(start 271.9705 -336.488532)
		(end 273.1135 -336.488532)
		(stroke
			(width 0.2)
			(type default)
		)
		(layer "In1.Cu")
	)
	(gr_line
		(start 271.9705 -334.688434)
		(end 273.1135 -334.688434)
		(stroke
			(width 0.2)
			(type default)
		)
		(layer "In1.Cu")
	)
	(gr_line
		(start 271.9705 -332.88859)
		(end 273.1135 -332.88859)
		(stroke
			(width 0.2)
			(type default)
		)
		(layer "In1.Cu")
	)
	(gr_line
		(start 271.9705 -331.088492)
		(end 273.1135 -331.088492)
		(stroke
			(width 0.2)
			(type default)
		)
		(layer "In1.Cu")
	)
	(gr_line
		(start 271.9705 -329.288648)
		(end 273.1135 -329.288648)
		(stroke
			(width 0.2)
			(type default)
		)
		(layer "In1.Cu")
	)
	(gr_line
		(start 271.9705 -316.68847)
		(end 273.1135 -316.68847)
		(stroke
			(width 0.2)
			(type default)
		)
		(layer "In1.Cu")
	)
	(gr_line
		(start 271.9705 -314.888626)
		(end 273.1135 -314.888626)
		(stroke
			(width 0.2)
			(type default)
		)
		(layer "In1.Cu")
	)
	(gr_line
		(start 271.9705 -313.088528)
		(end 273.1135 -313.088528)
		(stroke
			(width 0.2)
			(type default)
		)
		(layer "In1.Cu")
	)
	(gr_line
		(start 271.9705 -311.28843)
		(end 273.1135 -311.28843)
		(stroke
			(width 0.2)
			(type default)
		)
		(layer "In1.Cu")
	)
	(gr_line
		(start 271.9705 -309.488586)
		(end 273.1135 -309.488586)
		(stroke
			(width 0.2)
			(type default)
		)
		(layer "In1.Cu")
	)
	(gr_line
		(start 271.9705 -307.688488)
		(end 273.1135 -307.688488)
		(stroke
			(width 0.2)
			(type default)
		)
		(layer "In1.Cu")
	)
	(gr_arc
		(start 271.970754 -359.123996)
		(mid 271.5895 -359.504869)
		(end 271.9705 -359.885996)
		(stroke
			(width 0.2)
			(type default)
		)
		(layer "In1.Cu")
	)
	(gr_arc
		(start 271.970754 -357.323898)
		(mid 271.5895 -357.704771)
		(end 271.9705 -358.085898)
		(stroke
			(width 0.2)
			(type default)
		)
		(layer "In1.Cu")
	)
	(gr_arc
		(start 271.970754 -355.524054)
		(mid 271.5895 -355.904927)
		(end 271.9705 -356.286054)
		(stroke
			(width 0.2)
			(type default)
		)
		(layer "In1.Cu")
	)
	(gr_arc
		(start 271.970754 -353.723956)
		(mid 271.5895 -354.104829)
		(end 271.9705 -354.485956)
		(stroke
			(width 0.2)
			(type default)
		)
		(layer "In1.Cu")
	)
	(gr_arc
		(start 271.970754 -351.924112)
		(mid 271.5895 -352.304985)
		(end 271.9705 -352.686112)
		(stroke
			(width 0.2)
			(type default)
		)
		(layer "In1.Cu")
	)
	(gr_arc
		(start 271.970754 -350.124014)
		(mid 271.5895 -350.504887)
		(end 271.9705 -350.886014)
		(stroke
			(width 0.2)
			(type default)
		)
		(layer "In1.Cu")
	)
	(gr_arc
		(start 271.970754 -337.52155)
		(mid 271.58696 -337.904963)
		(end 271.9705 -338.28863)
		(stroke
			(width 0.2)
			(type default)
		)
		(layer "In1.Cu")
	)
	(gr_arc
		(start 271.970754 -335.721452)
		(mid 271.58696 -336.104865)
		(end 271.9705 -336.488532)
		(stroke
			(width 0.2)
			(type default)
		)
		(layer "In1.Cu")
	)
	(gr_arc
		(start 271.970754 -333.921354)
		(mid 271.58696 -334.304767)
		(end 271.9705 -334.688434)
		(stroke
			(width 0.2)
			(type default)
		)
		(layer "In1.Cu")
	)
	(gr_arc
		(start 271.970754 -332.12151)
		(mid 271.58696 -332.504923)
		(end 271.9705 -332.88859)
		(stroke
			(width 0.2)
			(type default)
		)
		(layer "In1.Cu")
	)
	(gr_arc
		(start 271.970754 -330.321412)
		(mid 271.58696 -330.704825)
		(end 271.9705 -331.088492)
		(stroke
			(width 0.2)
			(type default)
		)
		(layer "In1.Cu")
	)
	(gr_arc
		(start 271.970754 -328.521568)
		(mid 271.58696 -328.904981)
		(end 271.9705 -329.288648)
		(stroke
			(width 0.2)
			(type default)
		)
		(layer "In1.Cu")
	)
	(gr_arc
		(start 271.970754 -315.92139)
		(mid 271.58696 -316.304803)
		(end 271.9705 -316.68847)
		(stroke
			(width 0.2)
			(type default)
		)
		(layer "In1.Cu")
	)
	(gr_arc
		(start 271.970754 -314.121546)
		(mid 271.58696 -314.504959)
		(end 271.9705 -314.888626)
		(stroke
			(width 0.2)
			(type default)
		)
		(layer "In1.Cu")
	)
	(gr_arc
		(start 271.970754 -312.321448)
		(mid 271.58696 -312.704861)
		(end 271.9705 -313.088528)
		(stroke
			(width 0.2)
			(type default)
		)
		(layer "In1.Cu")
	)
	(gr_arc
		(start 271.970754 -310.52135)
		(mid 271.58696 -310.904763)
		(end 271.9705 -311.28843)
		(stroke
			(width 0.2)
			(type default)
		)
		(layer "In1.Cu")
	)
	(gr_arc
		(start 271.970754 -308.721506)
		(mid 271.58696 -309.104919)
		(end 271.9705 -309.488586)
		(stroke
			(width 0.2)
			(type default)
		)
		(layer "In1.Cu")
	)
	(gr_arc
		(start 271.970754 -306.921408)
		(mid 271.58696 -307.304821)
		(end 271.9705 -307.688488)
		(stroke
			(width 0.2)
			(type default)
		)
		(layer "In1.Cu")
	)
	(gr_arc
		(start 273.1135 -359.885996)
		(mid 273.4945 -359.504996)
		(end 273.1135 -359.123996)
		(stroke
			(width 0.2)
			(type default)
		)
		(layer "In1.Cu")
	)
	(gr_line
		(start 273.1135 -359.123996)
		(end 271.970754 -359.123996)
		(stroke
			(width 0.2)
			(type default)
		)
		(layer "In1.Cu")
	)
	(gr_arc
		(start 273.1135 -358.085898)
		(mid 273.4945 -357.704898)
		(end 273.1135 -357.323898)
		(stroke
			(width 0.2)
			(type default)
		)
		(layer "In1.Cu")
	)
	(gr_line
		(start 273.1135 -357.323898)
		(end 271.970754 -357.323898)
		(stroke
			(width 0.2)
			(type default)
		)
		(layer "In1.Cu")
	)
	(gr_arc
		(start 273.1135 -356.286054)
		(mid 273.4945 -355.905054)
		(end 273.1135 -355.524054)
		(stroke
			(width 0.2)
			(type default)
		)
		(layer "In1.Cu")
	)
	(gr_line
		(start 273.1135 -355.524054)
		(end 271.970754 -355.524054)
		(stroke
			(width 0.2)
			(type default)
		)
		(layer "In1.Cu")
	)
	(gr_arc
		(start 273.1135 -354.485956)
		(mid 273.4945 -354.104956)
		(end 273.1135 -353.723956)
		(stroke
			(width 0.2)
			(type default)
		)
		(layer "In1.Cu")
	)
	(gr_line
		(start 273.1135 -353.723956)
		(end 271.970754 -353.723956)
		(stroke
			(width 0.2)
			(type default)
		)
		(layer "In1.Cu")
	)
	(gr_arc
		(start 273.1135 -352.686112)
		(mid 273.4945 -352.305112)
		(end 273.1135 -351.924112)
		(stroke
			(width 0.2)
			(type default)
		)
		(layer "In1.Cu")
	)
	(gr_line
		(start 273.1135 -351.924112)
		(end 271.970754 -351.924112)
		(stroke
			(width 0.2)
			(type default)
		)
		(layer "In1.Cu")
	)
	(gr_arc
		(start 273.1135 -350.886014)
		(mid 273.4945 -350.505014)
		(end 273.1135 -350.124014)
		(stroke
			(width 0.2)
			(type default)
		)
		(layer "In1.Cu")
	)
	(gr_line
		(start 273.1135 -350.124014)
		(end 271.970754 -350.124014)
		(stroke
			(width 0.2)
			(type default)
		)
		(layer "In1.Cu")
	)
	(gr_arc
		(start 273.1135 -338.28863)
		(mid 273.49704 -337.90509)
		(end 273.1135 -337.52155)
		(stroke
			(width 0.2)
			(type default)
		)
		(layer "In1.Cu")
	)
	(gr_line
		(start 273.1135 -337.52155)
		(end 271.970754 -337.52155)
		(stroke
			(width 0.2)
			(type default)
		)
		(layer "In1.Cu")
	)
	(gr_arc
		(start 273.1135 -336.488532)
		(mid 273.49704 -336.104992)
		(end 273.1135 -335.721452)
		(stroke
			(width 0.2)
			(type default)
		)
		(layer "In1.Cu")
	)
	(gr_line
		(start 273.1135 -335.721452)
		(end 271.970754 -335.721452)
		(stroke
			(width 0.2)
			(type default)
		)
		(layer "In1.Cu")
	)
	(gr_arc
		(start 273.1135 -334.688434)
		(mid 273.49704 -334.304894)
		(end 273.1135 -333.921354)
		(stroke
			(width 0.2)
			(type default)
		)
		(layer "In1.Cu")
	)
	(gr_line
		(start 273.1135 -333.921354)
		(end 271.970754 -333.921354)
		(stroke
			(width 0.2)
			(type default)
		)
		(layer "In1.Cu")
	)
	(gr_arc
		(start 273.1135 -332.88859)
		(mid 273.49704 -332.50505)
		(end 273.1135 -332.12151)
		(stroke
			(width 0.2)
			(type default)
		)
		(layer "In1.Cu")
	)
	(gr_line
		(start 273.1135 -332.12151)
		(end 271.970754 -332.12151)
		(stroke
			(width 0.2)
			(type default)
		)
		(layer "In1.Cu")
	)
	(gr_arc
		(start 273.1135 -331.088492)
		(mid 273.49704 -330.704952)
		(end 273.1135 -330.321412)
		(stroke
			(width 0.2)
			(type default)
		)
		(layer "In1.Cu")
	)
	(gr_line
		(start 273.1135 -330.321412)
		(end 271.970754 -330.321412)
		(stroke
			(width 0.2)
			(type default)
		)
		(layer "In1.Cu")
	)
	(gr_arc
		(start 273.1135 -329.288648)
		(mid 273.49704 -328.905108)
		(end 273.1135 -328.521568)
		(stroke
			(width 0.2)
			(type default)
		)
		(layer "In1.Cu")
	)
	(gr_line
		(start 273.1135 -328.521568)
		(end 271.970754 -328.521568)
		(stroke
			(width 0.2)
			(type default)
		)
		(layer "In1.Cu")
	)
	(gr_arc
		(start 273.1135 -316.68847)
		(mid 273.49704 -316.30493)
		(end 273.1135 -315.92139)
		(stroke
			(width 0.2)
			(type default)
		)
		(layer "In1.Cu")
	)
	(gr_line
		(start 273.1135 -315.92139)
		(end 271.970754 -315.92139)
		(stroke
			(width 0.2)
			(type default)
		)
		(layer "In1.Cu")
	)
	(gr_arc
		(start 273.1135 -314.888626)
		(mid 273.49704 -314.505086)
		(end 273.1135 -314.121546)
		(stroke
			(width 0.2)
			(type default)
		)
		(layer "In1.Cu")
	)
	(gr_line
		(start 273.1135 -314.121546)
		(end 271.970754 -314.121546)
		(stroke
			(width 0.2)
			(type default)
		)
		(layer "In1.Cu")
	)
	(gr_arc
		(start 273.1135 -313.088528)
		(mid 273.49704 -312.704988)
		(end 273.1135 -312.321448)
		(stroke
			(width 0.2)
			(type default)
		)
		(layer "In1.Cu")
	)
	(gr_line
		(start 273.1135 -312.321448)
		(end 271.970754 -312.321448)
		(stroke
			(width 0.2)
			(type default)
		)
		(layer "In1.Cu")
	)
	(gr_arc
		(start 273.1135 -311.28843)
		(mid 273.49704 -310.90489)
		(end 273.1135 -310.52135)
		(stroke
			(width 0.2)
			(type default)
		)
		(layer "In1.Cu")
	)
	(gr_line
		(start 273.1135 -310.52135)
		(end 271.970754 -310.52135)
		(stroke
			(width 0.2)
			(type default)
		)
		(layer "In1.Cu")
	)
	(gr_arc
		(start 273.1135 -309.488586)
		(mid 273.49704 -309.105046)
		(end 273.1135 -308.721506)
		(stroke
			(width 0.2)
			(type default)
		)
		(layer "In1.Cu")
	)
	(gr_line
		(start 273.1135 -308.721506)
		(end 271.970754 -308.721506)
		(stroke
			(width 0.2)
			(type default)
		)
		(layer "In1.Cu")
	)
	(gr_arc
		(start 273.1135 -307.688488)
		(mid 273.49704 -307.304948)
		(end 273.1135 -306.921408)
		(stroke
			(width 0.2)
			(type default)
		)
		(layer "In1.Cu")
	)
	(gr_line
		(start 273.1135 -306.921408)
		(end 271.970754 -306.921408)
		(stroke
			(width 0.2)
			(type default)
		)
		(layer "In1.Cu")
	)
	(gr_line
		(start 278.23668 -356.453694)
		(end 279.636728 -356.453694)
		(stroke
			(width 0.2)
			(type default)
		)
		(layer "In1.Cu")
	)
	(gr_arc
		(start 278.23668 -355.356414)
		(mid 277.68804 -355.905054)
		(end 278.23668 -356.453694)
		(stroke
			(width 0.2)
			(type default)
		)
		(layer "In1.Cu")
	)
	(gr_line
		(start 278.23668 -352.853752)
		(end 279.636728 -352.853752)
		(stroke
			(width 0.2)
			(type default)
		)
		(layer "In1.Cu")
	)
	(gr_arc
		(start 278.23668 -351.756472)
		(mid 277.68804 -352.305112)
		(end 278.23668 -352.853752)
		(stroke
			(width 0.2)
			(type default)
		)
		(layer "In1.Cu")
	)
	(gr_line
		(start 278.23668 -349.25381)
		(end 279.636728 -349.25381)
		(stroke
			(width 0.2)
			(type default)
		)
		(layer "In1.Cu")
	)
	(gr_arc
		(start 278.23668 -348.15653)
		(mid 277.68804 -348.70517)
		(end 278.23668 -349.25381)
		(stroke
			(width 0.2)
			(type default)
		)
		(layer "In1.Cu")
	)
	(gr_line
		(start 278.23668 -345.653868)
		(end 279.636728 -345.653868)
		(stroke
			(width 0.2)
			(type default)
		)
		(layer "In1.Cu")
	)
	(gr_arc
		(start 278.23668 -344.556588)
		(mid 277.68804 -345.105228)
		(end 278.23668 -345.653868)
		(stroke
			(width 0.2)
			(type default)
		)
		(layer "In1.Cu")
	)
	(gr_line
		(start 278.23668 -342.053672)
		(end 279.636728 -342.053672)
		(stroke
			(width 0.2)
			(type default)
		)
		(layer "In1.Cu")
	)
	(gr_arc
		(start 278.23668 -340.956392)
		(mid 277.68804 -341.505032)
		(end 278.23668 -342.053672)
		(stroke
			(width 0.2)
			(type default)
		)
		(layer "In1.Cu")
	)
	(gr_line
		(start 278.23668 -338.45373)
		(end 279.636728 -338.45373)
		(stroke
			(width 0.2)
			(type default)
		)
		(layer "In1.Cu")
	)
	(gr_arc
		(start 278.23668 -337.35645)
		(mid 277.68804 -337.90509)
		(end 278.23668 -338.45373)
		(stroke
			(width 0.2)
			(type default)
		)
		(layer "In1.Cu")
	)
	(gr_line
		(start 278.23668 -334.853788)
		(end 279.636728 -334.853788)
		(stroke
			(width 0.2)
			(type default)
		)
		(layer "In1.Cu")
	)
	(gr_arc
		(start 278.23668 -333.756508)
		(mid 277.68804 -334.305148)
		(end 278.23668 -334.853788)
		(stroke
			(width 0.2)
			(type default)
		)
		(layer "In1.Cu")
	)
	(gr_line
		(start 278.23668 -331.253846)
		(end 279.636728 -331.253846)
		(stroke
			(width 0.2)
			(type default)
		)
		(layer "In1.Cu")
	)
	(gr_arc
		(start 278.23668 -330.156566)
		(mid 277.68804 -330.705206)
		(end 278.23668 -331.253846)
		(stroke
			(width 0.2)
			(type default)
		)
		(layer "In1.Cu")
	)
	(gr_line
		(start 278.23668 -327.653904)
		(end 279.636728 -327.653904)
		(stroke
			(width 0.2)
			(type default)
		)
		(layer "In1.Cu")
	)
	(gr_arc
		(start 278.23668 -326.556624)
		(mid 277.68804 -327.105264)
		(end 278.23668 -327.653904)
		(stroke
			(width 0.2)
			(type default)
		)
		(layer "In1.Cu")
	)
	(gr_line
		(start 278.23668 -324.053708)
		(end 279.636728 -324.053708)
		(stroke
			(width 0.2)
			(type default)
		)
		(layer "In1.Cu")
	)
	(gr_arc
		(start 278.23668 -322.956428)
		(mid 277.68804 -323.505068)
		(end 278.23668 -324.053708)
		(stroke
			(width 0.2)
			(type default)
		)
		(layer "In1.Cu")
	)
	(gr_line
		(start 278.23668 -320.453766)
		(end 279.636728 -320.453766)
		(stroke
			(width 0.2)
			(type default)
		)
		(layer "In1.Cu")
	)
	(gr_arc
		(start 278.23668 -319.356486)
		(mid 277.68804 -319.905126)
		(end 278.23668 -320.453766)
		(stroke
			(width 0.2)
			(type default)
		)
		(layer "In1.Cu")
	)
	(gr_line
		(start 278.23668 -316.853824)
		(end 279.636728 -316.853824)
		(stroke
			(width 0.2)
			(type default)
		)
		(layer "In1.Cu")
	)
	(gr_arc
		(start 278.23668 -315.756544)
		(mid 277.68804 -316.305184)
		(end 278.23668 -316.853824)
		(stroke
			(width 0.2)
			(type default)
		)
		(layer "In1.Cu")
	)
	(gr_line
		(start 278.23668 -313.253882)
		(end 279.636728 -313.253882)
		(stroke
			(width 0.2)
			(type default)
		)
		(layer "In1.Cu")
	)
	(gr_arc
		(start 278.23668 -312.156602)
		(mid 277.68804 -312.705242)
		(end 278.23668 -313.253882)
		(stroke
			(width 0.2)
			(type default)
		)
		(layer "In1.Cu")
	)
	(gr_line
		(start 278.23668 -309.653686)
		(end 279.636728 -309.653686)
		(stroke
			(width 0.2)
			(type default)
		)
		(layer "In1.Cu")
	)
	(gr_arc
		(start 278.23668 -308.556406)
		(mid 277.68804 -309.105046)
		(end 278.23668 -309.653686)
		(stroke
			(width 0.2)
			(type default)
		)
		(layer "In1.Cu")
	)
	(gr_line
		(start 278.23668 -306.053744)
		(end 279.636728 -306.053744)
		(stroke
			(width 0.2)
			(type default)
		)
		(layer "In1.Cu")
	)
	(gr_arc
		(start 278.23668 -304.956464)
		(mid 277.68804 -305.505104)
		(end 278.23668 -306.053744)
		(stroke
			(width 0.2)
			(type default)
		)
		(layer "In1.Cu")
	)
	(gr_line
		(start 278.23668 -302.453802)
		(end 279.636728 -302.453802)
		(stroke
			(width 0.2)
			(type default)
		)
		(layer "In1.Cu")
	)
	(gr_arc
		(start 278.23668 -301.356522)
		(mid 277.68804 -301.905162)
		(end 278.23668 -302.453802)
		(stroke
			(width 0.2)
			(type default)
		)
		(layer "In1.Cu")
	)
	(gr_line
		(start 278.23668 -298.85386)
		(end 279.636728 -298.85386)
		(stroke
			(width 0.2)
			(type default)
		)
		(layer "In1.Cu")
	)
	(gr_arc
		(start 278.23668 -297.75658)
		(mid 277.68804 -298.30522)
		(end 278.23668 -298.85386)
		(stroke
			(width 0.2)
			(type default)
		)
		(layer "In1.Cu")
	)
	(gr_line
		(start 278.23668 -295.253918)
		(end 279.636728 -295.253918)
		(stroke
			(width 0.2)
			(type default)
		)
		(layer "In1.Cu")
	)
	(gr_arc
		(start 278.23668 -294.156638)
		(mid 277.68804 -294.705278)
		(end 278.23668 -295.253918)
		(stroke
			(width 0.2)
			(type default)
		)
		(layer "In1.Cu")
	)
	(gr_line
		(start 278.23668 -262.453374)
		(end 279.636728 -262.453374)
		(stroke
			(width 0.2)
			(type default)
		)
		(layer "In1.Cu")
	)
	(gr_arc
		(start 278.23668 -261.351014)
		(mid 277.6855 -261.902194)
		(end 278.23668 -262.453374)
		(stroke
			(width 0.2)
			(type default)
		)
		(layer "In1.Cu")
	)
	(gr_line
		(start 278.23668 -258.853432)
		(end 279.636728 -258.853432)
		(stroke
			(width 0.2)
			(type default)
		)
		(layer "In1.Cu")
	)
	(gr_arc
		(start 278.23668 -257.751072)
		(mid 277.6855 -258.302252)
		(end 278.23668 -258.853432)
		(stroke
			(width 0.2)
			(type default)
		)
		(layer "In1.Cu")
	)
	(gr_line
		(start 278.23668 -255.25349)
		(end 279.636728 -255.25349)
		(stroke
			(width 0.2)
			(type default)
		)
		(layer "In1.Cu")
	)
	(gr_arc
		(start 278.23668 -254.15113)
		(mid 277.6855 -254.70231)
		(end 278.23668 -255.25349)
		(stroke
			(width 0.2)
			(type default)
		)
		(layer "In1.Cu")
	)
	(gr_line
		(start 278.23668 -251.653548)
		(end 279.636728 -251.653548)
		(stroke
			(width 0.2)
			(type default)
		)
		(layer "In1.Cu")
	)
	(gr_arc
		(start 278.23668 -250.551188)
		(mid 277.6855 -251.102368)
		(end 278.23668 -251.653548)
		(stroke
			(width 0.2)
			(type default)
		)
		(layer "In1.Cu")
	)
	(gr_line
		(start 278.236934 -355.356414)
		(end 278.23668 -355.356414)
		(stroke
			(width 0.2)
			(type default)
		)
		(layer "In1.Cu")
	)
	(gr_line
		(start 278.236934 -351.756472)
		(end 278.23668 -351.756472)
		(stroke
			(width 0.2)
			(type default)
		)
		(layer "In1.Cu")
	)
	(gr_line
		(start 278.236934 -348.15653)
		(end 278.23668 -348.15653)
		(stroke
			(width 0.2)
			(type default)
		)
		(layer "In1.Cu")
	)
	(gr_line
		(start 278.236934 -344.556588)
		(end 278.23668 -344.556588)
		(stroke
			(width 0.2)
			(type default)
		)
		(layer "In1.Cu")
	)
	(gr_line
		(start 278.236934 -340.956392)
		(end 278.23668 -340.956392)
		(stroke
			(width 0.2)
			(type default)
		)
		(layer "In1.Cu")
	)
	(gr_line
		(start 278.236934 -337.35645)
		(end 278.23668 -337.35645)
		(stroke
			(width 0.2)
			(type default)
		)
		(layer "In1.Cu")
	)
	(gr_line
		(start 278.236934 -333.756508)
		(end 278.23668 -333.756508)
		(stroke
			(width 0.2)
			(type default)
		)
		(layer "In1.Cu")
	)
	(gr_line
		(start 278.236934 -330.156566)
		(end 278.23668 -330.156566)
		(stroke
			(width 0.2)
			(type default)
		)
		(layer "In1.Cu")
	)
	(gr_line
		(start 278.236934 -326.556624)
		(end 278.23668 -326.556624)
		(stroke
			(width 0.2)
			(type default)
		)
		(layer "In1.Cu")
	)
	(gr_line
		(start 278.236934 -322.956428)
		(end 278.23668 -322.956428)
		(stroke
			(width 0.2)
			(type default)
		)
		(layer "In1.Cu")
	)
	(gr_line
		(start 278.236934 -319.356486)
		(end 278.23668 -319.356486)
		(stroke
			(width 0.2)
			(type default)
		)
		(layer "In1.Cu")
	)
	(gr_line
		(start 278.236934 -315.756544)
		(end 278.23668 -315.756544)
		(stroke
			(width 0.2)
			(type default)
		)
		(layer "In1.Cu")
	)
	(gr_line
		(start 278.236934 -312.156602)
		(end 278.23668 -312.156602)
		(stroke
			(width 0.2)
			(type default)
		)
		(layer "In1.Cu")
	)
	(gr_line
		(start 278.236934 -308.556406)
		(end 278.23668 -308.556406)
		(stroke
			(width 0.2)
			(type default)
		)
		(layer "In1.Cu")
	)
	(gr_line
		(start 278.236934 -304.956464)
		(end 278.23668 -304.956464)
		(stroke
			(width 0.2)
			(type default)
		)
		(layer "In1.Cu")
	)
	(gr_line
		(start 278.236934 -301.356522)
		(end 278.23668 -301.356522)
		(stroke
			(width 0.2)
			(type default)
		)
		(layer "In1.Cu")
	)
	(gr_line
		(start 278.236934 -297.75658)
		(end 278.23668 -297.75658)
		(stroke
			(width 0.2)
			(type default)
		)
		(layer "In1.Cu")
	)
	(gr_line
		(start 278.236934 -294.156638)
		(end 278.23668 -294.156638)
		(stroke
			(width 0.2)
			(type default)
		)
		(layer "In1.Cu")
	)
	(gr_line
		(start 278.236934 -261.351014)
		(end 278.23668 -261.351014)
		(stroke
			(width 0.2)
			(type default)
		)
		(layer "In1.Cu")
	)
	(gr_line
		(start 278.236934 -257.751072)
		(end 278.23668 -257.751072)
		(stroke
			(width 0.2)
			(type default)
		)
		(layer "In1.Cu")
	)
	(gr_line
		(start 278.236934 -254.15113)
		(end 278.23668 -254.15113)
		(stroke
			(width 0.2)
			(type default)
		)
		(layer "In1.Cu")
	)
	(gr_line
		(start 278.236934 -250.551188)
		(end 278.23668 -250.551188)
		(stroke
			(width 0.2)
			(type default)
		)
		(layer "In1.Cu")
	)
	(gr_line
		(start 278.424132 -177.848006)
		(end 278.425148 -177.850038)
		(stroke
			(width 0.2)
			(type default)
		)
		(layer "In1.Cu")
	)
	(gr_line
		(start 278.424132 -177.847752)
		(end 278.424132 -177.848006)
		(stroke
			(width 0.2)
			(type default)
		)
		(layer "In1.Cu")
	)
	(gr_line
		(start 278.424132 -173.848014)
		(end 278.425148 -173.850046)
		(stroke
			(width 0.2)
			(type default)
		)
		(layer "In1.Cu")
	)
	(gr_line
		(start 278.424132 -173.84776)
		(end 278.424132 -173.848014)
		(stroke
			(width 0.2)
			(type default)
		)
		(layer "In1.Cu")
	)
	(gr_line
		(start 278.424132 -169.848022)
		(end 278.425148 -169.850054)
		(stroke
			(width 0.2)
			(type default)
		)
		(layer "In1.Cu")
	)
	(gr_line
		(start 278.424132 -169.847768)
		(end 278.424132 -169.848022)
		(stroke
			(width 0.2)
			(type default)
		)
		(layer "In1.Cu")
	)
	(gr_line
		(start 278.424132 -165.84803)
		(end 278.425148 -165.850062)
		(stroke
			(width 0.2)
			(type default)
		)
		(layer "In1.Cu")
	)
	(gr_line
		(start 278.424132 -165.847776)
		(end 278.424132 -165.84803)
		(stroke
			(width 0.2)
			(type default)
		)
		(layer "In1.Cu")
	)
	(gr_line
		(start 278.424132 -137.848086)
		(end 278.425148 -137.850118)
		(stroke
			(width 0.2)
			(type default)
		)
		(layer "In1.Cu")
	)
	(gr_line
		(start 278.424132 -137.847832)
		(end 278.424132 -137.848086)
		(stroke
			(width 0.2)
			(type default)
		)
		(layer "In1.Cu")
	)
	(gr_line
		(start 278.424132 -81.548224)
		(end 278.425148 -81.550256)
		(stroke
			(width 0.2)
			(type default)
		)
		(layer "In1.Cu")
	)
	(gr_line
		(start 278.424132 -81.54797)
		(end 278.424132 -81.548224)
		(stroke
			(width 0.2)
			(type default)
		)
		(layer "In1.Cu")
	)
	(gr_line
		(start 278.424132 -77.548232)
		(end 278.425148 -77.550264)
		(stroke
			(width 0.2)
			(type default)
		)
		(layer "In1.Cu")
	)
	(gr_line
		(start 278.424132 -77.547978)
		(end 278.424132 -77.548232)
		(stroke
			(width 0.2)
			(type default)
		)
		(layer "In1.Cu")
	)
	(gr_line
		(start 278.424132 -73.54824)
		(end 278.425148 -73.550272)
		(stroke
			(width 0.2)
			(type default)
		)
		(layer "In1.Cu")
	)
	(gr_line
		(start 278.424132 -73.547986)
		(end 278.424132 -73.54824)
		(stroke
			(width 0.2)
			(type default)
		)
		(layer "In1.Cu")
	)
	(gr_line
		(start 278.424132 -69.548248)
		(end 278.425148 -69.55028)
		(stroke
			(width 0.2)
			(type default)
		)
		(layer "In1.Cu")
	)
	(gr_line
		(start 278.424132 -69.547994)
		(end 278.424132 -69.548248)
		(stroke
			(width 0.2)
			(type default)
		)
		(layer "In1.Cu")
	)
	(gr_line
		(start 278.424132 -65.548256)
		(end 278.425148 -65.550288)
		(stroke
			(width 0.2)
			(type default)
		)
		(layer "In1.Cu")
	)
	(gr_line
		(start 278.424132 -65.548002)
		(end 278.424132 -65.548256)
		(stroke
			(width 0.2)
			(type default)
		)
		(layer "In1.Cu")
	)
	(gr_line
		(start 278.424132 -61.548264)
		(end 278.425148 -61.550296)
		(stroke
			(width 0.2)
			(type default)
		)
		(layer "In1.Cu")
	)
	(gr_line
		(start 278.424132 -61.54801)
		(end 278.424132 -61.548264)
		(stroke
			(width 0.2)
			(type default)
		)
		(layer "In1.Cu")
	)
	(gr_line
		(start 278.424132 -57.548272)
		(end 278.425148 -57.550304)
		(stroke
			(width 0.2)
			(type default)
		)
		(layer "In1.Cu")
	)
	(gr_line
		(start 278.424132 -57.548018)
		(end 278.424132 -57.548272)
		(stroke
			(width 0.2)
			(type default)
		)
		(layer "In1.Cu")
	)
	(gr_line
		(start 278.424132 -53.54828)
		(end 278.425148 -53.550312)
		(stroke
			(width 0.2)
			(type default)
		)
		(layer "In1.Cu")
	)
	(gr_line
		(start 278.424132 -53.548026)
		(end 278.424132 -53.54828)
		(stroke
			(width 0.2)
			(type default)
		)
		(layer "In1.Cu")
	)
	(gr_line
		(start 278.424132 -49.548288)
		(end 278.425148 -49.55032)
		(stroke
			(width 0.2)
			(type default)
		)
		(layer "In1.Cu")
	)
	(gr_line
		(start 278.424132 -49.548034)
		(end 278.424132 -49.548288)
		(stroke
			(width 0.2)
			(type default)
		)
		(layer "In1.Cu")
	)
	(gr_line
		(start 278.424132 -45.548296)
		(end 278.425148 -45.550328)
		(stroke
			(width 0.2)
			(type default)
		)
		(layer "In1.Cu")
	)
	(gr_line
		(start 278.424132 -45.548042)
		(end 278.424132 -45.548296)
		(stroke
			(width 0.2)
			(type default)
		)
		(layer "In1.Cu")
	)
	(gr_line
		(start 278.424132 -41.548304)
		(end 278.425148 -41.550336)
		(stroke
			(width 0.2)
			(type default)
		)
		(layer "In1.Cu")
	)
	(gr_line
		(start 278.424132 -41.54805)
		(end 278.424132 -41.548304)
		(stroke
			(width 0.2)
			(type default)
		)
		(layer "In1.Cu")
	)
	(gr_line
		(start 278.424132 -37.548312)
		(end 278.425148 -37.550344)
		(stroke
			(width 0.2)
			(type default)
		)
		(layer "In1.Cu")
	)
	(gr_line
		(start 278.424132 -37.548058)
		(end 278.424132 -37.548312)
		(stroke
			(width 0.2)
			(type default)
		)
		(layer "In1.Cu")
	)
	(gr_line
		(start 278.424132 -17.548352)
		(end 278.425148 -17.550384)
		(stroke
			(width 0.2)
			(type default)
		)
		(layer "In1.Cu")
	)
	(gr_line
		(start 278.424132 -17.548098)
		(end 278.424132 -17.548352)
		(stroke
			(width 0.2)
			(type default)
		)
		(layer "In1.Cu")
	)
	(gr_arc
		(start 278.425148 -177.850038)
		(mid 278.100282 -178.824636)
		(end 279.07488 -179.149502)
		(stroke
			(width 0.2)
			(type default)
		)
		(layer "In1.Cu")
	)
	(gr_arc
		(start 278.425148 -173.850046)
		(mid 278.100282 -174.824644)
		(end 279.07488 -175.14951)
		(stroke
			(width 0.2)
			(type default)
		)
		(layer "In1.Cu")
	)
	(gr_arc
		(start 278.425148 -169.850054)
		(mid 278.100282 -170.824652)
		(end 279.07488 -171.149518)
		(stroke
			(width 0.2)
			(type default)
		)
		(layer "In1.Cu")
	)
	(gr_arc
		(start 278.425148 -165.850062)
		(mid 278.100282 -166.82466)
		(end 279.07488 -167.149526)
		(stroke
			(width 0.2)
			(type default)
		)
		(layer "In1.Cu")
	)
	(gr_arc
		(start 278.425148 -137.850118)
		(mid 278.100282 -138.824716)
		(end 279.07488 -139.149582)
		(stroke
			(width 0.2)
			(type default)
		)
		(layer "In1.Cu")
	)
	(gr_arc
		(start 278.425148 -81.550256)
		(mid 278.100282 -82.524854)
		(end 279.07488 -82.84972)
		(stroke
			(width 0.2)
			(type default)
		)
		(layer "In1.Cu")
	)
	(gr_arc
		(start 278.425148 -77.550264)
		(mid 278.100282 -78.524862)
		(end 279.07488 -78.849728)
		(stroke
			(width 0.2)
			(type default)
		)
		(layer "In1.Cu")
	)
	(gr_arc
		(start 278.425148 -73.550272)
		(mid 278.100282 -74.52487)
		(end 279.07488 -74.849736)
		(stroke
			(width 0.2)
			(type default)
		)
		(layer "In1.Cu")
	)
	(gr_arc
		(start 278.425148 -69.55028)
		(mid 278.100282 -70.524878)
		(end 279.07488 -70.849744)
		(stroke
			(width 0.2)
			(type default)
		)
		(layer "In1.Cu")
	)
	(gr_arc
		(start 278.425148 -65.550288)
		(mid 278.100282 -66.524886)
		(end 279.07488 -66.849752)
		(stroke
			(width 0.2)
			(type default)
		)
		(layer "In1.Cu")
	)
	(gr_arc
		(start 278.425148 -61.550296)
		(mid 278.100282 -62.524894)
		(end 279.07488 -62.84976)
		(stroke
			(width 0.2)
			(type default)
		)
		(layer "In1.Cu")
	)
	(gr_arc
		(start 278.425148 -57.550304)
		(mid 278.100282 -58.524902)
		(end 279.07488 -58.849768)
		(stroke
			(width 0.2)
			(type default)
		)
		(layer "In1.Cu")
	)
	(gr_arc
		(start 278.425148 -53.550312)
		(mid 278.100282 -54.52491)
		(end 279.07488 -54.849776)
		(stroke
			(width 0.2)
			(type default)
		)
		(layer "In1.Cu")
	)
	(gr_arc
		(start 278.425148 -49.55032)
		(mid 278.100282 -50.524918)
		(end 279.07488 -50.849784)
		(stroke
			(width 0.2)
			(type default)
		)
		(layer "In1.Cu")
	)
	(gr_arc
		(start 278.425148 -45.550328)
		(mid 278.100282 -46.524926)
		(end 279.07488 -46.849792)
		(stroke
			(width 0.2)
			(type default)
		)
		(layer "In1.Cu")
	)
	(gr_arc
		(start 278.425148 -41.550336)
		(mid 278.100282 -42.524934)
		(end 279.07488 -42.8498)
		(stroke
			(width 0.2)
			(type default)
		)
		(layer "In1.Cu")
	)
	(gr_arc
		(start 278.425148 -37.550344)
		(mid 278.100282 -38.524942)
		(end 279.07488 -38.849808)
		(stroke
			(width 0.2)
			(type default)
		)
		(layer "In1.Cu")
	)
	(gr_arc
		(start 278.425148 -17.550384)
		(mid 278.100282 -18.524982)
		(end 279.07488 -18.849848)
		(stroke
			(width 0.2)
			(type default)
		)
		(layer "In1.Cu")
	)
	(gr_arc
		(start 278.426418 -161.852356)
		(mid 278.102619 -162.8235)
		(end 279.073864 -163.147248)
		(stroke
			(width 0.2)
			(type default)
		)
		(layer "In1.Cu")
	)
	(gr_line
		(start 278.426418 -161.852102)
		(end 278.426418 -161.852356)
		(stroke
			(width 0.2)
			(type default)
		)
		(layer "In1.Cu")
	)
	(gr_arc
		(start 278.426418 -157.852364)
		(mid 278.102619 -158.823508)
		(end 279.073864 -159.147256)
		(stroke
			(width 0.2)
			(type default)
		)
		(layer "In1.Cu")
	)
	(gr_line
		(start 278.426418 -157.85211)
		(end 278.426418 -157.852364)
		(stroke
			(width 0.2)
			(type default)
		)
		(layer "In1.Cu")
	)
	(gr_arc
		(start 278.426418 -153.852372)
		(mid 278.102619 -154.823516)
		(end 279.073864 -155.147264)
		(stroke
			(width 0.2)
			(type default)
		)
		(layer "In1.Cu")
	)
	(gr_line
		(start 278.426418 -153.852118)
		(end 278.426418 -153.852372)
		(stroke
			(width 0.2)
			(type default)
		)
		(layer "In1.Cu")
	)
	(gr_arc
		(start 278.426418 -149.85238)
		(mid 278.102619 -150.823524)
		(end 279.073864 -151.147272)
		(stroke
			(width 0.2)
			(type default)
		)
		(layer "In1.Cu")
	)
	(gr_line
		(start 278.426418 -149.852126)
		(end 278.426418 -149.85238)
		(stroke
			(width 0.2)
			(type default)
		)
		(layer "In1.Cu")
	)
	(gr_arc
		(start 278.426418 -129.85242)
		(mid 278.102619 -130.823564)
		(end 279.073864 -131.147312)
		(stroke
			(width 0.2)
			(type default)
		)
		(layer "In1.Cu")
	)
	(gr_line
		(start 278.426418 -129.852166)
		(end 278.426418 -129.85242)
		(stroke
			(width 0.2)
			(type default)
		)
		(layer "In1.Cu")
	)
	(gr_arc
		(start 278.426418 -125.852428)
		(mid 278.102619 -126.823572)
		(end 279.073864 -127.14732)
		(stroke
			(width 0.2)
			(type default)
		)
		(layer "In1.Cu")
	)
	(gr_line
		(start 278.426418 -125.852174)
		(end 278.426418 -125.852428)
		(stroke
			(width 0.2)
			(type default)
		)
		(layer "In1.Cu")
	)
	(gr_arc
		(start 278.426418 -121.852436)
		(mid 278.102619 -122.82358)
		(end 279.073864 -123.147328)
		(stroke
			(width 0.2)
			(type default)
		)
		(layer "In1.Cu")
	)
	(gr_line
		(start 278.426418 -121.852182)
		(end 278.426418 -121.852436)
		(stroke
			(width 0.2)
			(type default)
		)
		(layer "In1.Cu")
	)
	(gr_arc
		(start 278.426418 -117.852444)
		(mid 278.102619 -118.823588)
		(end 279.073864 -119.147336)
		(stroke
			(width 0.2)
			(type default)
		)
		(layer "In1.Cu")
	)
	(gr_line
		(start 278.426418 -117.85219)
		(end 278.426418 -117.852444)
		(stroke
			(width 0.2)
			(type default)
		)
		(layer "In1.Cu")
	)
	(gr_arc
		(start 278.433784 -11.54049)
		(mid 278.093387 -12.52152)
		(end 279.077166 -12.854432)
		(stroke
			(width 0.2)
			(type default)
		)
		(layer "In1.Cu")
	)
	(gr_arc
		(start 278.44496 -113.868708)
		(mid 278.120865 -114.809139)
		(end 279.06345 -115.127024)
		(stroke
			(width 0.2)
			(type default)
		)
		(layer "In1.Cu")
	)
	(gr_line
		(start 279.06345 -115.127024)
		(end 281.063446 -114.127026)
		(stroke
			(width 0.2)
			(type default)
		)
		(layer "In1.Cu")
	)
	(gr_line
		(start 279.073864 -163.147248)
		(end 281.07386 -162.14725)
		(stroke
			(width 0.2)
			(type default)
		)
		(layer "In1.Cu")
	)
	(gr_line
		(start 279.073864 -159.147256)
		(end 281.07386 -158.147258)
		(stroke
			(width 0.2)
			(type default)
		)
		(layer "In1.Cu")
	)
	(gr_line
		(start 279.073864 -155.147264)
		(end 281.07386 -154.147266)
		(stroke
			(width 0.2)
			(type default)
		)
		(layer "In1.Cu")
	)
	(gr_line
		(start 279.073864 -151.147272)
		(end 281.07386 -150.147274)
		(stroke
			(width 0.2)
			(type default)
		)
		(layer "In1.Cu")
	)
	(gr_line
		(start 279.073864 -131.147312)
		(end 281.07386 -130.147314)
		(stroke
			(width 0.2)
			(type default)
		)
		(layer "In1.Cu")
	)
	(gr_line
		(start 279.073864 -127.14732)
		(end 281.07386 -126.147322)
		(stroke
			(width 0.2)
			(type default)
		)
		(layer "In1.Cu")
	)
	(gr_line
		(start 279.073864 -123.147328)
		(end 281.07386 -122.14733)
		(stroke
			(width 0.2)
			(type default)
		)
		(layer "In1.Cu")
	)
	(gr_line
		(start 279.073864 -119.147336)
		(end 281.07386 -118.147338)
		(stroke
			(width 0.2)
			(type default)
		)
		(layer "In1.Cu")
	)
	(gr_line
		(start 279.07488 -179.149502)
		(end 279.07615 -179.151788)
		(stroke
			(width 0.2)
			(type default)
		)
		(layer "In1.Cu")
	)
	(gr_line
		(start 279.07488 -175.14951)
		(end 279.07615 -175.151796)
		(stroke
			(width 0.2)
			(type default)
		)
		(layer "In1.Cu")
	)
	(gr_line
		(start 279.07488 -171.149518)
		(end 279.07615 -171.151804)
		(stroke
			(width 0.2)
			(type default)
		)
		(layer "In1.Cu")
	)
	(gr_line
		(start 279.07488 -167.149526)
		(end 279.07615 -167.151812)
		(stroke
			(width 0.2)
			(type default)
		)
		(layer "In1.Cu")
	)
	(gr_line
		(start 279.07488 -139.149582)
		(end 279.07615 -139.151868)
		(stroke
			(width 0.2)
			(type default)
		)
		(layer "In1.Cu")
	)
	(gr_line
		(start 279.07488 -82.84972)
		(end 279.07615 -82.852006)
		(stroke
			(width 0.2)
			(type default)
		)
		(layer "In1.Cu")
	)
	(gr_line
		(start 279.07488 -78.849728)
		(end 279.07615 -78.852014)
		(stroke
			(width 0.2)
			(type default)
		)
		(layer "In1.Cu")
	)
	(gr_line
		(start 279.07488 -74.849736)
		(end 279.07615 -74.852022)
		(stroke
			(width 0.2)
			(type default)
		)
		(layer "In1.Cu")
	)
	(gr_line
		(start 279.07488 -70.849744)
		(end 279.07615 -70.85203)
		(stroke
			(width 0.2)
			(type default)
		)
		(layer "In1.Cu")
	)
	(gr_line
		(start 279.07488 -66.849752)
		(end 279.07615 -66.852038)
		(stroke
			(width 0.2)
			(type default)
		)
		(layer "In1.Cu")
	)
	(gr_line
		(start 279.07488 -62.84976)
		(end 279.07615 -62.852046)
		(stroke
			(width 0.2)
			(type default)
		)
		(layer "In1.Cu")
	)
	(gr_line
		(start 279.07488 -58.849768)
		(end 279.07615 -58.852054)
		(stroke
			(width 0.2)
			(type default)
		)
		(layer "In1.Cu")
	)
	(gr_line
		(start 279.07488 -54.849776)
		(end 279.07615 -54.852062)
		(stroke
			(width 0.2)
			(type default)
		)
		(layer "In1.Cu")
	)
	(gr_line
		(start 279.07488 -50.849784)
		(end 279.07615 -50.85207)
		(stroke
			(width 0.2)
			(type default)
		)
		(layer "In1.Cu")
	)
	(gr_line
		(start 279.07488 -46.849792)
		(end 279.07615 -46.852078)
		(stroke
			(width 0.2)
			(type default)
		)
		(layer "In1.Cu")
	)
	(gr_line
		(start 279.07488 -42.8498)
		(end 279.07615 -42.852086)
		(stroke
			(width 0.2)
			(type default)
		)
		(layer "In1.Cu")
	)
	(gr_line
		(start 279.07488 -38.849808)
		(end 279.07615 -38.852094)
		(stroke
			(width 0.2)
			(type default)
		)
		(layer "In1.Cu")
	)
	(gr_line
		(start 279.07488 -18.849848)
		(end 279.07615 -18.852134)
		(stroke
			(width 0.2)
			(type default)
		)
		(layer "In1.Cu")
	)
	(gr_line
		(start 279.07615 -179.151788)
		(end 281.076146 -178.15179)
		(stroke
			(width 0.2)
			(type default)
		)
		(layer "In1.Cu")
	)
	(gr_line
		(start 279.07615 -175.151796)
		(end 281.076146 -174.151798)
		(stroke
			(width 0.2)
			(type default)
		)
		(layer "In1.Cu")
	)
	(gr_line
		(start 279.07615 -171.151804)
		(end 281.076146 -170.151806)
		(stroke
			(width 0.2)
			(type default)
		)
		(layer "In1.Cu")
	)
	(gr_line
		(start 279.07615 -167.151812)
		(end 281.076146 -166.151814)
		(stroke
			(width 0.2)
			(type default)
		)
		(layer "In1.Cu")
	)
	(gr_line
		(start 279.07615 -139.151868)
		(end 281.076146 -138.15187)
		(stroke
			(width 0.2)
			(type default)
		)
		(layer "In1.Cu")
	)
	(gr_line
		(start 279.07615 -82.852006)
		(end 281.076146 -81.852008)
		(stroke
			(width 0.2)
			(type default)
		)
		(layer "In1.Cu")
	)
	(gr_line
		(start 279.07615 -78.852014)
		(end 281.076146 -77.852016)
		(stroke
			(width 0.2)
			(type default)
		)
		(layer "In1.Cu")
	)
	(gr_line
		(start 279.07615 -74.852022)
		(end 281.076146 -73.852024)
		(stroke
			(width 0.2)
			(type default)
		)
		(layer "In1.Cu")
	)
	(gr_line
		(start 279.07615 -70.85203)
		(end 281.076146 -69.852032)
		(stroke
			(width 0.2)
			(type default)
		)
		(layer "In1.Cu")
	)
	(gr_line
		(start 279.07615 -66.852038)
		(end 281.076146 -65.85204)
		(stroke
			(width 0.2)
			(type default)
		)
		(layer "In1.Cu")
	)
	(gr_line
		(start 279.07615 -62.852046)
		(end 281.076146 -61.852048)
		(stroke
			(width 0.2)
			(type default)
		)
		(layer "In1.Cu")
	)
	(gr_line
		(start 279.07615 -58.852054)
		(end 281.076146 -57.852056)
		(stroke
			(width 0.2)
			(type default)
		)
		(layer "In1.Cu")
	)
	(gr_line
		(start 279.07615 -54.852062)
		(end 281.076146 -53.852064)
		(stroke
			(width 0.2)
			(type default)
		)
		(layer "In1.Cu")
	)
	(gr_line
		(start 279.07615 -50.85207)
		(end 281.076146 -49.852072)
		(stroke
			(width 0.2)
			(type default)
		)
		(layer "In1.Cu")
	)
	(gr_line
		(start 279.07615 -46.852078)
		(end 281.076146 -45.85208)
		(stroke
			(width 0.2)
			(type default)
		)
		(layer "In1.Cu")
	)
	(gr_line
		(start 279.07615 -42.852086)
		(end 281.076146 -41.852088)
		(stroke
			(width 0.2)
			(type default)
		)
		(layer "In1.Cu")
	)
	(gr_line
		(start 279.07615 -38.852094)
		(end 281.076146 -37.852096)
		(stroke
			(width 0.2)
			(type default)
		)
		(layer "In1.Cu")
	)
	(gr_line
		(start 279.07615 -18.852134)
		(end 281.076146 -17.852136)
		(stroke
			(width 0.2)
			(type default)
		)
		(layer "In1.Cu")
	)
	(gr_line
		(start 279.077166 -12.854432)
		(end 281.077162 -11.854434)
		(stroke
			(width 0.2)
			(type default)
		)
		(layer "In1.Cu")
	)
	(gr_line
		(start 279.236678 -358.253792)
		(end 280.636726 -358.253792)
		(stroke
			(width 0.2)
			(type default)
		)
		(layer "In1.Cu")
	)
	(gr_arc
		(start 279.236678 -357.156512)
		(mid 278.688038 -357.705152)
		(end 279.236678 -358.253792)
		(stroke
			(width 0.2)
			(type default)
		)
		(layer "In1.Cu")
	)
	(gr_line
		(start 279.236678 -354.65385)
		(end 280.636726 -354.65385)
		(stroke
			(width 0.2)
			(type default)
		)
		(layer "In1.Cu")
	)
	(gr_arc
		(start 279.236678 -353.55657)
		(mid 278.688038 -354.10521)
		(end 279.236678 -354.65385)
		(stroke
			(width 0.2)
			(type default)
		)
		(layer "In1.Cu")
	)
	(gr_line
		(start 279.236678 -351.053908)
		(end 280.636726 -351.053908)
		(stroke
			(width 0.2)
			(type default)
		)
		(layer "In1.Cu")
	)
	(gr_arc
		(start 279.236678 -349.956628)
		(mid 278.688038 -350.505268)
		(end 279.236678 -351.053908)
		(stroke
			(width 0.2)
			(type default)
		)
		(layer "In1.Cu")
	)
	(gr_line
		(start 279.236678 -347.453712)
		(end 280.636726 -347.453712)
		(stroke
			(width 0.2)
			(type default)
		)
		(layer "In1.Cu")
	)
	(gr_arc
		(start 279.236678 -346.356432)
		(mid 278.688038 -346.905072)
		(end 279.236678 -347.453712)
		(stroke
			(width 0.2)
			(type default)
		)
		(layer "In1.Cu")
	)
	(gr_line
		(start 279.236678 -343.85377)
		(end 280.636726 -343.85377)
		(stroke
			(width 0.2)
			(type default)
		)
		(layer "In1.Cu")
	)
	(gr_arc
		(start 279.236678 -342.75649)
		(mid 278.688038 -343.30513)
		(end 279.236678 -343.85377)
		(stroke
			(width 0.2)
			(type default)
		)
		(layer "In1.Cu")
	)
	(gr_line
		(start 279.236678 -340.253828)
		(end 280.636726 -340.253828)
		(stroke
			(width 0.2)
			(type default)
		)
		(layer "In1.Cu")
	)
	(gr_arc
		(start 279.236678 -339.156548)
		(mid 278.688038 -339.705188)
		(end 279.236678 -340.253828)
		(stroke
			(width 0.2)
			(type default)
		)
		(layer "In1.Cu")
	)
	(gr_line
		(start 279.236678 -336.653886)
		(end 280.636726 -336.653886)
		(stroke
			(width 0.2)
			(type default)
		)
		(layer "In1.Cu")
	)
	(gr_arc
		(start 279.236678 -335.556606)
		(mid 278.688038 -336.105246)
		(end 279.236678 -336.653886)
		(stroke
			(width 0.2)
			(type default)
		)
		(layer "In1.Cu")
	)
	(gr_line
		(start 279.236678 -333.05369)
		(end 280.636726 -333.05369)
		(stroke
			(width 0.2)
			(type default)
		)
		(layer "In1.Cu")
	)
	(gr_arc
		(start 279.236678 -331.95641)
		(mid 278.688038 -332.50505)
		(end 279.236678 -333.05369)
		(stroke
			(width 0.2)
			(type default)
		)
		(layer "In1.Cu")
	)
	(gr_line
		(start 279.236678 -329.453748)
		(end 280.636726 -329.453748)
		(stroke
			(width 0.2)
			(type default)
		)
		(layer "In1.Cu")
	)
	(gr_arc
		(start 279.236678 -328.356468)
		(mid 278.688038 -328.905108)
		(end 279.236678 -329.453748)
		(stroke
			(width 0.2)
			(type default)
		)
		(layer "In1.Cu")
	)
	(gr_line
		(start 279.236678 -325.853806)
		(end 280.636726 -325.853806)
		(stroke
			(width 0.2)
			(type default)
		)
		(layer "In1.Cu")
	)
	(gr_arc
		(start 279.236678 -324.756526)
		(mid 278.688038 -325.305166)
		(end 279.236678 -325.853806)
		(stroke
			(width 0.2)
			(type default)
		)
		(layer "In1.Cu")
	)
	(gr_line
		(start 279.236678 -322.253864)
		(end 280.636726 -322.253864)
		(stroke
			(width 0.2)
			(type default)
		)
		(layer "In1.Cu")
	)
	(gr_arc
		(start 279.236678 -321.156584)
		(mid 278.688038 -321.705224)
		(end 279.236678 -322.253864)
		(stroke
			(width 0.2)
			(type default)
		)
		(layer "In1.Cu")
	)
	(gr_line
		(start 279.236678 -318.653668)
		(end 280.636726 -318.653668)
		(stroke
			(width 0.2)
			(type default)
		)
		(layer "In1.Cu")
	)
	(gr_arc
		(start 279.236678 -317.556388)
		(mid 278.688038 -318.105028)
		(end 279.236678 -318.653668)
		(stroke
			(width 0.2)
			(type default)
		)
		(layer "In1.Cu")
	)
	(gr_line
		(start 279.236678 -315.053726)
		(end 280.636726 -315.053726)
		(stroke
			(width 0.2)
			(type default)
		)
		(layer "In1.Cu")
	)
	(gr_arc
		(start 279.236678 -313.956446)
		(mid 278.688038 -314.505086)
		(end 279.236678 -315.053726)
		(stroke
			(width 0.2)
			(type default)
		)
		(layer "In1.Cu")
	)
	(gr_line
		(start 279.236678 -311.453784)
		(end 280.636726 -311.453784)
		(stroke
			(width 0.2)
			(type default)
		)
		(layer "In1.Cu")
	)
	(gr_arc
		(start 279.236678 -310.356504)
		(mid 278.688038 -310.905144)
		(end 279.236678 -311.453784)
		(stroke
			(width 0.2)
			(type default)
		)
		(layer "In1.Cu")
	)
	(gr_line
		(start 279.236678 -307.853842)
		(end 280.636726 -307.853842)
		(stroke
			(width 0.2)
			(type default)
		)
		(layer "In1.Cu")
	)
	(gr_arc
		(start 279.236678 -306.756562)
		(mid 278.688038 -307.305202)
		(end 279.236678 -307.853842)
		(stroke
			(width 0.2)
			(type default)
		)
		(layer "In1.Cu")
	)
	(gr_line
		(start 279.236678 -304.2539)
		(end 280.636726 -304.2539)
		(stroke
			(width 0.2)
			(type default)
		)
		(layer "In1.Cu")
	)
	(gr_arc
		(start 279.236678 -303.15662)
		(mid 278.688038 -303.70526)
		(end 279.236678 -304.2539)
		(stroke
			(width 0.2)
			(type default)
		)
		(layer "In1.Cu")
	)
	(gr_line
		(start 279.236678 -300.653704)
		(end 280.636726 -300.653704)
		(stroke
			(width 0.2)
			(type default)
		)
		(layer "In1.Cu")
	)
	(gr_arc
		(start 279.236678 -299.556424)
		(mid 278.688038 -300.105064)
		(end 279.236678 -300.653704)
		(stroke
			(width 0.2)
			(type default)
		)
		(layer "In1.Cu")
	)
	(gr_line
		(start 279.236678 -297.053762)
		(end 280.636726 -297.053762)
		(stroke
			(width 0.2)
			(type default)
		)
		(layer "In1.Cu")
	)
	(gr_arc
		(start 279.236678 -295.956482)
		(mid 278.688038 -296.505122)
		(end 279.236678 -297.053762)
		(stroke
			(width 0.2)
			(type default)
		)
		(layer "In1.Cu")
	)
	(gr_line
		(start 279.236678 -264.253472)
		(end 280.636726 -264.253472)
		(stroke
			(width 0.2)
			(type default)
		)
		(layer "In1.Cu")
	)
	(gr_arc
		(start 279.236678 -263.151112)
		(mid 278.685498 -263.702292)
		(end 279.236678 -264.253472)
		(stroke
			(width 0.2)
			(type default)
		)
		(layer "In1.Cu")
	)
	(gr_line
		(start 279.236678 -260.65353)
		(end 280.636726 -260.65353)
		(stroke
			(width 0.2)
			(type default)
		)
		(layer "In1.Cu")
	)
	(gr_arc
		(start 279.236678 -259.55117)
		(mid 278.685498 -260.10235)
		(end 279.236678 -260.65353)
		(stroke
			(width 0.2)
			(type default)
		)
		(layer "In1.Cu")
	)
	(gr_line
		(start 279.236678 -257.053588)
		(end 280.636726 -257.053588)
		(stroke
			(width 0.2)
			(type default)
		)
		(layer "In1.Cu")
	)
	(gr_arc
		(start 279.236678 -255.951228)
		(mid 278.685498 -256.502408)
		(end 279.236678 -257.053588)
		(stroke
			(width 0.2)
			(type default)
		)
		(layer "In1.Cu")
	)
	(gr_line
		(start 279.236678 -253.453392)
		(end 280.636726 -253.453392)
		(stroke
			(width 0.2)
			(type default)
		)
		(layer "In1.Cu")
	)
	(gr_arc
		(start 279.236678 -252.351032)
		(mid 278.685498 -252.902212)
		(end 279.236678 -253.453392)
		(stroke
			(width 0.2)
			(type default)
		)
		(layer "In1.Cu")
	)
	(gr_line
		(start 279.236932 -357.156512)
		(end 279.236678 -357.156512)
		(stroke
			(width 0.2)
			(type default)
		)
		(layer "In1.Cu")
	)
	(gr_line
		(start 279.236932 -353.55657)
		(end 279.236678 -353.55657)
		(stroke
			(width 0.2)
			(type default)
		)
		(layer "In1.Cu")
	)
	(gr_line
		(start 279.236932 -349.956628)
		(end 279.236678 -349.956628)
		(stroke
			(width 0.2)
			(type default)
		)
		(layer "In1.Cu")
	)
	(gr_line
		(start 279.236932 -346.356432)
		(end 279.236678 -346.356432)
		(stroke
			(width 0.2)
			(type default)
		)
		(layer "In1.Cu")
	)
	(gr_line
		(start 279.236932 -342.75649)
		(end 279.236678 -342.75649)
		(stroke
			(width 0.2)
			(type default)
		)
		(layer "In1.Cu")
	)
	(gr_line
		(start 279.236932 -339.156548)
		(end 279.236678 -339.156548)
		(stroke
			(width 0.2)
			(type default)
		)
		(layer "In1.Cu")
	)
	(gr_line
		(start 279.236932 -335.556606)
		(end 279.236678 -335.556606)
		(stroke
			(width 0.2)
			(type default)
		)
		(layer "In1.Cu")
	)
	(gr_line
		(start 279.236932 -331.95641)
		(end 279.236678 -331.95641)
		(stroke
			(width 0.2)
			(type default)
		)
		(layer "In1.Cu")
	)
	(gr_line
		(start 279.236932 -328.356468)
		(end 279.236678 -328.356468)
		(stroke
			(width 0.2)
			(type default)
		)
		(layer "In1.Cu")
	)
	(gr_line
		(start 279.236932 -324.756526)
		(end 279.236678 -324.756526)
		(stroke
			(width 0.2)
			(type default)
		)
		(layer "In1.Cu")
	)
	(gr_line
		(start 279.236932 -321.156584)
		(end 279.236678 -321.156584)
		(stroke
			(width 0.2)
			(type default)
		)
		(layer "In1.Cu")
	)
	(gr_line
		(start 279.236932 -317.556388)
		(end 279.236678 -317.556388)
		(stroke
			(width 0.2)
			(type default)
		)
		(layer "In1.Cu")
	)
	(gr_line
		(start 279.236932 -313.956446)
		(end 279.236678 -313.956446)
		(stroke
			(width 0.2)
			(type default)
		)
		(layer "In1.Cu")
	)
	(gr_line
		(start 279.236932 -310.356504)
		(end 279.236678 -310.356504)
		(stroke
			(width 0.2)
			(type default)
		)
		(layer "In1.Cu")
	)
	(gr_line
		(start 279.236932 -306.756562)
		(end 279.236678 -306.756562)
		(stroke
			(width 0.2)
			(type default)
		)
		(layer "In1.Cu")
	)
	(gr_line
		(start 279.236932 -303.15662)
		(end 279.236678 -303.15662)
		(stroke
			(width 0.2)
			(type default)
		)
		(layer "In1.Cu")
	)
	(gr_line
		(start 279.236932 -299.556424)
		(end 279.236678 -299.556424)
		(stroke
			(width 0.2)
			(type default)
		)
		(layer "In1.Cu")
	)
	(gr_line
		(start 279.236932 -295.956482)
		(end 279.236678 -295.956482)
		(stroke
			(width 0.2)
			(type default)
		)
		(layer "In1.Cu")
	)
	(gr_line
		(start 279.236932 -263.151112)
		(end 279.236678 -263.151112)
		(stroke
			(width 0.2)
			(type default)
		)
		(layer "In1.Cu")
	)
	(gr_line
		(start 279.236932 -259.55117)
		(end 279.236678 -259.55117)
		(stroke
			(width 0.2)
			(type default)
		)
		(layer "In1.Cu")
	)
	(gr_line
		(start 279.236932 -255.951228)
		(end 279.236678 -255.951228)
		(stroke
			(width 0.2)
			(type default)
		)
		(layer "In1.Cu")
	)
	(gr_line
		(start 279.236932 -252.351032)
		(end 279.236678 -252.351032)
		(stroke
			(width 0.2)
			(type default)
		)
		(layer "In1.Cu")
	)
	(gr_arc
		(start 279.636728 -356.453694)
		(mid 280.185368 -355.905054)
		(end 279.636728 -355.356414)
		(stroke
			(width 0.2)
			(type default)
		)
		(layer "In1.Cu")
	)
	(gr_line
		(start 279.636728 -355.356414)
		(end 278.236934 -355.356414)
		(stroke
			(width 0.2)
			(type default)
		)
		(layer "In1.Cu")
	)
	(gr_arc
		(start 279.636728 -352.853752)
		(mid 280.185368 -352.305112)
		(end 279.636728 -351.756472)
		(stroke
			(width 0.2)
			(type default)
		)
		(layer "In1.Cu")
	)
	(gr_line
		(start 279.636728 -351.756472)
		(end 278.236934 -351.756472)
		(stroke
			(width 0.2)
			(type default)
		)
		(layer "In1.Cu")
	)
	(gr_arc
		(start 279.636728 -349.25381)
		(mid 280.185368 -348.70517)
		(end 279.636728 -348.15653)
		(stroke
			(width 0.2)
			(type default)
		)
		(layer "In1.Cu")
	)
	(gr_line
		(start 279.636728 -348.15653)
		(end 278.236934 -348.15653)
		(stroke
			(width 0.2)
			(type default)
		)
		(layer "In1.Cu")
	)
	(gr_arc
		(start 279.636728 -345.653868)
		(mid 280.185368 -345.105228)
		(end 279.636728 -344.556588)
		(stroke
			(width 0.2)
			(type default)
		)
		(layer "In1.Cu")
	)
	(gr_line
		(start 279.636728 -344.556588)
		(end 278.236934 -344.556588)
		(stroke
			(width 0.2)
			(type default)
		)
		(layer "In1.Cu")
	)
	(gr_arc
		(start 279.636728 -342.053672)
		(mid 280.185368 -341.505032)
		(end 279.636728 -340.956392)
		(stroke
			(width 0.2)
			(type default)
		)
		(layer "In1.Cu")
	)
	(gr_line
		(start 279.636728 -340.956392)
		(end 278.236934 -340.956392)
		(stroke
			(width 0.2)
			(type default)
		)
		(layer "In1.Cu")
	)
	(gr_arc
		(start 279.636728 -338.45373)
		(mid 280.185368 -337.90509)
		(end 279.636728 -337.35645)
		(stroke
			(width 0.2)
			(type default)
		)
		(layer "In1.Cu")
	)
	(gr_line
		(start 279.636728 -337.35645)
		(end 278.236934 -337.35645)
		(stroke
			(width 0.2)
			(type default)
		)
		(layer "In1.Cu")
	)
	(gr_arc
		(start 279.636728 -334.853788)
		(mid 280.185368 -334.305148)
		(end 279.636728 -333.756508)
		(stroke
			(width 0.2)
			(type default)
		)
		(layer "In1.Cu")
	)
	(gr_line
		(start 279.636728 -333.756508)
		(end 278.236934 -333.756508)
		(stroke
			(width 0.2)
			(type default)
		)
		(layer "In1.Cu")
	)
	(gr_arc
		(start 279.636728 -331.253846)
		(mid 280.185368 -330.705206)
		(end 279.636728 -330.156566)
		(stroke
			(width 0.2)
			(type default)
		)
		(layer "In1.Cu")
	)
	(gr_line
		(start 279.636728 -330.156566)
		(end 278.236934 -330.156566)
		(stroke
			(width 0.2)
			(type default)
		)
		(layer "In1.Cu")
	)
	(gr_arc
		(start 279.636728 -327.653904)
		(mid 280.185368 -327.105264)
		(end 279.636728 -326.556624)
		(stroke
			(width 0.2)
			(type default)
		)
		(layer "In1.Cu")
	)
	(gr_line
		(start 279.636728 -326.556624)
		(end 278.236934 -326.556624)
		(stroke
			(width 0.2)
			(type default)
		)
		(layer "In1.Cu")
	)
	(gr_arc
		(start 279.636728 -324.053708)
		(mid 280.185368 -323.505068)
		(end 279.636728 -322.956428)
		(stroke
			(width 0.2)
			(type default)
		)
		(layer "In1.Cu")
	)
	(gr_line
		(start 279.636728 -322.956428)
		(end 278.236934 -322.956428)
		(stroke
			(width 0.2)
			(type default)
		)
		(layer "In1.Cu")
	)
	(gr_arc
		(start 279.636728 -320.453766)
		(mid 280.185368 -319.905126)
		(end 279.636728 -319.356486)
		(stroke
			(width 0.2)
			(type default)
		)
		(layer "In1.Cu")
	)
	(gr_line
		(start 279.636728 -319.356486)
		(end 278.236934 -319.356486)
		(stroke
			(width 0.2)
			(type default)
		)
		(layer "In1.Cu")
	)
	(gr_arc
		(start 279.636728 -316.853824)
		(mid 280.185368 -316.305184)
		(end 279.636728 -315.756544)
		(stroke
			(width 0.2)
			(type default)
		)
		(layer "In1.Cu")
	)
	(gr_line
		(start 279.636728 -315.756544)
		(end 278.236934 -315.756544)
		(stroke
			(width 0.2)
			(type default)
		)
		(layer "In1.Cu")
	)
	(gr_arc
		(start 279.636728 -313.253882)
		(mid 280.185368 -312.705242)
		(end 279.636728 -312.156602)
		(stroke
			(width 0.2)
			(type default)
		)
		(layer "In1.Cu")
	)
	(gr_line
		(start 279.636728 -312.156602)
		(end 278.236934 -312.156602)
		(stroke
			(width 0.2)
			(type default)
		)
		(layer "In1.Cu")
	)
	(gr_arc
		(start 279.636728 -309.653686)
		(mid 280.185368 -309.105046)
		(end 279.636728 -308.556406)
		(stroke
			(width 0.2)
			(type default)
		)
		(layer "In1.Cu")
	)
	(gr_line
		(start 279.636728 -308.556406)
		(end 278.236934 -308.556406)
		(stroke
			(width 0.2)
			(type default)
		)
		(layer "In1.Cu")
	)
	(gr_arc
		(start 279.636728 -306.053744)
		(mid 280.185368 -305.505104)
		(end 279.636728 -304.956464)
		(stroke
			(width 0.2)
			(type default)
		)
		(layer "In1.Cu")
	)
	(gr_line
		(start 279.636728 -304.956464)
		(end 278.236934 -304.956464)
		(stroke
			(width 0.2)
			(type default)
		)
		(layer "In1.Cu")
	)
	(gr_arc
		(start 279.636728 -302.453802)
		(mid 280.185368 -301.905162)
		(end 279.636728 -301.356522)
		(stroke
			(width 0.2)
			(type default)
		)
		(layer "In1.Cu")
	)
	(gr_line
		(start 279.636728 -301.356522)
		(end 278.236934 -301.356522)
		(stroke
			(width 0.2)
			(type default)
		)
		(layer "In1.Cu")
	)
	(gr_arc
		(start 279.636728 -298.85386)
		(mid 280.185368 -298.30522)
		(end 279.636728 -297.75658)
		(stroke
			(width 0.2)
			(type default)
		)
		(layer "In1.Cu")
	)
	(gr_line
		(start 279.636728 -297.75658)
		(end 278.236934 -297.75658)
		(stroke
			(width 0.2)
			(type default)
		)
		(layer "In1.Cu")
	)
	(gr_arc
		(start 279.636728 -295.253918)
		(mid 280.185368 -294.705278)
		(end 279.636728 -294.156638)
		(stroke
			(width 0.2)
			(type default)
		)
		(layer "In1.Cu")
	)
	(gr_line
		(start 279.636728 -294.156638)
		(end 278.236934 -294.156638)
		(stroke
			(width 0.2)
			(type default)
		)
		(layer "In1.Cu")
	)
	(gr_arc
		(start 279.636728 -262.453374)
		(mid 280.187908 -261.902194)
		(end 279.636728 -261.351014)
		(stroke
			(width 0.2)
			(type default)
		)
		(layer "In1.Cu")
	)
	(gr_line
		(start 279.636728 -261.351014)
		(end 278.236934 -261.351014)
		(stroke
			(width 0.2)
			(type default)
		)
		(layer "In1.Cu")
	)
	(gr_arc
		(start 279.636728 -258.853432)
		(mid 280.187908 -258.302252)
		(end 279.636728 -257.751072)
		(stroke
			(width 0.2)
			(type default)
		)
		(layer "In1.Cu")
	)
	(gr_line
		(start 279.636728 -257.751072)
		(end 278.236934 -257.751072)
		(stroke
			(width 0.2)
			(type default)
		)
		(layer "In1.Cu")
	)
	(gr_arc
		(start 279.636728 -255.25349)
		(mid 280.187908 -254.70231)
		(end 279.636728 -254.15113)
		(stroke
			(width 0.2)
			(type default)
		)
		(layer "In1.Cu")
	)
	(gr_line
		(start 279.636728 -254.15113)
		(end 278.236934 -254.15113)
		(stroke
			(width 0.2)
			(type default)
		)
		(layer "In1.Cu")
	)
	(gr_arc
		(start 279.636728 -251.653548)
		(mid 280.187908 -251.102368)
		(end 279.636728 -250.551188)
		(stroke
			(width 0.2)
			(type default)
		)
		(layer "In1.Cu")
	)
	(gr_line
		(start 279.636728 -250.551188)
		(end 278.236934 -250.551188)
		(stroke
			(width 0.2)
			(type default)
		)
		(layer "In1.Cu")
	)
	(gr_line
		(start 280.422858 -10.545826)
		(end 278.433784 -11.54049)
		(stroke
			(width 0.2)
			(type default)
		)
		(layer "In1.Cu")
	)
	(gr_line
		(start 280.423874 -176.847754)
		(end 278.424132 -177.847752)
		(stroke
			(width 0.2)
			(type default)
		)
		(layer "In1.Cu")
	)
	(gr_line
		(start 280.423874 -172.847762)
		(end 278.424132 -173.84776)
		(stroke
			(width 0.2)
			(type default)
		)
		(layer "In1.Cu")
	)
	(gr_line
		(start 280.423874 -168.84777)
		(end 278.424132 -169.847768)
		(stroke
			(width 0.2)
			(type default)
		)
		(layer "In1.Cu")
	)
	(gr_line
		(start 280.423874 -164.847778)
		(end 278.424132 -165.847776)
		(stroke
			(width 0.2)
			(type default)
		)
		(layer "In1.Cu")
	)
	(gr_line
		(start 280.423874 -136.847834)
		(end 278.424132 -137.847832)
		(stroke
			(width 0.2)
			(type default)
		)
		(layer "In1.Cu")
	)
	(gr_line
		(start 280.423874 -80.547972)
		(end 278.424132 -81.54797)
		(stroke
			(width 0.2)
			(type default)
		)
		(layer "In1.Cu")
	)
	(gr_line
		(start 280.423874 -76.54798)
		(end 278.424132 -77.547978)
		(stroke
			(width 0.2)
			(type default)
		)
		(layer "In1.Cu")
	)
	(gr_line
		(start 280.423874 -72.547988)
		(end 278.424132 -73.547986)
		(stroke
			(width 0.2)
			(type default)
		)
		(layer "In1.Cu")
	)
	(gr_line
		(start 280.423874 -68.547996)
		(end 278.424132 -69.547994)
		(stroke
			(width 0.2)
			(type default)
		)
		(layer "In1.Cu")
	)
	(gr_line
		(start 280.423874 -64.548004)
		(end 278.424132 -65.548002)
		(stroke
			(width 0.2)
			(type default)
		)
		(layer "In1.Cu")
	)
	(gr_line
		(start 280.423874 -60.548012)
		(end 278.424132 -61.54801)
		(stroke
			(width 0.2)
			(type default)
		)
		(layer "In1.Cu")
	)
	(gr_line
		(start 280.423874 -56.54802)
		(end 278.424132 -57.548018)
		(stroke
			(width 0.2)
			(type default)
		)
		(layer "In1.Cu")
	)
	(gr_line
		(start 280.423874 -52.548028)
		(end 278.424132 -53.548026)
		(stroke
			(width 0.2)
			(type default)
		)
		(layer "In1.Cu")
	)
	(gr_line
		(start 280.423874 -48.548036)
		(end 278.424132 -49.548034)
		(stroke
			(width 0.2)
			(type default)
		)
		(layer "In1.Cu")
	)
	(gr_line
		(start 280.423874 -44.548044)
		(end 278.424132 -45.548042)
		(stroke
			(width 0.2)
			(type default)
		)
		(layer "In1.Cu")
	)
	(gr_line
		(start 280.423874 -40.548052)
		(end 278.424132 -41.54805)
		(stroke
			(width 0.2)
			(type default)
		)
		(layer "In1.Cu")
	)
	(gr_line
		(start 280.423874 -36.54806)
		(end 278.424132 -37.548058)
		(stroke
			(width 0.2)
			(type default)
		)
		(layer "In1.Cu")
	)
	(gr_line
		(start 280.423874 -16.5481)
		(end 278.424132 -17.548098)
		(stroke
			(width 0.2)
			(type default)
		)
		(layer "In1.Cu")
	)
	(gr_line
		(start 280.425144 -176.85004)
		(end 280.423874 -176.847754)
		(stroke
			(width 0.2)
			(type default)
		)
		(layer "In1.Cu")
	)
	(gr_line
		(start 280.425144 -172.850048)
		(end 280.423874 -172.847762)
		(stroke
			(width 0.2)
			(type default)
		)
		(layer "In1.Cu")
	)
	(gr_line
		(start 280.425144 -168.850056)
		(end 280.423874 -168.84777)
		(stroke
			(width 0.2)
			(type default)
		)
		(layer "In1.Cu")
	)
	(gr_line
		(start 280.425144 -164.850064)
		(end 280.423874 -164.847778)
		(stroke
			(width 0.2)
			(type default)
		)
		(layer "In1.Cu")
	)
	(gr_line
		(start 280.425144 -136.85012)
		(end 280.423874 -136.847834)
		(stroke
			(width 0.2)
			(type default)
		)
		(layer "In1.Cu")
	)
	(gr_line
		(start 280.425144 -80.550258)
		(end 280.423874 -80.547972)
		(stroke
			(width 0.2)
			(type default)
		)
		(layer "In1.Cu")
	)
	(gr_line
		(start 280.425144 -76.550266)
		(end 280.423874 -76.54798)
		(stroke
			(width 0.2)
			(type default)
		)
		(layer "In1.Cu")
	)
	(gr_line
		(start 280.425144 -72.550274)
		(end 280.423874 -72.547988)
		(stroke
			(width 0.2)
			(type default)
		)
		(layer "In1.Cu")
	)
	(gr_line
		(start 280.425144 -68.550282)
		(end 280.423874 -68.547996)
		(stroke
			(width 0.2)
			(type default)
		)
		(layer "In1.Cu")
	)
	(gr_line
		(start 280.425144 -64.55029)
		(end 280.423874 -64.548004)
		(stroke
			(width 0.2)
			(type default)
		)
		(layer "In1.Cu")
	)
	(gr_line
		(start 280.425144 -60.550298)
		(end 280.423874 -60.548012)
		(stroke
			(width 0.2)
			(type default)
		)
		(layer "In1.Cu")
	)
	(gr_line
		(start 280.425144 -56.550306)
		(end 280.423874 -56.54802)
		(stroke
			(width 0.2)
			(type default)
		)
		(layer "In1.Cu")
	)
	(gr_line
		(start 280.425144 -52.550314)
		(end 280.423874 -52.548028)
		(stroke
			(width 0.2)
			(type default)
		)
		(layer "In1.Cu")
	)
	(gr_line
		(start 280.425144 -48.550322)
		(end 280.423874 -48.548036)
		(stroke
			(width 0.2)
			(type default)
		)
		(layer "In1.Cu")
	)
	(gr_line
		(start 280.425144 -44.55033)
		(end 280.423874 -44.548044)
		(stroke
			(width 0.2)
			(type default)
		)
		(layer "In1.Cu")
	)
	(gr_line
		(start 280.425144 -40.550338)
		(end 280.423874 -40.548052)
		(stroke
			(width 0.2)
			(type default)
		)
		(layer "In1.Cu")
	)
	(gr_line
		(start 280.425144 -36.550346)
		(end 280.423874 -36.54806)
		(stroke
			(width 0.2)
			(type default)
		)
		(layer "In1.Cu")
	)
	(gr_line
		(start 280.425144 -16.550386)
		(end 280.423874 -16.5481)
		(stroke
			(width 0.2)
			(type default)
		)
		(layer "In1.Cu")
	)
	(gr_line
		(start 280.42616 -160.852358)
		(end 278.426418 -161.852102)
		(stroke
			(width 0.2)
			(type default)
		)
		(layer "In1.Cu")
	)
	(gr_line
		(start 280.42616 -156.852366)
		(end 278.426418 -157.85211)
		(stroke
			(width 0.2)
			(type default)
		)
		(layer "In1.Cu")
	)
	(gr_line
		(start 280.42616 -152.852374)
		(end 278.426418 -153.852118)
		(stroke
			(width 0.2)
			(type default)
		)
		(layer "In1.Cu")
	)
	(gr_line
		(start 280.42616 -148.852382)
		(end 278.426418 -149.852126)
		(stroke
			(width 0.2)
			(type default)
		)
		(layer "In1.Cu")
	)
	(gr_line
		(start 280.42616 -128.852422)
		(end 278.426418 -129.852166)
		(stroke
			(width 0.2)
			(type default)
		)
		(layer "In1.Cu")
	)
	(gr_line
		(start 280.42616 -124.85243)
		(end 278.426418 -125.852174)
		(stroke
			(width 0.2)
			(type default)
		)
		(layer "In1.Cu")
	)
	(gr_line
		(start 280.42616 -120.852438)
		(end 278.426418 -121.852182)
		(stroke
			(width 0.2)
			(type default)
		)
		(layer "In1.Cu")
	)
	(gr_line
		(start 280.42616 -116.852446)
		(end 278.426418 -117.85219)
		(stroke
			(width 0.2)
			(type default)
		)
		(layer "In1.Cu")
	)
	(gr_line
		(start 280.436574 -112.872774)
		(end 278.44496 -113.868708)
		(stroke
			(width 0.2)
			(type default)
		)
		(layer "In1.Cu")
	)
	(gr_arc
		(start 280.636726 -358.253792)
		(mid 281.185366 -357.705152)
		(end 280.636726 -357.156512)
		(stroke
			(width 0.2)
			(type default)
		)
		(layer "In1.Cu")
	)
	(gr_line
		(start 280.636726 -357.156512)
		(end 279.236932 -357.156512)
		(stroke
			(width 0.2)
			(type default)
		)
		(layer "In1.Cu")
	)
	(gr_arc
		(start 280.636726 -354.65385)
		(mid 281.185366 -354.10521)
		(end 280.636726 -353.55657)
		(stroke
			(width 0.2)
			(type default)
		)
		(layer "In1.Cu")
	)
	(gr_line
		(start 280.636726 -353.55657)
		(end 279.236932 -353.55657)
		(stroke
			(width 0.2)
			(type default)
		)
		(layer "In1.Cu")
	)
	(gr_arc
		(start 280.636726 -351.053908)
		(mid 281.185366 -350.505268)
		(end 280.636726 -349.956628)
		(stroke
			(width 0.2)
			(type default)
		)
		(layer "In1.Cu")
	)
	(gr_line
		(start 280.636726 -349.956628)
		(end 279.236932 -349.956628)
		(stroke
			(width 0.2)
			(type default)
		)
		(layer "In1.Cu")
	)
	(gr_arc
		(start 280.636726 -347.453712)
		(mid 281.185366 -346.905072)
		(end 280.636726 -346.356432)
		(stroke
			(width 0.2)
			(type default)
		)
		(layer "In1.Cu")
	)
	(gr_line
		(start 280.636726 -346.356432)
		(end 279.236932 -346.356432)
		(stroke
			(width 0.2)
			(type default)
		)
		(layer "In1.Cu")
	)
	(gr_arc
		(start 280.636726 -343.85377)
		(mid 281.185366 -343.30513)
		(end 280.636726 -342.75649)
		(stroke
			(width 0.2)
			(type default)
		)
		(layer "In1.Cu")
	)
	(gr_line
		(start 280.636726 -342.75649)
		(end 279.236932 -342.75649)
		(stroke
			(width 0.2)
			(type default)
		)
		(layer "In1.Cu")
	)
	(gr_arc
		(start 280.636726 -340.253828)
		(mid 281.185366 -339.705188)
		(end 280.636726 -339.156548)
		(stroke
			(width 0.2)
			(type default)
		)
		(layer "In1.Cu")
	)
	(gr_line
		(start 280.636726 -339.156548)
		(end 279.236932 -339.156548)
		(stroke
			(width 0.2)
			(type default)
		)
		(layer "In1.Cu")
	)
	(gr_arc
		(start 280.636726 -336.653886)
		(mid 281.185366 -336.105246)
		(end 280.636726 -335.556606)
		(stroke
			(width 0.2)
			(type default)
		)
		(layer "In1.Cu")
	)
	(gr_line
		(start 280.636726 -335.556606)
		(end 279.236932 -335.556606)
		(stroke
			(width 0.2)
			(type default)
		)
		(layer "In1.Cu")
	)
	(gr_arc
		(start 280.636726 -333.05369)
		(mid 281.185366 -332.50505)
		(end 280.636726 -331.95641)
		(stroke
			(width 0.2)
			(type default)
		)
		(layer "In1.Cu")
	)
	(gr_line
		(start 280.636726 -331.95641)
		(end 279.236932 -331.95641)
		(stroke
			(width 0.2)
			(type default)
		)
		(layer "In1.Cu")
	)
	(gr_arc
		(start 280.636726 -329.453748)
		(mid 281.185366 -328.905108)
		(end 280.636726 -328.356468)
		(stroke
			(width 0.2)
			(type default)
		)
		(layer "In1.Cu")
	)
	(gr_line
		(start 280.636726 -328.356468)
		(end 279.236932 -328.356468)
		(stroke
			(width 0.2)
			(type default)
		)
		(layer "In1.Cu")
	)
	(gr_arc
		(start 280.636726 -325.853806)
		(mid 281.185366 -325.305166)
		(end 280.636726 -324.756526)
		(stroke
			(width 0.2)
			(type default)
		)
		(layer "In1.Cu")
	)
	(gr_line
		(start 280.636726 -324.756526)
		(end 279.236932 -324.756526)
		(stroke
			(width 0.2)
			(type default)
		)
		(layer "In1.Cu")
	)
	(gr_arc
		(start 280.636726 -322.253864)
		(mid 281.185366 -321.705224)
		(end 280.636726 -321.156584)
		(stroke
			(width 0.2)
			(type default)
		)
		(layer "In1.Cu")
	)
	(gr_line
		(start 280.636726 -321.156584)
		(end 279.236932 -321.156584)
		(stroke
			(width 0.2)
			(type default)
		)
		(layer "In1.Cu")
	)
	(gr_arc
		(start 280.636726 -318.653668)
		(mid 281.185366 -318.105028)
		(end 280.636726 -317.556388)
		(stroke
			(width 0.2)
			(type default)
		)
		(layer "In1.Cu")
	)
	(gr_line
		(start 280.636726 -317.556388)
		(end 279.236932 -317.556388)
		(stroke
			(width 0.2)
			(type default)
		)
		(layer "In1.Cu")
	)
	(gr_arc
		(start 280.636726 -315.053726)
		(mid 281.185366 -314.505086)
		(end 280.636726 -313.956446)
		(stroke
			(width 0.2)
			(type default)
		)
		(layer "In1.Cu")
	)
	(gr_line
		(start 280.636726 -313.956446)
		(end 279.236932 -313.956446)
		(stroke
			(width 0.2)
			(type default)
		)
		(layer "In1.Cu")
	)
	(gr_arc
		(start 280.636726 -311.453784)
		(mid 281.185366 -310.905144)
		(end 280.636726 -310.356504)
		(stroke
			(width 0.2)
			(type default)
		)
		(layer "In1.Cu")
	)
	(gr_line
		(start 280.636726 -310.356504)
		(end 279.236932 -310.356504)
		(stroke
			(width 0.2)
			(type default)
		)
		(layer "In1.Cu")
	)
	(gr_arc
		(start 280.636726 -307.853842)
		(mid 281.185366 -307.305202)
		(end 280.636726 -306.756562)
		(stroke
			(width 0.2)
			(type default)
		)
		(layer "In1.Cu")
	)
	(gr_line
		(start 280.636726 -306.756562)
		(end 279.236932 -306.756562)
		(stroke
			(width 0.2)
			(type default)
		)
		(layer "In1.Cu")
	)
	(gr_arc
		(start 280.636726 -304.2539)
		(mid 281.185366 -303.70526)
		(end 280.636726 -303.15662)
		(stroke
			(width 0.2)
			(type default)
		)
		(layer "In1.Cu")
	)
	(gr_line
		(start 280.636726 -303.15662)
		(end 279.236932 -303.15662)
		(stroke
			(width 0.2)
			(type default)
		)
		(layer "In1.Cu")
	)
	(gr_arc
		(start 280.636726 -300.653704)
		(mid 281.185366 -300.105064)
		(end 280.636726 -299.556424)
		(stroke
			(width 0.2)
			(type default)
		)
		(layer "In1.Cu")
	)
	(gr_line
		(start 280.636726 -299.556424)
		(end 279.236932 -299.556424)
		(stroke
			(width 0.2)
			(type default)
		)
		(layer "In1.Cu")
	)
	(gr_arc
		(start 280.636726 -297.053762)
		(mid 281.185366 -296.505122)
		(end 280.636726 -295.956482)
		(stroke
			(width 0.2)
			(type default)
		)
		(layer "In1.Cu")
	)
	(gr_line
		(start 280.636726 -295.956482)
		(end 279.236932 -295.956482)
		(stroke
			(width 0.2)
			(type default)
		)
		(layer "In1.Cu")
	)
	(gr_arc
		(start 280.636726 -264.253472)
		(mid 281.187906 -263.702292)
		(end 280.636726 -263.151112)
		(stroke
			(width 0.2)
			(type default)
		)
		(layer "In1.Cu")
	)
	(gr_line
		(start 280.636726 -263.151112)
		(end 279.236932 -263.151112)
		(stroke
			(width 0.2)
			(type default)
		)
		(layer "In1.Cu")
	)
	(gr_arc
		(start 280.636726 -260.65353)
		(mid 281.187906 -260.10235)
		(end 280.636726 -259.55117)
		(stroke
			(width 0.2)
			(type default)
		)
		(layer "In1.Cu")
	)
	(gr_line
		(start 280.636726 -259.55117)
		(end 279.236932 -259.55117)
		(stroke
			(width 0.2)
			(type default)
		)
		(layer "In1.Cu")
	)
	(gr_arc
		(start 280.636726 -257.053588)
		(mid 281.187906 -256.502408)
		(end 280.636726 -255.951228)
		(stroke
			(width 0.2)
			(type default)
		)
		(layer "In1.Cu")
	)
	(gr_line
		(start 280.636726 -255.951228)
		(end 279.236932 -255.951228)
		(stroke
			(width 0.2)
			(type default)
		)
		(layer "In1.Cu")
	)
	(gr_arc
		(start 280.636726 -253.453392)
		(mid 281.187906 -252.902212)
		(end 280.636726 -252.351032)
		(stroke
			(width 0.2)
			(type default)
		)
		(layer "In1.Cu")
	)
	(gr_line
		(start 280.636726 -252.351032)
		(end 279.236932 -252.351032)
		(stroke
			(width 0.2)
			(type default)
		)
		(layer "In1.Cu")
	)
	(gr_arc
		(start 281.063446 -114.127026)
		(mid 281.377136 -113.186464)
		(end 280.436574 -112.872774)
		(stroke
			(width 0.2)
			(type default)
		)
		(layer "In1.Cu")
	)
	(gr_arc
		(start 281.07386 -162.14725)
		(mid 281.397456 -161.175954)
		(end 280.42616 -160.852358)
		(stroke
			(width 0.2)
			(type default)
		)
		(layer "In1.Cu")
	)
	(gr_arc
		(start 281.07386 -158.147258)
		(mid 281.397456 -157.175962)
		(end 280.42616 -156.852366)
		(stroke
			(width 0.2)
			(type default)
		)
		(layer "In1.Cu")
	)
	(gr_arc
		(start 281.07386 -154.147266)
		(mid 281.397456 -153.17597)
		(end 280.42616 -152.852374)
		(stroke
			(width 0.2)
			(type default)
		)
		(layer "In1.Cu")
	)
	(gr_arc
		(start 281.07386 -150.147274)
		(mid 281.397456 -149.175978)
		(end 280.42616 -148.852382)
		(stroke
			(width 0.2)
			(type default)
		)
		(layer "In1.Cu")
	)
	(gr_arc
		(start 281.07386 -130.147314)
		(mid 281.397456 -129.176018)
		(end 280.42616 -128.852422)
		(stroke
			(width 0.2)
			(type default)
		)
		(layer "In1.Cu")
	)
	(gr_arc
		(start 281.07386 -126.147322)
		(mid 281.397456 -125.176026)
		(end 280.42616 -124.85243)
		(stroke
			(width 0.2)
			(type default)
		)
		(layer "In1.Cu")
	)
	(gr_arc
		(start 281.07386 -122.14733)
		(mid 281.397456 -121.176034)
		(end 280.42616 -120.852438)
		(stroke
			(width 0.2)
			(type default)
		)
		(layer "In1.Cu")
	)
	(gr_arc
		(start 281.07386 -118.147338)
		(mid 281.397456 -117.176042)
		(end 280.42616 -116.852446)
		(stroke
			(width 0.2)
			(type default)
		)
		(layer "In1.Cu")
	)
	(gr_arc
		(start 281.074876 -178.149504)
		(mid 281.399742 -177.174906)
		(end 280.425144 -176.85004)
		(stroke
			(width 0.2)
			(type default)
		)
		(layer "In1.Cu")
	)
	(gr_arc
		(start 281.074876 -174.149512)
		(mid 281.399742 -173.174914)
		(end 280.425144 -172.850048)
		(stroke
			(width 0.2)
			(type default)
		)
		(layer "In1.Cu")
	)
	(gr_arc
		(start 281.074876 -170.14952)
		(mid 281.399742 -169.174922)
		(end 280.425144 -168.850056)
		(stroke
			(width 0.2)
			(type default)
		)
		(layer "In1.Cu")
	)
	(gr_arc
		(start 281.074876 -166.149528)
		(mid 281.399742 -165.17493)
		(end 280.425144 -164.850064)
		(stroke
			(width 0.2)
			(type default)
		)
		(layer "In1.Cu")
	)
	(gr_arc
		(start 281.074876 -138.149584)
		(mid 281.399742 -137.174986)
		(end 280.425144 -136.85012)
		(stroke
			(width 0.2)
			(type default)
		)
		(layer "In1.Cu")
	)
	(gr_arc
		(start 281.074876 -81.849722)
		(mid 281.399742 -80.875124)
		(end 280.425144 -80.550258)
		(stroke
			(width 0.2)
			(type default)
		)
		(layer "In1.Cu")
	)
	(gr_arc
		(start 281.074876 -77.84973)
		(mid 281.399742 -76.875132)
		(end 280.425144 -76.550266)
		(stroke
			(width 0.2)
			(type default)
		)
		(layer "In1.Cu")
	)
	(gr_arc
		(start 281.074876 -73.849738)
		(mid 281.399742 -72.87514)
		(end 280.425144 -72.550274)
		(stroke
			(width 0.2)
			(type default)
		)
		(layer "In1.Cu")
	)
	(gr_arc
		(start 281.074876 -69.849746)
		(mid 281.399742 -68.875148)
		(end 280.425144 -68.550282)
		(stroke
			(width 0.2)
			(type default)
		)
		(layer "In1.Cu")
	)
	(gr_arc
		(start 281.074876 -65.849754)
		(mid 281.399742 -64.875156)
		(end 280.425144 -64.55029)
		(stroke
			(width 0.2)
			(type default)
		)
		(layer "In1.Cu")
	)
	(gr_arc
		(start 281.074876 -61.849762)
		(mid 281.399742 -60.875164)
		(end 280.425144 -60.550298)
		(stroke
			(width 0.2)
			(type default)
		)
		(layer "In1.Cu")
	)
	(gr_arc
		(start 281.074876 -57.84977)
		(mid 281.399742 -56.875172)
		(end 280.425144 -56.550306)
		(stroke
			(width 0.2)
			(type default)
		)
		(layer "In1.Cu")
	)
	(gr_arc
		(start 281.074876 -53.849778)
		(mid 281.399742 -52.87518)
		(end 280.425144 -52.550314)
		(stroke
			(width 0.2)
			(type default)
		)
		(layer "In1.Cu")
	)
	(gr_arc
		(start 281.074876 -49.849786)
		(mid 281.399742 -48.875188)
		(end 280.425144 -48.550322)
		(stroke
			(width 0.2)
			(type default)
		)
		(layer "In1.Cu")
	)
	(gr_arc
		(start 281.074876 -45.849794)
		(mid 281.399742 -44.875196)
		(end 280.425144 -44.55033)
		(stroke
			(width 0.2)
			(type default)
		)
		(layer "In1.Cu")
	)
	(gr_arc
		(start 281.074876 -41.849802)
		(mid 281.399742 -40.875204)
		(end 280.425144 -40.550338)
		(stroke
			(width 0.2)
			(type default)
		)
		(layer "In1.Cu")
	)
	(gr_arc
		(start 281.074876 -37.84981)
		(mid 281.399742 -36.875212)
		(end 280.425144 -36.550346)
		(stroke
			(width 0.2)
			(type default)
		)
		(layer "In1.Cu")
	)
	(gr_arc
		(start 281.074876 -17.84985)
		(mid 281.399742 -16.875252)
		(end 280.425144 -16.550386)
		(stroke
			(width 0.2)
			(type default)
		)
		(layer "In1.Cu")
	)
	(gr_line
		(start 281.076146 -178.15179)
		(end 281.074876 -178.149504)
		(stroke
			(width 0.2)
			(type default)
		)
		(layer "In1.Cu")
	)
	(gr_line
		(start 281.076146 -174.151798)
		(end 281.074876 -174.149512)
		(stroke
			(width 0.2)
			(type default)
		)
		(layer "In1.Cu")
	)
	(gr_line
		(start 281.076146 -170.151806)
		(end 281.074876 -170.14952)
		(stroke
			(width 0.2)
			(type default)
		)
		(layer "In1.Cu")
	)
	(gr_line
		(start 281.076146 -166.151814)
		(end 281.074876 -166.149528)
		(stroke
			(width 0.2)
			(type default)
		)
		(layer "In1.Cu")
	)
	(gr_line
		(start 281.076146 -138.15187)
		(end 281.074876 -138.149584)
		(stroke
			(width 0.2)
			(type default)
		)
		(layer "In1.Cu")
	)
	(gr_line
		(start 281.076146 -81.852008)
		(end 281.074876 -81.849722)
		(stroke
			(width 0.2)
			(type default)
		)
		(layer "In1.Cu")
	)
	(gr_line
		(start 281.076146 -77.852016)
		(end 281.074876 -77.84973)
		(stroke
			(width 0.2)
			(type default)
		)
		(layer "In1.Cu")
	)
	(gr_line
		(start 281.076146 -73.852024)
		(end 281.074876 -73.849738)
		(stroke
			(width 0.2)
			(type default)
		)
		(layer "In1.Cu")
	)
	(gr_line
		(start 281.076146 -69.852032)
		(end 281.074876 -69.849746)
		(stroke
			(width 0.2)
			(type default)
		)
		(layer "In1.Cu")
	)
	(gr_line
		(start 281.076146 -65.85204)
		(end 281.074876 -65.849754)
		(stroke
			(width 0.2)
			(type default)
		)
		(layer "In1.Cu")
	)
	(gr_line
		(start 281.076146 -61.852048)
		(end 281.074876 -61.849762)
		(stroke
			(width 0.2)
			(type default)
		)
		(layer "In1.Cu")
	)
	(gr_line
		(start 281.076146 -57.852056)
		(end 281.074876 -57.84977)
		(stroke
			(width 0.2)
			(type default)
		)
		(layer "In1.Cu")
	)
	(gr_line
		(start 281.076146 -53.852064)
		(end 281.074876 -53.849778)
		(stroke
			(width 0.2)
			(type default)
		)
		(layer "In1.Cu")
	)
	(gr_line
		(start 281.076146 -49.852072)
		(end 281.074876 -49.849786)
		(stroke
			(width 0.2)
			(type default)
		)
		(layer "In1.Cu")
	)
	(gr_line
		(start 281.076146 -45.85208)
		(end 281.074876 -45.849794)
		(stroke
			(width 0.2)
			(type default)
		)
		(layer "In1.Cu")
	)
	(gr_line
		(start 281.076146 -41.852088)
		(end 281.074876 -41.849802)
		(stroke
			(width 0.2)
			(type default)
		)
		(layer "In1.Cu")
	)
	(gr_line
		(start 281.076146 -37.852096)
		(end 281.074876 -37.84981)
		(stroke
			(width 0.2)
			(type default)
		)
		(layer "In1.Cu")
	)
	(gr_line
		(start 281.076146 -17.852136)
		(end 281.074876 -17.84985)
		(stroke
			(width 0.2)
			(type default)
		)
		(layer "In1.Cu")
	)
	(gr_arc
		(start 281.077162 -11.854434)
		(mid 281.404314 -10.872978)
		(end 280.422858 -10.545826)
		(stroke
			(width 0.2)
			(type default)
		)
		(layer "In1.Cu")
	)
	(gr_line
		(start 282.83662 -264.250932)
		(end 284.236668 -264.250932)
		(stroke
			(width 0.2)
			(type default)
		)
		(layer "In1.Cu")
	)
	(gr_arc
		(start 282.83662 -263.153652)
		(mid 282.28798 -263.702292)
		(end 282.83662 -264.250932)
		(stroke
			(width 0.2)
			(type default)
		)
		(layer "In1.Cu")
	)
	(gr_line
		(start 282.922726 -35.854386)
		(end 284.922468 -36.854384)
		(stroke
			(width 0.2)
			(type default)
		)
		(layer "In1.Cu")
	)
	(gr_line
		(start 282.923742 -136.151874)
		(end 284.923738 -137.151872)
		(stroke
			(width 0.2)
			(type default)
		)
		(layer "In1.Cu")
	)
	(gr_line
		(start 282.923742 -108.15193)
		(end 284.923738 -109.151928)
		(stroke
			(width 0.2)
			(type default)
		)
		(layer "In1.Cu")
	)
	(gr_line
		(start 282.925012 -136.149588)
		(end 282.923742 -136.151874)
		(stroke
			(width 0.2)
			(type default)
		)
		(layer "In1.Cu")
	)
	(gr_line
		(start 282.925012 -108.149644)
		(end 282.923742 -108.15193)
		(stroke
			(width 0.2)
			(type default)
		)
		(layer "In1.Cu")
	)
	(gr_line
		(start 282.936442 -180.126894)
		(end 284.928056 -181.122574)
		(stroke
			(width 0.2)
			(type default)
		)
		(layer "In1.Cu")
	)
	(gr_line
		(start 282.936442 -176.126902)
		(end 284.928056 -177.122582)
		(stroke
			(width 0.2)
			(type default)
		)
		(layer "In1.Cu")
	)
	(gr_line
		(start 282.936442 -172.12691)
		(end 284.928056 -173.12259)
		(stroke
			(width 0.2)
			(type default)
		)
		(layer "In1.Cu")
	)
	(gr_line
		(start 282.936442 -168.126918)
		(end 284.928056 -169.122598)
		(stroke
			(width 0.2)
			(type default)
		)
		(layer "In1.Cu")
	)
	(gr_line
		(start 282.936442 -164.126926)
		(end 284.928056 -165.122606)
		(stroke
			(width 0.2)
			(type default)
		)
		(layer "In1.Cu")
	)
	(gr_line
		(start 282.936442 -160.126934)
		(end 284.936438 -161.126932)
		(stroke
			(width 0.2)
			(type default)
		)
		(layer "In1.Cu")
	)
	(gr_line
		(start 282.936442 -156.126942)
		(end 284.928056 -157.122622)
		(stroke
			(width 0.2)
			(type default)
		)
		(layer "In1.Cu")
	)
	(gr_line
		(start 282.936442 -152.12695)
		(end 284.928056 -153.12263)
		(stroke
			(width 0.2)
			(type default)
		)
		(layer "In1.Cu")
	)
	(gr_line
		(start 282.936442 -128.126998)
		(end 284.928056 -129.122678)
		(stroke
			(width 0.2)
			(type default)
		)
		(layer "In1.Cu")
	)
	(gr_line
		(start 282.936442 -124.127006)
		(end 284.928056 -125.122686)
		(stroke
			(width 0.2)
			(type default)
		)
		(layer "In1.Cu")
	)
	(gr_line
		(start 282.936442 -120.127014)
		(end 284.928056 -121.122694)
		(stroke
			(width 0.2)
			(type default)
		)
		(layer "In1.Cu")
	)
	(gr_line
		(start 282.936442 -116.127022)
		(end 284.928056 -117.122702)
		(stroke
			(width 0.2)
			(type default)
		)
		(layer "In1.Cu")
	)
	(gr_line
		(start 282.936442 -83.827112)
		(end 284.928056 -84.822792)
		(stroke
			(width 0.2)
			(type default)
		)
		(layer "In1.Cu")
	)
	(gr_line
		(start 282.936442 -79.82712)
		(end 284.928056 -80.8228)
		(stroke
			(width 0.2)
			(type default)
		)
		(layer "In1.Cu")
	)
	(gr_line
		(start 282.936442 -75.827128)
		(end 284.928056 -76.822808)
		(stroke
			(width 0.2)
			(type default)
		)
		(layer "In1.Cu")
	)
	(gr_line
		(start 282.936442 -71.827136)
		(end 284.928056 -72.822816)
		(stroke
			(width 0.2)
			(type default)
		)
		(layer "In1.Cu")
	)
	(gr_line
		(start 282.936442 -67.827144)
		(end 284.928056 -68.822824)
		(stroke
			(width 0.2)
			(type default)
		)
		(layer "In1.Cu")
	)
	(gr_line
		(start 282.936442 -63.827152)
		(end 284.928056 -64.822832)
		(stroke
			(width 0.2)
			(type default)
		)
		(layer "In1.Cu")
	)
	(gr_line
		(start 282.936442 -59.82716)
		(end 284.928056 -60.82284)
		(stroke
			(width 0.2)
			(type default)
		)
		(layer "In1.Cu")
	)
	(gr_line
		(start 282.936442 -55.827168)
		(end 284.928056 -56.822848)
		(stroke
			(width 0.2)
			(type default)
		)
		(layer "In1.Cu")
	)
	(gr_line
		(start 282.936442 -51.827176)
		(end 284.928056 -52.822856)
		(stroke
			(width 0.2)
			(type default)
		)
		(layer "In1.Cu")
	)
	(gr_line
		(start 282.936442 -47.827184)
		(end 284.928056 -48.822864)
		(stroke
			(width 0.2)
			(type default)
		)
		(layer "In1.Cu")
	)
	(gr_line
		(start 282.936442 -43.827192)
		(end 284.928056 -44.822872)
		(stroke
			(width 0.2)
			(type default)
		)
		(layer "In1.Cu")
	)
	(gr_line
		(start 282.936442 -39.8272)
		(end 284.928056 -40.82288)
		(stroke
			(width 0.2)
			(type default)
		)
		(layer "In1.Cu")
	)
	(gr_arc
		(start 283.563314 -178.872642)
		(mid 282.622752 -179.186332)
		(end 282.936442 -180.126894)
		(stroke
			(width 0.2)
			(type default)
		)
		(layer "In1.Cu")
	)
	(gr_arc
		(start 283.563314 -174.87265)
		(mid 282.622752 -175.18634)
		(end 282.936442 -176.126902)
		(stroke
			(width 0.2)
			(type default)
		)
		(layer "In1.Cu")
	)
	(gr_arc
		(start 283.563314 -170.872658)
		(mid 282.622752 -171.186348)
		(end 282.936442 -172.12691)
		(stroke
			(width 0.2)
			(type default)
		)
		(layer "In1.Cu")
	)
	(gr_arc
		(start 283.563314 -166.872666)
		(mid 282.622752 -167.186356)
		(end 282.936442 -168.126918)
		(stroke
			(width 0.2)
			(type default)
		)
		(layer "In1.Cu")
	)
	(gr_arc
		(start 283.563314 -162.872674)
		(mid 282.622752 -163.186364)
		(end 282.936442 -164.126926)
		(stroke
			(width 0.2)
			(type default)
		)
		(layer "In1.Cu")
	)
	(gr_arc
		(start 283.563314 -154.87269)
		(mid 282.622752 -155.18638)
		(end 282.936442 -156.126942)
		(stroke
			(width 0.2)
			(type default)
		)
		(layer "In1.Cu")
	)
	(gr_arc
		(start 283.563314 -150.872698)
		(mid 282.622752 -151.186388)
		(end 282.936442 -152.12695)
		(stroke
			(width 0.2)
			(type default)
		)
		(layer "In1.Cu")
	)
	(gr_arc
		(start 283.563314 -126.872746)
		(mid 282.622752 -127.186436)
		(end 282.936442 -128.126998)
		(stroke
			(width 0.2)
			(type default)
		)
		(layer "In1.Cu")
	)
	(gr_arc
		(start 283.563314 -122.872754)
		(mid 282.622752 -123.186444)
		(end 282.936442 -124.127006)
		(stroke
			(width 0.2)
			(type default)
		)
		(layer "In1.Cu")
	)
	(gr_arc
		(start 283.563314 -118.872762)
		(mid 282.622752 -119.186452)
		(end 282.936442 -120.127014)
		(stroke
			(width 0.2)
			(type default)
		)
		(layer "In1.Cu")
	)
	(gr_arc
		(start 283.563314 -114.87277)
		(mid 282.622752 -115.18646)
		(end 282.936442 -116.127022)
		(stroke
			(width 0.2)
			(type default)
		)
		(layer "In1.Cu")
	)
	(gr_arc
		(start 283.563314 -82.57286)
		(mid 282.622752 -82.88655)
		(end 282.936442 -83.827112)
		(stroke
			(width 0.2)
			(type default)
		)
		(layer "In1.Cu")
	)
	(gr_arc
		(start 283.563314 -78.572868)
		(mid 282.622752 -78.886558)
		(end 282.936442 -79.82712)
		(stroke
			(width 0.2)
			(type default)
		)
		(layer "In1.Cu")
	)
	(gr_arc
		(start 283.563314 -74.572876)
		(mid 282.622752 -74.886566)
		(end 282.936442 -75.827128)
		(stroke
			(width 0.2)
			(type default)
		)
		(layer "In1.Cu")
	)
	(gr_arc
		(start 283.563314 -70.572884)
		(mid 282.622752 -70.886574)
		(end 282.936442 -71.827136)
		(stroke
			(width 0.2)
			(type default)
		)
		(layer "In1.Cu")
	)
	(gr_arc
		(start 283.563314 -66.572892)
		(mid 282.622752 -66.886582)
		(end 282.936442 -67.827144)
		(stroke
			(width 0.2)
			(type default)
		)
		(layer "In1.Cu")
	)
	(gr_arc
		(start 283.563314 -62.5729)
		(mid 282.622752 -62.88659)
		(end 282.936442 -63.827152)
		(stroke
			(width 0.2)
			(type default)
		)
		(layer "In1.Cu")
	)
	(gr_arc
		(start 283.563314 -58.572908)
		(mid 282.622752 -58.886598)
		(end 282.936442 -59.82716)
		(stroke
			(width 0.2)
			(type default)
		)
		(layer "In1.Cu")
	)
	(gr_arc
		(start 283.563314 -54.572916)
		(mid 282.622752 -54.886606)
		(end 282.936442 -55.827168)
		(stroke
			(width 0.2)
			(type default)
		)
		(layer "In1.Cu")
	)
	(gr_arc
		(start 283.563314 -50.572924)
		(mid 282.622752 -50.886614)
		(end 282.936442 -51.827176)
		(stroke
			(width 0.2)
			(type default)
		)
		(layer "In1.Cu")
	)
	(gr_arc
		(start 283.563314 -46.572932)
		(mid 282.622752 -46.886622)
		(end 282.936442 -47.827184)
		(stroke
			(width 0.2)
			(type default)
		)
		(layer "In1.Cu")
	)
	(gr_arc
		(start 283.563314 -42.57294)
		(mid 282.622752 -42.88663)
		(end 282.936442 -43.827192)
		(stroke
			(width 0.2)
			(type default)
		)
		(layer "In1.Cu")
	)
	(gr_arc
		(start 283.563314 -38.572948)
		(mid 282.622752 -38.886638)
		(end 282.936442 -39.8272)
		(stroke
			(width 0.2)
			(type default)
		)
		(layer "In1.Cu")
	)
	(gr_arc
		(start 283.571696 -158.877)
		(mid 282.62492 -159.182185)
		(end 282.936442 -160.126934)
		(stroke
			(width 0.2)
			(type default)
		)
		(layer "In1.Cu")
	)
	(gr_arc
		(start 283.574744 -134.850124)
		(mid 282.600146 -135.17499)
		(end 282.925012 -136.149588)
		(stroke
			(width 0.2)
			(type default)
		)
		(layer "In1.Cu")
	)
	(gr_arc
		(start 283.574744 -106.85018)
		(mid 282.600146 -107.175046)
		(end 282.925012 -108.149644)
		(stroke
			(width 0.2)
			(type default)
		)
		(layer "In1.Cu")
	)
	(gr_line
		(start 283.576014 -134.847838)
		(end 283.574744 -134.850124)
		(stroke
			(width 0.2)
			(type default)
		)
		(layer "In1.Cu")
	)
	(gr_line
		(start 283.576014 -106.847894)
		(end 283.574744 -106.85018)
		(stroke
			(width 0.2)
			(type default)
		)
		(layer "In1.Cu")
	)
	(gr_arc
		(start 283.57703 -34.545778)
		(mid 282.595574 -34.87293)
		(end 282.922726 -35.854386)
		(stroke
			(width 0.2)
			(type default)
		)
		(layer "In1.Cu")
	)
	(gr_arc
		(start 284.236668 -264.250932)
		(mid 284.785308 -263.702292)
		(end 284.236668 -263.153652)
		(stroke
			(width 0.2)
			(type default)
		)
		(layer "In1.Cu")
	)
	(gr_line
		(start 284.236668 -263.153652)
		(end 282.83662 -263.153652)
		(stroke
			(width 0.2)
			(type default)
		)
		(layer "In1.Cu")
	)
	(gr_arc
		(start 284.922468 -36.854384)
		(mid 285.904229 -36.527384)
		(end 285.577026 -35.545776)
		(stroke
			(width 0.2)
			(type default)
		)
		(layer "In1.Cu")
	)
	(gr_line
		(start 284.923738 -137.151872)
		(end 284.923992 -137.151618)
		(stroke
			(width 0.2)
			(type default)
		)
		(layer "In1.Cu")
	)
	(gr_line
		(start 284.923738 -109.151928)
		(end 284.923992 -109.151674)
		(stroke
			(width 0.2)
			(type default)
		)
		(layer "In1.Cu")
	)
	(gr_line
		(start 284.923992 -137.151618)
		(end 284.925008 -137.149586)
		(stroke
			(width 0.2)
			(type default)
		)
		(layer "In1.Cu")
	)
	(gr_line
		(start 284.923992 -109.151674)
		(end 284.925008 -109.149642)
		(stroke
			(width 0.2)
			(type default)
		)
		(layer "In1.Cu")
	)
	(gr_arc
		(start 284.925008 -137.149586)
		(mid 285.899606 -136.82472)
		(end 285.57474 -135.850122)
		(stroke
			(width 0.2)
			(type default)
		)
		(layer "In1.Cu")
	)
	(gr_arc
		(start 284.925008 -109.149642)
		(mid 285.899606 -108.824776)
		(end 285.57474 -107.850178)
		(stroke
			(width 0.2)
			(type default)
		)
		(layer "In1.Cu")
	)
	(gr_arc
		(start 284.928056 -181.122574)
		(mid 285.874832 -180.817389)
		(end 285.56331 -179.87264)
		(stroke
			(width 0.2)
			(type default)
		)
		(layer "In1.Cu")
	)
	(gr_arc
		(start 284.928056 -177.122582)
		(mid 285.874832 -176.817397)
		(end 285.56331 -175.872648)
		(stroke
			(width 0.2)
			(type default)
		)
		(layer "In1.Cu")
	)
	(gr_arc
		(start 284.928056 -173.12259)
		(mid 285.874832 -172.817405)
		(end 285.56331 -171.872656)
		(stroke
			(width 0.2)
			(type default)
		)
		(layer "In1.Cu")
	)
	(gr_arc
		(start 284.928056 -169.122598)
		(mid 285.874832 -168.817413)
		(end 285.56331 -167.872664)
		(stroke
			(width 0.2)
			(type default)
		)
		(layer "In1.Cu")
	)
	(gr_arc
		(start 284.928056 -165.122606)
		(mid 285.874832 -164.817421)
		(end 285.56331 -163.872672)
		(stroke
			(width 0.2)
			(type default)
		)
		(layer "In1.Cu")
	)
	(gr_arc
		(start 284.928056 -157.122622)
		(mid 285.874832 -156.817437)
		(end 285.56331 -155.872688)
		(stroke
			(width 0.2)
			(type default)
		)
		(layer "In1.Cu")
	)
	(gr_arc
		(start 284.928056 -153.12263)
		(mid 285.874832 -152.817445)
		(end 285.56331 -151.872696)
		(stroke
			(width 0.2)
			(type default)
		)
		(layer "In1.Cu")
	)
	(gr_arc
		(start 284.928056 -129.122678)
		(mid 285.874832 -128.817493)
		(end 285.56331 -127.872744)
		(stroke
			(width 0.2)
			(type default)
		)
		(layer "In1.Cu")
	)
	(gr_arc
		(start 284.928056 -125.122686)
		(mid 285.874832 -124.817501)
		(end 285.56331 -123.872752)
		(stroke
			(width 0.2)
			(type default)
		)
		(layer "In1.Cu")
	)
	(gr_arc
		(start 284.928056 -121.122694)
		(mid 285.874832 -120.817509)
		(end 285.56331 -119.87276)
		(stroke
			(width 0.2)
			(type default)
		)
		(layer "In1.Cu")
	)
	(gr_arc
		(start 284.928056 -117.122702)
		(mid 285.874832 -116.817517)
		(end 285.56331 -115.872768)
		(stroke
			(width 0.2)
			(type default)
		)
		(layer "In1.Cu")
	)
	(gr_arc
		(start 284.928056 -84.822792)
		(mid 285.874832 -84.517607)
		(end 285.56331 -83.572858)
		(stroke
			(width 0.2)
			(type default)
		)
		(layer "In1.Cu")
	)
	(gr_arc
		(start 284.928056 -80.8228)
		(mid 285.874832 -80.517615)
		(end 285.56331 -79.572866)
		(stroke
			(width 0.2)
			(type default)
		)
		(layer "In1.Cu")
	)
	(gr_arc
		(start 284.928056 -76.822808)
		(mid 285.874832 -76.517623)
		(end 285.56331 -75.572874)
		(stroke
			(width 0.2)
			(type default)
		)
		(layer "In1.Cu")
	)
	(gr_arc
		(start 284.928056 -72.822816)
		(mid 285.874832 -72.517631)
		(end 285.56331 -71.572882)
		(stroke
			(width 0.2)
			(type default)
		)
		(layer "In1.Cu")
	)
	(gr_arc
		(start 284.928056 -68.822824)
		(mid 285.874832 -68.517639)
		(end 285.56331 -67.57289)
		(stroke
			(width 0.2)
			(type default)
		)
		(layer "In1.Cu")
	)
	(gr_arc
		(start 284.928056 -64.822832)
		(mid 285.874832 -64.517647)
		(end 285.56331 -63.572898)
		(stroke
			(width 0.2)
			(type default)
		)
		(layer "In1.Cu")
	)
	(gr_arc
		(start 284.928056 -60.82284)
		(mid 285.874832 -60.517655)
		(end 285.56331 -59.572906)
		(stroke
			(width 0.2)
			(type default)
		)
		(layer "In1.Cu")
	)
	(gr_arc
		(start 284.928056 -56.822848)
		(mid 285.874832 -56.517663)
		(end 285.56331 -55.572914)
		(stroke
			(width 0.2)
			(type default)
		)
		(layer "In1.Cu")
	)
	(gr_arc
		(start 284.928056 -52.822856)
		(mid 285.874832 -52.517671)
		(end 285.56331 -51.572922)
		(stroke
			(width 0.2)
			(type default)
		)
		(layer "In1.Cu")
	)
	(gr_arc
		(start 284.928056 -48.822864)
		(mid 285.874832 -48.517679)
		(end 285.56331 -47.57293)
		(stroke
			(width 0.2)
			(type default)
		)
		(layer "In1.Cu")
	)
	(gr_arc
		(start 284.928056 -44.822872)
		(mid 285.874832 -44.517687)
		(end 285.56331 -43.572938)
		(stroke
			(width 0.2)
			(type default)
		)
		(layer "In1.Cu")
	)
	(gr_arc
		(start 284.928056 -40.82288)
		(mid 285.874832 -40.517695)
		(end 285.56331 -39.572946)
		(stroke
			(width 0.2)
			(type default)
		)
		(layer "In1.Cu")
	)
	(gr_arc
		(start 284.936438 -161.126932)
		(mid 285.877 -160.813242)
		(end 285.56331 -159.87268)
		(stroke
			(width 0.2)
			(type default)
		)
		(layer "In1.Cu")
	)
	(gr_line
		(start 285.436564 -356.456234)
		(end 286.836612 -356.456234)
		(stroke
			(width 0.2)
			(type default)
		)
		(layer "In1.Cu")
	)
	(gr_arc
		(start 285.436564 -355.353874)
		(mid 284.885384 -355.905054)
		(end 285.436564 -356.456234)
		(stroke
			(width 0.2)
			(type default)
		)
		(layer "In1.Cu")
	)
	(gr_line
		(start 285.436564 -352.856292)
		(end 286.836612 -352.856292)
		(stroke
			(width 0.2)
			(type default)
		)
		(layer "In1.Cu")
	)
	(gr_arc
		(start 285.436564 -351.753932)
		(mid 284.885384 -352.305112)
		(end 285.436564 -352.856292)
		(stroke
			(width 0.2)
			(type default)
		)
		(layer "In1.Cu")
	)
	(gr_line
		(start 285.436564 -349.25635)
		(end 286.836612 -349.25635)
		(stroke
			(width 0.2)
			(type default)
		)
		(layer "In1.Cu")
	)
	(gr_arc
		(start 285.436564 -348.15399)
		(mid 284.885384 -348.70517)
		(end 285.436564 -349.25635)
		(stroke
			(width 0.2)
			(type default)
		)
		(layer "In1.Cu")
	)
	(gr_line
		(start 285.436564 -345.653868)
		(end 286.836612 -345.653868)
		(stroke
			(width 0.2)
			(type default)
		)
		(layer "In1.Cu")
	)
	(gr_arc
		(start 285.436564 -344.556588)
		(mid 284.887924 -345.105228)
		(end 285.436564 -345.653868)
		(stroke
			(width 0.2)
			(type default)
		)
		(layer "In1.Cu")
	)
	(gr_line
		(start 285.436564 -342.053672)
		(end 286.836612 -342.053672)
		(stroke
			(width 0.2)
			(type default)
		)
		(layer "In1.Cu")
	)
	(gr_arc
		(start 285.436564 -340.956392)
		(mid 284.887924 -341.505032)
		(end 285.436564 -342.053672)
		(stroke
			(width 0.2)
			(type default)
		)
		(layer "In1.Cu")
	)
	(gr_line
		(start 285.436564 -338.45373)
		(end 286.836612 -338.45373)
		(stroke
			(width 0.2)
			(type default)
		)
		(layer "In1.Cu")
	)
	(gr_arc
		(start 285.436564 -337.35645)
		(mid 284.887924 -337.90509)
		(end 285.436564 -338.45373)
		(stroke
			(width 0.2)
			(type default)
		)
		(layer "In1.Cu")
	)
	(gr_line
		(start 285.436564 -334.856328)
		(end 286.836612 -334.856328)
		(stroke
			(width 0.2)
			(type default)
		)
		(layer "In1.Cu")
	)
	(gr_arc
		(start 285.436564 -333.753968)
		(mid 284.885384 -334.305148)
		(end 285.436564 -334.856328)
		(stroke
			(width 0.2)
			(type default)
		)
		(layer "In1.Cu")
	)
	(gr_line
		(start 285.436564 -331.256386)
		(end 286.836612 -331.256386)
		(stroke
			(width 0.2)
			(type default)
		)
		(layer "In1.Cu")
	)
	(gr_arc
		(start 285.436564 -330.154026)
		(mid 284.885384 -330.705206)
		(end 285.436564 -331.256386)
		(stroke
			(width 0.2)
			(type default)
		)
		(layer "In1.Cu")
	)
	(gr_line
		(start 285.436564 -327.656444)
		(end 286.836612 -327.656444)
		(stroke
			(width 0.2)
			(type default)
		)
		(layer "In1.Cu")
	)
	(gr_arc
		(start 285.436564 -326.554084)
		(mid 284.885384 -327.105264)
		(end 285.436564 -327.656444)
		(stroke
			(width 0.2)
			(type default)
		)
		(layer "In1.Cu")
	)
	(gr_line
		(start 285.436564 -324.053708)
		(end 286.836612 -324.053708)
		(stroke
			(width 0.2)
			(type default)
		)
		(layer "In1.Cu")
	)
	(gr_arc
		(start 285.436564 -322.956428)
		(mid 284.887924 -323.505068)
		(end 285.436564 -324.053708)
		(stroke
			(width 0.2)
			(type default)
		)
		(layer "In1.Cu")
	)
	(gr_line
		(start 285.436564 -320.453766)
		(end 286.836612 -320.453766)
		(stroke
			(width 0.2)
			(type default)
		)
		(layer "In1.Cu")
	)
	(gr_arc
		(start 285.436564 -319.356486)
		(mid 284.887924 -319.905126)
		(end 285.436564 -320.453766)
		(stroke
			(width 0.2)
			(type default)
		)
		(layer "In1.Cu")
	)
	(gr_line
		(start 285.436564 -316.853824)
		(end 286.836612 -316.853824)
		(stroke
			(width 0.2)
			(type default)
		)
		(layer "In1.Cu")
	)
	(gr_arc
		(start 285.436564 -315.756544)
		(mid 284.887924 -316.305184)
		(end 285.436564 -316.853824)
		(stroke
			(width 0.2)
			(type default)
		)
		(layer "In1.Cu")
	)
	(gr_line
		(start 285.436564 -313.256422)
		(end 286.836612 -313.256422)
		(stroke
			(width 0.2)
			(type default)
		)
		(layer "In1.Cu")
	)
	(gr_arc
		(start 285.436564 -312.154062)
		(mid 284.885384 -312.705242)
		(end 285.436564 -313.256422)
		(stroke
			(width 0.2)
			(type default)
		)
		(layer "In1.Cu")
	)
	(gr_line
		(start 285.436564 -309.656226)
		(end 286.836612 -309.656226)
		(stroke
			(width 0.2)
			(type default)
		)
		(layer "In1.Cu")
	)
	(gr_arc
		(start 285.436564 -308.553866)
		(mid 284.885384 -309.105046)
		(end 285.436564 -309.656226)
		(stroke
			(width 0.2)
			(type default)
		)
		(layer "In1.Cu")
	)
	(gr_line
		(start 285.436564 -306.056284)
		(end 286.836612 -306.056284)
		(stroke
			(width 0.2)
			(type default)
		)
		(layer "In1.Cu")
	)
	(gr_arc
		(start 285.436564 -304.953924)
		(mid 284.885384 -305.505104)
		(end 285.436564 -306.056284)
		(stroke
			(width 0.2)
			(type default)
		)
		(layer "In1.Cu")
	)
	(gr_line
		(start 285.436564 -302.453802)
		(end 286.836612 -302.453802)
		(stroke
			(width 0.2)
			(type default)
		)
		(layer "In1.Cu")
	)
	(gr_arc
		(start 285.436564 -301.356522)
		(mid 284.887924 -301.905162)
		(end 285.436564 -302.453802)
		(stroke
			(width 0.2)
			(type default)
		)
		(layer "In1.Cu")
	)
	(gr_line
		(start 285.436564 -298.85386)
		(end 286.836612 -298.85386)
		(stroke
			(width 0.2)
			(type default)
		)
		(layer "In1.Cu")
	)
	(gr_arc
		(start 285.436564 -297.75658)
		(mid 284.887924 -298.30522)
		(end 285.436564 -298.85386)
		(stroke
			(width 0.2)
			(type default)
		)
		(layer "In1.Cu")
	)
	(gr_line
		(start 285.436564 -295.256458)
		(end 286.836612 -295.256458)
		(stroke
			(width 0.2)
			(type default)
		)
		(layer "In1.Cu")
	)
	(gr_arc
		(start 285.436564 -294.154098)
		(mid 284.885384 -294.705278)
		(end 285.436564 -295.256458)
		(stroke
			(width 0.2)
			(type default)
		)
		(layer "In1.Cu")
	)
	(gr_line
		(start 285.436564 -262.453374)
		(end 286.836612 -262.453374)
		(stroke
			(width 0.2)
			(type default)
		)
		(layer "In1.Cu")
	)
	(gr_arc
		(start 285.436564 -261.351014)
		(mid 284.885384 -261.902194)
		(end 285.436564 -262.453374)
		(stroke
			(width 0.2)
			(type default)
		)
		(layer "In1.Cu")
	)
	(gr_line
		(start 285.436564 -258.853432)
		(end 286.836612 -258.853432)
		(stroke
			(width 0.2)
			(type default)
		)
		(layer "In1.Cu")
	)
	(gr_arc
		(start 285.436564 -257.751072)
		(mid 284.885384 -258.302252)
		(end 285.436564 -258.853432)
		(stroke
			(width 0.2)
			(type default)
		)
		(layer "In1.Cu")
	)
	(gr_line
		(start 285.436564 -255.25349)
		(end 286.836612 -255.25349)
		(stroke
			(width 0.2)
			(type default)
		)
		(layer "In1.Cu")
	)
	(gr_arc
		(start 285.436564 -254.15113)
		(mid 284.885384 -254.70231)
		(end 285.436564 -255.25349)
		(stroke
			(width 0.2)
			(type default)
		)
		(layer "In1.Cu")
	)
	(gr_line
		(start 285.436564 -251.653548)
		(end 286.836612 -251.653548)
		(stroke
			(width 0.2)
			(type default)
		)
		(layer "In1.Cu")
	)
	(gr_arc
		(start 285.436564 -250.551188)
		(mid 284.885384 -251.102368)
		(end 285.436564 -251.653548)
		(stroke
			(width 0.2)
			(type default)
		)
		(layer "In1.Cu")
	)
	(gr_line
		(start 285.436818 -355.353874)
		(end 285.436564 -355.353874)
		(stroke
			(width 0.2)
			(type default)
		)
		(layer "In1.Cu")
	)
	(gr_line
		(start 285.436818 -351.753932)
		(end 285.436564 -351.753932)
		(stroke
			(width 0.2)
			(type default)
		)
		(layer "In1.Cu")
	)
	(gr_line
		(start 285.436818 -348.15399)
		(end 285.436564 -348.15399)
		(stroke
			(width 0.2)
			(type default)
		)
		(layer "In1.Cu")
	)
	(gr_line
		(start 285.436818 -344.556588)
		(end 285.436564 -344.556588)
		(stroke
			(width 0.2)
			(type default)
		)
		(layer "In1.Cu")
	)
	(gr_line
		(start 285.436818 -340.956392)
		(end 285.436564 -340.956392)
		(stroke
			(width 0.2)
			(type default)
		)
		(layer "In1.Cu")
	)
	(gr_line
		(start 285.436818 -337.35645)
		(end 285.436564 -337.35645)
		(stroke
			(width 0.2)
			(type default)
		)
		(layer "In1.Cu")
	)
	(gr_line
		(start 285.436818 -333.753968)
		(end 285.436564 -333.753968)
		(stroke
			(width 0.2)
			(type default)
		)
		(layer "In1.Cu")
	)
	(gr_line
		(start 285.436818 -330.154026)
		(end 285.436564 -330.154026)
		(stroke
			(width 0.2)
			(type default)
		)
		(layer "In1.Cu")
	)
	(gr_line
		(start 285.436818 -326.554084)
		(end 285.436564 -326.554084)
		(stroke
			(width 0.2)
			(type default)
		)
		(layer "In1.Cu")
	)
	(gr_line
		(start 285.436818 -322.956428)
		(end 285.436564 -322.956428)
		(stroke
			(width 0.2)
			(type default)
		)
		(layer "In1.Cu")
	)
	(gr_line
		(start 285.436818 -319.356486)
		(end 285.436564 -319.356486)
		(stroke
			(width 0.2)
			(type default)
		)
		(layer "In1.Cu")
	)
	(gr_line
		(start 285.436818 -315.756544)
		(end 285.436564 -315.756544)
		(stroke
			(width 0.2)
			(type default)
		)
		(layer "In1.Cu")
	)
	(gr_line
		(start 285.436818 -312.154062)
		(end 285.436564 -312.154062)
		(stroke
			(width 0.2)
			(type default)
		)
		(layer "In1.Cu")
	)
	(gr_line
		(start 285.436818 -308.553866)
		(end 285.436564 -308.553866)
		(stroke
			(width 0.2)
			(type default)
		)
		(layer "In1.Cu")
	)
	(gr_line
		(start 285.436818 -304.953924)
		(end 285.436564 -304.953924)
		(stroke
			(width 0.2)
			(type default)
		)
		(layer "In1.Cu")
	)
	(gr_line
		(start 285.436818 -301.356522)
		(end 285.436564 -301.356522)
		(stroke
			(width 0.2)
			(type default)
		)
		(layer "In1.Cu")
	)
	(gr_line
		(start 285.436818 -297.75658)
		(end 285.436564 -297.75658)
		(stroke
			(width 0.2)
			(type default)
		)
		(layer "In1.Cu")
	)
	(gr_line
		(start 285.436818 -294.154098)
		(end 285.436564 -294.154098)
		(stroke
			(width 0.2)
			(type default)
		)
		(layer "In1.Cu")
	)
	(gr_line
		(start 285.436818 -261.351014)
		(end 285.436564 -261.351014)
		(stroke
			(width 0.2)
			(type default)
		)
		(layer "In1.Cu")
	)
	(gr_line
		(start 285.436818 -257.751072)
		(end 285.436564 -257.751072)
		(stroke
			(width 0.2)
			(type default)
		)
		(layer "In1.Cu")
	)
	(gr_line
		(start 285.436818 -254.15113)
		(end 285.436564 -254.15113)
		(stroke
			(width 0.2)
			(type default)
		)
		(layer "In1.Cu")
	)
	(gr_line
		(start 285.436818 -250.551188)
		(end 285.436564 -250.551188)
		(stroke
			(width 0.2)
			(type default)
		)
		(layer "In1.Cu")
	)
	(gr_line
		(start 285.56331 -179.87264)
		(end 283.563314 -178.872642)
		(stroke
			(width 0.2)
			(type default)
		)
		(layer "In1.Cu")
	)
	(gr_line
		(start 285.56331 -175.872648)
		(end 283.563314 -174.87265)
		(stroke
			(width 0.2)
			(type default)
		)
		(layer "In1.Cu")
	)
	(gr_line
		(start 285.56331 -171.872656)
		(end 283.563314 -170.872658)
		(stroke
			(width 0.2)
			(type default)
		)
		(layer "In1.Cu")
	)
	(gr_line
		(start 285.56331 -167.872664)
		(end 283.563314 -166.872666)
		(stroke
			(width 0.2)
			(type default)
		)
		(layer "In1.Cu")
	)
	(gr_line
		(start 285.56331 -163.872672)
		(end 283.563314 -162.872674)
		(stroke
			(width 0.2)
			(type default)
		)
		(layer "In1.Cu")
	)
	(gr_line
		(start 285.56331 -159.87268)
		(end 283.571696 -158.877)
		(stroke
			(width 0.2)
			(type default)
		)
		(layer "In1.Cu")
	)
	(gr_line
		(start 285.56331 -155.872688)
		(end 283.563314 -154.87269)
		(stroke
			(width 0.2)
			(type default)
		)
		(layer "In1.Cu")
	)
	(gr_line
		(start 285.56331 -151.872696)
		(end 283.563314 -150.872698)
		(stroke
			(width 0.2)
			(type default)
		)
		(layer "In1.Cu")
	)
	(gr_line
		(start 285.56331 -127.872744)
		(end 283.563314 -126.872746)
		(stroke
			(width 0.2)
			(type default)
		)
		(layer "In1.Cu")
	)
	(gr_line
		(start 285.56331 -123.872752)
		(end 283.563314 -122.872754)
		(stroke
			(width 0.2)
			(type default)
		)
		(layer "In1.Cu")
	)
	(gr_line
		(start 285.56331 -119.87276)
		(end 283.563314 -118.872762)
		(stroke
			(width 0.2)
			(type default)
		)
		(layer "In1.Cu")
	)
	(gr_line
		(start 285.56331 -115.872768)
		(end 283.563314 -114.87277)
		(stroke
			(width 0.2)
			(type default)
		)
		(layer "In1.Cu")
	)
	(gr_line
		(start 285.56331 -83.572858)
		(end 283.563314 -82.57286)
		(stroke
			(width 0.2)
			(type default)
		)
		(layer "In1.Cu")
	)
	(gr_line
		(start 285.56331 -79.572866)
		(end 283.563314 -78.572868)
		(stroke
			(width 0.2)
			(type default)
		)
		(layer "In1.Cu")
	)
	(gr_line
		(start 285.56331 -75.572874)
		(end 283.563314 -74.572876)
		(stroke
			(width 0.2)
			(type default)
		)
		(layer "In1.Cu")
	)
	(gr_line
		(start 285.56331 -71.572882)
		(end 283.563314 -70.572884)
		(stroke
			(width 0.2)
			(type default)
		)
		(layer "In1.Cu")
	)
	(gr_line
		(start 285.56331 -67.57289)
		(end 283.563314 -66.572892)
		(stroke
			(width 0.2)
			(type default)
		)
		(layer "In1.Cu")
	)
	(gr_line
		(start 285.56331 -63.572898)
		(end 283.563314 -62.5729)
		(stroke
			(width 0.2)
			(type default)
		)
		(layer "In1.Cu")
	)
	(gr_line
		(start 285.56331 -59.572906)
		(end 283.563314 -58.572908)
		(stroke
			(width 0.2)
			(type default)
		)
		(layer "In1.Cu")
	)
	(gr_line
		(start 285.56331 -55.572914)
		(end 283.563314 -54.572916)
		(stroke
			(width 0.2)
			(type default)
		)
		(layer "In1.Cu")
	)
	(gr_line
		(start 285.56331 -51.572922)
		(end 283.563314 -50.572924)
		(stroke
			(width 0.2)
			(type default)
		)
		(layer "In1.Cu")
	)
	(gr_line
		(start 285.56331 -47.57293)
		(end 283.563314 -46.572932)
		(stroke
			(width 0.2)
			(type default)
		)
		(layer "In1.Cu")
	)
	(gr_line
		(start 285.56331 -43.572938)
		(end 283.563314 -42.57294)
		(stroke
			(width 0.2)
			(type default)
		)
		(layer "In1.Cu")
	)
	(gr_line
		(start 285.56331 -39.572946)
		(end 283.563314 -38.572948)
		(stroke
			(width 0.2)
			(type default)
		)
		(layer "In1.Cu")
	)
	(gr_line
		(start 285.57474 -135.850122)
		(end 285.57601 -135.847836)
		(stroke
			(width 0.2)
			(type default)
		)
		(layer "In1.Cu")
	)
	(gr_line
		(start 285.57474 -107.850178)
		(end 285.57601 -107.847892)
		(stroke
			(width 0.2)
			(type default)
		)
		(layer "In1.Cu")
	)
	(gr_line
		(start 285.57601 -135.847836)
		(end 283.576014 -134.847838)
		(stroke
			(width 0.2)
			(type default)
		)
		(layer "In1.Cu")
	)
	(gr_line
		(start 285.57601 -107.847892)
		(end 283.576014 -106.847894)
		(stroke
			(width 0.2)
			(type default)
		)
		(layer "In1.Cu")
	)
	(gr_line
		(start 285.577026 -35.545776)
		(end 283.57703 -34.545778)
		(stroke
			(width 0.2)
			(type default)
		)
		(layer "In1.Cu")
	)
	(gr_line
		(start 286.436562 -358.256332)
		(end 287.83661 -358.256332)
		(stroke
			(width 0.2)
			(type default)
		)
		(layer "In1.Cu")
	)
	(gr_arc
		(start 286.436562 -357.153972)
		(mid 285.885382 -357.705152)
		(end 286.436562 -358.256332)
		(stroke
			(width 0.2)
			(type default)
		)
		(layer "In1.Cu")
	)
	(gr_line
		(start 286.436562 -354.65639)
		(end 287.83661 -354.65639)
		(stroke
			(width 0.2)
			(type default)
		)
		(layer "In1.Cu")
	)
	(gr_arc
		(start 286.436562 -353.55403)
		(mid 285.885382 -354.10521)
		(end 286.436562 -354.65639)
		(stroke
			(width 0.2)
			(type default)
		)
		(layer "In1.Cu")
	)
	(gr_line
		(start 286.436562 -351.056448)
		(end 287.83661 -351.056448)
		(stroke
			(width 0.2)
			(type default)
		)
		(layer "In1.Cu")
	)
	(gr_arc
		(start 286.436562 -349.954088)
		(mid 285.885382 -350.505268)
		(end 286.436562 -351.056448)
		(stroke
			(width 0.2)
			(type default)
		)
		(layer "In1.Cu")
	)
	(gr_line
		(start 286.436562 -347.453712)
		(end 287.83661 -347.453712)
		(stroke
			(width 0.2)
			(type default)
		)
		(layer "In1.Cu")
	)
	(gr_arc
		(start 286.436562 -346.356432)
		(mid 285.887922 -346.905072)
		(end 286.436562 -347.453712)
		(stroke
			(width 0.2)
			(type default)
		)
		(layer "In1.Cu")
	)
	(gr_line
		(start 286.436562 -343.85377)
		(end 287.83661 -343.85377)
		(stroke
			(width 0.2)
			(type default)
		)
		(layer "In1.Cu")
	)
	(gr_arc
		(start 286.436562 -342.75649)
		(mid 285.887922 -343.30513)
		(end 286.436562 -343.85377)
		(stroke
			(width 0.2)
			(type default)
		)
		(layer "In1.Cu")
	)
	(gr_line
		(start 286.436562 -340.253828)
		(end 287.83661 -340.253828)
		(stroke
			(width 0.2)
			(type default)
		)
		(layer "In1.Cu")
	)
	(gr_arc
		(start 286.436562 -339.156548)
		(mid 285.887922 -339.705188)
		(end 286.436562 -340.253828)
		(stroke
			(width 0.2)
			(type default)
		)
		(layer "In1.Cu")
	)
	(gr_line
		(start 286.436562 -336.656426)
		(end 287.83661 -336.656426)
		(stroke
			(width 0.2)
			(type default)
		)
		(layer "In1.Cu")
	)
	(gr_arc
		(start 286.436562 -335.554066)
		(mid 285.885382 -336.105246)
		(end 286.436562 -336.656426)
		(stroke
			(width 0.2)
			(type default)
		)
		(layer "In1.Cu")
	)
	(gr_line
		(start 286.436562 -333.05623)
		(end 287.83661 -333.05623)
		(stroke
			(width 0.2)
			(type default)
		)
		(layer "In1.Cu")
	)
	(gr_arc
		(start 286.436562 -331.95387)
		(mid 285.885382 -332.50505)
		(end 286.436562 -333.05623)
		(stroke
			(width 0.2)
			(type default)
		)
		(layer "In1.Cu")
	)
	(gr_line
		(start 286.436562 -329.456288)
		(end 287.83661 -329.456288)
		(stroke
			(width 0.2)
			(type default)
		)
		(layer "In1.Cu")
	)
	(gr_arc
		(start 286.436562 -328.353928)
		(mid 285.885382 -328.905108)
		(end 286.436562 -329.456288)
		(stroke
			(width 0.2)
			(type default)
		)
		(layer "In1.Cu")
	)
	(gr_line
		(start 286.436562 -325.853806)
		(end 287.83661 -325.853806)
		(stroke
			(width 0.2)
			(type default)
		)
		(layer "In1.Cu")
	)
	(gr_arc
		(start 286.436562 -324.756526)
		(mid 285.887922 -325.305166)
		(end 286.436562 -325.853806)
		(stroke
			(width 0.2)
			(type default)
		)
		(layer "In1.Cu")
	)
	(gr_line
		(start 286.436562 -322.253864)
		(end 287.83661 -322.253864)
		(stroke
			(width 0.2)
			(type default)
		)
		(layer "In1.Cu")
	)
	(gr_arc
		(start 286.436562 -321.156584)
		(mid 285.887922 -321.705224)
		(end 286.436562 -322.253864)
		(stroke
			(width 0.2)
			(type default)
		)
		(layer "In1.Cu")
	)
	(gr_line
		(start 286.436562 -318.653668)
		(end 287.83661 -318.653668)
		(stroke
			(width 0.2)
			(type default)
		)
		(layer "In1.Cu")
	)
	(gr_arc
		(start 286.436562 -317.556388)
		(mid 285.887922 -318.105028)
		(end 286.436562 -318.653668)
		(stroke
			(width 0.2)
			(type default)
		)
		(layer "In1.Cu")
	)
	(gr_line
		(start 286.436562 -315.056266)
		(end 287.83661 -315.056266)
		(stroke
			(width 0.2)
			(type default)
		)
		(layer "In1.Cu")
	)
	(gr_arc
		(start 286.436562 -313.953906)
		(mid 285.885382 -314.505086)
		(end 286.436562 -315.056266)
		(stroke
			(width 0.2)
			(type default)
		)
		(layer "In1.Cu")
	)
	(gr_line
		(start 286.436562 -311.456324)
		(end 287.83661 -311.456324)
		(stroke
			(width 0.2)
			(type default)
		)
		(layer "In1.Cu")
	)
	(gr_arc
		(start 286.436562 -310.353964)
		(mid 285.885382 -310.905144)
		(end 286.436562 -311.456324)
		(stroke
			(width 0.2)
			(type default)
		)
		(layer "In1.Cu")
	)
	(gr_line
		(start 286.436562 -307.856382)
		(end 287.83661 -307.856382)
		(stroke
			(width 0.2)
			(type default)
		)
		(layer "In1.Cu")
	)
	(gr_arc
		(start 286.436562 -306.754022)
		(mid 285.885382 -307.305202)
		(end 286.436562 -307.856382)
		(stroke
			(width 0.2)
			(type default)
		)
		(layer "In1.Cu")
	)
	(gr_line
		(start 286.436562 -304.2539)
		(end 287.83661 -304.2539)
		(stroke
			(width 0.2)
			(type default)
		)
		(layer "In1.Cu")
	)
	(gr_arc
		(start 286.436562 -303.15662)
		(mid 285.887922 -303.70526)
		(end 286.436562 -304.2539)
		(stroke
			(width 0.2)
			(type default)
		)
		(layer "In1.Cu")
	)
	(gr_line
		(start 286.436562 -300.653704)
		(end 287.83661 -300.653704)
		(stroke
			(width 0.2)
			(type default)
		)
		(layer "In1.Cu")
	)
	(gr_arc
		(start 286.436562 -299.556424)
		(mid 285.887922 -300.105064)
		(end 286.436562 -300.653704)
		(stroke
			(width 0.2)
			(type default)
		)
		(layer "In1.Cu")
	)
	(gr_line
		(start 286.436562 -297.056302)
		(end 287.83661 -297.056302)
		(stroke
			(width 0.2)
			(type default)
		)
		(layer "In1.Cu")
	)
	(gr_arc
		(start 286.436562 -295.953942)
		(mid 285.885382 -296.505122)
		(end 286.436562 -297.056302)
		(stroke
			(width 0.2)
			(type default)
		)
		(layer "In1.Cu")
	)
	(gr_line
		(start 286.436562 -264.253472)
		(end 287.83661 -264.253472)
		(stroke
			(width 0.2)
			(type default)
		)
		(layer "In1.Cu")
	)
	(gr_arc
		(start 286.436562 -263.151112)
		(mid 285.885382 -263.702292)
		(end 286.436562 -264.253472)
		(stroke
			(width 0.2)
			(type default)
		)
		(layer "In1.Cu")
	)
	(gr_line
		(start 286.436562 -260.65353)
		(end 287.83661 -260.65353)
		(stroke
			(width 0.2)
			(type default)
		)
		(layer "In1.Cu")
	)
	(gr_arc
		(start 286.436562 -259.55117)
		(mid 285.885382 -260.10235)
		(end 286.436562 -260.65353)
		(stroke
			(width 0.2)
			(type default)
		)
		(layer "In1.Cu")
	)
	(gr_line
		(start 286.436562 -257.053588)
		(end 287.83661 -257.053588)
		(stroke
			(width 0.2)
			(type default)
		)
		(layer "In1.Cu")
	)
	(gr_arc
		(start 286.436562 -255.951228)
		(mid 285.885382 -256.502408)
		(end 286.436562 -257.053588)
		(stroke
			(width 0.2)
			(type default)
		)
		(layer "In1.Cu")
	)
	(gr_line
		(start 286.436562 -253.453392)
		(end 287.83661 -253.453392)
		(stroke
			(width 0.2)
			(type default)
		)
		(layer "In1.Cu")
	)
	(gr_arc
		(start 286.436562 -252.351032)
		(mid 285.885382 -252.902212)
		(end 286.436562 -253.453392)
		(stroke
			(width 0.2)
			(type default)
		)
		(layer "In1.Cu")
	)
	(gr_line
		(start 286.436816 -357.153972)
		(end 286.436562 -357.153972)
		(stroke
			(width 0.2)
			(type default)
		)
		(layer "In1.Cu")
	)
	(gr_line
		(start 286.436816 -353.55403)
		(end 286.436562 -353.55403)
		(stroke
			(width 0.2)
			(type default)
		)
		(layer "In1.Cu")
	)
	(gr_line
		(start 286.436816 -349.954088)
		(end 286.436562 -349.954088)
		(stroke
			(width 0.2)
			(type default)
		)
		(layer "In1.Cu")
	)
	(gr_line
		(start 286.436816 -346.356432)
		(end 286.436562 -346.356432)
		(stroke
			(width 0.2)
			(type default)
		)
		(layer "In1.Cu")
	)
	(gr_line
		(start 286.436816 -342.75649)
		(end 286.436562 -342.75649)
		(stroke
			(width 0.2)
			(type default)
		)
		(layer "In1.Cu")
	)
	(gr_line
		(start 286.436816 -339.156548)
		(end 286.436562 -339.156548)
		(stroke
			(width 0.2)
			(type default)
		)
		(layer "In1.Cu")
	)
	(gr_line
		(start 286.436816 -335.554066)
		(end 286.436562 -335.554066)
		(stroke
			(width 0.2)
			(type default)
		)
		(layer "In1.Cu")
	)
	(gr_line
		(start 286.436816 -331.95387)
		(end 286.436562 -331.95387)
		(stroke
			(width 0.2)
			(type default)
		)
		(layer "In1.Cu")
	)
	(gr_line
		(start 286.436816 -328.353928)
		(end 286.436562 -328.353928)
		(stroke
			(width 0.2)
			(type default)
		)
		(layer "In1.Cu")
	)
	(gr_line
		(start 286.436816 -324.756526)
		(end 286.436562 -324.756526)
		(stroke
			(width 0.2)
			(type default)
		)
		(layer "In1.Cu")
	)
	(gr_line
		(start 286.436816 -321.156584)
		(end 286.436562 -321.156584)
		(stroke
			(width 0.2)
			(type default)
		)
		(layer "In1.Cu")
	)
	(gr_line
		(start 286.436816 -317.556388)
		(end 286.436562 -317.556388)
		(stroke
			(width 0.2)
			(type default)
		)
		(layer "In1.Cu")
	)
	(gr_line
		(start 286.436816 -313.953906)
		(end 286.436562 -313.953906)
		(stroke
			(width 0.2)
			(type default)
		)
		(layer "In1.Cu")
	)
	(gr_line
		(start 286.436816 -310.353964)
		(end 286.436562 -310.353964)
		(stroke
			(width 0.2)
			(type default)
		)
		(layer "In1.Cu")
	)
	(gr_line
		(start 286.436816 -306.754022)
		(end 286.436562 -306.754022)
		(stroke
			(width 0.2)
			(type default)
		)
		(layer "In1.Cu")
	)
	(gr_line
		(start 286.436816 -303.15662)
		(end 286.436562 -303.15662)
		(stroke
			(width 0.2)
			(type default)
		)
		(layer "In1.Cu")
	)
	(gr_line
		(start 286.436816 -299.556424)
		(end 286.436562 -299.556424)
		(stroke
			(width 0.2)
			(type default)
		)
		(layer "In1.Cu")
	)
	(gr_line
		(start 286.436816 -295.953942)
		(end 286.436562 -295.953942)
		(stroke
			(width 0.2)
			(type default)
		)
		(layer "In1.Cu")
	)
	(gr_line
		(start 286.436816 -263.151112)
		(end 286.436562 -263.151112)
		(stroke
			(width 0.2)
			(type default)
		)
		(layer "In1.Cu")
	)
	(gr_line
		(start 286.436816 -259.55117)
		(end 286.436562 -259.55117)
		(stroke
			(width 0.2)
			(type default)
		)
		(layer "In1.Cu")
	)
	(gr_line
		(start 286.436816 -255.951228)
		(end 286.436562 -255.951228)
		(stroke
			(width 0.2)
			(type default)
		)
		(layer "In1.Cu")
	)
	(gr_line
		(start 286.436816 -252.351032)
		(end 286.436562 -252.351032)
		(stroke
			(width 0.2)
			(type default)
		)
		(layer "In1.Cu")
	)
	(gr_arc
		(start 286.836612 -356.456234)
		(mid 287.387792 -355.905054)
		(end 286.836612 -355.353874)
		(stroke
			(width 0.2)
			(type default)
		)
		(layer "In1.Cu")
	)
	(gr_line
		(start 286.836612 -355.353874)
		(end 285.436818 -355.353874)
		(stroke
			(width 0.2)
			(type default)
		)
		(layer "In1.Cu")
	)
	(gr_arc
		(start 286.836612 -352.856292)
		(mid 287.387792 -352.305112)
		(end 286.836612 -351.753932)
		(stroke
			(width 0.2)
			(type default)
		)
		(layer "In1.Cu")
	)
	(gr_line
		(start 286.836612 -351.753932)
		(end 285.436818 -351.753932)
		(stroke
			(width 0.2)
			(type default)
		)
		(layer "In1.Cu")
	)
	(gr_arc
		(start 286.836612 -349.25635)
		(mid 287.387792 -348.70517)
		(end 286.836612 -348.15399)
		(stroke
			(width 0.2)
			(type default)
		)
		(layer "In1.Cu")
	)
	(gr_line
		(start 286.836612 -348.15399)
		(end 285.436818 -348.15399)
		(stroke
			(width 0.2)
			(type default)
		)
		(layer "In1.Cu")
	)
	(gr_arc
		(start 286.836612 -345.653868)
		(mid 287.385252 -345.105228)
		(end 286.836612 -344.556588)
		(stroke
			(width 0.2)
			(type default)
		)
		(layer "In1.Cu")
	)
	(gr_line
		(start 286.836612 -344.556588)
		(end 285.436818 -344.556588)
		(stroke
			(width 0.2)
			(type default)
		)
		(layer "In1.Cu")
	)
	(gr_arc
		(start 286.836612 -342.053672)
		(mid 287.385252 -341.505032)
		(end 286.836612 -340.956392)
		(stroke
			(width 0.2)
			(type default)
		)
		(layer "In1.Cu")
	)
	(gr_line
		(start 286.836612 -340.956392)
		(end 285.436818 -340.956392)
		(stroke
			(width 0.2)
			(type default)
		)
		(layer "In1.Cu")
	)
	(gr_arc
		(start 286.836612 -338.45373)
		(mid 287.385252 -337.90509)
		(end 286.836612 -337.35645)
		(stroke
			(width 0.2)
			(type default)
		)
		(layer "In1.Cu")
	)
	(gr_line
		(start 286.836612 -337.35645)
		(end 285.436818 -337.35645)
		(stroke
			(width 0.2)
			(type default)
		)
		(layer "In1.Cu")
	)
	(gr_arc
		(start 286.836612 -334.856328)
		(mid 287.387792 -334.305148)
		(end 286.836612 -333.753968)
		(stroke
			(width 0.2)
			(type default)
		)
		(layer "In1.Cu")
	)
	(gr_line
		(start 286.836612 -333.753968)
		(end 285.436818 -333.753968)
		(stroke
			(width 0.2)
			(type default)
		)
		(layer "In1.Cu")
	)
	(gr_arc
		(start 286.836612 -331.256386)
		(mid 287.387792 -330.705206)
		(end 286.836612 -330.154026)
		(stroke
			(width 0.2)
			(type default)
		)
		(layer "In1.Cu")
	)
	(gr_line
		(start 286.836612 -330.154026)
		(end 285.436818 -330.154026)
		(stroke
			(width 0.2)
			(type default)
		)
		(layer "In1.Cu")
	)
	(gr_arc
		(start 286.836612 -327.656444)
		(mid 287.387792 -327.105264)
		(end 286.836612 -326.554084)
		(stroke
			(width 0.2)
			(type default)
		)
		(layer "In1.Cu")
	)
	(gr_line
		(start 286.836612 -326.554084)
		(end 285.436818 -326.554084)
		(stroke
			(width 0.2)
			(type default)
		)
		(layer "In1.Cu")
	)
	(gr_arc
		(start 286.836612 -324.053708)
		(mid 287.385252 -323.505068)
		(end 286.836612 -322.956428)
		(stroke
			(width 0.2)
			(type default)
		)
		(layer "In1.Cu")
	)
	(gr_line
		(start 286.836612 -322.956428)
		(end 285.436818 -322.956428)
		(stroke
			(width 0.2)
			(type default)
		)
		(layer "In1.Cu")
	)
	(gr_arc
		(start 286.836612 -320.453766)
		(mid 287.385252 -319.905126)
		(end 286.836612 -319.356486)
		(stroke
			(width 0.2)
			(type default)
		)
		(layer "In1.Cu")
	)
	(gr_line
		(start 286.836612 -319.356486)
		(end 285.436818 -319.356486)
		(stroke
			(width 0.2)
			(type default)
		)
		(layer "In1.Cu")
	)
	(gr_arc
		(start 286.836612 -316.853824)
		(mid 287.385252 -316.305184)
		(end 286.836612 -315.756544)
		(stroke
			(width 0.2)
			(type default)
		)
		(layer "In1.Cu")
	)
	(gr_line
		(start 286.836612 -315.756544)
		(end 285.436818 -315.756544)
		(stroke
			(width 0.2)
			(type default)
		)
		(layer "In1.Cu")
	)
	(gr_arc
		(start 286.836612 -313.256422)
		(mid 287.387792 -312.705242)
		(end 286.836612 -312.154062)
		(stroke
			(width 0.2)
			(type default)
		)
		(layer "In1.Cu")
	)
	(gr_line
		(start 286.836612 -312.154062)
		(end 285.436818 -312.154062)
		(stroke
			(width 0.2)
			(type default)
		)
		(layer "In1.Cu")
	)
	(gr_arc
		(start 286.836612 -309.656226)
		(mid 287.387792 -309.105046)
		(end 286.836612 -308.553866)
		(stroke
			(width 0.2)
			(type default)
		)
		(layer "In1.Cu")
	)
	(gr_line
		(start 286.836612 -308.553866)
		(end 285.436818 -308.553866)
		(stroke
			(width 0.2)
			(type default)
		)
		(layer "In1.Cu")
	)
	(gr_arc
		(start 286.836612 -306.056284)
		(mid 287.387792 -305.505104)
		(end 286.836612 -304.953924)
		(stroke
			(width 0.2)
			(type default)
		)
		(layer "In1.Cu")
	)
	(gr_line
		(start 286.836612 -304.953924)
		(end 285.436818 -304.953924)
		(stroke
			(width 0.2)
			(type default)
		)
		(layer "In1.Cu")
	)
	(gr_arc
		(start 286.836612 -302.453802)
		(mid 287.385252 -301.905162)
		(end 286.836612 -301.356522)
		(stroke
			(width 0.2)
			(type default)
		)
		(layer "In1.Cu")
	)
	(gr_line
		(start 286.836612 -301.356522)
		(end 285.436818 -301.356522)
		(stroke
			(width 0.2)
			(type default)
		)
		(layer "In1.Cu")
	)
	(gr_arc
		(start 286.836612 -298.85386)
		(mid 287.385252 -298.30522)
		(end 286.836612 -297.75658)
		(stroke
			(width 0.2)
			(type default)
		)
		(layer "In1.Cu")
	)
	(gr_line
		(start 286.836612 -297.75658)
		(end 285.436818 -297.75658)
		(stroke
			(width 0.2)
			(type default)
		)
		(layer "In1.Cu")
	)
	(gr_arc
		(start 286.836612 -295.256458)
		(mid 287.387792 -294.705278)
		(end 286.836612 -294.154098)
		(stroke
			(width 0.2)
			(type default)
		)
		(layer "In1.Cu")
	)
	(gr_line
		(start 286.836612 -294.154098)
		(end 285.436818 -294.154098)
		(stroke
			(width 0.2)
			(type default)
		)
		(layer "In1.Cu")
	)
	(gr_arc
		(start 286.836612 -262.453374)
		(mid 287.387792 -261.902194)
		(end 286.836612 -261.351014)
		(stroke
			(width 0.2)
			(type default)
		)
		(layer "In1.Cu")
	)
	(gr_line
		(start 286.836612 -261.351014)
		(end 285.436818 -261.351014)
		(stroke
			(width 0.2)
			(type default)
		)
		(layer "In1.Cu")
	)
	(gr_arc
		(start 286.836612 -258.853432)
		(mid 287.387792 -258.302252)
		(end 286.836612 -257.751072)
		(stroke
			(width 0.2)
			(type default)
		)
		(layer "In1.Cu")
	)
	(gr_line
		(start 286.836612 -257.751072)
		(end 285.436818 -257.751072)
		(stroke
			(width 0.2)
			(type default)
		)
		(layer "In1.Cu")
	)
	(gr_arc
		(start 286.836612 -255.25349)
		(mid 287.387792 -254.70231)
		(end 286.836612 -254.15113)
		(stroke
			(width 0.2)
			(type default)
		)
		(layer "In1.Cu")
	)
	(gr_line
		(start 286.836612 -254.15113)
		(end 285.436818 -254.15113)
		(stroke
			(width 0.2)
			(type default)
		)
		(layer "In1.Cu")
	)
	(gr_arc
		(start 286.836612 -251.653548)
		(mid 287.387792 -251.102368)
		(end 286.836612 -250.551188)
		(stroke
			(width 0.2)
			(type default)
		)
		(layer "In1.Cu")
	)
	(gr_line
		(start 286.836612 -250.551188)
		(end 285.436818 -250.551188)
		(stroke
			(width 0.2)
			(type default)
		)
		(layer "In1.Cu")
	)
	(gr_arc
		(start 287.83661 -358.256332)
		(mid 288.38779 -357.705152)
		(end 287.83661 -357.153972)
		(stroke
			(width 0.2)
			(type default)
		)
		(layer "In1.Cu")
	)
	(gr_line
		(start 287.83661 -357.153972)
		(end 286.436816 -357.153972)
		(stroke
			(width 0.2)
			(type default)
		)
		(layer "In1.Cu")
	)
	(gr_arc
		(start 287.83661 -354.65639)
		(mid 288.38779 -354.10521)
		(end 287.83661 -353.55403)
		(stroke
			(width 0.2)
			(type default)
		)
		(layer "In1.Cu")
	)
	(gr_line
		(start 287.83661 -353.55403)
		(end 286.436816 -353.55403)
		(stroke
			(width 0.2)
			(type default)
		)
		(layer "In1.Cu")
	)
	(gr_arc
		(start 287.83661 -351.056448)
		(mid 288.38779 -350.505268)
		(end 287.83661 -349.954088)
		(stroke
			(width 0.2)
			(type default)
		)
		(layer "In1.Cu")
	)
	(gr_line
		(start 287.83661 -349.954088)
		(end 286.436816 -349.954088)
		(stroke
			(width 0.2)
			(type default)
		)
		(layer "In1.Cu")
	)
	(gr_arc
		(start 287.83661 -347.453712)
		(mid 288.38525 -346.905072)
		(end 287.83661 -346.356432)
		(stroke
			(width 0.2)
			(type default)
		)
		(layer "In1.Cu")
	)
	(gr_line
		(start 287.83661 -346.356432)
		(end 286.436816 -346.356432)
		(stroke
			(width 0.2)
			(type default)
		)
		(layer "In1.Cu")
	)
	(gr_arc
		(start 287.83661 -343.85377)
		(mid 288.38525 -343.30513)
		(end 287.83661 -342.75649)
		(stroke
			(width 0.2)
			(type default)
		)
		(layer "In1.Cu")
	)
	(gr_line
		(start 287.83661 -342.75649)
		(end 286.436816 -342.75649)
		(stroke
			(width 0.2)
			(type default)
		)
		(layer "In1.Cu")
	)
	(gr_arc
		(start 287.83661 -340.253828)
		(mid 288.38525 -339.705188)
		(end 287.83661 -339.156548)
		(stroke
			(width 0.2)
			(type default)
		)
		(layer "In1.Cu")
	)
	(gr_line
		(start 287.83661 -339.156548)
		(end 286.436816 -339.156548)
		(stroke
			(width 0.2)
			(type default)
		)
		(layer "In1.Cu")
	)
	(gr_arc
		(start 287.83661 -336.656426)
		(mid 288.38779 -336.105246)
		(end 287.83661 -335.554066)
		(stroke
			(width 0.2)
			(type default)
		)
		(layer "In1.Cu")
	)
	(gr_line
		(start 287.83661 -335.554066)
		(end 286.436816 -335.554066)
		(stroke
			(width 0.2)
			(type default)
		)
		(layer "In1.Cu")
	)
	(gr_arc
		(start 287.83661 -333.05623)
		(mid 288.38779 -332.50505)
		(end 287.83661 -331.95387)
		(stroke
			(width 0.2)
			(type default)
		)
		(layer "In1.Cu")
	)
	(gr_line
		(start 287.83661 -331.95387)
		(end 286.436816 -331.95387)
		(stroke
			(width 0.2)
			(type default)
		)
		(layer "In1.Cu")
	)
	(gr_arc
		(start 287.83661 -329.456288)
		(mid 288.38779 -328.905108)
		(end 287.83661 -328.353928)
		(stroke
			(width 0.2)
			(type default)
		)
		(layer "In1.Cu")
	)
	(gr_line
		(start 287.83661 -328.353928)
		(end 286.436816 -328.353928)
		(stroke
			(width 0.2)
			(type default)
		)
		(layer "In1.Cu")
	)
	(gr_arc
		(start 287.83661 -325.853806)
		(mid 288.38525 -325.305166)
		(end 287.83661 -324.756526)
		(stroke
			(width 0.2)
			(type default)
		)
		(layer "In1.Cu")
	)
	(gr_line
		(start 287.83661 -324.756526)
		(end 286.436816 -324.756526)
		(stroke
			(width 0.2)
			(type default)
		)
		(layer "In1.Cu")
	)
	(gr_arc
		(start 287.83661 -322.253864)
		(mid 288.38525 -321.705224)
		(end 287.83661 -321.156584)
		(stroke
			(width 0.2)
			(type default)
		)
		(layer "In1.Cu")
	)
	(gr_line
		(start 287.83661 -321.156584)
		(end 286.436816 -321.156584)
		(stroke
			(width 0.2)
			(type default)
		)
		(layer "In1.Cu")
	)
	(gr_arc
		(start 287.83661 -318.653668)
		(mid 288.38525 -318.105028)
		(end 287.83661 -317.556388)
		(stroke
			(width 0.2)
			(type default)
		)
		(layer "In1.Cu")
	)
	(gr_line
		(start 287.83661 -317.556388)
		(end 286.436816 -317.556388)
		(stroke
			(width 0.2)
			(type default)
		)
		(layer "In1.Cu")
	)
	(gr_arc
		(start 287.83661 -315.056266)
		(mid 288.38779 -314.505086)
		(end 287.83661 -313.953906)
		(stroke
			(width 0.2)
			(type default)
		)
		(layer "In1.Cu")
	)
	(gr_line
		(start 287.83661 -313.953906)
		(end 286.436816 -313.953906)
		(stroke
			(width 0.2)
			(type default)
		)
		(layer "In1.Cu")
	)
	(gr_arc
		(start 287.83661 -311.456324)
		(mid 288.38779 -310.905144)
		(end 287.83661 -310.353964)
		(stroke
			(width 0.2)
			(type default)
		)
		(layer "In1.Cu")
	)
	(gr_line
		(start 287.83661 -310.353964)
		(end 286.436816 -310.353964)
		(stroke
			(width 0.2)
			(type default)
		)
		(layer "In1.Cu")
	)
	(gr_arc
		(start 287.83661 -307.856382)
		(mid 288.38779 -307.305202)
		(end 287.83661 -306.754022)
		(stroke
			(width 0.2)
			(type default)
		)
		(layer "In1.Cu")
	)
	(gr_line
		(start 287.83661 -306.754022)
		(end 286.436816 -306.754022)
		(stroke
			(width 0.2)
			(type default)
		)
		(layer "In1.Cu")
	)
	(gr_arc
		(start 287.83661 -304.2539)
		(mid 288.38525 -303.70526)
		(end 287.83661 -303.15662)
		(stroke
			(width 0.2)
			(type default)
		)
		(layer "In1.Cu")
	)
	(gr_line
		(start 287.83661 -303.15662)
		(end 286.436816 -303.15662)
		(stroke
			(width 0.2)
			(type default)
		)
		(layer "In1.Cu")
	)
	(gr_arc
		(start 287.83661 -300.653704)
		(mid 288.38525 -300.105064)
		(end 287.83661 -299.556424)
		(stroke
			(width 0.2)
			(type default)
		)
		(layer "In1.Cu")
	)
	(gr_line
		(start 287.83661 -299.556424)
		(end 286.436816 -299.556424)
		(stroke
			(width 0.2)
			(type default)
		)
		(layer "In1.Cu")
	)
	(gr_arc
		(start 287.83661 -297.056302)
		(mid 288.38779 -296.505122)
		(end 287.83661 -295.953942)
		(stroke
			(width 0.2)
			(type default)
		)
		(layer "In1.Cu")
	)
	(gr_line
		(start 287.83661 -295.953942)
		(end 286.436816 -295.953942)
		(stroke
			(width 0.2)
			(type default)
		)
		(layer "In1.Cu")
	)
	(gr_arc
		(start 287.83661 -264.253472)
		(mid 288.38779 -263.702292)
		(end 287.83661 -263.151112)
		(stroke
			(width 0.2)
			(type default)
		)
		(layer "In1.Cu")
	)
	(gr_line
		(start 287.83661 -263.151112)
		(end 286.436816 -263.151112)
		(stroke
			(width 0.2)
			(type default)
		)
		(layer "In1.Cu")
	)
	(gr_arc
		(start 287.83661 -260.65353)
		(mid 288.38779 -260.10235)
		(end 287.83661 -259.55117)
		(stroke
			(width 0.2)
			(type default)
		)
		(layer "In1.Cu")
	)
	(gr_line
		(start 287.83661 -259.55117)
		(end 286.436816 -259.55117)
		(stroke
			(width 0.2)
			(type default)
		)
		(layer "In1.Cu")
	)
	(gr_arc
		(start 287.83661 -257.053588)
		(mid 288.38779 -256.502408)
		(end 287.83661 -255.951228)
		(stroke
			(width 0.2)
			(type default)
		)
		(layer "In1.Cu")
	)
	(gr_line
		(start 287.83661 -255.951228)
		(end 286.436816 -255.951228)
		(stroke
			(width 0.2)
			(type default)
		)
		(layer "In1.Cu")
	)
	(gr_arc
		(start 287.83661 -253.453392)
		(mid 288.38779 -252.902212)
		(end 287.83661 -252.351032)
		(stroke
			(width 0.2)
			(type default)
		)
		(layer "In1.Cu")
	)
	(gr_line
		(start 287.83661 -252.351032)
		(end 286.436816 -252.351032)
		(stroke
			(width 0.2)
			(type default)
		)
		(layer "In1.Cu")
	)
	(gr_arc
		(start 295.699942 -373.000016)
		(mid 295.992835 -373.707121)
		(end 296.69994 -374.000014)
		(stroke
			(width 1.524)
			(type default)
		)
		(layer "In1.Cu")
	)
	(gr_line
		(start 295.699942 -350.19996)
		(end 295.699942 -373.000016)
		(stroke
			(width 1.524)
			(type default)
		)
		(layer "In1.Cu")
	)
	(gr_line
		(start 296.69994 -374.000014)
		(end 308.99989 -374.000014)
		(stroke
			(width 1.524)
			(type default)
		)
		(layer "In1.Cu")
	)
	(gr_arc
		(start 296.69994 -349.199962)
		(mid 295.992835 -349.492855)
		(end 295.699942 -350.19996)
		(stroke
			(width 1.524)
			(type default)
		)
		(layer "In1.Cu")
	)
	(gr_arc
		(start 299.999908 0.999998)
		(mid 300.292801 0.292893)
		(end 300.999906 0)
		(stroke
			(width 1.524)
			(type default)
		)
		(layer "In1.Cu")
	)
	(gr_arc
		(start 299.999908 37.800026)
		(mid 299.707007 38.507118)
		(end 298.99991 38.800024)
		(stroke
			(width 1.524)
			(type default)
		)
		(layer "In1.Cu")
	)
	(gr_line
		(start 299.999908 37.800026)
		(end 299.999908 0.999998)
		(stroke
			(width 1.524)
			(type default)
		)
		(layer "In1.Cu")
	)
	(gr_line
		(start 300.999906 0)
		(end 347.000068 0)
		(stroke
			(width 1.524)
			(type default)
		)
		(layer "In1.Cu")
	)
	(gr_line
		(start 308.99989 -421.200072)
		(end 201.000106 -421.200072)
		(stroke
			(width 1.524)
			(type default)
		)
		(layer "In1.Cu")
	)
	(gr_arc
		(start 308.99989 -421.200072)
		(mid 309.706993 -420.907181)
		(end 309.999888 -420.200074)
		(stroke
			(width 1.524)
			(type default)
		)
		(layer "In1.Cu")
	)
	(gr_arc
		(start 309.999888 -375.000012)
		(mid 309.706999 -374.292902)
		(end 308.99989 -374.000014)
		(stroke
			(width 1.524)
			(type default)
		)
		(layer "In1.Cu")
	)
	(gr_line
		(start 309.999888 -375.000012)
		(end 309.999888 -420.200074)
		(stroke
			(width 1.524)
			(type default)
		)
		(layer "In1.Cu")
	)
	(gr_line
		(start 319.2145 -43.008042)
		(end 320.3575 -43.008042)
		(stroke
			(width 0.2)
			(type default)
		)
		(layer "In1.Cu")
	)
	(gr_arc
		(start 319.214754 -42.246042)
		(mid 318.8335 -42.626915)
		(end 319.2145 -43.008042)
		(stroke
			(width 0.2)
			(type default)
		)
		(layer "In1.Cu")
	)
	(gr_arc
		(start 319.56756 -274.511516)
		(mid 319.9892 -274.933156)
		(end 320.41084 -274.511516)
		(stroke
			(width 0.2)
			(type default)
		)
		(layer "In1.Cu")
	)
	(gr_line
		(start 319.56756 -273.368516)
		(end 319.56756 -274.511516)
		(stroke
			(width 0.2)
			(type default)
		)
		(layer "In1.Cu")
	)
	(gr_arc
		(start 319.6082 -159.511238)
		(mid 319.989073 -159.892492)
		(end 320.3702 -159.511492)
		(stroke
			(width 0.2)
			(type default)
		)
		(layer "In1.Cu")
	)
	(gr_line
		(start 319.6082 -158.368492)
		(end 319.6082 -159.511238)
		(stroke
			(width 0.2)
			(type default)
		)
		(layer "In1.Cu")
	)
	(gr_arc
		(start 320.3575 -43.008042)
		(mid 320.7385 -42.627042)
		(end 320.3575 -42.246042)
		(stroke
			(width 0.2)
			(type default)
		)
		(layer "In1.Cu")
	)
	(gr_line
		(start 320.3575 -42.246042)
		(end 319.214754 -42.246042)
		(stroke
			(width 0.2)
			(type default)
		)
		(layer "In1.Cu")
	)
	(gr_line
		(start 320.3702 -159.511492)
		(end 320.3702 -158.368492)
		(stroke
			(width 0.2)
			(type default)
		)
		(layer "In1.Cu")
	)
	(gr_arc
		(start 320.3702 -158.368492)
		(mid 319.9892 -157.987492)
		(end 319.6082 -158.368492)
		(stroke
			(width 0.2)
			(type default)
		)
		(layer "In1.Cu")
	)
	(gr_line
		(start 320.41084 -274.511516)
		(end 320.41084 -273.36877)
		(stroke
			(width 0.2)
			(type default)
		)
		(layer "In1.Cu")
	)
	(gr_arc
		(start 320.41084 -273.36877)
		(mid 319.989327 -272.946876)
		(end 319.56756 -273.368516)
		(stroke
			(width 0.2)
			(type default)
		)
		(layer "In1.Cu")
	)
	(gr_arc
		(start 321.177412 -274.321016)
		(mid 321.192291 -274.356937)
		(end 321.228212 -274.371816)
		(stroke
			(width 0.2)
			(type default)
		)
		(layer "In1.Cu")
	)
	(gr_line
		(start 321.177412 -274.117816)
		(end 321.177412 -274.321016)
		(stroke
			(width 0.2)
			(type default)
		)
		(layer "In1.Cu")
	)
	(gr_arc
		(start 321.177412 -273.762216)
		(mid 321.192291 -273.798137)
		(end 321.228212 -273.813016)
		(stroke
			(width 0.2)
			(type default)
		)
		(layer "In1.Cu")
	)
	(gr_line
		(start 321.177412 -273.559016)
		(end 321.177412 -273.762216)
		(stroke
			(width 0.2)
			(type default)
		)
		(layer "In1.Cu")
	)
	(gr_arc
		(start 321.177412 -159.320992)
		(mid 321.192291 -159.356913)
		(end 321.228212 -159.371792)
		(stroke
			(width 0.2)
			(type default)
		)
		(layer "In1.Cu")
	)
	(gr_line
		(start 321.177412 -159.117792)
		(end 321.177412 -159.320992)
		(stroke
			(width 0.2)
			(type default)
		)
		(layer "In1.Cu")
	)
	(gr_arc
		(start 321.177412 -158.762192)
		(mid 321.192291 -158.798113)
		(end 321.228212 -158.812992)
		(stroke
			(width 0.2)
			(type default)
		)
		(layer "In1.Cu")
	)
	(gr_line
		(start 321.177412 -158.558992)
		(end 321.177412 -158.762192)
		(stroke
			(width 0.2)
			(type default)
		)
		(layer "In1.Cu")
	)
	(gr_arc
		(start 321.177412 -44.320968)
		(mid 321.192291 -44.356889)
		(end 321.228212 -44.371768)
		(stroke
			(width 0.2)
			(type default)
		)
		(layer "In1.Cu")
	)
	(gr_line
		(start 321.177412 -44.117768)
		(end 321.177412 -44.320968)
		(stroke
			(width 0.2)
			(type default)
		)
		(layer "In1.Cu")
	)
	(gr_arc
		(start 321.177412 -43.762168)
		(mid 321.192291 -43.798089)
		(end 321.228212 -43.812968)
		(stroke
			(width 0.2)
			(type default)
		)
		(layer "In1.Cu")
	)
	(gr_line
		(start 321.177412 -43.558968)
		(end 321.177412 -43.762168)
		(stroke
			(width 0.2)
			(type default)
		)
		(layer "In1.Cu")
	)
	(gr_line
		(start 321.228212 -274.371816)
		(end 322.041012 -274.371816)
		(stroke
			(width 0.2)
			(type default)
		)
		(layer "In1.Cu")
	)
	(gr_arc
		(start 321.228212 -274.067016)
		(mid 321.192291 -274.081895)
		(end 321.177412 -274.117816)
		(stroke
			(width 0.2)
			(type default)
		)
		(layer "In1.Cu")
	)
	(gr_line
		(start 321.228212 -273.813016)
		(end 322.041012 -273.813016)
		(stroke
			(width 0.2)
			(type default)
		)
		(layer "In1.Cu")
	)
	(gr_arc
		(start 321.228212 -273.508216)
		(mid 321.192291 -273.523095)
		(end 321.177412 -273.559016)
		(stroke
			(width 0.2)
			(type default)
		)
		(layer "In1.Cu")
	)
	(gr_line
		(start 321.228212 -159.371792)
		(end 322.041012 -159.371792)
		(stroke
			(width 0.2)
			(type default)
		)
		(layer "In1.Cu")
	)
	(gr_arc
		(start 321.228212 -159.066992)
		(mid 321.192291 -159.081871)
		(end 321.177412 -159.117792)
		(stroke
			(width 0.2)
			(type default)
		)
		(layer "In1.Cu")
	)
	(gr_line
		(start 321.228212 -158.812992)
		(end 322.041012 -158.812992)
		(stroke
			(width 0.2)
			(type default)
		)
		(layer "In1.Cu")
	)
	(gr_arc
		(start 321.228212 -158.508192)
		(mid 321.192291 -158.523071)
		(end 321.177412 -158.558992)
		(stroke
			(width 0.2)
			(type default)
		)
		(layer "In1.Cu")
	)
	(gr_line
		(start 321.228212 -44.371768)
		(end 322.041012 -44.371768)
		(stroke
			(width 0.2)
			(type default)
		)
		(layer "In1.Cu")
	)
	(gr_arc
		(start 321.228212 -44.066968)
		(mid 321.192291 -44.081847)
		(end 321.177412 -44.117768)
		(stroke
			(width 0.2)
			(type default)
		)
		(layer "In1.Cu")
	)
	(gr_line
		(start 321.228212 -43.812968)
		(end 322.041012 -43.812968)
		(stroke
			(width 0.2)
			(type default)
		)
		(layer "In1.Cu")
	)
	(gr_arc
		(start 321.228212 -43.508168)
		(mid 321.192291 -43.523047)
		(end 321.177412 -43.558968)
		(stroke
			(width 0.2)
			(type default)
		)
		(layer "In1.Cu")
	)
	(gr_arc
		(start 322.041012 -274.371816)
		(mid 322.076933 -274.356937)
		(end 322.091812 -274.321016)
		(stroke
			(width 0.2)
			(type default)
		)
		(layer "In1.Cu")
	)
	(gr_line
		(start 322.041012 -274.067016)
		(end 321.228212 -274.067016)
		(stroke
			(width 0.2)
			(type default)
		)
		(layer "In1.Cu")
	)
	(gr_arc
		(start 322.041012 -273.813016)
		(mid 322.076933 -273.798137)
		(end 322.091812 -273.762216)
		(stroke
			(width 0.2)
			(type default)
		)
		(layer "In1.Cu")
	)
	(gr_line
		(start 322.041012 -273.508216)
		(end 321.228212 -273.508216)
		(stroke
			(width 0.2)
			(type default)
		)
		(layer "In1.Cu")
	)
	(gr_arc
		(start 322.041012 -159.371792)
		(mid 322.076933 -159.356913)
		(end 322.091812 -159.320992)
		(stroke
			(width 0.2)
			(type default)
		)
		(layer "In1.Cu")
	)
	(gr_line
		(start 322.041012 -159.066992)
		(end 321.228212 -159.066992)
		(stroke
			(width 0.2)
			(type default)
		)
		(layer "In1.Cu")
	)
	(gr_arc
		(start 322.041012 -158.812992)
		(mid 322.076933 -158.798113)
		(end 322.091812 -158.762192)
		(stroke
			(width 0.2)
			(type default)
		)
		(layer "In1.Cu")
	)
	(gr_line
		(start 322.041012 -158.508192)
		(end 321.228212 -158.508192)
		(stroke
			(width 0.2)
			(type default)
		)
		(layer "In1.Cu")
	)
	(gr_arc
		(start 322.041012 -44.371768)
		(mid 322.076933 -44.356889)
		(end 322.091812 -44.320968)
		(stroke
			(width 0.2)
			(type default)
		)
		(layer "In1.Cu")
	)
	(gr_line
		(start 322.041012 -44.066968)
		(end 321.228212 -44.066968)
		(stroke
			(width 0.2)
			(type default)
		)
		(layer "In1.Cu")
	)
	(gr_arc
		(start 322.041012 -43.812968)
		(mid 322.076933 -43.798089)
		(end 322.091812 -43.762168)
		(stroke
			(width 0.2)
			(type default)
		)
		(layer "In1.Cu")
	)
	(gr_line
		(start 322.041012 -43.508168)
		(end 321.228212 -43.508168)
		(stroke
			(width 0.2)
			(type default)
		)
		(layer "In1.Cu")
	)
	(gr_line
		(start 322.091812 -274.321016)
		(end 322.091812 -274.117816)
		(stroke
			(width 0.2)
			(type default)
		)
		(layer "In1.Cu")
	)
	(gr_arc
		(start 322.091812 -274.117816)
		(mid 322.076933 -274.081895)
		(end 322.041012 -274.067016)
		(stroke
			(width 0.2)
			(type default)
		)
		(layer "In1.Cu")
	)
	(gr_line
		(start 322.091812 -273.762216)
		(end 322.091812 -273.559016)
		(stroke
			(width 0.2)
			(type default)
		)
		(layer "In1.Cu")
	)
	(gr_arc
		(start 322.091812 -273.559016)
		(mid 322.076933 -273.523095)
		(end 322.041012 -273.508216)
		(stroke
			(width 0.2)
			(type default)
		)
		(layer "In1.Cu")
	)
	(gr_line
		(start 322.091812 -159.320992)
		(end 322.091812 -159.117792)
		(stroke
			(width 0.2)
			(type default)
		)
		(layer "In1.Cu")
	)
	(gr_arc
		(start 322.091812 -159.117792)
		(mid 322.076933 -159.081871)
		(end 322.041012 -159.066992)
		(stroke
			(width 0.2)
			(type default)
		)
		(layer "In1.Cu")
	)
	(gr_line
		(start 322.091812 -158.762192)
		(end 322.091812 -158.558992)
		(stroke
			(width 0.2)
			(type default)
		)
		(layer "In1.Cu")
	)
	(gr_arc
		(start 322.091812 -158.558992)
		(mid 322.076933 -158.523071)
		(end 322.041012 -158.508192)
		(stroke
			(width 0.2)
			(type default)
		)
		(layer "In1.Cu")
	)
	(gr_line
		(start 322.091812 -44.320968)
		(end 322.091812 -44.117768)
		(stroke
			(width 0.2)
			(type default)
		)
		(layer "In1.Cu")
	)
	(gr_arc
		(start 322.091812 -44.117768)
		(mid 322.076933 -44.081847)
		(end 322.041012 -44.066968)
		(stroke
			(width 0.2)
			(type default)
		)
		(layer "In1.Cu")
	)
	(gr_line
		(start 322.091812 -43.762168)
		(end 322.091812 -43.558968)
		(stroke
			(width 0.2)
			(type default)
		)
		(layer "In1.Cu")
	)
	(gr_arc
		(start 322.091812 -43.558968)
		(mid 322.076933 -43.523047)
		(end 322.041012 -43.508168)
		(stroke
			(width 0.2)
			(type default)
		)
		(layer "In1.Cu")
	)
	(gr_line
		(start 322.6816 -46.818042)
		(end 323.824346 -46.818042)
		(stroke
			(width 0.2)
			(type default)
		)
		(layer "In1.Cu")
	)
	(gr_arc
		(start 322.6816 -46.056042)
		(mid 322.3006 -46.437042)
		(end 322.6816 -46.818042)
		(stroke
			(width 0.2)
			(type default)
		)
		(layer "In1.Cu")
	)
	(gr_arc
		(start 323.824346 -46.818042)
		(mid 324.2056 -46.437169)
		(end 323.8246 -46.056042)
		(stroke
			(width 0.2)
			(type default)
		)
		(layer "In1.Cu")
	)
	(gr_line
		(start 323.8246 -46.056042)
		(end 322.6816 -46.056042)
		(stroke
			(width 0.2)
			(type default)
		)
		(layer "In1.Cu")
	)
	(gr_arc
		(start 324.358 -278.321516)
		(mid 324.739 -278.702516)
		(end 325.12 -278.321516)
		(stroke
			(width 0.2)
			(type default)
		)
		(layer "In1.Cu")
	)
	(gr_line
		(start 324.358 -277.178516)
		(end 324.358 -278.321516)
		(stroke
			(width 0.2)
			(type default)
		)
		(layer "In1.Cu")
	)
	(gr_arc
		(start 324.358 -163.321492)
		(mid 324.739 -163.702492)
		(end 325.12 -163.321492)
		(stroke
			(width 0.2)
			(type default)
		)
		(layer "In1.Cu")
	)
	(gr_line
		(start 324.358 -162.178492)
		(end 324.358 -163.321492)
		(stroke
			(width 0.2)
			(type default)
		)
		(layer "In1.Cu")
	)
	(gr_line
		(start 325.12 -278.321516)
		(end 325.12 -277.17877)
		(stroke
			(width 0.2)
			(type default)
		)
		(layer "In1.Cu")
	)
	(gr_arc
		(start 325.12 -277.17877)
		(mid 324.739127 -276.797516)
		(end 324.358 -277.178516)
		(stroke
			(width 0.2)
			(type default)
		)
		(layer "In1.Cu")
	)
	(gr_line
		(start 325.12 -163.321492)
		(end 325.12 -162.178746)
		(stroke
			(width 0.2)
			(type default)
		)
		(layer "In1.Cu")
	)
	(gr_arc
		(start 325.12 -162.178746)
		(mid 324.739127 -161.797492)
		(end 324.358 -162.178492)
		(stroke
			(width 0.2)
			(type default)
		)
		(layer "In1.Cu")
	)
	(gr_line
		(start 326.193912 -279.350216)
		(end 326.193912 -276.149816)
		(stroke
			(width 0.2)
			(type default)
		)
		(layer "In1.Cu")
	)
	(gr_rect
		(start 326.193912 -276.810216)
		(end 328.556112 -278.689816)
		(stroke
			(width 0)
			(type default)
		)
		(fill no)
		(layer "In1.Cu")
	)
	(gr_line
		(start 326.193912 -276.149816)
		(end 328.556112 -276.149816)
		(stroke
			(width 0.2)
			(type default)
		)
		(layer "In1.Cu")
	)
	(gr_line
		(start 326.193912 -275.540216)
		(end 326.193912 -272.339816)
		(stroke
			(width 0.2)
			(type default)
		)
		(layer "In1.Cu")
	)
	(gr_rect
		(start 326.193912 -273.000216)
		(end 328.556112 -274.879816)
		(stroke
			(width 0)
			(type default)
		)
		(fill no)
		(layer "In1.Cu")
	)
	(gr_line
		(start 326.193912 -272.339816)
		(end 328.556112 -272.340578)
		(stroke
			(width 0.2)
			(type default)
		)
		(layer "In1.Cu")
	)
	(gr_line
		(start 326.193912 -164.350192)
		(end 326.193912 -161.149792)
		(stroke
			(width 0.2)
			(type default)
		)
		(layer "In1.Cu")
	)
	(gr_rect
		(start 326.193912 -161.810192)
		(end 328.556112 -163.689792)
		(stroke
			(width 0)
			(type default)
		)
		(fill no)
		(layer "In1.Cu")
	)
	(gr_line
		(start 326.193912 -161.149792)
		(end 328.556112 -161.149792)
		(stroke
			(width 0.2)
			(type default)
		)
		(layer "In1.Cu")
	)
	(gr_line
		(start 326.193912 -160.540192)
		(end 326.193912 -157.339792)
		(stroke
			(width 0.2)
			(type default)
		)
		(layer "In1.Cu")
	)
	(gr_rect
		(start 326.193912 -158.000192)
		(end 328.556112 -159.879792)
		(stroke
			(width 0)
			(type default)
		)
		(fill no)
		(layer "In1.Cu")
	)
	(gr_line
		(start 326.193912 -157.339792)
		(end 328.556112 -157.340554)
		(stroke
			(width 0.2)
			(type default)
		)
		(layer "In1.Cu")
	)
	(gr_line
		(start 326.193912 -49.350168)
		(end 326.193912 -46.149768)
		(stroke
			(width 0.2)
			(type default)
		)
		(layer "In1.Cu")
	)
	(gr_rect
		(start 326.193912 -46.810168)
		(end 328.556112 -48.689768)
		(stroke
			(width 0)
			(type default)
		)
		(fill no)
		(layer "In1.Cu")
	)
	(gr_line
		(start 326.193912 -46.149768)
		(end 328.556112 -46.149768)
		(stroke
			(width 0.2)
			(type default)
		)
		(layer "In1.Cu")
	)
	(gr_line
		(start 326.193912 -45.540168)
		(end 326.193912 -42.339768)
		(stroke
			(width 0.2)
			(type default)
		)
		(layer "In1.Cu")
	)
	(gr_rect
		(start 326.193912 -43.000168)
		(end 328.556112 -44.879768)
		(stroke
			(width 0)
			(type default)
		)
		(fill no)
		(layer "In1.Cu")
	)
	(gr_line
		(start 326.193912 -42.339768)
		(end 328.556112 -42.34053)
		(stroke
			(width 0.2)
			(type default)
		)
		(layer "In1.Cu")
	)
	(gr_line
		(start 328.556112 -279.350216)
		(end 326.193912 -279.350216)
		(stroke
			(width 0.2)
			(type default)
		)
		(layer "In1.Cu")
	)
	(gr_line
		(start 328.556112 -276.149816)
		(end 328.556112 -279.350216)
		(stroke
			(width 0.2)
			(type default)
		)
		(layer "In1.Cu")
	)
	(gr_line
		(start 328.556112 -275.540216)
		(end 326.193912 -275.540216)
		(stroke
			(width 0.2)
			(type default)
		)
		(layer "In1.Cu")
	)
	(gr_line
		(start 328.556112 -272.340578)
		(end 328.556112 -275.540216)
		(stroke
			(width 0.2)
			(type default)
		)
		(layer "In1.Cu")
	)
	(gr_line
		(start 328.556112 -164.350192)
		(end 326.193912 -164.350192)
		(stroke
			(width 0.2)
			(type default)
		)
		(layer "In1.Cu")
	)
	(gr_line
		(start 328.556112 -161.149792)
		(end 328.556112 -164.350192)
		(stroke
			(width 0.2)
			(type default)
		)
		(layer "In1.Cu")
	)
	(gr_line
		(start 328.556112 -160.540192)
		(end 326.193912 -160.540192)
		(stroke
			(width 0.2)
			(type default)
		)
		(layer "In1.Cu")
	)
	(gr_line
		(start 328.556112 -157.340554)
		(end 328.556112 -160.540192)
		(stroke
			(width 0.2)
			(type default)
		)
		(layer "In1.Cu")
	)
	(gr_line
		(start 328.556112 -49.350168)
		(end 326.193912 -49.350168)
		(stroke
			(width 0.2)
			(type default)
		)
		(layer "In1.Cu")
	)
	(gr_line
		(start 328.556112 -46.149768)
		(end 328.556112 -49.350168)
		(stroke
			(width 0.2)
			(type default)
		)
		(layer "In1.Cu")
	)
	(gr_line
		(start 328.556112 -45.540168)
		(end 326.193912 -45.540168)
		(stroke
			(width 0.2)
			(type default)
		)
		(layer "In1.Cu")
	)
	(gr_line
		(start 328.556112 -42.34053)
		(end 328.556112 -45.540168)
		(stroke
			(width 0.2)
			(type default)
		)
		(layer "In1.Cu")
	)
	(gr_arc
		(start 348.000066 -13.999972)
		(mid 348.292959 -14.707077)
		(end 349.000064 -14.99997)
		(stroke
			(width 1.524)
			(type default)
		)
		(layer "In1.Cu")
	)
	(gr_arc
		(start 348.000066 -0.999998)
		(mid 347.707171 -0.292905)
		(end 347.000068 0)
		(stroke
			(width 1.524)
			(type default)
		)
		(layer "In1.Cu")
	)
	(gr_line
		(start 348.000066 -0.999998)
		(end 348.000066 -13.999972)
		(stroke
			(width 1.524)
			(type default)
		)
		(layer "In1.Cu")
	)
	(gr_line
		(start 349.000064 -14.99997)
		(end 394.999972 -14.99997)
		(stroke
			(width 1.524)
			(type default)
		)
		(layer "In1.Cu")
	)
	(gr_line
		(start 350.764602 -43.013122)
		(end 351.907602 -43.013122)
		(stroke
			(width 0.2)
			(type default)
		)
		(layer "In1.Cu")
	)
	(gr_arc
		(start 350.764856 -42.240962)
		(mid 350.378522 -42.626915)
		(end 350.764602 -43.013122)
		(stroke
			(width 0.2)
			(type default)
		)
		(layer "In1.Cu")
	)
	(gr_arc
		(start 351.158302 -274.511262)
		(mid 351.539175 -274.892516)
		(end 351.920302 -274.511516)
		(stroke
			(width 0.2)
			(type default)
		)
		(layer "In1.Cu")
	)
	(gr_line
		(start 351.158302 -273.368516)
		(end 351.158302 -274.511262)
		(stroke
			(width 0.2)
			(type default)
		)
		(layer "In1.Cu")
	)
	(gr_arc
		(start 351.158302 -159.511238)
		(mid 351.539175 -159.892492)
		(end 351.920302 -159.511492)
		(stroke
			(width 0.2)
			(type default)
		)
		(layer "In1.Cu")
	)
	(gr_line
		(start 351.158302 -158.368492)
		(end 351.158302 -159.511238)
		(stroke
			(width 0.2)
			(type default)
		)
		(layer "In1.Cu")
	)
	(gr_arc
		(start 351.907602 -43.013122)
		(mid 352.293682 -42.627042)
		(end 351.907602 -42.240962)
		(stroke
			(width 0.2)
			(type default)
		)
		(layer "In1.Cu")
	)
	(gr_line
		(start 351.907602 -42.240962)
		(end 350.764856 -42.240962)
		(stroke
			(width 0.2)
			(type default)
		)
		(layer "In1.Cu")
	)
	(gr_line
		(start 351.920302 -274.511516)
		(end 351.920302 -273.368516)
		(stroke
			(width 0.2)
			(type default)
		)
		(layer "In1.Cu")
	)
	(gr_arc
		(start 351.920302 -273.368516)
		(mid 351.539302 -272.987516)
		(end 351.158302 -273.368516)
		(stroke
			(width 0.2)
			(type default)
		)
		(layer "In1.Cu")
	)
	(gr_line
		(start 351.920302 -159.511492)
		(end 351.920302 -158.368492)
		(stroke
			(width 0.2)
			(type default)
		)
		(layer "In1.Cu")
	)
	(gr_arc
		(start 351.920302 -158.368492)
		(mid 351.539302 -157.987492)
		(end 351.158302 -158.368492)
		(stroke
			(width 0.2)
			(type default)
		)
		(layer "In1.Cu")
	)
	(gr_arc
		(start 352.727514 -274.321016)
		(mid 352.742393 -274.356937)
		(end 352.778314 -274.371816)
		(stroke
			(width 0.2)
			(type default)
		)
		(layer "In1.Cu")
	)
	(gr_line
		(start 352.727514 -274.117816)
		(end 352.727514 -274.321016)
		(stroke
			(width 0.2)
			(type default)
		)
		(layer "In1.Cu")
	)
	(gr_arc
		(start 352.727514 -273.762216)
		(mid 352.742393 -273.798137)
		(end 352.778314 -273.813016)
		(stroke
			(width 0.2)
			(type default)
		)
		(layer "In1.Cu")
	)
	(gr_line
		(start 352.727514 -273.559016)
		(end 352.727514 -273.762216)
		(stroke
			(width 0.2)
			(type default)
		)
		(layer "In1.Cu")
	)
	(gr_arc
		(start 352.727514 -159.320992)
		(mid 352.742393 -159.356913)
		(end 352.778314 -159.371792)
		(stroke
			(width 0.2)
			(type default)
		)
		(layer "In1.Cu")
	)
	(gr_line
		(start 352.727514 -159.117792)
		(end 352.727514 -159.320992)
		(stroke
			(width 0.2)
			(type default)
		)
		(layer "In1.Cu")
	)
	(gr_arc
		(start 352.727514 -158.762192)
		(mid 352.742393 -158.798113)
		(end 352.778314 -158.812992)
		(stroke
			(width 0.2)
			(type default)
		)
		(layer "In1.Cu")
	)
	(gr_line
		(start 352.727514 -158.558992)
		(end 352.727514 -158.762192)
		(stroke
			(width 0.2)
			(type default)
		)
		(layer "In1.Cu")
	)
	(gr_arc
		(start 352.727514 -44.320968)
		(mid 352.742393 -44.356889)
		(end 352.778314 -44.371768)
		(stroke
			(width 0.2)
			(type default)
		)
		(layer "In1.Cu")
	)
	(gr_line
		(start 352.727514 -44.117768)
		(end 352.727514 -44.320968)
		(stroke
			(width 0.2)
			(type default)
		)
		(layer "In1.Cu")
	)
	(gr_arc
		(start 352.727514 -43.762168)
		(mid 352.742393 -43.798089)
		(end 352.778314 -43.812968)
		(stroke
			(width 0.2)
			(type default)
		)
		(layer "In1.Cu")
	)
	(gr_line
		(start 352.727514 -43.558968)
		(end 352.727514 -43.762168)
		(stroke
			(width 0.2)
			(type default)
		)
		(layer "In1.Cu")
	)
	(gr_line
		(start 352.778314 -274.371816)
		(end 353.591114 -274.371816)
		(stroke
			(width 0.2)
			(type default)
		)
		(layer "In1.Cu")
	)
	(gr_arc
		(start 352.778314 -274.067016)
		(mid 352.742393 -274.081895)
		(end 352.727514 -274.117816)
		(stroke
			(width 0.2)
			(type default)
		)
		(layer "In1.Cu")
	)
	(gr_line
		(start 352.778314 -273.813016)
		(end 353.591114 -273.813016)
		(stroke
			(width 0.2)
			(type default)
		)
		(layer "In1.Cu")
	)
	(gr_arc
		(start 352.778314 -273.508216)
		(mid 352.742393 -273.523095)
		(end 352.727514 -273.559016)
		(stroke
			(width 0.2)
			(type default)
		)
		(layer "In1.Cu")
	)
	(gr_line
		(start 352.778314 -159.371792)
		(end 353.591114 -159.371792)
		(stroke
			(width 0.2)
			(type default)
		)
		(layer "In1.Cu")
	)
	(gr_arc
		(start 352.778314 -159.066992)
		(mid 352.742393 -159.081871)
		(end 352.727514 -159.117792)
		(stroke
			(width 0.2)
			(type default)
		)
		(layer "In1.Cu")
	)
	(gr_line
		(start 352.778314 -158.812992)
		(end 353.591114 -158.812992)
		(stroke
			(width 0.2)
			(type default)
		)
		(layer "In1.Cu")
	)
	(gr_arc
		(start 352.778314 -158.508192)
		(mid 352.742393 -158.523071)
		(end 352.727514 -158.558992)
		(stroke
			(width 0.2)
			(type default)
		)
		(layer "In1.Cu")
	)
	(gr_line
		(start 352.778314 -44.371768)
		(end 353.591114 -44.371768)
		(stroke
			(width 0.2)
			(type default)
		)
		(layer "In1.Cu")
	)
	(gr_arc
		(start 352.778314 -44.066968)
		(mid 352.742393 -44.081847)
		(end 352.727514 -44.117768)
		(stroke
			(width 0.2)
			(type default)
		)
		(layer "In1.Cu")
	)
	(gr_line
		(start 352.778314 -43.812968)
		(end 353.591114 -43.812968)
		(stroke
			(width 0.2)
			(type default)
		)
		(layer "In1.Cu")
	)
	(gr_arc
		(start 352.778314 -43.508168)
		(mid 352.742393 -43.523047)
		(end 352.727514 -43.558968)
		(stroke
			(width 0.2)
			(type default)
		)
		(layer "In1.Cu")
	)
	(gr_arc
		(start 353.591114 -274.371816)
		(mid 353.627035 -274.356937)
		(end 353.641914 -274.321016)
		(stroke
			(width 0.2)
			(type default)
		)
		(layer "In1.Cu")
	)
	(gr_line
		(start 353.591114 -274.067016)
		(end 352.778314 -274.067016)
		(stroke
			(width 0.2)
			(type default)
		)
		(layer "In1.Cu")
	)
	(gr_arc
		(start 353.591114 -273.813016)
		(mid 353.627035 -273.798137)
		(end 353.641914 -273.762216)
		(stroke
			(width 0.2)
			(type default)
		)
		(layer "In1.Cu")
	)
	(gr_line
		(start 353.591114 -273.508216)
		(end 352.778314 -273.508216)
		(stroke
			(width 0.2)
			(type default)
		)
		(layer "In1.Cu")
	)
	(gr_arc
		(start 353.591114 -159.371792)
		(mid 353.627035 -159.356913)
		(end 353.641914 -159.320992)
		(stroke
			(width 0.2)
			(type default)
		)
		(layer "In1.Cu")
	)
	(gr_line
		(start 353.591114 -159.066992)
		(end 352.778314 -159.066992)
		(stroke
			(width 0.2)
			(type default)
		)
		(layer "In1.Cu")
	)
	(gr_arc
		(start 353.591114 -158.812992)
		(mid 353.627035 -158.798113)
		(end 353.641914 -158.762192)
		(stroke
			(width 0.2)
			(type default)
		)
		(layer "In1.Cu")
	)
	(gr_line
		(start 353.591114 -158.508192)
		(end 352.778314 -158.508192)
		(stroke
			(width 0.2)
			(type default)
		)
		(layer "In1.Cu")
	)
	(gr_arc
		(start 353.591114 -44.371768)
		(mid 353.627035 -44.356889)
		(end 353.641914 -44.320968)
		(stroke
			(width 0.2)
			(type default)
		)
		(layer "In1.Cu")
	)
	(gr_line
		(start 353.591114 -44.066968)
		(end 352.778314 -44.066968)
		(stroke
			(width 0.2)
			(type default)
		)
		(layer "In1.Cu")
	)
	(gr_arc
		(start 353.591114 -43.812968)
		(mid 353.627035 -43.798089)
		(end 353.641914 -43.762168)
		(stroke
			(width 0.2)
			(type default)
		)
		(layer "In1.Cu")
	)
	(gr_line
		(start 353.591114 -43.508168)
		(end 352.778314 -43.508168)
		(stroke
			(width 0.2)
			(type default)
		)
		(layer "In1.Cu")
	)
	(gr_line
		(start 353.641914 -274.321016)
		(end 353.641914 -274.117816)
		(stroke
			(width 0.2)
			(type default)
		)
		(layer "In1.Cu")
	)
	(gr_arc
		(start 353.641914 -274.117816)
		(mid 353.627035 -274.081895)
		(end 353.591114 -274.067016)
		(stroke
			(width 0.2)
			(type default)
		)
		(layer "In1.Cu")
	)
	(gr_line
		(start 353.641914 -273.762216)
		(end 353.641914 -273.559016)
		(stroke
			(width 0.2)
			(type default)
		)
		(layer "In1.Cu")
	)
	(gr_arc
		(start 353.641914 -273.559016)
		(mid 353.627035 -273.523095)
		(end 353.591114 -273.508216)
		(stroke
			(width 0.2)
			(type default)
		)
		(layer "In1.Cu")
	)
	(gr_line
		(start 353.641914 -159.320992)
		(end 353.641914 -159.117792)
		(stroke
			(width 0.2)
			(type default)
		)
		(layer "In1.Cu")
	)
	(gr_arc
		(start 353.641914 -159.117792)
		(mid 353.627035 -159.081871)
		(end 353.591114 -159.066992)
		(stroke
			(width 0.2)
			(type default)
		)
		(layer "In1.Cu")
	)
	(gr_line
		(start 353.641914 -158.762192)
		(end 353.641914 -158.558992)
		(stroke
			(width 0.2)
			(type default)
		)
		(layer "In1.Cu")
	)
	(gr_arc
		(start 353.641914 -158.558992)
		(mid 353.627035 -158.523071)
		(end 353.591114 -158.508192)
		(stroke
			(width 0.2)
			(type default)
		)
		(layer "In1.Cu")
	)
	(gr_line
		(start 353.641914 -44.320968)
		(end 353.641914 -44.117768)
		(stroke
			(width 0.2)
			(type default)
		)
		(layer "In1.Cu")
	)
	(gr_arc
		(start 353.641914 -44.117768)
		(mid 353.627035 -44.081847)
		(end 353.591114 -44.066968)
		(stroke
			(width 0.2)
			(type default)
		)
		(layer "In1.Cu")
	)
	(gr_line
		(start 353.641914 -43.762168)
		(end 353.641914 -43.558968)
		(stroke
			(width 0.2)
			(type default)
		)
		(layer "In1.Cu")
	)
	(gr_arc
		(start 353.641914 -43.558968)
		(mid 353.627035 -43.523047)
		(end 353.591114 -43.508168)
		(stroke
			(width 0.2)
			(type default)
		)
		(layer "In1.Cu")
	)
	(gr_arc
		(start 354.601272 -22.350222)
		(mid 355.149912 -22.898862)
		(end 355.698552 -22.350222)
		(stroke
			(width 0.2)
			(type default)
		)
		(layer "In1.Cu")
	)
	(gr_line
		(start 354.601272 -20.950174)
		(end 354.601272 -22.350222)
		(stroke
			(width 0.2)
			(type default)
		)
		(layer "In1.Cu")
	)
	(gr_arc
		(start 354.601272 -18.750026)
		(mid 355.149912 -19.298666)
		(end 355.698552 -18.750026)
		(stroke
			(width 0.2)
			(type default)
		)
		(layer "In1.Cu")
	)
	(gr_line
		(start 354.601272 -17.349978)
		(end 354.601272 -18.750026)
		(stroke
			(width 0.2)
			(type default)
		)
		(layer "In1.Cu")
	)
	(gr_line
		(start 355.698552 -22.350222)
		(end 355.698552 -20.950428)
		(stroke
			(width 0.2)
			(type default)
		)
		(layer "In1.Cu")
	)
	(gr_arc
		(start 355.698552 -20.950428)
		(mid 355.150039 -20.401534)
		(end 354.601272 -20.950174)
		(stroke
			(width 0.2)
			(type default)
		)
		(layer "In1.Cu")
	)
	(gr_line
		(start 355.698552 -18.750026)
		(end 355.698552 -17.350232)
		(stroke
			(width 0.2)
			(type default)
		)
		(layer "In1.Cu")
	)
	(gr_arc
		(start 355.698552 -17.350232)
		(mid 355.150039 -16.801338)
		(end 354.601272 -17.349978)
		(stroke
			(width 0.2)
			(type default)
		)
		(layer "In1.Cu")
	)
	(gr_arc
		(start 355.903022 -48.321468)
		(mid 356.289102 -48.707548)
		(end 356.675182 -48.321468)
		(stroke
			(width 0.2)
			(type default)
		)
		(layer "In1.Cu")
	)
	(gr_line
		(start 355.903022 -47.178468)
		(end 355.903022 -48.321468)
		(stroke
			(width 0.2)
			(type default)
		)
		(layer "In1.Cu")
	)
	(gr_arc
		(start 355.908102 -278.321516)
		(mid 356.289102 -278.702516)
		(end 356.670102 -278.321516)
		(stroke
			(width 0.2)
			(type default)
		)
		(layer "In1.Cu")
	)
	(gr_line
		(start 355.908102 -277.178516)
		(end 355.908102 -278.321516)
		(stroke
			(width 0.2)
			(type default)
		)
		(layer "In1.Cu")
	)
	(gr_arc
		(start 355.908102 -163.321492)
		(mid 356.289102 -163.702492)
		(end 356.670102 -163.321492)
		(stroke
			(width 0.2)
			(type default)
		)
		(layer "In1.Cu")
	)
	(gr_line
		(start 355.908102 -162.178492)
		(end 355.908102 -163.321492)
		(stroke
			(width 0.2)
			(type default)
		)
		(layer "In1.Cu")
	)
	(gr_arc
		(start 356.40137 -23.35022)
		(mid 356.95001 -23.89886)
		(end 357.49865 -23.35022)
		(stroke
			(width 0.2)
			(type default)
		)
		(layer "In1.Cu")
	)
	(gr_line
		(start 356.40137 -21.950172)
		(end 356.40137 -23.35022)
		(stroke
			(width 0.2)
			(type default)
		)
		(layer "In1.Cu")
	)
	(gr_arc
		(start 356.40137 -19.750024)
		(mid 356.95001 -20.298664)
		(end 357.49865 -19.750024)
		(stroke
			(width 0.2)
			(type default)
		)
		(layer "In1.Cu")
	)
	(gr_line
		(start 356.40137 -18.35023)
		(end 356.40137 -19.750024)
		(stroke
			(width 0.2)
			(type default)
		)
		(layer "In1.Cu")
	)
	(gr_line
		(start 356.670102 -278.321516)
		(end 356.670102 -277.17877)
		(stroke
			(width 0.2)
			(type default)
		)
		(layer "In1.Cu")
	)
	(gr_arc
		(start 356.670102 -277.17877)
		(mid 356.289229 -276.797516)
		(end 355.908102 -277.178516)
		(stroke
			(width 0.2)
			(type default)
		)
		(layer "In1.Cu")
	)
	(gr_line
		(start 356.670102 -163.321492)
		(end 356.670102 -162.178746)
		(stroke
			(width 0.2)
			(type default)
		)
		(layer "In1.Cu")
	)
	(gr_arc
		(start 356.670102 -162.178746)
		(mid 356.289229 -161.797492)
		(end 355.908102 -162.178492)
		(stroke
			(width 0.2)
			(type default)
		)
		(layer "In1.Cu")
	)
	(gr_line
		(start 356.675182 -48.321468)
		(end 356.675182 -47.178722)
		(stroke
			(width 0.2)
			(type default)
		)
		(layer "In1.Cu")
	)
	(gr_arc
		(start 356.675182 -47.178722)
		(mid 356.289229 -46.792388)
		(end 355.903022 -47.178468)
		(stroke
			(width 0.2)
			(type default)
		)
		(layer "In1.Cu")
	)
	(gr_line
		(start 357.49865 -23.35022)
		(end 357.49865 -21.950426)
		(stroke
			(width 0.2)
			(type default)
		)
		(layer "In1.Cu")
	)
	(gr_arc
		(start 357.49865 -21.950426)
		(mid 356.950137 -21.401532)
		(end 356.40137 -21.950172)
		(stroke
			(width 0.2)
			(type default)
		)
		(layer "In1.Cu")
	)
	(gr_line
		(start 357.49865 -19.750024)
		(end 357.49865 -18.350484)
		(stroke
			(width 0.2)
			(type default)
		)
		(layer "In1.Cu")
	)
	(gr_arc
		(start 357.49865 -18.350484)
		(mid 356.950137 -17.80159)
		(end 356.40137 -18.35023)
		(stroke
			(width 0.2)
			(type default)
		)
		(layer "In1.Cu")
	)
	(gr_line
		(start 357.744014 -279.350216)
		(end 357.744014 -276.149816)
		(stroke
			(width 0.2)
			(type default)
		)
		(layer "In1.Cu")
	)
	(gr_rect
		(start 357.744014 -276.810216)
		(end 360.106214 -278.689816)
		(stroke
			(width 0)
			(type default)
		)
		(fill no)
		(layer "In1.Cu")
	)
	(gr_line
		(start 357.744014 -276.149816)
		(end 360.106214 -276.149816)
		(stroke
			(width 0.2)
			(type default)
		)
		(layer "In1.Cu")
	)
	(gr_line
		(start 357.744014 -275.540216)
		(end 357.744014 -272.339816)
		(stroke
			(width 0.2)
			(type default)
		)
		(layer "In1.Cu")
	)
	(gr_rect
		(start 357.744014 -273.000216)
		(end 360.106214 -274.879816)
		(stroke
			(width 0)
			(type default)
		)
		(fill no)
		(layer "In1.Cu")
	)
	(gr_line
		(start 357.744014 -272.339816)
		(end 360.106214 -272.340578)
		(stroke
			(width 0.2)
			(type default)
		)
		(layer "In1.Cu")
	)
	(gr_line
		(start 357.744014 -164.350192)
		(end 357.744014 -161.149792)
		(stroke
			(width 0.2)
			(type default)
		)
		(layer "In1.Cu")
	)
	(gr_rect
		(start 357.744014 -161.810192)
		(end 360.106214 -163.689792)
		(stroke
			(width 0)
			(type default)
		)
		(fill no)
		(layer "In1.Cu")
	)
	(gr_line
		(start 357.744014 -161.149792)
		(end 360.106214 -161.149792)
		(stroke
			(width 0.2)
			(type default)
		)
		(layer "In1.Cu")
	)
	(gr_line
		(start 357.744014 -160.540192)
		(end 357.744014 -157.339792)
		(stroke
			(width 0.2)
			(type default)
		)
		(layer "In1.Cu")
	)
	(gr_rect
		(start 357.744014 -158.000192)
		(end 360.106214 -159.879792)
		(stroke
			(width 0)
			(type default)
		)
		(fill no)
		(layer "In1.Cu")
	)
	(gr_line
		(start 357.744014 -157.339792)
		(end 360.106214 -157.340554)
		(stroke
			(width 0.2)
			(type default)
		)
		(layer "In1.Cu")
	)
	(gr_line
		(start 357.744014 -49.350168)
		(end 357.744014 -46.149768)
		(stroke
			(width 0.2)
			(type default)
		)
		(layer "In1.Cu")
	)
	(gr_rect
		(start 357.744014 -46.810168)
		(end 360.106214 -48.689768)
		(stroke
			(width 0)
			(type default)
		)
		(fill no)
		(layer "In1.Cu")
	)
	(gr_line
		(start 357.744014 -46.149768)
		(end 360.106214 -46.149768)
		(stroke
			(width 0.2)
			(type default)
		)
		(layer "In1.Cu")
	)
	(gr_line
		(start 357.744014 -45.540168)
		(end 357.744014 -42.339768)
		(stroke
			(width 0.2)
			(type default)
		)
		(layer "In1.Cu")
	)
	(gr_rect
		(start 357.744014 -43.000168)
		(end 360.106214 -44.879768)
		(stroke
			(width 0)
			(type default)
		)
		(fill no)
		(layer "In1.Cu")
	)
	(gr_line
		(start 357.744014 -42.339768)
		(end 360.106214 -42.34053)
		(stroke
			(width 0.2)
			(type default)
		)
		(layer "In1.Cu")
	)
	(gr_arc
		(start 358.201468 -22.350222)
		(mid 358.750108 -22.898862)
		(end 359.298748 -22.350222)
		(stroke
			(width 0.2)
			(type default)
		)
		(layer "In1.Cu")
	)
	(gr_line
		(start 358.201468 -20.950174)
		(end 358.201468 -22.350222)
		(stroke
			(width 0.2)
			(type default)
		)
		(layer "In1.Cu")
	)
	(gr_arc
		(start 358.201468 -18.750026)
		(mid 358.750108 -19.298666)
		(end 359.298748 -18.750026)
		(stroke
			(width 0.2)
			(type default)
		)
		(layer "In1.Cu")
	)
	(gr_line
		(start 358.201468 -17.349978)
		(end 358.201468 -18.750026)
		(stroke
			(width 0.2)
			(type default)
		)
		(layer "In1.Cu")
	)
	(gr_line
		(start 358.2162 -146.685)
		(end 363.1438 -151.6126)
		(stroke
			(width 0.381)
			(type default)
		)
		(layer "In1.Cu")
	)
	(gr_line
		(start 358.2162 -130.4036)
		(end 358.2162 -146.685)
		(stroke
			(width 0.381)
			(type default)
		)
		(layer "In1.Cu")
	)
	(gr_line
		(start 359.180384 -129.439416)
		(end 358.2162 -130.4036)
		(stroke
			(width 0.381)
			(type default)
		)
		(layer "In1.Cu")
	)
	(gr_line
		(start 359.298748 -22.350222)
		(end 359.298748 -20.950428)
		(stroke
			(width 0.2)
			(type default)
		)
		(layer "In1.Cu")
	)
	(gr_arc
		(start 359.298748 -20.950428)
		(mid 358.750235 -20.401534)
		(end 358.201468 -20.950174)
		(stroke
			(width 0.2)
			(type default)
		)
		(layer "In1.Cu")
	)
	(gr_line
		(start 359.298748 -18.750026)
		(end 359.298748 -17.350232)
		(stroke
			(width 0.2)
			(type default)
		)
		(layer "In1.Cu")
	)
	(gr_arc
		(start 359.298748 -17.350232)
		(mid 358.750235 -16.801338)
		(end 358.201468 -17.349978)
		(stroke
			(width 0.2)
			(type default)
		)
		(layer "In1.Cu")
	)
	(gr_arc
		(start 360.001312 -23.35022)
		(mid 360.549952 -23.89886)
		(end 361.098592 -23.35022)
		(stroke
			(width 0.2)
			(type default)
		)
		(layer "In1.Cu")
	)
	(gr_line
		(start 360.001312 -21.950172)
		(end 360.001312 -23.35022)
		(stroke
			(width 0.2)
			(type default)
		)
		(layer "In1.Cu")
	)
	(gr_arc
		(start 360.001312 -19.750024)
		(mid 360.549952 -20.298664)
		(end 361.098592 -19.750024)
		(stroke
			(width 0.2)
			(type default)
		)
		(layer "In1.Cu")
	)
	(gr_line
		(start 360.001312 -18.35023)
		(end 360.001312 -19.750024)
		(stroke
			(width 0.2)
			(type default)
		)
		(layer "In1.Cu")
	)
	(gr_line
		(start 360.106214 -279.350216)
		(end 357.744014 -279.350216)
		(stroke
			(width 0.2)
			(type default)
		)
		(layer "In1.Cu")
	)
	(gr_line
		(start 360.106214 -276.149816)
		(end 360.106214 -279.350216)
		(stroke
			(width 0.2)
			(type default)
		)
		(layer "In1.Cu")
	)
	(gr_line
		(start 360.106214 -275.540216)
		(end 357.744014 -275.540216)
		(stroke
			(width 0.2)
			(type default)
		)
		(layer "In1.Cu")
	)
	(gr_line
		(start 360.106214 -272.340578)
		(end 360.106214 -275.540216)
		(stroke
			(width 0.2)
			(type default)
		)
		(layer "In1.Cu")
	)
	(gr_line
		(start 360.106214 -164.350192)
		(end 357.744014 -164.350192)
		(stroke
			(width 0.2)
			(type default)
		)
		(layer "In1.Cu")
	)
	(gr_line
		(start 360.106214 -161.149792)
		(end 360.106214 -164.350192)
		(stroke
			(width 0.2)
			(type default)
		)
		(layer "In1.Cu")
	)
	(gr_line
		(start 360.106214 -160.540192)
		(end 357.744014 -160.540192)
		(stroke
			(width 0.2)
			(type default)
		)
		(layer "In1.Cu")
	)
	(gr_line
		(start 360.106214 -157.340554)
		(end 360.106214 -160.540192)
		(stroke
			(width 0.2)
			(type default)
		)
		(layer "In1.Cu")
	)
	(gr_line
		(start 360.106214 -49.350168)
		(end 357.744014 -49.350168)
		(stroke
			(width 0.2)
			(type default)
		)
		(layer "In1.Cu")
	)
	(gr_line
		(start 360.106214 -46.149768)
		(end 360.106214 -49.350168)
		(stroke
			(width 0.2)
			(type default)
		)
		(layer "In1.Cu")
	)
	(gr_line
		(start 360.106214 -45.540168)
		(end 357.744014 -45.540168)
		(stroke
			(width 0.2)
			(type default)
		)
		(layer "In1.Cu")
	)
	(gr_line
		(start 360.106214 -42.34053)
		(end 360.106214 -45.540168)
		(stroke
			(width 0.2)
			(type default)
		)
		(layer "In1.Cu")
	)
	(gr_line
		(start 361.098592 -23.35022)
		(end 361.098592 -21.950426)
		(stroke
			(width 0.2)
			(type default)
		)
		(layer "In1.Cu")
	)
	(gr_arc
		(start 361.098592 -21.950426)
		(mid 360.550079 -21.401532)
		(end 360.001312 -21.950172)
		(stroke
			(width 0.2)
			(type default)
		)
		(layer "In1.Cu")
	)
	(gr_line
		(start 361.098592 -19.750024)
		(end 361.098592 -18.350484)
		(stroke
			(width 0.2)
			(type default)
		)
		(layer "In1.Cu")
	)
	(gr_arc
		(start 361.098592 -18.350484)
		(mid 360.550079 -17.80159)
		(end 360.001312 -18.35023)
		(stroke
			(width 0.2)
			(type default)
		)
		(layer "In1.Cu")
	)
	(gr_arc
		(start 361.80141 -29.550106)
		(mid 362.35005 -30.098746)
		(end 362.89869 -29.550106)
		(stroke
			(width 0.2)
			(type default)
		)
		(layer "In1.Cu")
	)
	(gr_line
		(start 361.80141 -28.150058)
		(end 361.80141 -29.550106)
		(stroke
			(width 0.2)
			(type default)
		)
		(layer "In1.Cu")
	)
	(gr_arc
		(start 361.80141 -22.350222)
		(mid 362.35005 -22.898862)
		(end 362.89869 -22.350222)
		(stroke
			(width 0.2)
			(type default)
		)
		(layer "In1.Cu")
	)
	(gr_line
		(start 361.80141 -20.950174)
		(end 361.80141 -22.350222)
		(stroke
			(width 0.2)
			(type default)
		)
		(layer "In1.Cu")
	)
	(gr_arc
		(start 361.80141 -18.750026)
		(mid 362.35005 -19.298666)
		(end 362.89869 -18.750026)
		(stroke
			(width 0.2)
			(type default)
		)
		(layer "In1.Cu")
	)
	(gr_line
		(start 361.80141 -17.349978)
		(end 361.80141 -18.750026)
		(stroke
			(width 0.2)
			(type default)
		)
		(layer "In1.Cu")
	)
	(gr_line
		(start 362.89869 -29.550106)
		(end 362.89869 -28.150312)
		(stroke
			(width 0.2)
			(type default)
		)
		(layer "In1.Cu")
	)
	(gr_arc
		(start 362.89869 -28.150312)
		(mid 362.350177 -27.601418)
		(end 361.80141 -28.150058)
		(stroke
			(width 0.2)
			(type default)
		)
		(layer "In1.Cu")
	)
	(gr_line
		(start 362.89869 -22.350222)
		(end 362.89869 -20.950428)
		(stroke
			(width 0.2)
			(type default)
		)
		(layer "In1.Cu")
	)
	(gr_arc
		(start 362.89869 -20.950428)
		(mid 362.350177 -20.401534)
		(end 361.80141 -20.950174)
		(stroke
			(width 0.2)
			(type default)
		)
		(layer "In1.Cu")
	)
	(gr_line
		(start 362.89869 -18.750026)
		(end 362.89869 -17.350232)
		(stroke
			(width 0.2)
			(type default)
		)
		(layer "In1.Cu")
	)
	(gr_arc
		(start 362.89869 -17.350232)
		(mid 362.350177 -16.801338)
		(end 361.80141 -17.349978)
		(stroke
			(width 0.2)
			(type default)
		)
		(layer "In1.Cu")
	)
	(gr_line
		(start 363.1438 -151.6126)
		(end 375.8946 -151.6126)
		(stroke
			(width 0.381)
			(type default)
		)
		(layer "In1.Cu")
	)
	(gr_arc
		(start 363.601254 -23.35022)
		(mid 364.149894 -23.89886)
		(end 364.698534 -23.35022)
		(stroke
			(width 0.2)
			(type default)
		)
		(layer "In1.Cu")
	)
	(gr_line
		(start 363.601254 -21.950172)
		(end 363.601254 -23.35022)
		(stroke
			(width 0.2)
			(type default)
		)
		(layer "In1.Cu")
	)
	(gr_arc
		(start 363.601254 -19.750024)
		(mid 364.149894 -20.298664)
		(end 364.698534 -19.750024)
		(stroke
			(width 0.2)
			(type default)
		)
		(layer "In1.Cu")
	)
	(gr_line
		(start 363.601254 -18.35023)
		(end 363.601254 -19.750024)
		(stroke
			(width 0.2)
			(type default)
		)
		(layer "In1.Cu")
	)
	(gr_line
		(start 364.698534 -23.35022)
		(end 364.698534 -21.950426)
		(stroke
			(width 0.2)
			(type default)
		)
		(layer "In1.Cu")
	)
	(gr_arc
		(start 364.698534 -21.950426)
		(mid 364.150021 -21.401532)
		(end 363.601254 -21.950172)
		(stroke
			(width 0.2)
			(type default)
		)
		(layer "In1.Cu")
	)
	(gr_line
		(start 364.698534 -19.750024)
		(end 364.698534 -18.350484)
		(stroke
			(width 0.2)
			(type default)
		)
		(layer "In1.Cu")
	)
	(gr_arc
		(start 364.698534 -18.350484)
		(mid 364.150021 -17.80159)
		(end 363.601254 -18.35023)
		(stroke
			(width 0.2)
			(type default)
		)
		(layer "In1.Cu")
	)
	(gr_arc
		(start 365.401352 -22.350222)
		(mid 365.949992 -22.898862)
		(end 366.498632 -22.350222)
		(stroke
			(width 0.2)
			(type default)
		)
		(layer "In1.Cu")
	)
	(gr_line
		(start 365.401352 -20.950174)
		(end 365.401352 -22.350222)
		(stroke
			(width 0.2)
			(type default)
		)
		(layer "In1.Cu")
	)
	(gr_arc
		(start 365.401352 -18.750026)
		(mid 365.949992 -19.298666)
		(end 366.498632 -18.750026)
		(stroke
			(width 0.2)
			(type default)
		)
		(layer "In1.Cu")
	)
	(gr_line
		(start 365.401352 -17.349978)
		(end 365.401352 -18.750026)
		(stroke
			(width 0.2)
			(type default)
		)
		(layer "In1.Cu")
	)
	(gr_line
		(start 366.498632 -22.350222)
		(end 366.498632 -20.950428)
		(stroke
			(width 0.2)
			(type default)
		)
		(layer "In1.Cu")
	)
	(gr_arc
		(start 366.498632 -20.950428)
		(mid 365.950119 -20.401534)
		(end 365.401352 -20.950174)
		(stroke
			(width 0.2)
			(type default)
		)
		(layer "In1.Cu")
	)
	(gr_line
		(start 366.498632 -18.750026)
		(end 366.498632 -17.350232)
		(stroke
			(width 0.2)
			(type default)
		)
		(layer "In1.Cu")
	)
	(gr_arc
		(start 366.498632 -17.350232)
		(mid 365.950119 -16.801338)
		(end 365.401352 -17.349978)
		(stroke
			(width 0.2)
			(type default)
		)
		(layer "In1.Cu")
	)
	(gr_arc
		(start 367.19891 -30.54985)
		(mid 367.749963 -31.101284)
		(end 368.30127 -30.550104)
		(stroke
			(width 0.2)
			(type default)
		)
		(layer "In1.Cu")
	)
	(gr_line
		(start 367.19891 -29.150056)
		(end 367.19891 -30.54985)
		(stroke
			(width 0.2)
			(type default)
		)
		(layer "In1.Cu")
	)
	(gr_arc
		(start 367.20145 -23.35022)
		(mid 367.75009 -23.89886)
		(end 368.29873 -23.35022)
		(stroke
			(width 0.2)
			(type default)
		)
		(layer "In1.Cu")
	)
	(gr_line
		(start 367.20145 -21.950172)
		(end 367.20145 -23.35022)
		(stroke
			(width 0.2)
			(type default)
		)
		(layer "In1.Cu")
	)
	(gr_arc
		(start 367.20145 -19.750024)
		(mid 367.75009 -20.298664)
		(end 368.29873 -19.750024)
		(stroke
			(width 0.2)
			(type default)
		)
		(layer "In1.Cu")
	)
	(gr_line
		(start 367.20145 -18.35023)
		(end 367.20145 -19.750024)
		(stroke
			(width 0.2)
			(type default)
		)
		(layer "In1.Cu")
	)
	(gr_line
		(start 368.29873 -23.35022)
		(end 368.29873 -21.950426)
		(stroke
			(width 0.2)
			(type default)
		)
		(layer "In1.Cu")
	)
	(gr_arc
		(start 368.29873 -21.950426)
		(mid 367.750217 -21.401532)
		(end 367.20145 -21.950172)
		(stroke
			(width 0.2)
			(type default)
		)
		(layer "In1.Cu")
	)
	(gr_line
		(start 368.29873 -19.750024)
		(end 368.29873 -18.350484)
		(stroke
			(width 0.2)
			(type default)
		)
		(layer "In1.Cu")
	)
	(gr_arc
		(start 368.29873 -18.350484)
		(mid 367.750217 -17.80159)
		(end 367.20145 -18.35023)
		(stroke
			(width 0.2)
			(type default)
		)
		(layer "In1.Cu")
	)
	(gr_line
		(start 368.30127 -30.550104)
		(end 368.30127 -29.150056)
		(stroke
			(width 0.2)
			(type default)
		)
		(layer "In1.Cu")
	)
	(gr_arc
		(start 368.30127 -29.150056)
		(mid 367.75009 -28.598876)
		(end 367.19891 -29.150056)
		(stroke
			(width 0.2)
			(type default)
		)
		(layer "In1.Cu")
	)
	(gr_line
		(start 372.0084 -129.439416)
		(end 359.180384 -129.439416)
		(stroke
			(width 0.381)
			(type default)
		)
		(layer "In1.Cu")
	)
	(gr_line
		(start 373.912384 -131.3434)
		(end 372.0084 -129.439416)
		(stroke
			(width 0.381)
			(type default)
		)
		(layer "In1.Cu")
	)
	(gr_line
		(start 375.8946 -151.6126)
		(end 385.8514 -141.6558)
		(stroke
			(width 0.381)
			(type default)
		)
		(layer "In1.Cu")
	)
	(gr_arc
		(start 376.201432 -22.350222)
		(mid 376.750072 -22.898862)
		(end 377.298712 -22.350222)
		(stroke
			(width 0.2)
			(type default)
		)
		(layer "In1.Cu")
	)
	(gr_line
		(start 376.201432 -20.950174)
		(end 376.201432 -22.350222)
		(stroke
			(width 0.2)
			(type default)
		)
		(layer "In1.Cu")
	)
	(gr_arc
		(start 376.201432 -18.750026)
		(mid 376.750072 -19.298666)
		(end 377.298712 -18.750026)
		(stroke
			(width 0.2)
			(type default)
		)
		(layer "In1.Cu")
	)
	(gr_line
		(start 376.201432 -17.349978)
		(end 376.201432 -18.750026)
		(stroke
			(width 0.2)
			(type default)
		)
		(layer "In1.Cu")
	)
	(gr_line
		(start 377.298712 -22.350222)
		(end 377.298712 -20.950428)
		(stroke
			(width 0.2)
			(type default)
		)
		(layer "In1.Cu")
	)
	(gr_arc
		(start 377.298712 -20.950428)
		(mid 376.750199 -20.401534)
		(end 376.201432 -20.950174)
		(stroke
			(width 0.2)
			(type default)
		)
		(layer "In1.Cu")
	)
	(gr_line
		(start 377.298712 -18.750026)
		(end 377.298712 -17.350232)
		(stroke
			(width 0.2)
			(type default)
		)
		(layer "In1.Cu")
	)
	(gr_arc
		(start 377.298712 -17.350232)
		(mid 376.750199 -16.801338)
		(end 376.201432 -17.349978)
		(stroke
			(width 0.2)
			(type default)
		)
		(layer "In1.Cu")
	)
	(gr_arc
		(start 378.001276 -23.35022)
		(mid 378.549916 -23.89886)
		(end 379.098556 -23.35022)
		(stroke
			(width 0.2)
			(type default)
		)
		(layer "In1.Cu")
	)
	(gr_line
		(start 378.001276 -21.950172)
		(end 378.001276 -23.35022)
		(stroke
			(width 0.2)
			(type default)
		)
		(layer "In1.Cu")
	)
	(gr_arc
		(start 378.001276 -19.750024)
		(mid 378.549916 -20.298664)
		(end 379.098556 -19.750024)
		(stroke
			(width 0.2)
			(type default)
		)
		(layer "In1.Cu")
	)
	(gr_line
		(start 378.001276 -18.35023)
		(end 378.001276 -19.750024)
		(stroke
			(width 0.2)
			(type default)
		)
		(layer "In1.Cu")
	)
	(gr_line
		(start 379.098556 -23.35022)
		(end 379.098556 -21.950426)
		(stroke
			(width 0.2)
			(type default)
		)
		(layer "In1.Cu")
	)
	(gr_arc
		(start 379.098556 -21.950426)
		(mid 378.550043 -21.401532)
		(end 378.001276 -21.950172)
		(stroke
			(width 0.2)
			(type default)
		)
		(layer "In1.Cu")
	)
	(gr_line
		(start 379.098556 -19.750024)
		(end 379.098556 -18.350484)
		(stroke
			(width 0.2)
			(type default)
		)
		(layer "In1.Cu")
	)
	(gr_arc
		(start 379.098556 -18.350484)
		(mid 378.550043 -17.80159)
		(end 378.001276 -18.35023)
		(stroke
			(width 0.2)
			(type default)
		)
		(layer "In1.Cu")
	)
	(gr_arc
		(start 379.801374 -22.350222)
		(mid 380.350014 -22.898862)
		(end 380.898654 -22.350222)
		(stroke
			(width 0.2)
			(type default)
		)
		(layer "In1.Cu")
	)
	(gr_line
		(start 379.801374 -20.950174)
		(end 379.801374 -22.350222)
		(stroke
			(width 0.2)
			(type default)
		)
		(layer "In1.Cu")
	)
	(gr_arc
		(start 379.801374 -18.750026)
		(mid 380.350014 -19.298666)
		(end 380.898654 -18.750026)
		(stroke
			(width 0.2)
			(type default)
		)
		(layer "In1.Cu")
	)
	(gr_line
		(start 379.801374 -17.349978)
		(end 379.801374 -18.750026)
		(stroke
			(width 0.2)
			(type default)
		)
		(layer "In1.Cu")
	)
	(gr_line
		(start 380.898654 -22.350222)
		(end 380.898654 -20.950428)
		(stroke
			(width 0.2)
			(type default)
		)
		(layer "In1.Cu")
	)
	(gr_arc
		(start 380.898654 -20.950428)
		(mid 380.350141 -20.401534)
		(end 379.801374 -20.950174)
		(stroke
			(width 0.2)
			(type default)
		)
		(layer "In1.Cu")
	)
	(gr_line
		(start 380.898654 -18.750026)
		(end 380.898654 -17.350232)
		(stroke
			(width 0.2)
			(type default)
		)
		(layer "In1.Cu")
	)
	(gr_arc
		(start 380.898654 -17.350232)
		(mid 380.350141 -16.801338)
		(end 379.801374 -17.349978)
		(stroke
			(width 0.2)
			(type default)
		)
		(layer "In1.Cu")
	)
	(gr_line
		(start 381.1016 -131.3434)
		(end 373.912384 -131.3434)
		(stroke
			(width 0.381)
			(type default)
		)
		(layer "In1.Cu")
	)
	(gr_arc
		(start 381.598932 -30.550104)
		(mid 382.150112 -31.101284)
		(end 382.701292 -30.550104)
		(stroke
			(width 0.2)
			(type default)
		)
		(layer "In1.Cu")
	)
	(gr_line
		(start 381.598932 -29.150056)
		(end 381.598932 -30.550104)
		(stroke
			(width 0.2)
			(type default)
		)
		(layer "In1.Cu")
	)
	(gr_arc
		(start 381.601472 -23.35022)
		(mid 382.150112 -23.89886)
		(end 382.698752 -23.35022)
		(stroke
			(width 0.2)
			(type default)
		)
		(layer "In1.Cu")
	)
	(gr_line
		(start 381.601472 -21.950172)
		(end 381.601472 -23.35022)
		(stroke
			(width 0.2)
			(type default)
		)
		(layer "In1.Cu")
	)
	(gr_arc
		(start 381.601472 -19.750024)
		(mid 382.150112 -20.298664)
		(end 382.698752 -19.750024)
		(stroke
			(width 0.2)
			(type default)
		)
		(layer "In1.Cu")
	)
	(gr_line
		(start 381.601472 -18.35023)
		(end 381.601472 -19.750024)
		(stroke
			(width 0.2)
			(type default)
		)
		(layer "In1.Cu")
	)
	(gr_line
		(start 382.698752 -23.35022)
		(end 382.698752 -21.950426)
		(stroke
			(width 0.2)
			(type default)
		)
		(layer "In1.Cu")
	)
	(gr_arc
		(start 382.698752 -21.950426)
		(mid 382.150239 -21.401532)
		(end 381.601472 -21.950172)
		(stroke
			(width 0.2)
			(type default)
		)
		(layer "In1.Cu")
	)
	(gr_line
		(start 382.698752 -19.750024)
		(end 382.698752 -18.350484)
		(stroke
			(width 0.2)
			(type default)
		)
		(layer "In1.Cu")
	)
	(gr_arc
		(start 382.698752 -18.350484)
		(mid 382.150239 -17.80159)
		(end 381.601472 -18.35023)
		(stroke
			(width 0.2)
			(type default)
		)
		(layer "In1.Cu")
	)
	(gr_line
		(start 382.701292 -30.550104)
		(end 382.701292 -29.15031)
		(stroke
			(width 0.2)
			(type default)
		)
		(layer "In1.Cu")
	)
	(gr_arc
		(start 382.701292 -29.15031)
		(mid 382.150239 -28.598876)
		(end 381.598932 -29.150056)
		(stroke
			(width 0.2)
			(type default)
		)
		(layer "In1.Cu")
	)
	(gr_arc
		(start 382.70815 -274.511262)
		(mid 383.089023 -274.892516)
		(end 383.47015 -274.511516)
		(stroke
			(width 0.2)
			(type default)
		)
		(layer "In1.Cu")
	)
	(gr_line
		(start 382.70815 -273.368516)
		(end 382.70815 -274.511262)
		(stroke
			(width 0.2)
			(type default)
		)
		(layer "In1.Cu")
	)
	(gr_arc
		(start 382.70815 -159.511238)
		(mid 383.089023 -159.892492)
		(end 383.47015 -159.511492)
		(stroke
			(width 0.2)
			(type default)
		)
		(layer "In1.Cu")
	)
	(gr_line
		(start 382.70815 -158.368492)
		(end 382.70815 -159.511238)
		(stroke
			(width 0.2)
			(type default)
		)
		(layer "In1.Cu")
	)
	(gr_line
		(start 382.7653 -46.5328)
		(end 383.908046 -46.5328)
		(stroke
			(width 0.2)
			(type default)
		)
		(layer "In1.Cu")
	)
	(gr_arc
		(start 382.7653 -45.7708)
		(mid 382.3843 -46.1518)
		(end 382.7653 -46.5328)
		(stroke
			(width 0.2)
			(type default)
		)
		(layer "In1.Cu")
	)
	(gr_arc
		(start 383.401316 -22.350222)
		(mid 383.949956 -22.898862)
		(end 384.498596 -22.350222)
		(stroke
			(width 0.2)
			(type default)
		)
		(layer "In1.Cu")
	)
	(gr_line
		(start 383.401316 -20.950174)
		(end 383.401316 -22.350222)
		(stroke
			(width 0.2)
			(type default)
		)
		(layer "In1.Cu")
	)
	(gr_arc
		(start 383.401316 -18.750026)
		(mid 383.949956 -19.298666)
		(end 384.498596 -18.750026)
		(stroke
			(width 0.2)
			(type default)
		)
		(layer "In1.Cu")
	)
	(gr_line
		(start 383.401316 -17.349978)
		(end 383.401316 -18.750026)
		(stroke
			(width 0.2)
			(type default)
		)
		(layer "In1.Cu")
	)
	(gr_line
		(start 383.47015 -274.511516)
		(end 383.47015 -273.368516)
		(stroke
			(width 0.2)
			(type default)
		)
		(layer "In1.Cu")
	)
	(gr_arc
		(start 383.47015 -273.368516)
		(mid 383.08915 -272.987516)
		(end 382.70815 -273.368516)
		(stroke
			(width 0.2)
			(type default)
		)
		(layer "In1.Cu")
	)
	(gr_line
		(start 383.47015 -159.511492)
		(end 383.47015 -158.368492)
		(stroke
			(width 0.2)
			(type default)
		)
		(layer "In1.Cu")
	)
	(gr_arc
		(start 383.47015 -158.368492)
		(mid 383.08915 -157.987492)
		(end 382.70815 -158.368492)
		(stroke
			(width 0.2)
			(type default)
		)
		(layer "In1.Cu")
	)
	(gr_arc
		(start 383.908046 -46.5328)
		(mid 384.2893 -46.151927)
		(end 383.9083 -45.7708)
		(stroke
			(width 0.2)
			(type default)
		)
		(layer "In1.Cu")
	)
	(gr_line
		(start 383.9083 -45.7708)
		(end 382.7653 -45.7708)
		(stroke
			(width 0.2)
			(type default)
		)
		(layer "In1.Cu")
	)
	(gr_arc
		(start 384.277362 -274.321016)
		(mid 384.292241 -274.356937)
		(end 384.328162 -274.371816)
		(stroke
			(width 0.2)
			(type default)
		)
		(layer "In1.Cu")
	)
	(gr_line
		(start 384.277362 -274.117816)
		(end 384.277362 -274.321016)
		(stroke
			(width 0.2)
			(type default)
		)
		(layer "In1.Cu")
	)
	(gr_arc
		(start 384.277362 -273.762216)
		(mid 384.292241 -273.798137)
		(end 384.328162 -273.813016)
		(stroke
			(width 0.2)
			(type default)
		)
		(layer "In1.Cu")
	)
	(gr_line
		(start 384.277362 -273.559016)
		(end 384.277362 -273.762216)
		(stroke
			(width 0.2)
			(type default)
		)
		(layer "In1.Cu")
	)
	(gr_arc
		(start 384.277362 -159.320992)
		(mid 384.292241 -159.356913)
		(end 384.328162 -159.371792)
		(stroke
			(width 0.2)
			(type default)
		)
		(layer "In1.Cu")
	)
	(gr_line
		(start 384.277362 -159.117792)
		(end 384.277362 -159.320992)
		(stroke
			(width 0.2)
			(type default)
		)
		(layer "In1.Cu")
	)
	(gr_arc
		(start 384.277362 -158.762192)
		(mid 384.292241 -158.798113)
		(end 384.328162 -158.812992)
		(stroke
			(width 0.2)
			(type default)
		)
		(layer "In1.Cu")
	)
	(gr_line
		(start 384.277362 -158.558992)
		(end 384.277362 -158.762192)
		(stroke
			(width 0.2)
			(type default)
		)
		(layer "In1.Cu")
	)
	(gr_arc
		(start 384.277362 -44.320968)
		(mid 384.292241 -44.356889)
		(end 384.328162 -44.371768)
		(stroke
			(width 0.2)
			(type default)
		)
		(layer "In1.Cu")
	)
	(gr_line
		(start 384.277362 -44.117768)
		(end 384.277362 -44.320968)
		(stroke
			(width 0.2)
			(type default)
		)
		(layer "In1.Cu")
	)
	(gr_arc
		(start 384.277362 -43.762168)
		(mid 384.292241 -43.798089)
		(end 384.328162 -43.812968)
		(stroke
			(width 0.2)
			(type default)
		)
		(layer "In1.Cu")
	)
	(gr_line
		(start 384.277362 -43.558968)
		(end 384.277362 -43.762168)
		(stroke
			(width 0.2)
			(type default)
		)
		(layer "In1.Cu")
	)
	(gr_line
		(start 384.328162 -274.371816)
		(end 385.140962 -274.371816)
		(stroke
			(width 0.2)
			(type default)
		)
		(layer "In1.Cu")
	)
	(gr_arc
		(start 384.328162 -274.067016)
		(mid 384.292241 -274.081895)
		(end 384.277362 -274.117816)
		(stroke
			(width 0.2)
			(type default)
		)
		(layer "In1.Cu")
	)
	(gr_line
		(start 384.328162 -273.813016)
		(end 385.140962 -273.813016)
		(stroke
			(width 0.2)
			(type default)
		)
		(layer "In1.Cu")
	)
	(gr_arc
		(start 384.328162 -273.508216)
		(mid 384.292241 -273.523095)
		(end 384.277362 -273.559016)
		(stroke
			(width 0.2)
			(type default)
		)
		(layer "In1.Cu")
	)
	(gr_line
		(start 384.328162 -159.371792)
		(end 385.140962 -159.371792)
		(stroke
			(width 0.2)
			(type default)
		)
		(layer "In1.Cu")
	)
	(gr_arc
		(start 384.328162 -159.066992)
		(mid 384.292241 -159.081871)
		(end 384.277362 -159.117792)
		(stroke
			(width 0.2)
			(type default)
		)
		(layer "In1.Cu")
	)
	(gr_line
		(start 384.328162 -158.812992)
		(end 385.140962 -158.812992)
		(stroke
			(width 0.2)
			(type default)
		)
		(layer "In1.Cu")
	)
	(gr_arc
		(start 384.328162 -158.508192)
		(mid 384.292241 -158.523071)
		(end 384.277362 -158.558992)
		(stroke
			(width 0.2)
			(type default)
		)
		(layer "In1.Cu")
	)
	(gr_line
		(start 384.328162 -44.371768)
		(end 385.140962 -44.371768)
		(stroke
			(width 0.2)
			(type default)
		)
		(layer "In1.Cu")
	)
	(gr_arc
		(start 384.328162 -44.066968)
		(mid 384.292241 -44.081847)
		(end 384.277362 -44.117768)
		(stroke
			(width 0.2)
			(type default)
		)
		(layer "In1.Cu")
	)
	(gr_line
		(start 384.328162 -43.812968)
		(end 385.140962 -43.812968)
		(stroke
			(width 0.2)
			(type default)
		)
		(layer "In1.Cu")
	)
	(gr_arc
		(start 384.328162 -43.508168)
		(mid 384.292241 -43.523047)
		(end 384.277362 -43.558968)
		(stroke
			(width 0.2)
			(type default)
		)
		(layer "In1.Cu")
	)
	(gr_line
		(start 384.498596 -22.350222)
		(end 384.498596 -20.950428)
		(stroke
			(width 0.2)
			(type default)
		)
		(layer "In1.Cu")
	)
	(gr_arc
		(start 384.498596 -20.950428)
		(mid 383.950083 -20.401534)
		(end 383.401316 -20.950174)
		(stroke
			(width 0.2)
			(type default)
		)
		(layer "In1.Cu")
	)
	(gr_line
		(start 384.498596 -18.750026)
		(end 384.498596 -17.350232)
		(stroke
			(width 0.2)
			(type default)
		)
		(layer "In1.Cu")
	)
	(gr_arc
		(start 384.498596 -17.350232)
		(mid 383.950083 -16.801338)
		(end 383.401316 -17.349978)
		(stroke
			(width 0.2)
			(type default)
		)
		(layer "In1.Cu")
	)
	(gr_arc
		(start 385.140962 -274.371816)
		(mid 385.176883 -274.356937)
		(end 385.191762 -274.321016)
		(stroke
			(width 0.2)
			(type default)
		)
		(layer "In1.Cu")
	)
	(gr_line
		(start 385.140962 -274.067016)
		(end 384.328162 -274.067016)
		(stroke
			(width 0.2)
			(type default)
		)
		(layer "In1.Cu")
	)
	(gr_arc
		(start 385.140962 -273.813016)
		(mid 385.176883 -273.798137)
		(end 385.191762 -273.762216)
		(stroke
			(width 0.2)
			(type default)
		)
		(layer "In1.Cu")
	)
	(gr_line
		(start 385.140962 -273.508216)
		(end 384.328162 -273.508216)
		(stroke
			(width 0.2)
			(type default)
		)
		(layer "In1.Cu")
	)
	(gr_arc
		(start 385.140962 -159.371792)
		(mid 385.176883 -159.356913)
		(end 385.191762 -159.320992)
		(stroke
			(width 0.2)
			(type default)
		)
		(layer "In1.Cu")
	)
	(gr_line
		(start 385.140962 -159.066992)
		(end 384.328162 -159.066992)
		(stroke
			(width 0.2)
			(type default)
		)
		(layer "In1.Cu")
	)
	(gr_arc
		(start 385.140962 -158.812992)
		(mid 385.176883 -158.798113)
		(end 385.191762 -158.762192)
		(stroke
			(width 0.2)
			(type default)
		)
		(layer "In1.Cu")
	)
	(gr_line
		(start 385.140962 -158.508192)
		(end 384.328162 -158.508192)
		(stroke
			(width 0.2)
			(type default)
		)
		(layer "In1.Cu")
	)
	(gr_arc
		(start 385.140962 -44.371768)
		(mid 385.176883 -44.356889)
		(end 385.191762 -44.320968)
		(stroke
			(width 0.2)
			(type default)
		)
		(layer "In1.Cu")
	)
	(gr_line
		(start 385.140962 -44.066968)
		(end 384.328162 -44.066968)
		(stroke
			(width 0.2)
			(type default)
		)
		(layer "In1.Cu")
	)
	(gr_arc
		(start 385.140962 -43.812968)
		(mid 385.176883 -43.798089)
		(end 385.191762 -43.762168)
		(stroke
			(width 0.2)
			(type default)
		)
		(layer "In1.Cu")
	)
	(gr_line
		(start 385.140962 -43.508168)
		(end 384.328162 -43.508168)
		(stroke
			(width 0.2)
			(type default)
		)
		(layer "In1.Cu")
	)
	(gr_line
		(start 385.191762 -274.321016)
		(end 385.191762 -274.117816)
		(stroke
			(width 0.2)
			(type default)
		)
		(layer "In1.Cu")
	)
	(gr_arc
		(start 385.191762 -274.117816)
		(mid 385.176883 -274.081895)
		(end 385.140962 -274.067016)
		(stroke
			(width 0.2)
			(type default)
		)
		(layer "In1.Cu")
	)
	(gr_line
		(start 385.191762 -273.762216)
		(end 385.191762 -273.559016)
		(stroke
			(width 0.2)
			(type default)
		)
		(layer "In1.Cu")
	)
	(gr_arc
		(start 385.191762 -273.559016)
		(mid 385.176883 -273.523095)
		(end 385.140962 -273.508216)
		(stroke
			(width 0.2)
			(type default)
		)
		(layer "In1.Cu")
	)
	(gr_line
		(start 385.191762 -159.320992)
		(end 385.191762 -159.117792)
		(stroke
			(width 0.2)
			(type default)
		)
		(layer "In1.Cu")
	)
	(gr_arc
		(start 385.191762 -159.117792)
		(mid 385.176883 -159.081871)
		(end 385.140962 -159.066992)
		(stroke
			(width 0.2)
			(type default)
		)
		(layer "In1.Cu")
	)
	(gr_line
		(start 385.191762 -158.762192)
		(end 385.191762 -158.558992)
		(stroke
			(width 0.2)
			(type default)
		)
		(layer "In1.Cu")
	)
	(gr_arc
		(start 385.191762 -158.558992)
		(mid 385.176883 -158.523071)
		(end 385.140962 -158.508192)
		(stroke
			(width 0.2)
			(type default)
		)
		(layer "In1.Cu")
	)
	(gr_line
		(start 385.191762 -44.320968)
		(end 385.191762 -44.117768)
		(stroke
			(width 0.2)
			(type default)
		)
		(layer "In1.Cu")
	)
	(gr_arc
		(start 385.191762 -44.117768)
		(mid 385.176883 -44.081847)
		(end 385.140962 -44.066968)
		(stroke
			(width 0.2)
			(type default)
		)
		(layer "In1.Cu")
	)
	(gr_line
		(start 385.191762 -43.762168)
		(end 385.191762 -43.558968)
		(stroke
			(width 0.2)
			(type default)
		)
		(layer "In1.Cu")
	)
	(gr_arc
		(start 385.191762 -43.558968)
		(mid 385.176883 -43.523047)
		(end 385.140962 -43.508168)
		(stroke
			(width 0.2)
			(type default)
		)
		(layer "In1.Cu")
	)
	(gr_arc
		(start 385.201414 -23.35022)
		(mid 385.750054 -23.89886)
		(end 386.298694 -23.35022)
		(stroke
			(width 0.2)
			(type default)
		)
		(layer "In1.Cu")
	)
	(gr_line
		(start 385.201414 -21.950172)
		(end 385.201414 -23.35022)
		(stroke
			(width 0.2)
			(type default)
		)
		(layer "In1.Cu")
	)
	(gr_arc
		(start 385.201414 -19.750024)
		(mid 385.750054 -20.298664)
		(end 386.298694 -19.750024)
		(stroke
			(width 0.2)
			(type default)
		)
		(layer "In1.Cu")
	)
	(gr_line
		(start 385.201414 -18.35023)
		(end 385.201414 -19.750024)
		(stroke
			(width 0.2)
			(type default)
		)
		(layer "In1.Cu")
	)
	(gr_line
		(start 385.8514 -141.6558)
		(end 385.8514 -136.0932)
		(stroke
			(width 0.381)
			(type default)
		)
		(layer "In1.Cu")
	)
	(gr_line
		(start 385.8514 -136.0932)
		(end 381.1016 -131.3434)
		(stroke
			(width 0.381)
			(type default)
		)
		(layer "In1.Cu")
	)
	(gr_line
		(start 386.298694 -23.35022)
		(end 386.298694 -21.950426)
		(stroke
			(width 0.2)
			(type default)
		)
		(layer "In1.Cu")
	)
	(gr_arc
		(start 386.298694 -21.950426)
		(mid 385.750181 -21.401532)
		(end 385.201414 -21.950172)
		(stroke
			(width 0.2)
			(type default)
		)
		(layer "In1.Cu")
	)
	(gr_line
		(start 386.298694 -19.750024)
		(end 386.298694 -18.350484)
		(stroke
			(width 0.2)
			(type default)
		)
		(layer "In1.Cu")
	)
	(gr_arc
		(start 386.298694 -18.350484)
		(mid 385.750181 -17.80159)
		(end 385.201414 -18.35023)
		(stroke
			(width 0.2)
			(type default)
		)
		(layer "In1.Cu")
	)
	(gr_arc
		(start 387.001258 -22.350222)
		(mid 387.549898 -22.898862)
		(end 388.098538 -22.350222)
		(stroke
			(width 0.2)
			(type default)
		)
		(layer "In1.Cu")
	)
	(gr_line
		(start 387.001258 -20.950174)
		(end 387.001258 -22.350222)
		(stroke
			(width 0.2)
			(type default)
		)
		(layer "In1.Cu")
	)
	(gr_arc
		(start 387.001258 -18.750026)
		(mid 387.549898 -19.298666)
		(end 388.098538 -18.750026)
		(stroke
			(width 0.2)
			(type default)
		)
		(layer "In1.Cu")
	)
	(gr_line
		(start 387.001258 -17.349978)
		(end 387.001258 -18.750026)
		(stroke
			(width 0.2)
			(type default)
		)
		(layer "In1.Cu")
	)
	(gr_arc
		(start 387.45795 -278.321516)
		(mid 387.83895 -278.702516)
		(end 388.21995 -278.321516)
		(stroke
			(width 0.2)
			(type default)
		)
		(layer "In1.Cu")
	)
	(gr_line
		(start 387.45795 -277.178516)
		(end 387.45795 -278.321516)
		(stroke
			(width 0.2)
			(type default)
		)
		(layer "In1.Cu")
	)
	(gr_arc
		(start 387.45795 -163.321492)
		(mid 387.83895 -163.702492)
		(end 388.21995 -163.321492)
		(stroke
			(width 0.2)
			(type default)
		)
		(layer "In1.Cu")
	)
	(gr_line
		(start 387.45795 -162.178492)
		(end 387.45795 -163.321492)
		(stroke
			(width 0.2)
			(type default)
		)
		(layer "In1.Cu")
	)
	(gr_arc
		(start 387.45795 -48.321468)
		(mid 387.83895 -48.702468)
		(end 388.21995 -48.321468)
		(stroke
			(width 0.2)
			(type default)
		)
		(layer "In1.Cu")
	)
	(gr_line
		(start 387.45795 -47.178468)
		(end 387.45795 -48.321468)
		(stroke
			(width 0.2)
			(type default)
		)
		(layer "In1.Cu")
	)
	(gr_line
		(start 388.098538 -22.350222)
		(end 388.098538 -20.950428)
		(stroke
			(width 0.2)
			(type default)
		)
		(layer "In1.Cu")
	)
	(gr_arc
		(start 388.098538 -20.950428)
		(mid 387.550025 -20.401534)
		(end 387.001258 -20.950174)
		(stroke
			(width 0.2)
			(type default)
		)
		(layer "In1.Cu")
	)
	(gr_line
		(start 388.098538 -18.750026)
		(end 388.098538 -17.350232)
		(stroke
			(width 0.2)
			(type default)
		)
		(layer "In1.Cu")
	)
	(gr_arc
		(start 388.098538 -17.350232)
		(mid 387.550025 -16.801338)
		(end 387.001258 -17.349978)
		(stroke
			(width 0.2)
			(type default)
		)
		(layer "In1.Cu")
	)
	(gr_line
		(start 388.21995 -278.321516)
		(end 388.21995 -277.17877)
		(stroke
			(width 0.2)
			(type default)
		)
		(layer "In1.Cu")
	)
	(gr_arc
		(start 388.21995 -277.17877)
		(mid 387.839077 -276.797516)
		(end 387.45795 -277.178516)
		(stroke
			(width 0.2)
			(type default)
		)
		(layer "In1.Cu")
	)
	(gr_line
		(start 388.21995 -163.321492)
		(end 388.21995 -162.178746)
		(stroke
			(width 0.2)
			(type default)
		)
		(layer "In1.Cu")
	)
	(gr_arc
		(start 388.21995 -162.178746)
		(mid 387.839077 -161.797492)
		(end 387.45795 -162.178492)
		(stroke
			(width 0.2)
			(type default)
		)
		(layer "In1.Cu")
	)
	(gr_line
		(start 388.21995 -48.321468)
		(end 388.21995 -47.178722)
		(stroke
			(width 0.2)
			(type default)
		)
		(layer "In1.Cu")
	)
	(gr_arc
		(start 388.21995 -47.178722)
		(mid 387.839077 -46.797468)
		(end 387.45795 -47.178468)
		(stroke
			(width 0.2)
			(type default)
		)
		(layer "In1.Cu")
	)
	(gr_arc
		(start 388.801356 -30.550104)
		(mid 389.349996 -31.098744)
		(end 389.898636 -30.550104)
		(stroke
			(width 0.2)
			(type default)
		)
		(layer "In1.Cu")
	)
	(gr_line
		(start 388.801356 -29.150056)
		(end 388.801356 -30.550104)
		(stroke
			(width 0.2)
			(type default)
		)
		(layer "In1.Cu")
	)
	(gr_arc
		(start 388.801356 -23.35022)
		(mid 389.349996 -23.89886)
		(end 389.898636 -23.35022)
		(stroke
			(width 0.2)
			(type default)
		)
		(layer "In1.Cu")
	)
	(gr_line
		(start 388.801356 -21.950172)
		(end 388.801356 -23.35022)
		(stroke
			(width 0.2)
			(type default)
		)
		(layer "In1.Cu")
	)
	(gr_arc
		(start 388.801356 -19.750024)
		(mid 389.349996 -20.298664)
		(end 389.898636 -19.750024)
		(stroke
			(width 0.2)
			(type default)
		)
		(layer "In1.Cu")
	)
	(gr_line
		(start 388.801356 -18.35023)
		(end 388.801356 -19.750024)
		(stroke
			(width 0.2)
			(type default)
		)
		(layer "In1.Cu")
	)
	(gr_line
		(start 389.293862 -279.350216)
		(end 389.293862 -276.149816)
		(stroke
			(width 0.2)
			(type default)
		)
		(layer "In1.Cu")
	)
	(gr_rect
		(start 389.293862 -276.810216)
		(end 391.656062 -278.689816)
		(stroke
			(width 0)
			(type default)
		)
		(fill no)
		(layer "In1.Cu")
	)
	(gr_line
		(start 389.293862 -276.149816)
		(end 391.656062 -276.149816)
		(stroke
			(width 0.2)
			(type default)
		)
		(layer "In1.Cu")
	)
	(gr_line
		(start 389.293862 -275.540216)
		(end 389.293862 -272.339816)
		(stroke
			(width 0.2)
			(type default)
		)
		(layer "In1.Cu")
	)
	(gr_rect
		(start 389.293862 -273.000216)
		(end 391.656062 -274.879816)
		(stroke
			(width 0)
			(type default)
		)
		(fill no)
		(layer "In1.Cu")
	)
	(gr_line
		(start 389.293862 -272.339816)
		(end 391.656062 -272.340578)
		(stroke
			(width 0.2)
			(type default)
		)
		(layer "In1.Cu")
	)
	(gr_line
		(start 389.293862 -164.350192)
		(end 389.293862 -161.149792)
		(stroke
			(width 0.2)
			(type default)
		)
		(layer "In1.Cu")
	)
	(gr_rect
		(start 389.293862 -161.810192)
		(end 391.656062 -163.689792)
		(stroke
			(width 0)
			(type default)
		)
		(fill no)
		(layer "In1.Cu")
	)
	(gr_line
		(start 389.293862 -161.149792)
		(end 391.656062 -161.149792)
		(stroke
			(width 0.2)
			(type default)
		)
		(layer "In1.Cu")
	)
	(gr_line
		(start 389.293862 -160.540192)
		(end 389.293862 -157.339792)
		(stroke
			(width 0.2)
			(type default)
		)
		(layer "In1.Cu")
	)
	(gr_rect
		(start 389.293862 -158.000192)
		(end 391.656062 -159.879792)
		(stroke
			(width 0)
			(type default)
		)
		(fill no)
		(layer "In1.Cu")
	)
	(gr_line
		(start 389.293862 -157.339792)
		(end 391.656062 -157.340554)
		(stroke
			(width 0.2)
			(type default)
		)
		(layer "In1.Cu")
	)
	(gr_line
		(start 389.293862 -49.350168)
		(end 389.293862 -46.149768)
		(stroke
			(width 0.2)
			(type default)
		)
		(layer "In1.Cu")
	)
	(gr_rect
		(start 389.293862 -46.810168)
		(end 391.656062 -48.689768)
		(stroke
			(width 0)
			(type default)
		)
		(fill no)
		(layer "In1.Cu")
	)
	(gr_line
		(start 389.293862 -46.149768)
		(end 391.656062 -46.149768)
		(stroke
			(width 0.2)
			(type default)
		)
		(layer "In1.Cu")
	)
	(gr_line
		(start 389.293862 -45.540168)
		(end 389.293862 -42.339768)
		(stroke
			(width 0.2)
			(type default)
		)
		(layer "In1.Cu")
	)
	(gr_rect
		(start 389.293862 -43.000168)
		(end 391.656062 -44.879768)
		(stroke
			(width 0)
			(type default)
		)
		(fill no)
		(layer "In1.Cu")
	)
	(gr_line
		(start 389.293862 -42.339768)
		(end 391.656062 -42.34053)
		(stroke
			(width 0.2)
			(type default)
		)
		(layer "In1.Cu")
	)
	(gr_line
		(start 389.898636 -30.550104)
		(end 389.898636 -29.15031)
		(stroke
			(width 0.2)
			(type default)
		)
		(layer "In1.Cu")
	)
	(gr_arc
		(start 389.898636 -29.15031)
		(mid 389.350123 -28.601416)
		(end 388.801356 -29.150056)
		(stroke
			(width 0.2)
			(type default)
		)
		(layer "In1.Cu")
	)
	(gr_line
		(start 389.898636 -23.35022)
		(end 389.898636 -21.950426)
		(stroke
			(width 0.2)
			(type default)
		)
		(layer "In1.Cu")
	)
	(gr_arc
		(start 389.898636 -21.950426)
		(mid 389.350123 -21.401532)
		(end 388.801356 -21.950172)
		(stroke
			(width 0.2)
			(type default)
		)
		(layer "In1.Cu")
	)
	(gr_line
		(start 389.898636 -19.750024)
		(end 389.898636 -18.350484)
		(stroke
			(width 0.2)
			(type default)
		)
		(layer "In1.Cu")
	)
	(gr_arc
		(start 389.898636 -18.350484)
		(mid 389.350123 -17.80159)
		(end 388.801356 -18.35023)
		(stroke
			(width 0.2)
			(type default)
		)
		(layer "In1.Cu")
	)
	(gr_line
		(start 391.656062 -279.350216)
		(end 389.293862 -279.350216)
		(stroke
			(width 0.2)
			(type default)
		)
		(layer "In1.Cu")
	)
	(gr_line
		(start 391.656062 -276.149816)
		(end 391.656062 -279.350216)
		(stroke
			(width 0.2)
			(type default)
		)
		(layer "In1.Cu")
	)
	(gr_line
		(start 391.656062 -275.540216)
		(end 389.293862 -275.540216)
		(stroke
			(width 0.2)
			(type default)
		)
		(layer "In1.Cu")
	)
	(gr_line
		(start 391.656062 -272.340578)
		(end 391.656062 -275.540216)
		(stroke
			(width 0.2)
			(type default)
		)
		(layer "In1.Cu")
	)
	(gr_line
		(start 391.656062 -164.350192)
		(end 389.293862 -164.350192)
		(stroke
			(width 0.2)
			(type default)
		)
		(layer "In1.Cu")
	)
	(gr_line
		(start 391.656062 -161.149792)
		(end 391.656062 -164.350192)
		(stroke
			(width 0.2)
			(type default)
		)
		(layer "In1.Cu")
	)
	(gr_line
		(start 391.656062 -160.540192)
		(end 389.293862 -160.540192)
		(stroke
			(width 0.2)
			(type default)
		)
		(layer "In1.Cu")
	)
	(gr_line
		(start 391.656062 -157.340554)
		(end 391.656062 -160.540192)
		(stroke
			(width 0.2)
			(type default)
		)
		(layer "In1.Cu")
	)
	(gr_line
		(start 391.656062 -49.350168)
		(end 389.293862 -49.350168)
		(stroke
			(width 0.2)
			(type default)
		)
		(layer "In1.Cu")
	)
	(gr_line
		(start 391.656062 -46.149768)
		(end 391.656062 -49.350168)
		(stroke
			(width 0.2)
			(type default)
		)
		(layer "In1.Cu")
	)
	(gr_line
		(start 391.656062 -45.540168)
		(end 389.293862 -45.540168)
		(stroke
			(width 0.2)
			(type default)
		)
		(layer "In1.Cu")
	)
	(gr_line
		(start 391.656062 -42.34053)
		(end 391.656062 -45.540168)
		(stroke
			(width 0.2)
			(type default)
		)
		(layer "In1.Cu")
	)
	(gr_arc
		(start 394.999972 -14.99997)
		(mid 395.707077 -14.707077)
		(end 395.99997 -13.999972)
		(stroke
			(width 1.524)
			(type default)
		)
		(layer "In1.Cu")
	)
	(gr_line
		(start 395.99997 -13.999972)
		(end 395.99997 -0.999998)
		(stroke
			(width 1.524)
			(type default)
		)
		(layer "In1.Cu")
	)
	(gr_arc
		(start 396.999968 0)
		(mid 396.292883 -0.292904)
		(end 395.99997 -0.999998)
		(stroke
			(width 1.524)
			(type default)
		)
		(layer "In1.Cu")
	)
	(gr_line
		(start 396.999968 0)
		(end 490.450124 0)
		(stroke
			(width 1.524)
			(type default)
		)
		(layer "In1.Cu")
	)
	(gr_arc
		(start 414.258252 -274.511262)
		(mid 414.639125 -274.892516)
		(end 415.020252 -274.511516)
		(stroke
			(width 0.2)
			(type default)
		)
		(layer "In1.Cu")
	)
	(gr_line
		(start 414.258252 -273.368516)
		(end 414.258252 -274.511262)
		(stroke
			(width 0.2)
			(type default)
		)
		(layer "In1.Cu")
	)
	(gr_arc
		(start 414.258252 -159.511238)
		(mid 414.639125 -159.892492)
		(end 415.020252 -159.511492)
		(stroke
			(width 0.2)
			(type default)
		)
		(layer "In1.Cu")
	)
	(gr_line
		(start 414.258252 -158.368492)
		(end 414.258252 -159.511238)
		(stroke
			(width 0.2)
			(type default)
		)
		(layer "In1.Cu")
	)
	(gr_arc
		(start 414.258252 -44.511214)
		(mid 414.639125 -44.892468)
		(end 415.020252 -44.511468)
		(stroke
			(width 0.2)
			(type default)
		)
		(layer "In1.Cu")
	)
	(gr_line
		(start 414.258252 -43.368468)
		(end 414.258252 -44.511214)
		(stroke
			(width 0.2)
			(type default)
		)
		(layer "In1.Cu")
	)
	(gr_line
		(start 415.020252 -274.511516)
		(end 415.020252 -273.368516)
		(stroke
			(width 0.2)
			(type default)
		)
		(layer "In1.Cu")
	)
	(gr_arc
		(start 415.020252 -273.368516)
		(mid 414.639252 -272.987516)
		(end 414.258252 -273.368516)
		(stroke
			(width 0.2)
			(type default)
		)
		(layer "In1.Cu")
	)
	(gr_line
		(start 415.020252 -159.511492)
		(end 415.020252 -158.368492)
		(stroke
			(width 0.2)
			(type default)
		)
		(layer "In1.Cu")
	)
	(gr_arc
		(start 415.020252 -158.368492)
		(mid 414.639252 -157.987492)
		(end 414.258252 -158.368492)
		(stroke
			(width 0.2)
			(type default)
		)
		(layer "In1.Cu")
	)
	(gr_line
		(start 415.020252 -44.511468)
		(end 415.020252 -43.368468)
		(stroke
			(width 0.2)
			(type default)
		)
		(layer "In1.Cu")
	)
	(gr_arc
		(start 415.020252 -43.368468)
		(mid 414.639252 -42.987468)
		(end 414.258252 -43.368468)
		(stroke
			(width 0.2)
			(type default)
		)
		(layer "In1.Cu")
	)
	(gr_arc
		(start 415.827464 -274.321016)
		(mid 415.842343 -274.356937)
		(end 415.878264 -274.371816)
		(stroke
			(width 0.2)
			(type default)
		)
		(layer "In1.Cu")
	)
	(gr_line
		(start 415.827464 -274.117816)
		(end 415.827464 -274.321016)
		(stroke
			(width 0.2)
			(type default)
		)
		(layer "In1.Cu")
	)
	(gr_arc
		(start 415.827464 -273.762216)
		(mid 415.842343 -273.798137)
		(end 415.878264 -273.813016)
		(stroke
			(width 0.2)
			(type default)
		)
		(layer "In1.Cu")
	)
	(gr_line
		(start 415.827464 -273.559016)
		(end 415.827464 -273.762216)
		(stroke
			(width 0.2)
			(type default)
		)
		(layer "In1.Cu")
	)
	(gr_arc
		(start 415.827464 -159.320992)
		(mid 415.842343 -159.356913)
		(end 415.878264 -159.371792)
		(stroke
			(width 0.2)
			(type default)
		)
		(layer "In1.Cu")
	)
	(gr_line
		(start 415.827464 -159.117792)
		(end 415.827464 -159.320992)
		(stroke
			(width 0.2)
			(type default)
		)
		(layer "In1.Cu")
	)
	(gr_arc
		(start 415.827464 -158.762192)
		(mid 415.842343 -158.798113)
		(end 415.878264 -158.812992)
		(stroke
			(width 0.2)
			(type default)
		)
		(layer "In1.Cu")
	)
	(gr_line
		(start 415.827464 -158.558992)
		(end 415.827464 -158.762192)
		(stroke
			(width 0.2)
			(type default)
		)
		(layer "In1.Cu")
	)
	(gr_arc
		(start 415.827464 -44.320968)
		(mid 415.842343 -44.356889)
		(end 415.878264 -44.371768)
		(stroke
			(width 0.2)
			(type default)
		)
		(layer "In1.Cu")
	)
	(gr_line
		(start 415.827464 -44.117768)
		(end 415.827464 -44.320968)
		(stroke
			(width 0.2)
			(type default)
		)
		(layer "In1.Cu")
	)
	(gr_arc
		(start 415.827464 -43.762168)
		(mid 415.842343 -43.798089)
		(end 415.878264 -43.812968)
		(stroke
			(width 0.2)
			(type default)
		)
		(layer "In1.Cu")
	)
	(gr_line
		(start 415.827464 -43.558968)
		(end 415.827464 -43.762168)
		(stroke
			(width 0.2)
			(type default)
		)
		(layer "In1.Cu")
	)
	(gr_line
		(start 415.878264 -274.371816)
		(end 416.691064 -274.371816)
		(stroke
			(width 0.2)
			(type default)
		)
		(layer "In1.Cu")
	)
	(gr_arc
		(start 415.878264 -274.067016)
		(mid 415.842343 -274.081895)
		(end 415.827464 -274.117816)
		(stroke
			(width 0.2)
			(type default)
		)
		(layer "In1.Cu")
	)
	(gr_line
		(start 415.878264 -273.813016)
		(end 416.691064 -273.813016)
		(stroke
			(width 0.2)
			(type default)
		)
		(layer "In1.Cu")
	)
	(gr_arc
		(start 415.878264 -273.508216)
		(mid 415.842343 -273.523095)
		(end 415.827464 -273.559016)
		(stroke
			(width 0.2)
			(type default)
		)
		(layer "In1.Cu")
	)
	(gr_line
		(start 415.878264 -159.371792)
		(end 416.691064 -159.371792)
		(stroke
			(width 0.2)
			(type default)
		)
		(layer "In1.Cu")
	)
	(gr_arc
		(start 415.878264 -159.066992)
		(mid 415.842343 -159.081871)
		(end 415.827464 -159.117792)
		(stroke
			(width 0.2)
			(type default)
		)
		(layer "In1.Cu")
	)
	(gr_line
		(start 415.878264 -158.812992)
		(end 416.691064 -158.812992)
		(stroke
			(width 0.2)
			(type default)
		)
		(layer "In1.Cu")
	)
	(gr_arc
		(start 415.878264 -158.508192)
		(mid 415.842343 -158.523071)
		(end 415.827464 -158.558992)
		(stroke
			(width 0.2)
			(type default)
		)
		(layer "In1.Cu")
	)
	(gr_line
		(start 415.878264 -44.371768)
		(end 416.691064 -44.371768)
		(stroke
			(width 0.2)
			(type default)
		)
		(layer "In1.Cu")
	)
	(gr_arc
		(start 415.878264 -44.066968)
		(mid 415.842343 -44.081847)
		(end 415.827464 -44.117768)
		(stroke
			(width 0.2)
			(type default)
		)
		(layer "In1.Cu")
	)
	(gr_line
		(start 415.878264 -43.812968)
		(end 416.691064 -43.812968)
		(stroke
			(width 0.2)
			(type default)
		)
		(layer "In1.Cu")
	)
	(gr_arc
		(start 415.878264 -43.508168)
		(mid 415.842343 -43.523047)
		(end 415.827464 -43.558968)
		(stroke
			(width 0.2)
			(type default)
		)
		(layer "In1.Cu")
	)
	(gr_arc
		(start 416.691064 -274.371816)
		(mid 416.726985 -274.356937)
		(end 416.741864 -274.321016)
		(stroke
			(width 0.2)
			(type default)
		)
		(layer "In1.Cu")
	)
	(gr_line
		(start 416.691064 -274.067016)
		(end 415.878264 -274.067016)
		(stroke
			(width 0.2)
			(type default)
		)
		(layer "In1.Cu")
	)
	(gr_arc
		(start 416.691064 -273.813016)
		(mid 416.726985 -273.798137)
		(end 416.741864 -273.762216)
		(stroke
			(width 0.2)
			(type default)
		)
		(layer "In1.Cu")
	)
	(gr_line
		(start 416.691064 -273.508216)
		(end 415.878264 -273.508216)
		(stroke
			(width 0.2)
			(type default)
		)
		(layer "In1.Cu")
	)
	(gr_arc
		(start 416.691064 -159.371792)
		(mid 416.726985 -159.356913)
		(end 416.741864 -159.320992)
		(stroke
			(width 0.2)
			(type default)
		)
		(layer "In1.Cu")
	)
	(gr_line
		(start 416.691064 -159.066992)
		(end 415.878264 -159.066992)
		(stroke
			(width 0.2)
			(type default)
		)
		(layer "In1.Cu")
	)
	(gr_arc
		(start 416.691064 -158.812992)
		(mid 416.726985 -158.798113)
		(end 416.741864 -158.762192)
		(stroke
			(width 0.2)
			(type default)
		)
		(layer "In1.Cu")
	)
	(gr_line
		(start 416.691064 -158.508192)
		(end 415.878264 -158.508192)
		(stroke
			(width 0.2)
			(type default)
		)
		(layer "In1.Cu")
	)
	(gr_arc
		(start 416.691064 -44.371768)
		(mid 416.726985 -44.356889)
		(end 416.741864 -44.320968)
		(stroke
			(width 0.2)
			(type default)
		)
		(layer "In1.Cu")
	)
	(gr_line
		(start 416.691064 -44.066968)
		(end 415.878264 -44.066968)
		(stroke
			(width 0.2)
			(type default)
		)
		(layer "In1.Cu")
	)
	(gr_arc
		(start 416.691064 -43.812968)
		(mid 416.726985 -43.798089)
		(end 416.741864 -43.762168)
		(stroke
			(width 0.2)
			(type default)
		)
		(layer "In1.Cu")
	)
	(gr_line
		(start 416.691064 -43.508168)
		(end 415.878264 -43.508168)
		(stroke
			(width 0.2)
			(type default)
		)
		(layer "In1.Cu")
	)
	(gr_line
		(start 416.741864 -274.321016)
		(end 416.741864 -274.117816)
		(stroke
			(width 0.2)
			(type default)
		)
		(layer "In1.Cu")
	)
	(gr_arc
		(start 416.741864 -274.117816)
		(mid 416.726985 -274.081895)
		(end 416.691064 -274.067016)
		(stroke
			(width 0.2)
			(type default)
		)
		(layer "In1.Cu")
	)
	(gr_line
		(start 416.741864 -273.762216)
		(end 416.741864 -273.559016)
		(stroke
			(width 0.2)
			(type default)
		)
		(layer "In1.Cu")
	)
	(gr_arc
		(start 416.741864 -273.559016)
		(mid 416.726985 -273.523095)
		(end 416.691064 -273.508216)
		(stroke
			(width 0.2)
			(type default)
		)
		(layer "In1.Cu")
	)
	(gr_line
		(start 416.741864 -159.320992)
		(end 416.741864 -159.117792)
		(stroke
			(width 0.2)
			(type default)
		)
		(layer "In1.Cu")
	)
	(gr_arc
		(start 416.741864 -159.117792)
		(mid 416.726985 -159.081871)
		(end 416.691064 -159.066992)
		(stroke
			(width 0.2)
			(type default)
		)
		(layer "In1.Cu")
	)
	(gr_line
		(start 416.741864 -158.762192)
		(end 416.741864 -158.558992)
		(stroke
			(width 0.2)
			(type default)
		)
		(layer "In1.Cu")
	)
	(gr_arc
		(start 416.741864 -158.558992)
		(mid 416.726985 -158.523071)
		(end 416.691064 -158.508192)
		(stroke
			(width 0.2)
			(type default)
		)
		(layer "In1.Cu")
	)
	(gr_line
		(start 416.741864 -44.320968)
		(end 416.741864 -44.117768)
		(stroke
			(width 0.2)
			(type default)
		)
		(layer "In1.Cu")
	)
	(gr_arc
		(start 416.741864 -44.117768)
		(mid 416.726985 -44.081847)
		(end 416.691064 -44.066968)
		(stroke
			(width 0.2)
			(type default)
		)
		(layer "In1.Cu")
	)
	(gr_line
		(start 416.741864 -43.762168)
		(end 416.741864 -43.558968)
		(stroke
			(width 0.2)
			(type default)
		)
		(layer "In1.Cu")
	)
	(gr_arc
		(start 416.741864 -43.558968)
		(mid 416.726985 -43.523047)
		(end 416.691064 -43.508168)
		(stroke
			(width 0.2)
			(type default)
		)
		(layer "In1.Cu")
	)
	(gr_arc
		(start 419.008052 -278.321516)
		(mid 419.389052 -278.702516)
		(end 419.770052 -278.321516)
		(stroke
			(width 0.2)
			(type default)
		)
		(layer "In1.Cu")
	)
	(gr_line
		(start 419.008052 -277.178516)
		(end 419.008052 -278.321516)
		(stroke
			(width 0.2)
			(type default)
		)
		(layer "In1.Cu")
	)
	(gr_arc
		(start 419.008052 -163.321492)
		(mid 419.389052 -163.702492)
		(end 419.770052 -163.321492)
		(stroke
			(width 0.2)
			(type default)
		)
		(layer "In1.Cu")
	)
	(gr_line
		(start 419.008052 -162.178492)
		(end 419.008052 -163.321492)
		(stroke
			(width 0.2)
			(type default)
		)
		(layer "In1.Cu")
	)
	(gr_arc
		(start 419.008052 -48.321468)
		(mid 419.389052 -48.702468)
		(end 419.770052 -48.321468)
		(stroke
			(width 0.2)
			(type default)
		)
		(layer "In1.Cu")
	)
	(gr_line
		(start 419.008052 -47.178468)
		(end 419.008052 -48.321468)
		(stroke
			(width 0.2)
			(type default)
		)
		(layer "In1.Cu")
	)
	(gr_line
		(start 419.770052 -278.321516)
		(end 419.770052 -277.17877)
		(stroke
			(width 0.2)
			(type default)
		)
		(layer "In1.Cu")
	)
	(gr_arc
		(start 419.770052 -277.17877)
		(mid 419.389179 -276.797516)
		(end 419.008052 -277.178516)
		(stroke
			(width 0.2)
			(type default)
		)
		(layer "In1.Cu")
	)
	(gr_line
		(start 419.770052 -163.321492)
		(end 419.770052 -162.178746)
		(stroke
			(width 0.2)
			(type default)
		)
		(layer "In1.Cu")
	)
	(gr_arc
		(start 419.770052 -162.178746)
		(mid 419.389179 -161.797492)
		(end 419.008052 -162.178492)
		(stroke
			(width 0.2)
			(type default)
		)
		(layer "In1.Cu")
	)
	(gr_line
		(start 419.770052 -48.321468)
		(end 419.770052 -47.178722)
		(stroke
			(width 0.2)
			(type default)
		)
		(layer "In1.Cu")
	)
	(gr_arc
		(start 419.770052 -47.178722)
		(mid 419.389179 -46.797468)
		(end 419.008052 -47.178468)
		(stroke
			(width 0.2)
			(type default)
		)
		(layer "In1.Cu")
	)
	(gr_line
		(start 420.843964 -279.350216)
		(end 420.843964 -276.149816)
		(stroke
			(width 0.2)
			(type default)
		)
		(layer "In1.Cu")
	)
	(gr_rect
		(start 420.843964 -276.810216)
		(end 423.206164 -278.689816)
		(stroke
			(width 0)
			(type default)
		)
		(fill no)
		(layer "In1.Cu")
	)
	(gr_line
		(start 420.843964 -276.149816)
		(end 423.206164 -276.149816)
		(stroke
			(width 0.2)
			(type default)
		)
		(layer "In1.Cu")
	)
	(gr_line
		(start 420.843964 -275.540216)
		(end 420.843964 -272.339816)
		(stroke
			(width 0.2)
			(type default)
		)
		(layer "In1.Cu")
	)
	(gr_rect
		(start 420.843964 -273.000216)
		(end 423.206164 -274.879816)
		(stroke
			(width 0)
			(type default)
		)
		(fill no)
		(layer "In1.Cu")
	)
	(gr_line
		(start 420.843964 -272.339816)
		(end 423.206164 -272.340578)
		(stroke
			(width 0.2)
			(type default)
		)
		(layer "In1.Cu")
	)
	(gr_line
		(start 420.843964 -164.350192)
		(end 420.843964 -161.149792)
		(stroke
			(width 0.2)
			(type default)
		)
		(layer "In1.Cu")
	)
	(gr_rect
		(start 420.843964 -161.810192)
		(end 423.206164 -163.689792)
		(stroke
			(width 0)
			(type default)
		)
		(fill no)
		(layer "In1.Cu")
	)
	(gr_line
		(start 420.843964 -161.149792)
		(end 423.206164 -161.149792)
		(stroke
			(width 0.2)
			(type default)
		)
		(layer "In1.Cu")
	)
	(gr_line
		(start 420.843964 -160.540192)
		(end 420.843964 -157.339792)
		(stroke
			(width 0.2)
			(type default)
		)
		(layer "In1.Cu")
	)
	(gr_rect
		(start 420.843964 -158.000192)
		(end 423.206164 -159.879792)
		(stroke
			(width 0)
			(type default)
		)
		(fill no)
		(layer "In1.Cu")
	)
	(gr_line
		(start 420.843964 -157.339792)
		(end 423.206164 -157.340554)
		(stroke
			(width 0.2)
			(type default)
		)
		(layer "In1.Cu")
	)
	(gr_line
		(start 420.843964 -49.350168)
		(end 420.843964 -46.149768)
		(stroke
			(width 0.2)
			(type default)
		)
		(layer "In1.Cu")
	)
	(gr_rect
		(start 420.843964 -46.810168)
		(end 423.206164 -48.689768)
		(stroke
			(width 0)
			(type default)
		)
		(fill no)
		(layer "In1.Cu")
	)
	(gr_line
		(start 420.843964 -46.149768)
		(end 423.206164 -46.149768)
		(stroke
			(width 0.2)
			(type default)
		)
		(layer "In1.Cu")
	)
	(gr_line
		(start 420.843964 -45.540168)
		(end 420.843964 -42.339768)
		(stroke
			(width 0.2)
			(type default)
		)
		(layer "In1.Cu")
	)
	(gr_rect
		(start 420.843964 -43.000168)
		(end 423.206164 -44.879768)
		(stroke
			(width 0)
			(type default)
		)
		(fill no)
		(layer "In1.Cu")
	)
	(gr_line
		(start 420.843964 -42.339768)
		(end 423.206164 -42.34053)
		(stroke
			(width 0.2)
			(type default)
		)
		(layer "In1.Cu")
	)
	(gr_line
		(start 423.206164 -279.350216)
		(end 420.843964 -279.350216)
		(stroke
			(width 0.2)
			(type default)
		)
		(layer "In1.Cu")
	)
	(gr_line
		(start 423.206164 -276.149816)
		(end 423.206164 -279.350216)
		(stroke
			(width 0.2)
			(type default)
		)
		(layer "In1.Cu")
	)
	(gr_line
		(start 423.206164 -275.540216)
		(end 420.843964 -275.540216)
		(stroke
			(width 0.2)
			(type default)
		)
		(layer "In1.Cu")
	)
	(gr_line
		(start 423.206164 -272.340578)
		(end 423.206164 -275.540216)
		(stroke
			(width 0.2)
			(type default)
		)
		(layer "In1.Cu")
	)
	(gr_line
		(start 423.206164 -164.350192)
		(end 420.843964 -164.350192)
		(stroke
			(width 0.2)
			(type default)
		)
		(layer "In1.Cu")
	)
	(gr_line
		(start 423.206164 -161.149792)
		(end 423.206164 -164.350192)
		(stroke
			(width 0.2)
			(type default)
		)
		(layer "In1.Cu")
	)
	(gr_line
		(start 423.206164 -160.540192)
		(end 420.843964 -160.540192)
		(stroke
			(width 0.2)
			(type default)
		)
		(layer "In1.Cu")
	)
	(gr_line
		(start 423.206164 -157.340554)
		(end 423.206164 -160.540192)
		(stroke
			(width 0.2)
			(type default)
		)
		(layer "In1.Cu")
	)
	(gr_line
		(start 423.206164 -49.350168)
		(end 420.843964 -49.350168)
		(stroke
			(width 0.2)
			(type default)
		)
		(layer "In1.Cu")
	)
	(gr_line
		(start 423.206164 -46.149768)
		(end 423.206164 -49.350168)
		(stroke
			(width 0.2)
			(type default)
		)
		(layer "In1.Cu")
	)
	(gr_line
		(start 423.206164 -45.540168)
		(end 420.843964 -45.540168)
		(stroke
			(width 0.2)
			(type default)
		)
		(layer "In1.Cu")
	)
	(gr_line
		(start 423.206164 -42.34053)
		(end 423.206164 -45.540168)
		(stroke
			(width 0.2)
			(type default)
		)
		(layer "In1.Cu")
	)
	(gr_arc
		(start 437.8579 -163.321492)
		(mid 438.2389 -163.702492)
		(end 438.6199 -163.321492)
		(stroke
			(width 0.2)
			(type default)
		)
		(layer "In1.Cu")
	)
	(gr_line
		(start 437.8579 -162.178492)
		(end 437.8579 -163.321492)
		(stroke
			(width 0.2)
			(type default)
		)
		(layer "In1.Cu")
	)
	(gr_line
		(start 438.6199 -163.321492)
		(end 438.6199 -162.178746)
		(stroke
			(width 0.2)
			(type default)
		)
		(layer "In1.Cu")
	)
	(gr_arc
		(start 438.6199 -162.178746)
		(mid 438.239027 -161.797492)
		(end 437.8579 -162.178492)
		(stroke
			(width 0.2)
			(type default)
		)
		(layer "In1.Cu")
	)
	(gr_arc
		(start 439.4581 -159.511238)
		(mid 439.838973 -159.892492)
		(end 440.2201 -159.511492)
		(stroke
			(width 0.2)
			(type default)
		)
		(layer "In1.Cu")
	)
	(gr_line
		(start 439.4581 -158.368492)
		(end 439.4581 -159.511238)
		(stroke
			(width 0.2)
			(type default)
		)
		(layer "In1.Cu")
	)
	(gr_line
		(start 440.2201 -159.511492)
		(end 440.2201 -158.368492)
		(stroke
			(width 0.2)
			(type default)
		)
		(layer "In1.Cu")
	)
	(gr_arc
		(start 440.2201 -158.368492)
		(mid 439.8391 -157.987492)
		(end 439.4581 -158.368492)
		(stroke
			(width 0.2)
			(type default)
		)
		(layer "In1.Cu")
	)
	(gr_arc
		(start 441.027312 -159.320992)
		(mid 441.042191 -159.356913)
		(end 441.078112 -159.371792)
		(stroke
			(width 0.2)
			(type default)
		)
		(layer "In1.Cu")
	)
	(gr_line
		(start 441.027312 -159.117792)
		(end 441.027312 -159.320992)
		(stroke
			(width 0.2)
			(type default)
		)
		(layer "In1.Cu")
	)
	(gr_arc
		(start 441.027312 -158.762192)
		(mid 441.042191 -158.798113)
		(end 441.078112 -158.812992)
		(stroke
			(width 0.2)
			(type default)
		)
		(layer "In1.Cu")
	)
	(gr_line
		(start 441.027312 -158.558992)
		(end 441.027312 -158.762192)
		(stroke
			(width 0.2)
			(type default)
		)
		(layer "In1.Cu")
	)
	(gr_line
		(start 441.078112 -159.371792)
		(end 441.890912 -159.371792)
		(stroke
			(width 0.2)
			(type default)
		)
		(layer "In1.Cu")
	)
	(gr_arc
		(start 441.078112 -159.066992)
		(mid 441.042191 -159.081871)
		(end 441.027312 -159.117792)
		(stroke
			(width 0.2)
			(type default)
		)
		(layer "In1.Cu")
	)
	(gr_line
		(start 441.078112 -158.812992)
		(end 441.890912 -158.812992)
		(stroke
			(width 0.2)
			(type default)
		)
		(layer "In1.Cu")
	)
	(gr_arc
		(start 441.078112 -158.508192)
		(mid 441.042191 -158.523071)
		(end 441.027312 -158.558992)
		(stroke
			(width 0.2)
			(type default)
		)
		(layer "In1.Cu")
	)
	(gr_arc
		(start 441.890912 -159.371792)
		(mid 441.926833 -159.356913)
		(end 441.941712 -159.320992)
		(stroke
			(width 0.2)
			(type default)
		)
		(layer "In1.Cu")
	)
	(gr_line
		(start 441.890912 -159.066992)
		(end 441.078112 -159.066992)
		(stroke
			(width 0.2)
			(type default)
		)
		(layer "In1.Cu")
	)
	(gr_arc
		(start 441.890912 -158.812992)
		(mid 441.926833 -158.798113)
		(end 441.941712 -158.762192)
		(stroke
			(width 0.2)
			(type default)
		)
		(layer "In1.Cu")
	)
	(gr_line
		(start 441.890912 -158.508192)
		(end 441.078112 -158.508192)
		(stroke
			(width 0.2)
			(type default)
		)
		(layer "In1.Cu")
	)
	(gr_line
		(start 441.941712 -159.320992)
		(end 441.941712 -159.117792)
		(stroke
			(width 0.2)
			(type default)
		)
		(layer "In1.Cu")
	)
	(gr_arc
		(start 441.941712 -159.117792)
		(mid 441.926833 -159.081871)
		(end 441.890912 -159.066992)
		(stroke
			(width 0.2)
			(type default)
		)
		(layer "In1.Cu")
	)
	(gr_line
		(start 441.941712 -158.762192)
		(end 441.941712 -158.558992)
		(stroke
			(width 0.2)
			(type default)
		)
		(layer "In1.Cu")
	)
	(gr_arc
		(start 441.941712 -158.558992)
		(mid 441.926833 -158.523071)
		(end 441.890912 -158.508192)
		(stroke
			(width 0.2)
			(type default)
		)
		(layer "In1.Cu")
	)
	(gr_arc
		(start 445.8081 -274.511262)
		(mid 446.188973 -274.892516)
		(end 446.5701 -274.511516)
		(stroke
			(width 0.2)
			(type default)
		)
		(layer "In1.Cu")
	)
	(gr_line
		(start 445.8081 -273.368516)
		(end 445.8081 -274.511262)
		(stroke
			(width 0.2)
			(type default)
		)
		(layer "In1.Cu")
	)
	(gr_arc
		(start 445.8081 -44.511214)
		(mid 446.188973 -44.892468)
		(end 446.5701 -44.511468)
		(stroke
			(width 0.2)
			(type default)
		)
		(layer "In1.Cu")
	)
	(gr_line
		(start 445.8081 -43.368468)
		(end 445.8081 -44.511214)
		(stroke
			(width 0.2)
			(type default)
		)
		(layer "In1.Cu")
	)
	(gr_line
		(start 446.5701 -274.511516)
		(end 446.5701 -273.368516)
		(stroke
			(width 0.2)
			(type default)
		)
		(layer "In1.Cu")
	)
	(gr_arc
		(start 446.5701 -273.368516)
		(mid 446.1891 -272.987516)
		(end 445.8081 -273.368516)
		(stroke
			(width 0.2)
			(type default)
		)
		(layer "In1.Cu")
	)
	(gr_line
		(start 446.5701 -44.511468)
		(end 446.5701 -43.368468)
		(stroke
			(width 0.2)
			(type default)
		)
		(layer "In1.Cu")
	)
	(gr_arc
		(start 446.5701 -43.368468)
		(mid 446.1891 -42.987468)
		(end 445.8081 -43.368468)
		(stroke
			(width 0.2)
			(type default)
		)
		(layer "In1.Cu")
	)
	(gr_arc
		(start 447.377312 -274.321016)
		(mid 447.392191 -274.356937)
		(end 447.428112 -274.371816)
		(stroke
			(width 0.2)
			(type default)
		)
		(layer "In1.Cu")
	)
	(gr_line
		(start 447.377312 -274.117816)
		(end 447.377312 -274.321016)
		(stroke
			(width 0.2)
			(type default)
		)
		(layer "In1.Cu")
	)
	(gr_arc
		(start 447.377312 -273.762216)
		(mid 447.392191 -273.798137)
		(end 447.428112 -273.813016)
		(stroke
			(width 0.2)
			(type default)
		)
		(layer "In1.Cu")
	)
	(gr_line
		(start 447.377312 -273.559016)
		(end 447.377312 -273.762216)
		(stroke
			(width 0.2)
			(type default)
		)
		(layer "In1.Cu")
	)
	(gr_arc
		(start 447.377312 -44.320968)
		(mid 447.392191 -44.356889)
		(end 447.428112 -44.371768)
		(stroke
			(width 0.2)
			(type default)
		)
		(layer "In1.Cu")
	)
	(gr_line
		(start 447.377312 -44.117768)
		(end 447.377312 -44.320968)
		(stroke
			(width 0.2)
			(type default)
		)
		(layer "In1.Cu")
	)
	(gr_arc
		(start 447.377312 -43.762168)
		(mid 447.392191 -43.798089)
		(end 447.428112 -43.812968)
		(stroke
			(width 0.2)
			(type default)
		)
		(layer "In1.Cu")
	)
	(gr_line
		(start 447.377312 -43.558968)
		(end 447.377312 -43.762168)
		(stroke
			(width 0.2)
			(type default)
		)
		(layer "In1.Cu")
	)
	(gr_line
		(start 447.428112 -274.371816)
		(end 448.240912 -274.371816)
		(stroke
			(width 0.2)
			(type default)
		)
		(layer "In1.Cu")
	)
	(gr_arc
		(start 447.428112 -274.067016)
		(mid 447.392191 -274.081895)
		(end 447.377312 -274.117816)
		(stroke
			(width 0.2)
			(type default)
		)
		(layer "In1.Cu")
	)
	(gr_line
		(start 447.428112 -273.813016)
		(end 448.240912 -273.813016)
		(stroke
			(width 0.2)
			(type default)
		)
		(layer "In1.Cu")
	)
	(gr_arc
		(start 447.428112 -273.508216)
		(mid 447.392191 -273.523095)
		(end 447.377312 -273.559016)
		(stroke
			(width 0.2)
			(type default)
		)
		(layer "In1.Cu")
	)
	(gr_line
		(start 447.428112 -44.371768)
		(end 448.240912 -44.371768)
		(stroke
			(width 0.2)
			(type default)
		)
		(layer "In1.Cu")
	)
	(gr_arc
		(start 447.428112 -44.066968)
		(mid 447.392191 -44.081847)
		(end 447.377312 -44.117768)
		(stroke
			(width 0.2)
			(type default)
		)
		(layer "In1.Cu")
	)
	(gr_line
		(start 447.428112 -43.812968)
		(end 448.240912 -43.812968)
		(stroke
			(width 0.2)
			(type default)
		)
		(layer "In1.Cu")
	)
	(gr_arc
		(start 447.428112 -43.508168)
		(mid 447.392191 -43.523047)
		(end 447.377312 -43.558968)
		(stroke
			(width 0.2)
			(type default)
		)
		(layer "In1.Cu")
	)
	(gr_arc
		(start 448.240912 -274.371816)
		(mid 448.276833 -274.356937)
		(end 448.291712 -274.321016)
		(stroke
			(width 0.2)
			(type default)
		)
		(layer "In1.Cu")
	)
	(gr_line
		(start 448.240912 -274.067016)
		(end 447.428112 -274.067016)
		(stroke
			(width 0.2)
			(type default)
		)
		(layer "In1.Cu")
	)
	(gr_arc
		(start 448.240912 -273.813016)
		(mid 448.276833 -273.798137)
		(end 448.291712 -273.762216)
		(stroke
			(width 0.2)
			(type default)
		)
		(layer "In1.Cu")
	)
	(gr_line
		(start 448.240912 -273.508216)
		(end 447.428112 -273.508216)
		(stroke
			(width 0.2)
			(type default)
		)
		(layer "In1.Cu")
	)
	(gr_arc
		(start 448.240912 -44.371768)
		(mid 448.276833 -44.356889)
		(end 448.291712 -44.320968)
		(stroke
			(width 0.2)
			(type default)
		)
		(layer "In1.Cu")
	)
	(gr_line
		(start 448.240912 -44.066968)
		(end 447.428112 -44.066968)
		(stroke
			(width 0.2)
			(type default)
		)
		(layer "In1.Cu")
	)
	(gr_arc
		(start 448.240912 -43.812968)
		(mid 448.276833 -43.798089)
		(end 448.291712 -43.762168)
		(stroke
			(width 0.2)
			(type default)
		)
		(layer "In1.Cu")
	)
	(gr_line
		(start 448.240912 -43.508168)
		(end 447.428112 -43.508168)
		(stroke
			(width 0.2)
			(type default)
		)
		(layer "In1.Cu")
	)
	(gr_line
		(start 448.291712 -274.321016)
		(end 448.291712 -274.117816)
		(stroke
			(width 0.2)
			(type default)
		)
		(layer "In1.Cu")
	)
	(gr_arc
		(start 448.291712 -274.117816)
		(mid 448.276833 -274.081895)
		(end 448.240912 -274.067016)
		(stroke
			(width 0.2)
			(type default)
		)
		(layer "In1.Cu")
	)
	(gr_line
		(start 448.291712 -273.762216)
		(end 448.291712 -273.559016)
		(stroke
			(width 0.2)
			(type default)
		)
		(layer "In1.Cu")
	)
	(gr_arc
		(start 448.291712 -273.559016)
		(mid 448.276833 -273.523095)
		(end 448.240912 -273.508216)
		(stroke
			(width 0.2)
			(type default)
		)
		(layer "In1.Cu")
	)
	(gr_line
		(start 448.291712 -44.320968)
		(end 448.291712 -44.117768)
		(stroke
			(width 0.2)
			(type default)
		)
		(layer "In1.Cu")
	)
	(gr_arc
		(start 448.291712 -44.117768)
		(mid 448.276833 -44.081847)
		(end 448.240912 -44.066968)
		(stroke
			(width 0.2)
			(type default)
		)
		(layer "In1.Cu")
	)
	(gr_line
		(start 448.291712 -43.762168)
		(end 448.291712 -43.558968)
		(stroke
			(width 0.2)
			(type default)
		)
		(layer "In1.Cu")
	)
	(gr_arc
		(start 448.291712 -43.558968)
		(mid 448.276833 -43.523047)
		(end 448.240912 -43.508168)
		(stroke
			(width 0.2)
			(type default)
		)
		(layer "In1.Cu")
	)
	(gr_arc
		(start 450.5579 -278.321516)
		(mid 450.9389 -278.702516)
		(end 451.3199 -278.321516)
		(stroke
			(width 0.2)
			(type default)
		)
		(layer "In1.Cu")
	)
	(gr_line
		(start 450.5579 -277.178516)
		(end 450.5579 -278.321516)
		(stroke
			(width 0.2)
			(type default)
		)
		(layer "In1.Cu")
	)
	(gr_arc
		(start 450.5579 -48.321468)
		(mid 450.9389 -48.702468)
		(end 451.3199 -48.321468)
		(stroke
			(width 0.2)
			(type default)
		)
		(layer "In1.Cu")
	)
	(gr_line
		(start 450.5579 -47.178468)
		(end 450.5579 -48.321468)
		(stroke
			(width 0.2)
			(type default)
		)
		(layer "In1.Cu")
	)
	(gr_line
		(start 451.3199 -278.321516)
		(end 451.3199 -277.17877)
		(stroke
			(width 0.2)
			(type default)
		)
		(layer "In1.Cu")
	)
	(gr_arc
		(start 451.3199 -277.17877)
		(mid 450.939027 -276.797516)
		(end 450.5579 -277.178516)
		(stroke
			(width 0.2)
			(type default)
		)
		(layer "In1.Cu")
	)
	(gr_line
		(start 451.3199 -48.321468)
		(end 451.3199 -47.178722)
		(stroke
			(width 0.2)
			(type default)
		)
		(layer "In1.Cu")
	)
	(gr_arc
		(start 451.3199 -47.178722)
		(mid 450.939027 -46.797468)
		(end 450.5579 -47.178468)
		(stroke
			(width 0.2)
			(type default)
		)
		(layer "In1.Cu")
	)
	(gr_line
		(start 452.393812 -279.350216)
		(end 452.393812 -276.149816)
		(stroke
			(width 0.2)
			(type default)
		)
		(layer "In1.Cu")
	)
	(gr_rect
		(start 452.393812 -276.810216)
		(end 454.756012 -278.689816)
		(stroke
			(width 0)
			(type default)
		)
		(fill no)
		(layer "In1.Cu")
	)
	(gr_line
		(start 452.393812 -276.149816)
		(end 454.756012 -276.149816)
		(stroke
			(width 0.2)
			(type default)
		)
		(layer "In1.Cu")
	)
	(gr_line
		(start 452.393812 -275.540216)
		(end 452.393812 -272.339816)
		(stroke
			(width 0.2)
			(type default)
		)
		(layer "In1.Cu")
	)
	(gr_rect
		(start 452.393812 -273.000216)
		(end 454.756012 -274.879816)
		(stroke
			(width 0)
			(type default)
		)
		(fill no)
		(layer "In1.Cu")
	)
	(gr_line
		(start 452.393812 -272.339816)
		(end 454.756012 -272.340578)
		(stroke
			(width 0.2)
			(type default)
		)
		(layer "In1.Cu")
	)
	(gr_line
		(start 452.393812 -164.350192)
		(end 452.393812 -161.149792)
		(stroke
			(width 0.2)
			(type default)
		)
		(layer "In1.Cu")
	)
	(gr_rect
		(start 452.393812 -161.810192)
		(end 454.756012 -163.689792)
		(stroke
			(width 0)
			(type default)
		)
		(fill no)
		(layer "In1.Cu")
	)
	(gr_line
		(start 452.393812 -161.149792)
		(end 454.756012 -161.149792)
		(stroke
			(width 0.2)
			(type default)
		)
		(layer "In1.Cu")
	)
	(gr_line
		(start 452.393812 -160.540192)
		(end 452.393812 -157.339792)
		(stroke
			(width 0.2)
			(type default)
		)
		(layer "In1.Cu")
	)
	(gr_rect
		(start 452.393812 -158.000192)
		(end 454.756012 -159.879792)
		(stroke
			(width 0)
			(type default)
		)
		(fill no)
		(layer "In1.Cu")
	)
	(gr_line
		(start 452.393812 -157.339792)
		(end 454.756012 -157.340554)
		(stroke
			(width 0.2)
			(type default)
		)
		(layer "In1.Cu")
	)
	(gr_line
		(start 452.393812 -49.350168)
		(end 452.393812 -46.149768)
		(stroke
			(width 0.2)
			(type default)
		)
		(layer "In1.Cu")
	)
	(gr_rect
		(start 452.393812 -46.810168)
		(end 454.756012 -48.689768)
		(stroke
			(width 0)
			(type default)
		)
		(fill no)
		(layer "In1.Cu")
	)
	(gr_line
		(start 452.393812 -46.149768)
		(end 454.756012 -46.149768)
		(stroke
			(width 0.2)
			(type default)
		)
		(layer "In1.Cu")
	)
	(gr_line
		(start 452.393812 -45.540168)
		(end 452.393812 -42.339768)
		(stroke
			(width 0.2)
			(type default)
		)
		(layer "In1.Cu")
	)
	(gr_rect
		(start 452.393812 -43.000168)
		(end 454.756012 -44.879768)
		(stroke
			(width 0)
			(type default)
		)
		(fill no)
		(layer "In1.Cu")
	)
	(gr_line
		(start 452.393812 -42.339768)
		(end 454.756012 -42.34053)
		(stroke
			(width 0.2)
			(type default)
		)
		(layer "In1.Cu")
	)
	(gr_line
		(start 454.756012 -279.350216)
		(end 452.393812 -279.350216)
		(stroke
			(width 0.2)
			(type default)
		)
		(layer "In1.Cu")
	)
	(gr_line
		(start 454.756012 -276.149816)
		(end 454.756012 -279.350216)
		(stroke
			(width 0.2)
			(type default)
		)
		(layer "In1.Cu")
	)
	(gr_line
		(start 454.756012 -275.540216)
		(end 452.393812 -275.540216)
		(stroke
			(width 0.2)
			(type default)
		)
		(layer "In1.Cu")
	)
	(gr_line
		(start 454.756012 -272.340578)
		(end 454.756012 -275.540216)
		(stroke
			(width 0.2)
			(type default)
		)
		(layer "In1.Cu")
	)
	(gr_line
		(start 454.756012 -164.350192)
		(end 452.393812 -164.350192)
		(stroke
			(width 0.2)
			(type default)
		)
		(layer "In1.Cu")
	)
	(gr_line
		(start 454.756012 -161.149792)
		(end 454.756012 -164.350192)
		(stroke
			(width 0.2)
			(type default)
		)
		(layer "In1.Cu")
	)
	(gr_line
		(start 454.756012 -160.540192)
		(end 452.393812 -160.540192)
		(stroke
			(width 0.2)
			(type default)
		)
		(layer "In1.Cu")
	)
	(gr_line
		(start 454.756012 -157.340554)
		(end 454.756012 -160.540192)
		(stroke
			(width 0.2)
			(type default)
		)
		(layer "In1.Cu")
	)
	(gr_line
		(start 454.756012 -49.350168)
		(end 452.393812 -49.350168)
		(stroke
			(width 0.2)
			(type default)
		)
		(layer "In1.Cu")
	)
	(gr_line
		(start 454.756012 -46.149768)
		(end 454.756012 -49.350168)
		(stroke
			(width 0.2)
			(type default)
		)
		(layer "In1.Cu")
	)
	(gr_line
		(start 454.756012 -45.540168)
		(end 452.393812 -45.540168)
		(stroke
			(width 0.2)
			(type default)
		)
		(layer "In1.Cu")
	)
	(gr_line
		(start 454.756012 -42.34053)
		(end 454.756012 -45.540168)
		(stroke
			(width 0.2)
			(type default)
		)
		(layer "In1.Cu")
	)
	(gr_arc
		(start 477.358202 -274.511262)
		(mid 477.739075 -274.892516)
		(end 478.120202 -274.511516)
		(stroke
			(width 0.2)
			(type default)
		)
		(layer "In1.Cu")
	)
	(gr_line
		(start 477.358202 -273.368516)
		(end 477.358202 -274.511262)
		(stroke
			(width 0.2)
			(type default)
		)
		(layer "In1.Cu")
	)
	(gr_arc
		(start 477.358202 -159.511238)
		(mid 477.739075 -159.892492)
		(end 478.120202 -159.511492)
		(stroke
			(width 0.2)
			(type default)
		)
		(layer "In1.Cu")
	)
	(gr_line
		(start 477.358202 -158.368492)
		(end 477.358202 -159.511238)
		(stroke
			(width 0.2)
			(type default)
		)
		(layer "In1.Cu")
	)
	(gr_arc
		(start 477.358202 -44.511214)
		(mid 477.739075 -44.892468)
		(end 478.120202 -44.511468)
		(stroke
			(width 0.2)
			(type default)
		)
		(layer "In1.Cu")
	)
	(gr_line
		(start 477.358202 -43.368468)
		(end 477.358202 -44.511214)
		(stroke
			(width 0.2)
			(type default)
		)
		(layer "In1.Cu")
	)
	(gr_line
		(start 478.120202 -274.511516)
		(end 478.120202 -273.368516)
		(stroke
			(width 0.2)
			(type default)
		)
		(layer "In1.Cu")
	)
	(gr_arc
		(start 478.120202 -273.368516)
		(mid 477.739202 -272.987516)
		(end 477.358202 -273.368516)
		(stroke
			(width 0.2)
			(type default)
		)
		(layer "In1.Cu")
	)
	(gr_line
		(start 478.120202 -159.511492)
		(end 478.120202 -158.368492)
		(stroke
			(width 0.2)
			(type default)
		)
		(layer "In1.Cu")
	)
	(gr_arc
		(start 478.120202 -158.368492)
		(mid 477.739202 -157.987492)
		(end 477.358202 -158.368492)
		(stroke
			(width 0.2)
			(type default)
		)
		(layer "In1.Cu")
	)
	(gr_line
		(start 478.120202 -44.511468)
		(end 478.120202 -43.368468)
		(stroke
			(width 0.2)
			(type default)
		)
		(layer "In1.Cu")
	)
	(gr_arc
		(start 478.120202 -43.368468)
		(mid 477.739202 -42.987468)
		(end 477.358202 -43.368468)
		(stroke
			(width 0.2)
			(type default)
		)
		(layer "In1.Cu")
	)
	(gr_arc
		(start 478.927414 -274.321016)
		(mid 478.942293 -274.356937)
		(end 478.978214 -274.371816)
		(stroke
			(width 0.2)
			(type default)
		)
		(layer "In1.Cu")
	)
	(gr_line
		(start 478.927414 -274.117816)
		(end 478.927414 -274.321016)
		(stroke
			(width 0.2)
			(type default)
		)
		(layer "In1.Cu")
	)
	(gr_arc
		(start 478.927414 -273.762216)
		(mid 478.942293 -273.798137)
		(end 478.978214 -273.813016)
		(stroke
			(width 0.2)
			(type default)
		)
		(layer "In1.Cu")
	)
	(gr_line
		(start 478.927414 -273.559016)
		(end 478.927414 -273.762216)
		(stroke
			(width 0.2)
			(type default)
		)
		(layer "In1.Cu")
	)
	(gr_arc
		(start 478.927414 -159.320992)
		(mid 478.942293 -159.356913)
		(end 478.978214 -159.371792)
		(stroke
			(width 0.2)
			(type default)
		)
		(layer "In1.Cu")
	)
	(gr_line
		(start 478.927414 -159.117792)
		(end 478.927414 -159.320992)
		(stroke
			(width 0.2)
			(type default)
		)
		(layer "In1.Cu")
	)
	(gr_arc
		(start 478.927414 -158.762192)
		(mid 478.942293 -158.798113)
		(end 478.978214 -158.812992)
		(stroke
			(width 0.2)
			(type default)
		)
		(layer "In1.Cu")
	)
	(gr_line
		(start 478.927414 -158.558992)
		(end 478.927414 -158.762192)
		(stroke
			(width 0.2)
			(type default)
		)
		(layer "In1.Cu")
	)
	(gr_arc
		(start 478.927414 -44.320968)
		(mid 478.942293 -44.356889)
		(end 478.978214 -44.371768)
		(stroke
			(width 0.2)
			(type default)
		)
		(layer "In1.Cu")
	)
	(gr_line
		(start 478.927414 -44.117768)
		(end 478.927414 -44.320968)
		(stroke
			(width 0.2)
			(type default)
		)
		(layer "In1.Cu")
	)
	(gr_arc
		(start 478.927414 -43.762168)
		(mid 478.942293 -43.798089)
		(end 478.978214 -43.812968)
		(stroke
			(width 0.2)
			(type default)
		)
		(layer "In1.Cu")
	)
	(gr_line
		(start 478.927414 -43.558968)
		(end 478.927414 -43.762168)
		(stroke
			(width 0.2)
			(type default)
		)
		(layer "In1.Cu")
	)
	(gr_line
		(start 478.978214 -274.371816)
		(end 479.791014 -274.371816)
		(stroke
			(width 0.2)
			(type default)
		)
		(layer "In1.Cu")
	)
	(gr_arc
		(start 478.978214 -274.067016)
		(mid 478.942293 -274.081895)
		(end 478.927414 -274.117816)
		(stroke
			(width 0.2)
			(type default)
		)
		(layer "In1.Cu")
	)
	(gr_line
		(start 478.978214 -273.813016)
		(end 479.791014 -273.813016)
		(stroke
			(width 0.2)
			(type default)
		)
		(layer "In1.Cu")
	)
	(gr_arc
		(start 478.978214 -273.508216)
		(mid 478.942293 -273.523095)
		(end 478.927414 -273.559016)
		(stroke
			(width 0.2)
			(type default)
		)
		(layer "In1.Cu")
	)
	(gr_line
		(start 478.978214 -159.371792)
		(end 479.791014 -159.371792)
		(stroke
			(width 0.2)
			(type default)
		)
		(layer "In1.Cu")
	)
	(gr_arc
		(start 478.978214 -159.066992)
		(mid 478.942293 -159.081871)
		(end 478.927414 -159.117792)
		(stroke
			(width 0.2)
			(type default)
		)
		(layer "In1.Cu")
	)
	(gr_line
		(start 478.978214 -158.812992)
		(end 479.791014 -158.812992)
		(stroke
			(width 0.2)
			(type default)
		)
		(layer "In1.Cu")
	)
	(gr_arc
		(start 478.978214 -158.508192)
		(mid 478.942293 -158.523071)
		(end 478.927414 -158.558992)
		(stroke
			(width 0.2)
			(type default)
		)
		(layer "In1.Cu")
	)
	(gr_line
		(start 478.978214 -44.371768)
		(end 479.791014 -44.371768)
		(stroke
			(width 0.2)
			(type default)
		)
		(layer "In1.Cu")
	)
	(gr_arc
		(start 478.978214 -44.066968)
		(mid 478.942293 -44.081847)
		(end 478.927414 -44.117768)
		(stroke
			(width 0.2)
			(type default)
		)
		(layer "In1.Cu")
	)
	(gr_line
		(start 478.978214 -43.812968)
		(end 479.791014 -43.812968)
		(stroke
			(width 0.2)
			(type default)
		)
		(layer "In1.Cu")
	)
	(gr_arc
		(start 478.978214 -43.508168)
		(mid 478.942293 -43.523047)
		(end 478.927414 -43.558968)
		(stroke
			(width 0.2)
			(type default)
		)
		(layer "In1.Cu")
	)
	(gr_arc
		(start 479.791014 -274.371816)
		(mid 479.826935 -274.356937)
		(end 479.841814 -274.321016)
		(stroke
			(width 0.2)
			(type default)
		)
		(layer "In1.Cu")
	)
	(gr_line
		(start 479.791014 -274.067016)
		(end 478.978214 -274.067016)
		(stroke
			(width 0.2)
			(type default)
		)
		(layer "In1.Cu")
	)
	(gr_arc
		(start 479.791014 -273.813016)
		(mid 479.826935 -273.798137)
		(end 479.841814 -273.762216)
		(stroke
			(width 0.2)
			(type default)
		)
		(layer "In1.Cu")
	)
	(gr_line
		(start 479.791014 -273.508216)
		(end 478.978214 -273.508216)
		(stroke
			(width 0.2)
			(type default)
		)
		(layer "In1.Cu")
	)
	(gr_arc
		(start 479.791014 -159.371792)
		(mid 479.826935 -159.356913)
		(end 479.841814 -159.320992)
		(stroke
			(width 0.2)
			(type default)
		)
		(layer "In1.Cu")
	)
	(gr_line
		(start 479.791014 -159.066992)
		(end 478.978214 -159.066992)
		(stroke
			(width 0.2)
			(type default)
		)
		(layer "In1.Cu")
	)
	(gr_arc
		(start 479.791014 -158.812992)
		(mid 479.826935 -158.798113)
		(end 479.841814 -158.762192)
		(stroke
			(width 0.2)
			(type default)
		)
		(layer "In1.Cu")
	)
	(gr_line
		(start 479.791014 -158.508192)
		(end 478.978214 -158.508192)
		(stroke
			(width 0.2)
			(type default)
		)
		(layer "In1.Cu")
	)
	(gr_arc
		(start 479.791014 -44.371768)
		(mid 479.826935 -44.356889)
		(end 479.841814 -44.320968)
		(stroke
			(width 0.2)
			(type default)
		)
		(layer "In1.Cu")
	)
	(gr_line
		(start 479.791014 -44.066968)
		(end 478.978214 -44.066968)
		(stroke
			(width 0.2)
			(type default)
		)
		(layer "In1.Cu")
	)
	(gr_arc
		(start 479.791014 -43.812968)
		(mid 479.826935 -43.798089)
		(end 479.841814 -43.762168)
		(stroke
			(width 0.2)
			(type default)
		)
		(layer "In1.Cu")
	)
	(gr_line
		(start 479.791014 -43.508168)
		(end 478.978214 -43.508168)
		(stroke
			(width 0.2)
			(type default)
		)
		(layer "In1.Cu")
	)
	(gr_line
		(start 479.841814 -274.321016)
		(end 479.841814 -274.117816)
		(stroke
			(width 0.2)
			(type default)
		)
		(layer "In1.Cu")
	)
	(gr_arc
		(start 479.841814 -274.117816)
		(mid 479.826935 -274.081895)
		(end 479.791014 -274.067016)
		(stroke
			(width 0.2)
			(type default)
		)
		(layer "In1.Cu")
	)
	(gr_line
		(start 479.841814 -273.762216)
		(end 479.841814 -273.559016)
		(stroke
			(width 0.2)
			(type default)
		)
		(layer "In1.Cu")
	)
	(gr_arc
		(start 479.841814 -273.559016)
		(mid 479.826935 -273.523095)
		(end 479.791014 -273.508216)
		(stroke
			(width 0.2)
			(type default)
		)
		(layer "In1.Cu")
	)
	(gr_line
		(start 479.841814 -159.320992)
		(end 479.841814 -159.117792)
		(stroke
			(width 0.2)
			(type default)
		)
		(layer "In1.Cu")
	)
	(gr_arc
		(start 479.841814 -159.117792)
		(mid 479.826935 -159.081871)
		(end 479.791014 -159.066992)
		(stroke
			(width 0.2)
			(type default)
		)
		(layer "In1.Cu")
	)
	(gr_line
		(start 479.841814 -158.762192)
		(end 479.841814 -158.558992)
		(stroke
			(width 0.2)
			(type default)
		)
		(layer "In1.Cu")
	)
	(gr_arc
		(start 479.841814 -158.558992)
		(mid 479.826935 -158.523071)
		(end 479.791014 -158.508192)
		(stroke
			(width 0.2)
			(type default)
		)
		(layer "In1.Cu")
	)
	(gr_line
		(start 479.841814 -44.320968)
		(end 479.841814 -44.117768)
		(stroke
			(width 0.2)
			(type default)
		)
		(layer "In1.Cu")
	)
	(gr_arc
		(start 479.841814 -44.117768)
		(mid 479.826935 -44.081847)
		(end 479.791014 -44.066968)
		(stroke
			(width 0.2)
			(type default)
		)
		(layer "In1.Cu")
	)
	(gr_line
		(start 479.841814 -43.762168)
		(end 479.841814 -43.558968)
		(stroke
			(width 0.2)
			(type default)
		)
		(layer "In1.Cu")
	)
	(gr_arc
		(start 479.841814 -43.558968)
		(mid 479.826935 -43.523047)
		(end 479.791014 -43.508168)
		(stroke
			(width 0.2)
			(type default)
		)
		(layer "In1.Cu")
	)
	(gr_arc
		(start 482.108002 -278.321516)
		(mid 482.489002 -278.702516)
		(end 482.870002 -278.321516)
		(stroke
			(width 0.2)
			(type default)
		)
		(layer "In1.Cu")
	)
	(gr_line
		(start 482.108002 -277.178516)
		(end 482.108002 -278.321516)
		(stroke
			(width 0.2)
			(type default)
		)
		(layer "In1.Cu")
	)
	(gr_arc
		(start 482.108002 -163.321492)
		(mid 482.489002 -163.702492)
		(end 482.870002 -163.321492)
		(stroke
			(width 0.2)
			(type default)
		)
		(layer "In1.Cu")
	)
	(gr_line
		(start 482.108002 -162.178492)
		(end 482.108002 -163.321492)
		(stroke
			(width 0.2)
			(type default)
		)
		(layer "In1.Cu")
	)
	(gr_arc
		(start 482.108002 -48.321468)
		(mid 482.489002 -48.702468)
		(end 482.870002 -48.321468)
		(stroke
			(width 0.2)
			(type default)
		)
		(layer "In1.Cu")
	)
	(gr_line
		(start 482.108002 -47.178468)
		(end 482.108002 -48.321468)
		(stroke
			(width 0.2)
			(type default)
		)
		(layer "In1.Cu")
	)
	(gr_line
		(start 482.870002 -278.321516)
		(end 482.870002 -277.17877)
		(stroke
			(width 0.2)
			(type default)
		)
		(layer "In1.Cu")
	)
	(gr_arc
		(start 482.870002 -277.17877)
		(mid 482.489129 -276.797516)
		(end 482.108002 -277.178516)
		(stroke
			(width 0.2)
			(type default)
		)
		(layer "In1.Cu")
	)
	(gr_line
		(start 482.870002 -163.321492)
		(end 482.870002 -162.178746)
		(stroke
			(width 0.2)
			(type default)
		)
		(layer "In1.Cu")
	)
	(gr_arc
		(start 482.870002 -162.178746)
		(mid 482.489129 -161.797492)
		(end 482.108002 -162.178492)
		(stroke
			(width 0.2)
			(type default)
		)
		(layer "In1.Cu")
	)
	(gr_line
		(start 482.870002 -48.321468)
		(end 482.870002 -47.178722)
		(stroke
			(width 0.2)
			(type default)
		)
		(layer "In1.Cu")
	)
	(gr_arc
		(start 482.870002 -47.178722)
		(mid 482.489129 -46.797468)
		(end 482.108002 -47.178468)
		(stroke
			(width 0.2)
			(type default)
		)
		(layer "In1.Cu")
	)
	(gr_line
		(start 483.943914 -279.350216)
		(end 483.943914 -276.149816)
		(stroke
			(width 0.2)
			(type default)
		)
		(layer "In1.Cu")
	)
	(gr_rect
		(start 483.943914 -276.810216)
		(end 486.306114 -278.689816)
		(stroke
			(width 0)
			(type default)
		)
		(fill no)
		(layer "In1.Cu")
	)
	(gr_line
		(start 483.943914 -276.149816)
		(end 486.306114 -276.149816)
		(stroke
			(width 0.2)
			(type default)
		)
		(layer "In1.Cu")
	)
	(gr_line
		(start 483.943914 -275.540216)
		(end 483.943914 -272.339816)
		(stroke
			(width 0.2)
			(type default)
		)
		(layer "In1.Cu")
	)
	(gr_rect
		(start 483.943914 -273.000216)
		(end 486.306114 -274.879816)
		(stroke
			(width 0)
			(type default)
		)
		(fill no)
		(layer "In1.Cu")
	)
	(gr_line
		(start 483.943914 -272.339816)
		(end 486.306114 -272.340578)
		(stroke
			(width 0.2)
			(type default)
		)
		(layer "In1.Cu")
	)
	(gr_line
		(start 483.943914 -164.350192)
		(end 483.943914 -161.149792)
		(stroke
			(width 0.2)
			(type default)
		)
		(layer "In1.Cu")
	)
	(gr_rect
		(start 483.943914 -161.810192)
		(end 486.306114 -163.689792)
		(stroke
			(width 0)
			(type default)
		)
		(fill no)
		(layer "In1.Cu")
	)
	(gr_line
		(start 483.943914 -161.149792)
		(end 486.306114 -161.149792)
		(stroke
			(width 0.2)
			(type default)
		)
		(layer "In1.Cu")
	)
	(gr_line
		(start 483.943914 -160.540192)
		(end 483.943914 -157.339792)
		(stroke
			(width 0.2)
			(type default)
		)
		(layer "In1.Cu")
	)
	(gr_rect
		(start 483.943914 -158.000192)
		(end 486.306114 -159.879792)
		(stroke
			(width 0)
			(type default)
		)
		(fill no)
		(layer "In1.Cu")
	)
	(gr_line
		(start 483.943914 -157.339792)
		(end 486.306114 -157.340554)
		(stroke
			(width 0.2)
			(type default)
		)
		(layer "In1.Cu")
	)
	(gr_line
		(start 483.943914 -49.350168)
		(end 483.943914 -46.149768)
		(stroke
			(width 0.2)
			(type default)
		)
		(layer "In1.Cu")
	)
	(gr_rect
		(start 483.943914 -46.810168)
		(end 486.306114 -48.689768)
		(stroke
			(width 0)
			(type default)
		)
		(fill no)
		(layer "In1.Cu")
	)
	(gr_line
		(start 483.943914 -46.149768)
		(end 486.306114 -46.149768)
		(stroke
			(width 0.2)
			(type default)
		)
		(layer "In1.Cu")
	)
	(gr_line
		(start 483.943914 -45.540168)
		(end 483.943914 -42.339768)
		(stroke
			(width 0.2)
			(type default)
		)
		(layer "In1.Cu")
	)
	(gr_rect
		(start 483.943914 -43.000168)
		(end 486.306114 -44.879768)
		(stroke
			(width 0)
			(type default)
		)
		(fill no)
		(layer "In1.Cu")
	)
	(gr_line
		(start 483.943914 -42.339768)
		(end 486.306114 -42.34053)
		(stroke
			(width 0.2)
			(type default)
		)
		(layer "In1.Cu")
	)
	(gr_line
		(start 486.306114 -279.350216)
		(end 483.943914 -279.350216)
		(stroke
			(width 0.2)
			(type default)
		)
		(layer "In1.Cu")
	)
	(gr_line
		(start 486.306114 -276.149816)
		(end 486.306114 -279.350216)
		(stroke
			(width 0.2)
			(type default)
		)
		(layer "In1.Cu")
	)
	(gr_line
		(start 486.306114 -275.540216)
		(end 483.943914 -275.540216)
		(stroke
			(width 0.2)
			(type default)
		)
		(layer "In1.Cu")
	)
	(gr_line
		(start 486.306114 -272.340578)
		(end 486.306114 -275.540216)
		(stroke
			(width 0.2)
			(type default)
		)
		(layer "In1.Cu")
	)
	(gr_line
		(start 486.306114 -164.350192)
		(end 483.943914 -164.350192)
		(stroke
			(width 0.2)
			(type default)
		)
		(layer "In1.Cu")
	)
	(gr_line
		(start 486.306114 -161.149792)
		(end 486.306114 -164.350192)
		(stroke
			(width 0.2)
			(type default)
		)
		(layer "In1.Cu")
	)
	(gr_line
		(start 486.306114 -160.540192)
		(end 483.943914 -160.540192)
		(stroke
			(width 0.2)
			(type default)
		)
		(layer "In1.Cu")
	)
	(gr_line
		(start 486.306114 -157.340554)
		(end 486.306114 -160.540192)
		(stroke
			(width 0.2)
			(type default)
		)
		(layer "In1.Cu")
	)
	(gr_line
		(start 486.306114 -49.350168)
		(end 483.943914 -49.350168)
		(stroke
			(width 0.2)
			(type default)
		)
		(layer "In1.Cu")
	)
	(gr_line
		(start 486.306114 -46.149768)
		(end 486.306114 -49.350168)
		(stroke
			(width 0.2)
			(type default)
		)
		(layer "In1.Cu")
	)
	(gr_line
		(start 486.306114 -45.540168)
		(end 483.943914 -45.540168)
		(stroke
			(width 0.2)
			(type default)
		)
		(layer "In1.Cu")
	)
	(gr_line
		(start 486.306114 -42.34053)
		(end 486.306114 -45.540168)
		(stroke
			(width 0.2)
			(type default)
		)
		(layer "In1.Cu")
	)
	(gr_line
		(start 490.450124 -349.199962)
		(end 296.69994 -349.199962)
		(stroke
			(width 1.524)
			(type default)
		)
		(layer "In1.Cu")
	)
	(gr_arc
		(start 490.450124 -349.199962)
		(mid 491.157201 -348.907059)
		(end 491.450122 -348.199964)
		(stroke
			(width 1.524)
			(type default)
		)
		(layer "In1.Cu")
	)
	(gr_arc
		(start 491.450122 -0.999998)
		(mid 491.15723 -0.292885)
		(end 490.450124 0)
		(stroke
			(width 1.524)
			(type default)
		)
		(layer "In1.Cu")
	)
	(gr_line
		(start 491.450122 -0.999998)
		(end 491.450122 -348.199964)
		(stroke
			(width 1.524)
			(type default)
		)
		(layer "In1.Cu")
	)
	(gr_line
		(start 135.09117 -31.56839)
		(end 135.10387 -31.594806)
		(stroke
			(width 0.06985)
			(type default)
		)
		(layer "In2.Cu")
	)
	(gr_line
		(start 135.569198 -32.549846)
		(end 135.588248 -32.588962)
		(stroke
			(width 0.06985)
			(type default)
		)
		(layer "In2.Cu")
	)
	(gr_line
		(start 135.588248 -32.588962)
		(end 135.62457 -32.613092)
		(stroke
			(width 0.06985)
			(type default)
		)
		(layer "In2.Cu")
	)
	(gr_line
		(start 136.068054 -30.062678)
		(end 136.150096 -30.14472)
		(stroke
			(width 0.06985)
			(type default)
		)
		(layer "In2.Cu")
	)
	(gr_line
		(start 136.068054 -29.646118)
		(end 136.150096 -29.564076)
		(stroke
			(width 0.06985)
			(type default)
		)
		(layer "In2.Cu")
	)
	(gr_line
		(start 136.150096 -30.14472)
		(end 136.150096 -30.550104)
		(stroke
			(width 0.06985)
			(type default)
		)
		(layer "In2.Cu")
	)
	(gr_line
		(start 136.150096 -29.150056)
		(end 136.150096 -29.564076)
		(stroke
			(width 0.06985)
			(type default)
		)
		(layer "In2.Cu")
	)
	(gr_line
		(start 137.977626 -34.169858)
		(end 137.992866 -34.179764)
		(stroke
			(width 0.06985)
			(type default)
		)
		(layer "In2.Cu")
	)
	(gr_line
		(start 137.992866 -34.179764)
		(end 138.010138 -34.18332)
		(stroke
			(width 0.06985)
			(type default)
		)
		(layer "In2.Cu")
	)
	(gr_line
		(start 143.003524 -35.20694)
		(end 143.0274 -35.211766)
		(stroke
			(width 0.06985)
			(type default)
		)
		(layer "In2.Cu")
	)
	(gr_line
		(start 143.0274 -35.211766)
		(end 143.051022 -35.206686)
		(stroke
			(width 0.06985)
			(type default)
		)
		(layer "In2.Cu")
	)
	(gr_line
		(start 158.89605 -31.45282)
		(end 158.919672 -31.44774)
		(stroke
			(width 0.06985)
			(type default)
		)
		(layer "In2.Cu")
	)
	(gr_line
		(start 158.919672 -31.44774)
		(end 158.943548 -31.452566)
		(stroke
			(width 0.06985)
			(type default)
		)
		(layer "In2.Cu")
	)
	(gr_line
		(start 168.069006 -33.62071)
		(end 168.092882 -33.625536)
		(stroke
			(width 0.06985)
			(type default)
		)
		(layer "In2.Cu")
	)
	(gr_line
		(start 168.092882 -33.625536)
		(end 168.116504 -33.620456)
		(stroke
			(width 0.06985)
			(type default)
		)
		(layer "In2.Cu")
	)
	(gr_line
		(start 174.610522 -31.905448)
		(end 174.634144 -31.900368)
		(stroke
			(width 0.06985)
			(type default)
		)
		(layer "In2.Cu")
	)
	(gr_line
		(start 174.634144 -31.900368)
		(end 174.65802 -31.905194)
		(stroke
			(width 0.06985)
			(type default)
		)
		(layer "In2.Cu")
	)
	(gr_line
		(start 179.960524 -33.290256)
		(end 179.9844 -33.295082)
		(stroke
			(width 0.06985)
			(type default)
		)
		(layer "In2.Cu")
	)
	(gr_line
		(start 179.9844 -33.295082)
		(end 180.008022 -33.290002)
		(stroke
			(width 0.06985)
			(type default)
		)
		(layer "In2.Cu")
	)
	(gr_line
		(start 186.77128 -31.51632)
		(end 186.794902 -31.51124)
		(stroke
			(width 0.06985)
			(type default)
		)
		(layer "In2.Cu")
	)
	(gr_line
		(start 186.794902 -31.51124)
		(end 186.818778 -31.516066)
		(stroke
			(width 0.06985)
			(type default)
		)
		(layer "In2.Cu")
	)
	(gr_line
		(start 193.965068 -33.278572)
		(end 193.98996 -33.283652)
		(stroke
			(width 0.06985)
			(type default)
		)
		(layer "In2.Cu")
	)
	(gr_line
		(start 193.98996 -33.283652)
		(end 194.016122 -33.278064)
		(stroke
			(width 0.06985)
			(type default)
		)
		(layer "In2.Cu")
	)
	(gr_line
		(start 200.433432 -31.579312)
		(end 200.457054 -31.574232)
		(stroke
			(width 0.06985)
			(type default)
		)
		(layer "In2.Cu")
	)
	(gr_line
		(start 200.457054 -31.574232)
		(end 200.48093 -31.579058)
		(stroke
			(width 0.06985)
			(type default)
		)
		(layer "In2.Cu")
	)
	(gr_line
		(start 207.065118 -33.226248)
		(end 207.088994 -33.231074)
		(stroke
			(width 0.06985)
			(type default)
		)
		(layer "In2.Cu")
	)
	(gr_line
		(start 207.088994 -33.231074)
		(end 207.112616 -33.225994)
		(stroke
			(width 0.06985)
			(type default)
		)
		(layer "In2.Cu")
	)
	(gr_line
		(start 220.59011 -29.98851)
		(end 220.613732 -29.98343)
		(stroke
			(width 0.06985)
			(type default)
		)
		(layer "In2.Cu")
	)
	(gr_line
		(start 220.613732 -29.98343)
		(end 220.637608 -29.988256)
		(stroke
			(width 0.06985)
			(type default)
		)
		(layer "In2.Cu")
	)
	(gr_line
		(start 232.29951 -32.675068)
		(end 232.908094 -32.799782)
		(stroke
			(width 0.06985)
			(type default)
		)
		(layer "In2.Cu")
	)
	(gr_line
		(start 232.322878 -32.379412)
		(end 232.485184 -32.272478)
		(stroke
			(width 0.06985)
			(type default)
		)
		(layer "In2.Cu")
	)
	(gr_line
		(start 232.485184 -32.272478)
		(end 232.895648 -32.356552)
		(stroke
			(width 0.06985)
			(type default)
		)
		(layer "In2.Cu")
	)
	(gr_line
		(start 232.895648 -32.356552)
		(end 233.002582 -32.518604)
		(stroke
			(width 0.06985)
			(type default)
		)
		(layer "In2.Cu")
	)
	(gr_line
		(start 233.394504 -32.89935)
		(end 234.003088 -33.024064)
		(stroke
			(width 0.06985)
			(type default)
		)
		(layer "In2.Cu")
	)
	(gr_line
		(start 233.417872 -32.60344)
		(end 233.579924 -32.49676)
		(stroke
			(width 0.06985)
			(type default)
		)
		(layer "In2.Cu")
	)
	(gr_line
		(start 233.579924 -32.49676)
		(end 233.990642 -32.580834)
		(stroke
			(width 0.06985)
			(type default)
		)
		(layer "In2.Cu")
	)
	(gr_line
		(start 233.990642 -32.580834)
		(end 234.097322 -32.742632)
		(stroke
			(width 0.06985)
			(type default)
		)
		(layer "In2.Cu")
	)
	(gr_line
		(start 234.488736 -33.123632)
		(end 235.097574 -33.248346)
		(stroke
			(width 0.06985)
			(type default)
		)
		(layer "In2.Cu")
	)
	(gr_line
		(start 234.512866 -32.827722)
		(end 234.674918 -32.721042)
		(stroke
			(width 0.06985)
			(type default)
		)
		(layer "In2.Cu")
	)
	(gr_line
		(start 234.674918 -32.721042)
		(end 235.085382 -32.805116)
		(stroke
			(width 0.06985)
			(type default)
		)
		(layer "In2.Cu")
	)
	(gr_line
		(start 235.085382 -32.805116)
		(end 235.192316 -32.966914)
		(stroke
			(width 0.06985)
			(type default)
		)
		(layer "In2.Cu")
	)
	(gr_line
		(start 240.549938 -35.200082)
		(end 241.294666 -35.5727)
		(stroke
			(width 0.06985)
			(type default)
		)
		(layer "In2.Cu")
	)
	(gr_line
		(start 241.294666 -35.5727)
		(end 241.478562 -35.510978)
		(stroke
			(width 0.06985)
			(type default)
		)
		(layer "In2.Cu")
	)
	(gr_line
		(start 241.744246 -35.64382)
		(end 241.80546 -35.827716)
		(stroke
			(width 0.06985)
			(type default)
		)
		(layer "In2.Cu")
	)
	(gr_line
		(start 241.80546 -35.827716)
		(end 242.549934 -36.20008)
		(stroke
			(width 0.06985)
			(type default)
		)
		(layer "In2.Cu")
	)
	(gr_line
		(start 0 -348.199964)
		(end 0 -0.999998)
		(stroke
			(width 1.524)
			(type default)
		)
		(layer "In3.Cu")
	)
	(gr_arc
		(start 0 -348.199964)
		(mid 0.292894 -348.907067)
		(end 0.999998 -349.199962)
		(stroke
			(width 1.524)
			(type default)
		)
		(layer "In3.Cu")
	)
	(gr_arc
		(start 0.999998 0)
		(mid 0.292893 -0.292893)
		(end 0 -0.999998)
		(stroke
			(width 1.524)
			(type default)
		)
		(layer "In3.Cu")
	)
	(gr_line
		(start 0.999998 0)
		(end 101.000052 0)
		(stroke
			(width 1.524)
			(type default)
		)
		(layer "In3.Cu")
	)
	(gr_arc
		(start 32.127952 -278.321516)
		(mid 32.508952 -278.702516)
		(end 32.889952 -278.321516)
		(stroke
			(width 0.2)
			(type default)
		)
		(layer "In3.Cu")
	)
	(gr_line
		(start 32.127952 -277.178516)
		(end 32.127952 -278.321516)
		(stroke
			(width 0.2)
			(type default)
		)
		(layer "In3.Cu")
	)
	(gr_arc
		(start 32.127952 -163.321492)
		(mid 32.508952 -163.702492)
		(end 32.889952 -163.321492)
		(stroke
			(width 0.2)
			(type default)
		)
		(layer "In3.Cu")
	)
	(gr_line
		(start 32.127952 -162.178492)
		(end 32.127952 -163.321492)
		(stroke
			(width 0.2)
			(type default)
		)
		(layer "In3.Cu")
	)
	(gr_arc
		(start 32.127952 -48.321468)
		(mid 32.508952 -48.702468)
		(end 32.889952 -48.321468)
		(stroke
			(width 0.2)
			(type default)
		)
		(layer "In3.Cu")
	)
	(gr_line
		(start 32.127952 -47.178468)
		(end 32.127952 -48.321468)
		(stroke
			(width 0.2)
			(type default)
		)
		(layer "In3.Cu")
	)
	(gr_line
		(start 32.889952 -278.321516)
		(end 32.889952 -277.17877)
		(stroke
			(width 0.2)
			(type default)
		)
		(layer "In3.Cu")
	)
	(gr_arc
		(start 32.889952 -277.17877)
		(mid 32.509079 -276.797516)
		(end 32.127952 -277.178516)
		(stroke
			(width 0.2)
			(type default)
		)
		(layer "In3.Cu")
	)
	(gr_line
		(start 32.889952 -163.321492)
		(end 32.889952 -162.178746)
		(stroke
			(width 0.2)
			(type default)
		)
		(layer "In3.Cu")
	)
	(gr_arc
		(start 32.889952 -162.178746)
		(mid 32.509079 -161.797492)
		(end 32.127952 -162.178492)
		(stroke
			(width 0.2)
			(type default)
		)
		(layer "In3.Cu")
	)
	(gr_line
		(start 32.889952 -48.321468)
		(end 32.889952 -47.178722)
		(stroke
			(width 0.2)
			(type default)
		)
		(layer "In3.Cu")
	)
	(gr_arc
		(start 32.889952 -47.178722)
		(mid 32.509079 -46.797468)
		(end 32.127952 -47.178468)
		(stroke
			(width 0.2)
			(type default)
		)
		(layer "In3.Cu")
	)
	(gr_arc
		(start 63.6778 -278.321516)
		(mid 64.0588 -278.702516)
		(end 64.4398 -278.321516)
		(stroke
			(width 0.2)
			(type default)
		)
		(layer "In3.Cu")
	)
	(gr_line
		(start 63.6778 -277.178516)
		(end 63.6778 -278.321516)
		(stroke
			(width 0.2)
			(type default)
		)
		(layer "In3.Cu")
	)
	(gr_arc
		(start 63.6778 -163.321492)
		(mid 64.0588 -163.702492)
		(end 64.4398 -163.321492)
		(stroke
			(width 0.2)
			(type default)
		)
		(layer "In3.Cu")
	)
	(gr_line
		(start 63.6778 -162.178492)
		(end 63.6778 -163.321492)
		(stroke
			(width 0.2)
			(type default)
		)
		(layer "In3.Cu")
	)
	(gr_arc
		(start 63.6778 -48.321468)
		(mid 64.0588 -48.702468)
		(end 64.4398 -48.321468)
		(stroke
			(width 0.2)
			(type default)
		)
		(layer "In3.Cu")
	)
	(gr_line
		(start 63.6778 -47.178468)
		(end 63.6778 -48.321468)
		(stroke
			(width 0.2)
			(type default)
		)
		(layer "In3.Cu")
	)
	(gr_line
		(start 64.4398 -278.321516)
		(end 64.4398 -277.17877)
		(stroke
			(width 0.2)
			(type default)
		)
		(layer "In3.Cu")
	)
	(gr_arc
		(start 64.4398 -277.17877)
		(mid 64.058927 -276.797516)
		(end 63.6778 -277.178516)
		(stroke
			(width 0.2)
			(type default)
		)
		(layer "In3.Cu")
	)
	(gr_line
		(start 64.4398 -163.321492)
		(end 64.4398 -162.178746)
		(stroke
			(width 0.2)
			(type default)
		)
		(layer "In3.Cu")
	)
	(gr_arc
		(start 64.4398 -162.178746)
		(mid 64.058927 -161.797492)
		(end 63.6778 -162.178492)
		(stroke
			(width 0.2)
			(type default)
		)
		(layer "In3.Cu")
	)
	(gr_line
		(start 64.4398 -48.321468)
		(end 64.4398 -47.178722)
		(stroke
			(width 0.2)
			(type default)
		)
		(layer "In3.Cu")
	)
	(gr_arc
		(start 64.4398 -47.178722)
		(mid 64.058927 -46.797468)
		(end 63.6778 -47.178468)
		(stroke
			(width 0.2)
			(type default)
		)
		(layer "In3.Cu")
	)
	(gr_arc
		(start 95.227902 -278.321516)
		(mid 95.608902 -278.702516)
		(end 95.989902 -278.321516)
		(stroke
			(width 0.2)
			(type default)
		)
		(layer "In3.Cu")
	)
	(gr_line
		(start 95.227902 -277.178516)
		(end 95.227902 -278.321516)
		(stroke
			(width 0.2)
			(type default)
		)
		(layer "In3.Cu")
	)
	(gr_arc
		(start 95.227902 -163.321492)
		(mid 95.608902 -163.702492)
		(end 95.989902 -163.321492)
		(stroke
			(width 0.2)
			(type default)
		)
		(layer "In3.Cu")
	)
	(gr_line
		(start 95.227902 -162.178492)
		(end 95.227902 -163.321492)
		(stroke
			(width 0.2)
			(type default)
		)
		(layer "In3.Cu")
	)
	(gr_arc
		(start 95.227902 -48.321468)
		(mid 95.608902 -48.702468)
		(end 95.989902 -48.321468)
		(stroke
			(width 0.2)
			(type default)
		)
		(layer "In3.Cu")
	)
	(gr_line
		(start 95.227902 -47.178468)
		(end 95.227902 -48.321468)
		(stroke
			(width 0.2)
			(type default)
		)
		(layer "In3.Cu")
	)
	(gr_line
		(start 95.989902 -278.321516)
		(end 95.989902 -277.17877)
		(stroke
			(width 0.2)
			(type default)
		)
		(layer "In3.Cu")
	)
	(gr_arc
		(start 95.989902 -277.17877)
		(mid 95.609029 -276.797516)
		(end 95.227902 -277.178516)
		(stroke
			(width 0.2)
			(type default)
		)
		(layer "In3.Cu")
	)
	(gr_line
		(start 95.989902 -163.321492)
		(end 95.989902 -162.178746)
		(stroke
			(width 0.2)
			(type default)
		)
		(layer "In3.Cu")
	)
	(gr_arc
		(start 95.989902 -162.178746)
		(mid 95.609029 -161.797492)
		(end 95.227902 -162.178492)
		(stroke
			(width 0.2)
			(type default)
		)
		(layer "In3.Cu")
	)
	(gr_line
		(start 95.989902 -48.321468)
		(end 95.989902 -47.178722)
		(stroke
			(width 0.2)
			(type default)
		)
		(layer "In3.Cu")
	)
	(gr_arc
		(start 95.989902 -47.178722)
		(mid 95.609029 -46.797468)
		(end 95.227902 -47.178468)
		(stroke
			(width 0.2)
			(type default)
		)
		(layer "In3.Cu")
	)
	(gr_arc
		(start 102.00005 -13.999972)
		(mid 102.292943 -14.707077)
		(end 103.000048 -14.99997)
		(stroke
			(width 1.524)
			(type default)
		)
		(layer "In3.Cu")
	)
	(gr_arc
		(start 102.00005 -0.999998)
		(mid 101.707154 -0.292911)
		(end 101.000052 0)
		(stroke
			(width 1.524)
			(type default)
		)
		(layer "In3.Cu")
	)
	(gr_line
		(start 102.00005 -0.999998)
		(end 102.00005 -13.999972)
		(stroke
			(width 1.524)
			(type default)
		)
		(layer "In3.Cu")
	)
	(gr_line
		(start 103.000048 -14.99997)
		(end 148.999956 -14.99997)
		(stroke
			(width 1.524)
			(type default)
		)
		(layer "In3.Cu")
	)
	(gr_arc
		(start 108.601256 -22.350222)
		(mid 109.149896 -22.898862)
		(end 109.698536 -22.350222)
		(stroke
			(width 0.2)
			(type default)
		)
		(layer "In3.Cu")
	)
	(gr_line
		(start 108.601256 -20.950174)
		(end 108.601256 -22.350222)
		(stroke
			(width 0.2)
			(type default)
		)
		(layer "In3.Cu")
	)
	(gr_arc
		(start 108.601256 -18.750026)
		(mid 109.149896 -19.298666)
		(end 109.698536 -18.750026)
		(stroke
			(width 0.2)
			(type default)
		)
		(layer "In3.Cu")
	)
	(gr_line
		(start 108.601256 -17.349978)
		(end 108.601256 -18.750026)
		(stroke
			(width 0.2)
			(type default)
		)
		(layer "In3.Cu")
	)
	(gr_line
		(start 109.698536 -22.350222)
		(end 109.698536 -20.950428)
		(stroke
			(width 0.2)
			(type default)
		)
		(layer "In3.Cu")
	)
	(gr_arc
		(start 109.698536 -20.950428)
		(mid 109.150023 -20.401534)
		(end 108.601256 -20.950174)
		(stroke
			(width 0.2)
			(type default)
		)
		(layer "In3.Cu")
	)
	(gr_line
		(start 109.698536 -18.750026)
		(end 109.698536 -17.350232)
		(stroke
			(width 0.2)
			(type default)
		)
		(layer "In3.Cu")
	)
	(gr_arc
		(start 109.698536 -17.350232)
		(mid 109.150023 -16.801338)
		(end 108.601256 -17.349978)
		(stroke
			(width 0.2)
			(type default)
		)
		(layer "In3.Cu")
	)
	(gr_arc
		(start 110.401354 -23.35022)
		(mid 110.949994 -23.89886)
		(end 111.498634 -23.35022)
		(stroke
			(width 0.2)
			(type default)
		)
		(layer "In3.Cu")
	)
	(gr_line
		(start 110.401354 -21.950172)
		(end 110.401354 -23.35022)
		(stroke
			(width 0.2)
			(type default)
		)
		(layer "In3.Cu")
	)
	(gr_arc
		(start 110.401354 -19.750024)
		(mid 110.949994 -20.298664)
		(end 111.498634 -19.750024)
		(stroke
			(width 0.2)
			(type default)
		)
		(layer "In3.Cu")
	)
	(gr_line
		(start 110.401354 -18.35023)
		(end 110.401354 -19.750024)
		(stroke
			(width 0.2)
			(type default)
		)
		(layer "In3.Cu")
	)
	(gr_line
		(start 111.498634 -23.35022)
		(end 111.498634 -21.950426)
		(stroke
			(width 0.2)
			(type default)
		)
		(layer "In3.Cu")
	)
	(gr_arc
		(start 111.498634 -21.950426)
		(mid 110.950121 -21.401532)
		(end 110.401354 -21.950172)
		(stroke
			(width 0.2)
			(type default)
		)
		(layer "In3.Cu")
	)
	(gr_line
		(start 111.498634 -19.750024)
		(end 111.498634 -18.350484)
		(stroke
			(width 0.2)
			(type default)
		)
		(layer "In3.Cu")
	)
	(gr_arc
		(start 111.498634 -18.350484)
		(mid 110.950121 -17.80159)
		(end 110.401354 -18.35023)
		(stroke
			(width 0.2)
			(type default)
		)
		(layer "In3.Cu")
	)
	(gr_arc
		(start 112.201452 -22.350222)
		(mid 112.750092 -22.898862)
		(end 113.298732 -22.350222)
		(stroke
			(width 0.2)
			(type default)
		)
		(layer "In3.Cu")
	)
	(gr_line
		(start 112.201452 -20.950174)
		(end 112.201452 -22.350222)
		(stroke
			(width 0.2)
			(type default)
		)
		(layer "In3.Cu")
	)
	(gr_arc
		(start 112.201452 -18.750026)
		(mid 112.750092 -19.298666)
		(end 113.298732 -18.750026)
		(stroke
			(width 0.2)
			(type default)
		)
		(layer "In3.Cu")
	)
	(gr_line
		(start 112.201452 -17.349978)
		(end 112.201452 -18.750026)
		(stroke
			(width 0.2)
			(type default)
		)
		(layer "In3.Cu")
	)
	(gr_line
		(start 113.298732 -22.350222)
		(end 113.298732 -20.950428)
		(stroke
			(width 0.2)
			(type default)
		)
		(layer "In3.Cu")
	)
	(gr_arc
		(start 113.298732 -20.950428)
		(mid 112.750219 -20.401534)
		(end 112.201452 -20.950174)
		(stroke
			(width 0.2)
			(type default)
		)
		(layer "In3.Cu")
	)
	(gr_line
		(start 113.298732 -18.750026)
		(end 113.298732 -17.350232)
		(stroke
			(width 0.2)
			(type default)
		)
		(layer "In3.Cu")
	)
	(gr_arc
		(start 113.298732 -17.350232)
		(mid 112.750219 -16.801338)
		(end 112.201452 -17.349978)
		(stroke
			(width 0.2)
			(type default)
		)
		(layer "In3.Cu")
	)
	(gr_arc
		(start 114.001296 -23.35022)
		(mid 114.549936 -23.89886)
		(end 115.098576 -23.35022)
		(stroke
			(width 0.2)
			(type default)
		)
		(layer "In3.Cu")
	)
	(gr_line
		(start 114.001296 -21.950172)
		(end 114.001296 -23.35022)
		(stroke
			(width 0.2)
			(type default)
		)
		(layer "In3.Cu")
	)
	(gr_arc
		(start 114.001296 -19.750024)
		(mid 114.549936 -20.298664)
		(end 115.098576 -19.750024)
		(stroke
			(width 0.2)
			(type default)
		)
		(layer "In3.Cu")
	)
	(gr_line
		(start 114.001296 -18.35023)
		(end 114.001296 -19.750024)
		(stroke
			(width 0.2)
			(type default)
		)
		(layer "In3.Cu")
	)
	(gr_line
		(start 115.098576 -23.35022)
		(end 115.098576 -21.950426)
		(stroke
			(width 0.2)
			(type default)
		)
		(layer "In3.Cu")
	)
	(gr_arc
		(start 115.098576 -21.950426)
		(mid 114.550063 -21.401532)
		(end 114.001296 -21.950172)
		(stroke
			(width 0.2)
			(type default)
		)
		(layer "In3.Cu")
	)
	(gr_line
		(start 115.098576 -19.750024)
		(end 115.098576 -18.350484)
		(stroke
			(width 0.2)
			(type default)
		)
		(layer "In3.Cu")
	)
	(gr_arc
		(start 115.098576 -18.350484)
		(mid 114.550063 -17.80159)
		(end 114.001296 -18.35023)
		(stroke
			(width 0.2)
			(type default)
		)
		(layer "In3.Cu")
	)
	(gr_arc
		(start 115.801394 -29.550106)
		(mid 116.350034 -30.098746)
		(end 116.898674 -29.550106)
		(stroke
			(width 0.2)
			(type default)
		)
		(layer "In3.Cu")
	)
	(gr_line
		(start 115.801394 -28.150058)
		(end 115.801394 -29.550106)
		(stroke
			(width 0.2)
			(type default)
		)
		(layer "In3.Cu")
	)
	(gr_arc
		(start 115.801394 -22.350222)
		(mid 116.350034 -22.898862)
		(end 116.898674 -22.350222)
		(stroke
			(width 0.2)
			(type default)
		)
		(layer "In3.Cu")
	)
	(gr_line
		(start 115.801394 -20.950174)
		(end 115.801394 -22.350222)
		(stroke
			(width 0.2)
			(type default)
		)
		(layer "In3.Cu")
	)
	(gr_arc
		(start 115.801394 -18.750026)
		(mid 116.350034 -19.298666)
		(end 116.898674 -18.750026)
		(stroke
			(width 0.2)
			(type default)
		)
		(layer "In3.Cu")
	)
	(gr_line
		(start 115.801394 -17.349978)
		(end 115.801394 -18.750026)
		(stroke
			(width 0.2)
			(type default)
		)
		(layer "In3.Cu")
	)
	(gr_line
		(start 116.898674 -29.550106)
		(end 116.898674 -28.150312)
		(stroke
			(width 0.2)
			(type default)
		)
		(layer "In3.Cu")
	)
	(gr_arc
		(start 116.898674 -28.150312)
		(mid 116.350161 -27.601418)
		(end 115.801394 -28.150058)
		(stroke
			(width 0.2)
			(type default)
		)
		(layer "In3.Cu")
	)
	(gr_line
		(start 116.898674 -22.350222)
		(end 116.898674 -20.950428)
		(stroke
			(width 0.2)
			(type default)
		)
		(layer "In3.Cu")
	)
	(gr_arc
		(start 116.898674 -20.950428)
		(mid 116.350161 -20.401534)
		(end 115.801394 -20.950174)
		(stroke
			(width 0.2)
			(type default)
		)
		(layer "In3.Cu")
	)
	(gr_line
		(start 116.898674 -18.750026)
		(end 116.898674 -17.350232)
		(stroke
			(width 0.2)
			(type default)
		)
		(layer "In3.Cu")
	)
	(gr_arc
		(start 116.898674 -17.350232)
		(mid 116.350161 -16.801338)
		(end 115.801394 -17.349978)
		(stroke
			(width 0.2)
			(type default)
		)
		(layer "In3.Cu")
	)
	(gr_arc
		(start 117.601238 -23.35022)
		(mid 118.149878 -23.89886)
		(end 118.698518 -23.35022)
		(stroke
			(width 0.2)
			(type default)
		)
		(layer "In3.Cu")
	)
	(gr_line
		(start 117.601238 -21.950172)
		(end 117.601238 -23.35022)
		(stroke
			(width 0.2)
			(type default)
		)
		(layer "In3.Cu")
	)
	(gr_arc
		(start 117.601238 -19.750024)
		(mid 118.149878 -20.298664)
		(end 118.698518 -19.750024)
		(stroke
			(width 0.2)
			(type default)
		)
		(layer "In3.Cu")
	)
	(gr_line
		(start 117.601238 -18.35023)
		(end 117.601238 -19.750024)
		(stroke
			(width 0.2)
			(type default)
		)
		(layer "In3.Cu")
	)
	(gr_line
		(start 118.698518 -23.35022)
		(end 118.698518 -21.950426)
		(stroke
			(width 0.2)
			(type default)
		)
		(layer "In3.Cu")
	)
	(gr_arc
		(start 118.698518 -21.950426)
		(mid 118.150005 -21.401532)
		(end 117.601238 -21.950172)
		(stroke
			(width 0.2)
			(type default)
		)
		(layer "In3.Cu")
	)
	(gr_line
		(start 118.698518 -19.750024)
		(end 118.698518 -18.350484)
		(stroke
			(width 0.2)
			(type default)
		)
		(layer "In3.Cu")
	)
	(gr_arc
		(start 118.698518 -18.350484)
		(mid 118.150005 -17.80159)
		(end 117.601238 -18.35023)
		(stroke
			(width 0.2)
			(type default)
		)
		(layer "In3.Cu")
	)
	(gr_arc
		(start 119.401336 -22.350222)
		(mid 119.949976 -22.898862)
		(end 120.498616 -22.350222)
		(stroke
			(width 0.2)
			(type default)
		)
		(layer "In3.Cu")
	)
	(gr_line
		(start 119.401336 -20.950174)
		(end 119.401336 -22.350222)
		(stroke
			(width 0.2)
			(type default)
		)
		(layer "In3.Cu")
	)
	(gr_arc
		(start 119.401336 -18.750026)
		(mid 119.949976 -19.298666)
		(end 120.498616 -18.750026)
		(stroke
			(width 0.2)
			(type default)
		)
		(layer "In3.Cu")
	)
	(gr_line
		(start 119.401336 -17.349978)
		(end 119.401336 -18.750026)
		(stroke
			(width 0.2)
			(type default)
		)
		(layer "In3.Cu")
	)
	(gr_line
		(start 120.498616 -22.350222)
		(end 120.498616 -20.950428)
		(stroke
			(width 0.2)
			(type default)
		)
		(layer "In3.Cu")
	)
	(gr_arc
		(start 120.498616 -20.950428)
		(mid 119.950103 -20.401534)
		(end 119.401336 -20.950174)
		(stroke
			(width 0.2)
			(type default)
		)
		(layer "In3.Cu")
	)
	(gr_line
		(start 120.498616 -18.750026)
		(end 120.498616 -17.350232)
		(stroke
			(width 0.2)
			(type default)
		)
		(layer "In3.Cu")
	)
	(gr_arc
		(start 120.498616 -17.350232)
		(mid 119.950103 -16.801338)
		(end 119.401336 -17.349978)
		(stroke
			(width 0.2)
			(type default)
		)
		(layer "In3.Cu")
	)
	(gr_arc
		(start 121.198894 -30.54985)
		(mid 121.749947 -31.101284)
		(end 122.301254 -30.550104)
		(stroke
			(width 0.2)
			(type default)
		)
		(layer "In3.Cu")
	)
	(gr_line
		(start 121.198894 -29.150056)
		(end 121.198894 -30.54985)
		(stroke
			(width 0.2)
			(type default)
		)
		(layer "In3.Cu")
	)
	(gr_arc
		(start 121.201434 -23.35022)
		(mid 121.750074 -23.89886)
		(end 122.298714 -23.35022)
		(stroke
			(width 0.2)
			(type default)
		)
		(layer "In3.Cu")
	)
	(gr_line
		(start 121.201434 -21.950172)
		(end 121.201434 -23.35022)
		(stroke
			(width 0.2)
			(type default)
		)
		(layer "In3.Cu")
	)
	(gr_arc
		(start 121.201434 -19.750024)
		(mid 121.750074 -20.298664)
		(end 122.298714 -19.750024)
		(stroke
			(width 0.2)
			(type default)
		)
		(layer "In3.Cu")
	)
	(gr_line
		(start 121.201434 -18.35023)
		(end 121.201434 -19.750024)
		(stroke
			(width 0.2)
			(type default)
		)
		(layer "In3.Cu")
	)
	(gr_line
		(start 122.298714 -23.35022)
		(end 122.298714 -21.950426)
		(stroke
			(width 0.2)
			(type default)
		)
		(layer "In3.Cu")
	)
	(gr_arc
		(start 122.298714 -21.950426)
		(mid 121.750201 -21.401532)
		(end 121.201434 -21.950172)
		(stroke
			(width 0.2)
			(type default)
		)
		(layer "In3.Cu")
	)
	(gr_line
		(start 122.298714 -19.750024)
		(end 122.298714 -18.350484)
		(stroke
			(width 0.2)
			(type default)
		)
		(layer "In3.Cu")
	)
	(gr_arc
		(start 122.298714 -18.350484)
		(mid 121.750201 -17.80159)
		(end 121.201434 -18.35023)
		(stroke
			(width 0.2)
			(type default)
		)
		(layer "In3.Cu")
	)
	(gr_line
		(start 122.301254 -30.550104)
		(end 122.301254 -29.150056)
		(stroke
			(width 0.2)
			(type default)
		)
		(layer "In3.Cu")
	)
	(gr_arc
		(start 122.301254 -29.150056)
		(mid 121.750074 -28.598876)
		(end 121.198894 -29.150056)
		(stroke
			(width 0.2)
			(type default)
		)
		(layer "In3.Cu")
	)
	(gr_arc
		(start 126.77775 -278.321516)
		(mid 127.15875 -278.702516)
		(end 127.53975 -278.321516)
		(stroke
			(width 0.2)
			(type default)
		)
		(layer "In3.Cu")
	)
	(gr_line
		(start 126.77775 -277.178516)
		(end 126.77775 -278.321516)
		(stroke
			(width 0.2)
			(type default)
		)
		(layer "In3.Cu")
	)
	(gr_arc
		(start 126.77775 -163.321492)
		(mid 127.15875 -163.702492)
		(end 127.53975 -163.321492)
		(stroke
			(width 0.2)
			(type default)
		)
		(layer "In3.Cu")
	)
	(gr_line
		(start 126.77775 -162.178492)
		(end 126.77775 -163.321492)
		(stroke
			(width 0.2)
			(type default)
		)
		(layer "In3.Cu")
	)
	(gr_arc
		(start 126.77775 -48.321468)
		(mid 127.15875 -48.702468)
		(end 127.53975 -48.321468)
		(stroke
			(width 0.2)
			(type default)
		)
		(layer "In3.Cu")
	)
	(gr_line
		(start 126.77775 -47.178468)
		(end 126.77775 -48.321468)
		(stroke
			(width 0.2)
			(type default)
		)
		(layer "In3.Cu")
	)
	(gr_line
		(start 127.53975 -278.321516)
		(end 127.53975 -277.17877)
		(stroke
			(width 0.2)
			(type default)
		)
		(layer "In3.Cu")
	)
	(gr_arc
		(start 127.53975 -277.17877)
		(mid 127.158877 -276.797516)
		(end 126.77775 -277.178516)
		(stroke
			(width 0.2)
			(type default)
		)
		(layer "In3.Cu")
	)
	(gr_line
		(start 127.53975 -163.321492)
		(end 127.53975 -162.178746)
		(stroke
			(width 0.2)
			(type default)
		)
		(layer "In3.Cu")
	)
	(gr_arc
		(start 127.53975 -162.178746)
		(mid 127.158877 -161.797492)
		(end 126.77775 -162.178492)
		(stroke
			(width 0.2)
			(type default)
		)
		(layer "In3.Cu")
	)
	(gr_line
		(start 127.53975 -48.321468)
		(end 127.53975 -47.178722)
		(stroke
			(width 0.2)
			(type default)
		)
		(layer "In3.Cu")
	)
	(gr_arc
		(start 127.53975 -47.178722)
		(mid 127.158877 -46.797468)
		(end 126.77775 -47.178468)
		(stroke
			(width 0.2)
			(type default)
		)
		(layer "In3.Cu")
	)
	(gr_arc
		(start 130.201416 -22.350222)
		(mid 130.750056 -22.898862)
		(end 131.298696 -22.350222)
		(stroke
			(width 0.2)
			(type default)
		)
		(layer "In3.Cu")
	)
	(gr_line
		(start 130.201416 -20.950174)
		(end 130.201416 -22.350222)
		(stroke
			(width 0.2)
			(type default)
		)
		(layer "In3.Cu")
	)
	(gr_arc
		(start 130.201416 -18.750026)
		(mid 130.750056 -19.298666)
		(end 131.298696 -18.750026)
		(stroke
			(width 0.2)
			(type default)
		)
		(layer "In3.Cu")
	)
	(gr_line
		(start 130.201416 -17.349978)
		(end 130.201416 -18.750026)
		(stroke
			(width 0.2)
			(type default)
		)
		(layer "In3.Cu")
	)
	(gr_line
		(start 131.298696 -22.350222)
		(end 131.298696 -20.950428)
		(stroke
			(width 0.2)
			(type default)
		)
		(layer "In3.Cu")
	)
	(gr_arc
		(start 131.298696 -20.950428)
		(mid 130.750183 -20.401534)
		(end 130.201416 -20.950174)
		(stroke
			(width 0.2)
			(type default)
		)
		(layer "In3.Cu")
	)
	(gr_line
		(start 131.298696 -18.750026)
		(end 131.298696 -17.350232)
		(stroke
			(width 0.2)
			(type default)
		)
		(layer "In3.Cu")
	)
	(gr_arc
		(start 131.298696 -17.350232)
		(mid 130.750183 -16.801338)
		(end 130.201416 -17.349978)
		(stroke
			(width 0.2)
			(type default)
		)
		(layer "In3.Cu")
	)
	(gr_arc
		(start 132.00126 -23.35022)
		(mid 132.5499 -23.89886)
		(end 133.09854 -23.35022)
		(stroke
			(width 0.2)
			(type default)
		)
		(layer "In3.Cu")
	)
	(gr_line
		(start 132.00126 -21.950172)
		(end 132.00126 -23.35022)
		(stroke
			(width 0.2)
			(type default)
		)
		(layer "In3.Cu")
	)
	(gr_arc
		(start 132.00126 -19.74977)
		(mid 132.549773 -20.298664)
		(end 133.09854 -19.750024)
		(stroke
			(width 0.2)
			(type default)
		)
		(layer "In3.Cu")
	)
	(gr_line
		(start 132.00126 -18.35023)
		(end 132.00126 -19.74977)
		(stroke
			(width 0.2)
			(type default)
		)
		(layer "In3.Cu")
	)
	(gr_line
		(start 133.09854 -23.35022)
		(end 133.09854 -21.950426)
		(stroke
			(width 0.2)
			(type default)
		)
		(layer "In3.Cu")
	)
	(gr_arc
		(start 133.09854 -21.950426)
		(mid 132.550027 -21.401532)
		(end 132.00126 -21.950172)
		(stroke
			(width 0.2)
			(type default)
		)
		(layer "In3.Cu")
	)
	(gr_line
		(start 133.09854 -19.750024)
		(end 133.09854 -18.35023)
		(stroke
			(width 0.2)
			(type default)
		)
		(layer "In3.Cu")
	)
	(gr_arc
		(start 133.09854 -18.35023)
		(mid 132.5499 -17.80159)
		(end 132.00126 -18.35023)
		(stroke
			(width 0.2)
			(type default)
		)
		(layer "In3.Cu")
	)
	(gr_arc
		(start 133.801358 -22.350222)
		(mid 134.349998 -22.898862)
		(end 134.898638 -22.350222)
		(stroke
			(width 0.2)
			(type default)
		)
		(layer "In3.Cu")
	)
	(gr_line
		(start 133.801358 -20.950174)
		(end 133.801358 -22.350222)
		(stroke
			(width 0.2)
			(type default)
		)
		(layer "In3.Cu")
	)
	(gr_arc
		(start 133.801358 -18.750026)
		(mid 134.349998 -19.298666)
		(end 134.898638 -18.750026)
		(stroke
			(width 0.2)
			(type default)
		)
		(layer "In3.Cu")
	)
	(gr_line
		(start 133.801358 -17.349978)
		(end 133.801358 -18.750026)
		(stroke
			(width 0.2)
			(type default)
		)
		(layer "In3.Cu")
	)
	(gr_line
		(start 134.898638 -22.350222)
		(end 134.898638 -20.950428)
		(stroke
			(width 0.2)
			(type default)
		)
		(layer "In3.Cu")
	)
	(gr_arc
		(start 134.898638 -20.950428)
		(mid 134.350125 -20.401534)
		(end 133.801358 -20.950174)
		(stroke
			(width 0.2)
			(type default)
		)
		(layer "In3.Cu")
	)
	(gr_line
		(start 134.898638 -18.750026)
		(end 134.898638 -17.350232)
		(stroke
			(width 0.2)
			(type default)
		)
		(layer "In3.Cu")
	)
	(gr_arc
		(start 134.898638 -17.350232)
		(mid 134.350125 -16.801338)
		(end 133.801358 -17.349978)
		(stroke
			(width 0.2)
			(type default)
		)
		(layer "In3.Cu")
	)
	(gr_arc
		(start 135.601456 -30.550104)
		(mid 136.150096 -31.098744)
		(end 136.698736 -30.550104)
		(stroke
			(width 0.2)
			(type default)
		)
		(layer "In3.Cu")
	)
	(gr_line
		(start 135.601456 -29.150056)
		(end 135.601456 -30.550104)
		(stroke
			(width 0.2)
			(type default)
		)
		(layer "In3.Cu")
	)
	(gr_arc
		(start 135.601456 -23.35022)
		(mid 136.150096 -23.89886)
		(end 136.698736 -23.35022)
		(stroke
			(width 0.2)
			(type default)
		)
		(layer "In3.Cu")
	)
	(gr_line
		(start 135.601456 -21.950172)
		(end 135.601456 -23.35022)
		(stroke
			(width 0.2)
			(type default)
		)
		(layer "In3.Cu")
	)
	(gr_arc
		(start 135.601456 -19.750024)
		(mid 136.150096 -20.298664)
		(end 136.698736 -19.750024)
		(stroke
			(width 0.2)
			(type default)
		)
		(layer "In3.Cu")
	)
	(gr_line
		(start 135.601456 -18.35023)
		(end 135.601456 -19.750024)
		(stroke
			(width 0.2)
			(type default)
		)
		(layer "In3.Cu")
	)
	(gr_line
		(start 136.698736 -30.550104)
		(end 136.698736 -29.15031)
		(stroke
			(width 0.2)
			(type default)
		)
		(layer "In3.Cu")
	)
	(gr_arc
		(start 136.698736 -29.15031)
		(mid 136.150223 -28.601416)
		(end 135.601456 -29.150056)
		(stroke
			(width 0.2)
			(type default)
		)
		(layer "In3.Cu")
	)
	(gr_line
		(start 136.698736 -23.35022)
		(end 136.698736 -21.950426)
		(stroke
			(width 0.2)
			(type default)
		)
		(layer "In3.Cu")
	)
	(gr_arc
		(start 136.698736 -21.950426)
		(mid 136.150223 -21.401532)
		(end 135.601456 -21.950172)
		(stroke
			(width 0.2)
			(type default)
		)
		(layer "In3.Cu")
	)
	(gr_line
		(start 136.698736 -19.750024)
		(end 136.698736 -18.350484)
		(stroke
			(width 0.2)
			(type default)
		)
		(layer "In3.Cu")
	)
	(gr_arc
		(start 136.698736 -18.350484)
		(mid 136.150223 -17.80159)
		(end 135.601456 -18.35023)
		(stroke
			(width 0.2)
			(type default)
		)
		(layer "In3.Cu")
	)
	(gr_arc
		(start 137.4013 -22.350222)
		(mid 137.94994 -22.898862)
		(end 138.49858 -22.350222)
		(stroke
			(width 0.2)
			(type default)
		)
		(layer "In3.Cu")
	)
	(gr_line
		(start 137.4013 -20.950174)
		(end 137.4013 -22.350222)
		(stroke
			(width 0.2)
			(type default)
		)
		(layer "In3.Cu")
	)
	(gr_arc
		(start 137.4013 -18.750026)
		(mid 137.94994 -19.298666)
		(end 138.49858 -18.750026)
		(stroke
			(width 0.2)
			(type default)
		)
		(layer "In3.Cu")
	)
	(gr_line
		(start 137.4013 -17.349978)
		(end 137.4013 -18.750026)
		(stroke
			(width 0.2)
			(type default)
		)
		(layer "In3.Cu")
	)
	(gr_line
		(start 138.49858 -22.350222)
		(end 138.49858 -20.950428)
		(stroke
			(width 0.2)
			(type default)
		)
		(layer "In3.Cu")
	)
	(gr_arc
		(start 138.49858 -20.950428)
		(mid 137.950067 -20.401534)
		(end 137.4013 -20.950174)
		(stroke
			(width 0.2)
			(type default)
		)
		(layer "In3.Cu")
	)
	(gr_line
		(start 138.49858 -18.750026)
		(end 138.49858 -17.350232)
		(stroke
			(width 0.2)
			(type default)
		)
		(layer "In3.Cu")
	)
	(gr_arc
		(start 138.49858 -17.350232)
		(mid 137.950067 -16.801338)
		(end 137.4013 -17.349978)
		(stroke
			(width 0.2)
			(type default)
		)
		(layer "In3.Cu")
	)
	(gr_arc
		(start 139.201398 -23.35022)
		(mid 139.750038 -23.89886)
		(end 140.298678 -23.35022)
		(stroke
			(width 0.2)
			(type default)
		)
		(layer "In3.Cu")
	)
	(gr_line
		(start 139.201398 -21.950172)
		(end 139.201398 -23.35022)
		(stroke
			(width 0.2)
			(type default)
		)
		(layer "In3.Cu")
	)
	(gr_arc
		(start 139.201398 -19.750024)
		(mid 139.750038 -20.298664)
		(end 140.298678 -19.750024)
		(stroke
			(width 0.2)
			(type default)
		)
		(layer "In3.Cu")
	)
	(gr_line
		(start 139.201398 -18.35023)
		(end 139.201398 -19.750024)
		(stroke
			(width 0.2)
			(type default)
		)
		(layer "In3.Cu")
	)
	(gr_line
		(start 140.298678 -23.35022)
		(end 140.298678 -21.950426)
		(stroke
			(width 0.2)
			(type default)
		)
		(layer "In3.Cu")
	)
	(gr_arc
		(start 140.298678 -21.950426)
		(mid 139.750165 -21.401532)
		(end 139.201398 -21.950172)
		(stroke
			(width 0.2)
			(type default)
		)
		(layer "In3.Cu")
	)
	(gr_line
		(start 140.298678 -19.750024)
		(end 140.298678 -18.350484)
		(stroke
			(width 0.2)
			(type default)
		)
		(layer "In3.Cu")
	)
	(gr_arc
		(start 140.298678 -18.350484)
		(mid 139.750165 -17.80159)
		(end 139.201398 -18.35023)
		(stroke
			(width 0.2)
			(type default)
		)
		(layer "In3.Cu")
	)
	(gr_arc
		(start 141.001242 -22.350222)
		(mid 141.549882 -22.898862)
		(end 142.098522 -22.350222)
		(stroke
			(width 0.2)
			(type default)
		)
		(layer "In3.Cu")
	)
	(gr_line
		(start 141.001242 -20.950174)
		(end 141.001242 -22.350222)
		(stroke
			(width 0.2)
			(type default)
		)
		(layer "In3.Cu")
	)
	(gr_arc
		(start 141.001242 -18.750026)
		(mid 141.549882 -19.298666)
		(end 142.098522 -18.750026)
		(stroke
			(width 0.2)
			(type default)
		)
		(layer "In3.Cu")
	)
	(gr_line
		(start 141.001242 -17.349978)
		(end 141.001242 -18.750026)
		(stroke
			(width 0.2)
			(type default)
		)
		(layer "In3.Cu")
	)
	(gr_line
		(start 142.098522 -22.350222)
		(end 142.098522 -20.950428)
		(stroke
			(width 0.2)
			(type default)
		)
		(layer "In3.Cu")
	)
	(gr_arc
		(start 142.098522 -20.950428)
		(mid 141.550009 -20.401534)
		(end 141.001242 -20.950174)
		(stroke
			(width 0.2)
			(type default)
		)
		(layer "In3.Cu")
	)
	(gr_line
		(start 142.098522 -18.750026)
		(end 142.098522 -17.350232)
		(stroke
			(width 0.2)
			(type default)
		)
		(layer "In3.Cu")
	)
	(gr_arc
		(start 142.098522 -17.350232)
		(mid 141.550009 -16.801338)
		(end 141.001242 -17.349978)
		(stroke
			(width 0.2)
			(type default)
		)
		(layer "In3.Cu")
	)
	(gr_arc
		(start 142.80134 -30.550104)
		(mid 143.34998 -31.098744)
		(end 143.89862 -30.550104)
		(stroke
			(width 0.2)
			(type default)
		)
		(layer "In3.Cu")
	)
	(gr_line
		(start 142.80134 -29.150056)
		(end 142.80134 -30.550104)
		(stroke
			(width 0.2)
			(type default)
		)
		(layer "In3.Cu")
	)
	(gr_arc
		(start 142.80134 -23.35022)
		(mid 143.34998 -23.89886)
		(end 143.89862 -23.35022)
		(stroke
			(width 0.2)
			(type default)
		)
		(layer "In3.Cu")
	)
	(gr_line
		(start 142.80134 -21.950172)
		(end 142.80134 -23.35022)
		(stroke
			(width 0.2)
			(type default)
		)
		(layer "In3.Cu")
	)
	(gr_arc
		(start 142.80134 -19.750024)
		(mid 143.34998 -20.298664)
		(end 143.89862 -19.750024)
		(stroke
			(width 0.2)
			(type default)
		)
		(layer "In3.Cu")
	)
	(gr_line
		(start 142.80134 -18.35023)
		(end 142.80134 -19.750024)
		(stroke
			(width 0.2)
			(type default)
		)
		(layer "In3.Cu")
	)
	(gr_line
		(start 143.89862 -30.550104)
		(end 143.89862 -29.15031)
		(stroke
			(width 0.2)
			(type default)
		)
		(layer "In3.Cu")
	)
	(gr_arc
		(start 143.89862 -29.15031)
		(mid 143.350107 -28.601416)
		(end 142.80134 -29.150056)
		(stroke
			(width 0.2)
			(type default)
		)
		(layer "In3.Cu")
	)
	(gr_line
		(start 143.89862 -23.35022)
		(end 143.89862 -21.950426)
		(stroke
			(width 0.2)
			(type default)
		)
		(layer "In3.Cu")
	)
	(gr_arc
		(start 143.89862 -21.950426)
		(mid 143.350107 -21.401532)
		(end 142.80134 -21.950172)
		(stroke
			(width 0.2)
			(type default)
		)
		(layer "In3.Cu")
	)
	(gr_line
		(start 143.89862 -19.750024)
		(end 143.89862 -18.350484)
		(stroke
			(width 0.2)
			(type default)
		)
		(layer "In3.Cu")
	)
	(gr_arc
		(start 143.89862 -18.350484)
		(mid 143.350107 -17.80159)
		(end 142.80134 -18.35023)
		(stroke
			(width 0.2)
			(type default)
		)
		(layer "In3.Cu")
	)
	(gr_arc
		(start 148.999956 -14.99997)
		(mid 149.707061 -14.707077)
		(end 149.999954 -13.999972)
		(stroke
			(width 1.524)
			(type default)
		)
		(layer "In3.Cu")
	)
	(gr_line
		(start 149.999954 -13.999972)
		(end 149.999954 -0.999998)
		(stroke
			(width 1.524)
			(type default)
		)
		(layer "In3.Cu")
	)
	(gr_arc
		(start 150.999952 0)
		(mid 150.292877 -0.292909)
		(end 149.999954 -0.999998)
		(stroke
			(width 1.524)
			(type default)
		)
		(layer "In3.Cu")
	)
	(gr_line
		(start 150.999952 0)
		(end 199.00011 0)
		(stroke
			(width 1.524)
			(type default)
		)
		(layer "In3.Cu")
	)
	(gr_arc
		(start 158.327852 -278.321516)
		(mid 158.708852 -278.702516)
		(end 159.089852 -278.321516)
		(stroke
			(width 0.2)
			(type default)
		)
		(layer "In3.Cu")
	)
	(gr_line
		(start 158.327852 -277.178516)
		(end 158.327852 -278.321516)
		(stroke
			(width 0.2)
			(type default)
		)
		(layer "In3.Cu")
	)
	(gr_arc
		(start 158.327852 -163.321492)
		(mid 158.708852 -163.702492)
		(end 159.089852 -163.321492)
		(stroke
			(width 0.2)
			(type default)
		)
		(layer "In3.Cu")
	)
	(gr_line
		(start 158.327852 -162.178492)
		(end 158.327852 -163.321492)
		(stroke
			(width 0.2)
			(type default)
		)
		(layer "In3.Cu")
	)
	(gr_arc
		(start 158.327852 -48.321468)
		(mid 158.708852 -48.702468)
		(end 159.089852 -48.321468)
		(stroke
			(width 0.2)
			(type default)
		)
		(layer "In3.Cu")
	)
	(gr_line
		(start 158.327852 -47.178468)
		(end 158.327852 -48.321468)
		(stroke
			(width 0.2)
			(type default)
		)
		(layer "In3.Cu")
	)
	(gr_line
		(start 159.089852 -278.321516)
		(end 159.089852 -277.17877)
		(stroke
			(width 0.2)
			(type default)
		)
		(layer "In3.Cu")
	)
	(gr_arc
		(start 159.089852 -277.17877)
		(mid 158.708979 -276.797516)
		(end 158.327852 -277.178516)
		(stroke
			(width 0.2)
			(type default)
		)
		(layer "In3.Cu")
	)
	(gr_line
		(start 159.089852 -163.321492)
		(end 159.089852 -162.178746)
		(stroke
			(width 0.2)
			(type default)
		)
		(layer "In3.Cu")
	)
	(gr_arc
		(start 159.089852 -162.178746)
		(mid 158.708979 -161.797492)
		(end 158.327852 -162.178492)
		(stroke
			(width 0.2)
			(type default)
		)
		(layer "In3.Cu")
	)
	(gr_line
		(start 159.089852 -48.321468)
		(end 159.089852 -47.178722)
		(stroke
			(width 0.2)
			(type default)
		)
		(layer "In3.Cu")
	)
	(gr_arc
		(start 159.089852 -47.178722)
		(mid 158.708979 -46.797468)
		(end 158.327852 -47.178468)
		(stroke
			(width 0.2)
			(type default)
		)
		(layer "In3.Cu")
	)
	(gr_line
		(start 189.6999 -349.199962)
		(end 0.999998 -349.199962)
		(stroke
			(width 1.524)
			(type default)
		)
		(layer "In3.Cu")
	)
	(gr_arc
		(start 189.877954 -278.321516)
		(mid 190.258954 -278.702516)
		(end 190.639954 -278.321516)
		(stroke
			(width 0.2)
			(type default)
		)
		(layer "In3.Cu")
	)
	(gr_line
		(start 189.877954 -277.178516)
		(end 189.877954 -278.321516)
		(stroke
			(width 0.2)
			(type default)
		)
		(layer "In3.Cu")
	)
	(gr_arc
		(start 189.877954 -163.321492)
		(mid 190.258954 -163.702492)
		(end 190.639954 -163.321492)
		(stroke
			(width 0.2)
			(type default)
		)
		(layer "In3.Cu")
	)
	(gr_line
		(start 189.877954 -162.178492)
		(end 189.877954 -163.321492)
		(stroke
			(width 0.2)
			(type default)
		)
		(layer "In3.Cu")
	)
	(gr_arc
		(start 189.877954 -48.321468)
		(mid 190.258954 -48.702468)
		(end 190.639954 -48.321468)
		(stroke
			(width 0.2)
			(type default)
		)
		(layer "In3.Cu")
	)
	(gr_line
		(start 189.877954 -47.178468)
		(end 189.877954 -48.321468)
		(stroke
			(width 0.2)
			(type default)
		)
		(layer "In3.Cu")
	)
	(gr_line
		(start 190.639954 -278.321516)
		(end 190.639954 -277.17877)
		(stroke
			(width 0.2)
			(type default)
		)
		(layer "In3.Cu")
	)
	(gr_arc
		(start 190.639954 -277.17877)
		(mid 190.259081 -276.797516)
		(end 189.877954 -277.178516)
		(stroke
			(width 0.2)
			(type default)
		)
		(layer "In3.Cu")
	)
	(gr_line
		(start 190.639954 -163.321492)
		(end 190.639954 -162.178746)
		(stroke
			(width 0.2)
			(type default)
		)
		(layer "In3.Cu")
	)
	(gr_arc
		(start 190.639954 -162.178746)
		(mid 190.259081 -161.797492)
		(end 189.877954 -162.178492)
		(stroke
			(width 0.2)
			(type default)
		)
		(layer "In3.Cu")
	)
	(gr_line
		(start 190.639954 -48.321468)
		(end 190.639954 -47.178722)
		(stroke
			(width 0.2)
			(type default)
		)
		(layer "In3.Cu")
	)
	(gr_arc
		(start 190.639954 -47.178722)
		(mid 190.259081 -46.797468)
		(end 189.877954 -47.178468)
		(stroke
			(width 0.2)
			(type default)
		)
		(layer "In3.Cu")
	)
	(gr_line
		(start 190.699898 -372.000018)
		(end 190.699898 -350.19996)
		(stroke
			(width 1.524)
			(type default)
		)
		(layer "In3.Cu")
	)
	(gr_arc
		(start 190.699898 -372.000018)
		(mid 190.992797 -372.707113)
		(end 191.699896 -373.000016)
		(stroke
			(width 1.524)
			(type default)
		)
		(layer "In3.Cu")
	)
	(gr_arc
		(start 190.699898 -350.19996)
		(mid 190.407005 -349.492855)
		(end 189.6999 -349.199962)
		(stroke
			(width 1.524)
			(type default)
		)
		(layer "In3.Cu")
	)
	(gr_line
		(start 199.00011 -373.000016)
		(end 191.699896 -373.000016)
		(stroke
			(width 1.524)
			(type default)
		)
		(layer "In3.Cu")
	)
	(gr_arc
		(start 199.00011 0)
		(mid 199.707215 0.292893)
		(end 200.000108 0.999998)
		(stroke
			(width 1.524)
			(type default)
		)
		(layer "In3.Cu")
	)
	(gr_line
		(start 200.000108 -420.200074)
		(end 200.000108 -374.000014)
		(stroke
			(width 1.524)
			(type default)
		)
		(layer "In3.Cu")
	)
	(gr_arc
		(start 200.000108 -420.200074)
		(mid 200.292992 -420.907194)
		(end 201.000106 -421.200072)
		(stroke
			(width 1.524)
			(type default)
		)
		(layer "In3.Cu")
	)
	(gr_arc
		(start 200.000108 -374.000014)
		(mid 199.707215 -373.292909)
		(end 199.00011 -373.000016)
		(stroke
			(width 1.524)
			(type default)
		)
		(layer "In3.Cu")
	)
	(gr_arc
		(start 201.000106 1.999996)
		(mid 200.292997 1.707105)
		(end 200.000108 0.999998)
		(stroke
			(width 1.524)
			(type default)
		)
		(layer "In3.Cu")
	)
	(gr_line
		(start 201.000106 1.999996)
		(end 219.00007 1.999996)
		(stroke
			(width 1.524)
			(type default)
		)
		(layer "In3.Cu")
	)
	(gr_arc
		(start 209.451448 -415.600134)
		(mid 210.000088 -416.148774)
		(end 210.548728 -415.600134)
		(stroke
			(width 0.2)
			(type default)
		)
		(layer "In3.Cu")
	)
	(gr_line
		(start 209.451448 -414.200086)
		(end 209.451448 -415.600134)
		(stroke
			(width 0.2)
			(type default)
		)
		(layer "In3.Cu")
	)
	(gr_arc
		(start 209.451448 -412.000192)
		(mid 210.000088 -412.548832)
		(end 210.548728 -412.000192)
		(stroke
			(width 0.2)
			(type default)
		)
		(layer "In3.Cu")
	)
	(gr_line
		(start 209.451448 -410.600144)
		(end 209.451448 -412.000192)
		(stroke
			(width 0.2)
			(type default)
		)
		(layer "In3.Cu")
	)
	(gr_arc
		(start 209.451448 -408.399996)
		(mid 210.000088 -408.948636)
		(end 210.548728 -408.399996)
		(stroke
			(width 0.2)
			(type default)
		)
		(layer "In3.Cu")
	)
	(gr_line
		(start 209.451448 -407.000202)
		(end 209.451448 -408.399996)
		(stroke
			(width 0.2)
			(type default)
		)
		(layer "In3.Cu")
	)
	(gr_line
		(start 210.548728 -415.600134)
		(end 210.548728 -414.20034)
		(stroke
			(width 0.2)
			(type default)
		)
		(layer "In3.Cu")
	)
	(gr_arc
		(start 210.548728 -414.20034)
		(mid 210.000215 -413.651446)
		(end 209.451448 -414.200086)
		(stroke
			(width 0.2)
			(type default)
		)
		(layer "In3.Cu")
	)
	(gr_line
		(start 210.548728 -412.000192)
		(end 210.548728 -410.600398)
		(stroke
			(width 0.2)
			(type default)
		)
		(layer "In3.Cu")
	)
	(gr_arc
		(start 210.548728 -410.600398)
		(mid 210.000215 -410.051504)
		(end 209.451448 -410.600144)
		(stroke
			(width 0.2)
			(type default)
		)
		(layer "In3.Cu")
	)
	(gr_line
		(start 210.548728 -408.399996)
		(end 210.548728 -407.000456)
		(stroke
			(width 0.2)
			(type default)
		)
		(layer "In3.Cu")
	)
	(gr_arc
		(start 210.548728 -407.000456)
		(mid 210.000215 -406.451562)
		(end 209.451448 -407.000202)
		(stroke
			(width 0.2)
			(type default)
		)
		(layer "In3.Cu")
	)
	(gr_arc
		(start 211.251546 -418.200078)
		(mid 211.800186 -418.748718)
		(end 212.348826 -418.200078)
		(stroke
			(width 0.2)
			(type default)
		)
		(layer "In3.Cu")
	)
	(gr_line
		(start 211.251546 -416.80003)
		(end 211.251546 -418.200078)
		(stroke
			(width 0.2)
			(type default)
		)
		(layer "In3.Cu")
	)
	(gr_arc
		(start 211.251546 -407.399998)
		(mid 211.800186 -407.948638)
		(end 212.348826 -407.399998)
		(stroke
			(width 0.2)
			(type default)
		)
		(layer "In3.Cu")
	)
	(gr_line
		(start 211.251546 -405.99995)
		(end 211.251546 -407.399998)
		(stroke
			(width 0.2)
			(type default)
		)
		(layer "In3.Cu")
	)
	(gr_line
		(start 212.348826 -418.200078)
		(end 212.348826 -416.800284)
		(stroke
			(width 0.2)
			(type default)
		)
		(layer "In3.Cu")
	)
	(gr_arc
		(start 212.348826 -416.800284)
		(mid 211.800313 -416.25139)
		(end 211.251546 -416.80003)
		(stroke
			(width 0.2)
			(type default)
		)
		(layer "In3.Cu")
	)
	(gr_line
		(start 212.348826 -407.399998)
		(end 212.348826 -406.000204)
		(stroke
			(width 0.2)
			(type default)
		)
		(layer "In3.Cu")
	)
	(gr_arc
		(start 212.348826 -406.000204)
		(mid 211.800313 -405.45131)
		(end 211.251546 -405.99995)
		(stroke
			(width 0.2)
			(type default)
		)
		(layer "In3.Cu")
	)
	(gr_arc
		(start 213.05139 -415.600134)
		(mid 213.60003 -416.148774)
		(end 214.14867 -415.600134)
		(stroke
			(width 0.2)
			(type default)
		)
		(layer "In3.Cu")
	)
	(gr_line
		(start 213.05139 -414.200086)
		(end 213.05139 -415.600134)
		(stroke
			(width 0.2)
			(type default)
		)
		(layer "In3.Cu")
	)
	(gr_arc
		(start 213.05139 -408.399996)
		(mid 213.60003 -408.948636)
		(end 214.14867 -408.399996)
		(stroke
			(width 0.2)
			(type default)
		)
		(layer "In3.Cu")
	)
	(gr_line
		(start 213.05139 -407.000202)
		(end 213.05139 -408.399996)
		(stroke
			(width 0.2)
			(type default)
		)
		(layer "In3.Cu")
	)
	(gr_line
		(start 214.14867 -415.600134)
		(end 214.14867 -414.20034)
		(stroke
			(width 0.2)
			(type default)
		)
		(layer "In3.Cu")
	)
	(gr_arc
		(start 214.14867 -414.20034)
		(mid 213.600157 -413.651446)
		(end 213.05139 -414.200086)
		(stroke
			(width 0.2)
			(type default)
		)
		(layer "In3.Cu")
	)
	(gr_line
		(start 214.14867 -408.399996)
		(end 214.14867 -407.000456)
		(stroke
			(width 0.2)
			(type default)
		)
		(layer "In3.Cu")
	)
	(gr_arc
		(start 214.14867 -407.000456)
		(mid 213.600157 -406.451562)
		(end 213.05139 -407.000202)
		(stroke
			(width 0.2)
			(type default)
		)
		(layer "In3.Cu")
	)
	(gr_arc
		(start 214.851488 -418.200078)
		(mid 215.400128 -418.748718)
		(end 215.948768 -418.200078)
		(stroke
			(width 0.2)
			(type default)
		)
		(layer "In3.Cu")
	)
	(gr_line
		(start 214.851488 -416.80003)
		(end 214.851488 -418.200078)
		(stroke
			(width 0.2)
			(type default)
		)
		(layer "In3.Cu")
	)
	(gr_arc
		(start 214.851488 -407.399998)
		(mid 215.400128 -407.948638)
		(end 215.948768 -407.399998)
		(stroke
			(width 0.2)
			(type default)
		)
		(layer "In3.Cu")
	)
	(gr_line
		(start 214.851488 -405.99995)
		(end 214.851488 -407.399998)
		(stroke
			(width 0.2)
			(type default)
		)
		(layer "In3.Cu")
	)
	(gr_line
		(start 215.948768 -418.200078)
		(end 215.948768 -416.800284)
		(stroke
			(width 0.2)
			(type default)
		)
		(layer "In3.Cu")
	)
	(gr_arc
		(start 215.948768 -416.800284)
		(mid 215.400255 -416.25139)
		(end 214.851488 -416.80003)
		(stroke
			(width 0.2)
			(type default)
		)
		(layer "In3.Cu")
	)
	(gr_line
		(start 215.948768 -407.399998)
		(end 215.948768 -406.000204)
		(stroke
			(width 0.2)
			(type default)
		)
		(layer "In3.Cu")
	)
	(gr_arc
		(start 215.948768 -406.000204)
		(mid 215.400255 -405.45131)
		(end 214.851488 -405.99995)
		(stroke
			(width 0.2)
			(type default)
		)
		(layer "In3.Cu")
	)
	(gr_arc
		(start 216.651332 -415.600134)
		(mid 217.199972 -416.148774)
		(end 217.748612 -415.600134)
		(stroke
			(width 0.2)
			(type default)
		)
		(layer "In3.Cu")
	)
	(gr_line
		(start 216.651332 -414.200086)
		(end 216.651332 -415.600134)
		(stroke
			(width 0.2)
			(type default)
		)
		(layer "In3.Cu")
	)
	(gr_arc
		(start 216.651332 -408.399996)
		(mid 217.199972 -408.948636)
		(end 217.748612 -408.399996)
		(stroke
			(width 0.2)
			(type default)
		)
		(layer "In3.Cu")
	)
	(gr_line
		(start 216.651332 -407.000202)
		(end 216.651332 -408.399996)
		(stroke
			(width 0.2)
			(type default)
		)
		(layer "In3.Cu")
	)
	(gr_line
		(start 217.748612 -415.600134)
		(end 217.748612 -414.20034)
		(stroke
			(width 0.2)
			(type default)
		)
		(layer "In3.Cu")
	)
	(gr_arc
		(start 217.748612 -414.20034)
		(mid 217.200099 -413.651446)
		(end 216.651332 -414.200086)
		(stroke
			(width 0.2)
			(type default)
		)
		(layer "In3.Cu")
	)
	(gr_line
		(start 217.748612 -408.399996)
		(end 217.748612 -407.000456)
		(stroke
			(width 0.2)
			(type default)
		)
		(layer "In3.Cu")
	)
	(gr_arc
		(start 217.748612 -407.000456)
		(mid 217.200099 -406.451562)
		(end 216.651332 -407.000202)
		(stroke
			(width 0.2)
			(type default)
		)
		(layer "In3.Cu")
	)
	(gr_arc
		(start 218.45143 -418.200078)
		(mid 219.00007 -418.748718)
		(end 219.54871 -418.200078)
		(stroke
			(width 0.2)
			(type default)
		)
		(layer "In3.Cu")
	)
	(gr_line
		(start 218.45143 -416.80003)
		(end 218.45143 -418.200078)
		(stroke
			(width 0.2)
			(type default)
		)
		(layer "In3.Cu")
	)
	(gr_arc
		(start 218.45143 -407.399998)
		(mid 219.00007 -407.948638)
		(end 219.54871 -407.399998)
		(stroke
			(width 0.2)
			(type default)
		)
		(layer "In3.Cu")
	)
	(gr_line
		(start 218.45143 -405.99995)
		(end 218.45143 -407.399998)
		(stroke
			(width 0.2)
			(type default)
		)
		(layer "In3.Cu")
	)
	(gr_arc
		(start 219.00007 1.999996)
		(mid 219.707175 2.292889)
		(end 220.000068 2.999994)
		(stroke
			(width 1.524)
			(type default)
		)
		(layer "In3.Cu")
	)
	(gr_line
		(start 219.54871 -418.200078)
		(end 219.54871 -416.800284)
		(stroke
			(width 0.2)
			(type default)
		)
		(layer "In3.Cu")
	)
	(gr_arc
		(start 219.54871 -416.800284)
		(mid 219.000197 -416.25139)
		(end 218.45143 -416.80003)
		(stroke
			(width 0.2)
			(type default)
		)
		(layer "In3.Cu")
	)
	(gr_line
		(start 219.54871 -407.399998)
		(end 219.54871 -406.000204)
		(stroke
			(width 0.2)
			(type default)
		)
		(layer "In3.Cu")
	)
	(gr_arc
		(start 219.54871 -406.000204)
		(mid 219.000197 -405.45131)
		(end 218.45143 -405.99995)
		(stroke
			(width 0.2)
			(type default)
		)
		(layer "In3.Cu")
	)
	(gr_line
		(start 220.000068 2.999994)
		(end 220.000068 37.800026)
		(stroke
			(width 1.524)
			(type default)
		)
		(layer "In3.Cu")
	)
	(gr_arc
		(start 220.251528 -415.600134)
		(mid 220.800168 -416.148774)
		(end 221.348808 -415.600134)
		(stroke
			(width 0.2)
			(type default)
		)
		(layer "In3.Cu")
	)
	(gr_line
		(start 220.251528 -414.200086)
		(end 220.251528 -415.600134)
		(stroke
			(width 0.2)
			(type default)
		)
		(layer "In3.Cu")
	)
	(gr_arc
		(start 220.251528 -408.399996)
		(mid 220.800168 -408.948636)
		(end 221.348808 -408.399996)
		(stroke
			(width 0.2)
			(type default)
		)
		(layer "In3.Cu")
	)
	(gr_line
		(start 220.251528 -407.000202)
		(end 220.251528 -408.399996)
		(stroke
			(width 0.2)
			(type default)
		)
		(layer "In3.Cu")
	)
	(gr_arc
		(start 221.000066 38.800024)
		(mid 220.292973 38.507121)
		(end 220.000068 37.800026)
		(stroke
			(width 1.524)
			(type default)
		)
		(layer "In3.Cu")
	)
	(gr_line
		(start 221.000066 38.800024)
		(end 298.99991 38.800024)
		(stroke
			(width 1.524)
			(type default)
		)
		(layer "In3.Cu")
	)
	(gr_line
		(start 221.348808 -415.600134)
		(end 221.348808 -414.20034)
		(stroke
			(width 0.2)
			(type default)
		)
		(layer "In3.Cu")
	)
	(gr_arc
		(start 221.348808 -414.20034)
		(mid 220.800295 -413.651446)
		(end 220.251528 -414.200086)
		(stroke
			(width 0.2)
			(type default)
		)
		(layer "In3.Cu")
	)
	(gr_line
		(start 221.348808 -408.399996)
		(end 221.348808 -407.000456)
		(stroke
			(width 0.2)
			(type default)
		)
		(layer "In3.Cu")
	)
	(gr_arc
		(start 221.348808 -407.000456)
		(mid 220.800295 -406.451562)
		(end 220.251528 -407.000202)
		(stroke
			(width 0.2)
			(type default)
		)
		(layer "In3.Cu")
	)
	(gr_arc
		(start 222.051372 -418.200078)
		(mid 222.600012 -418.748718)
		(end 223.148652 -418.200078)
		(stroke
			(width 0.2)
			(type default)
		)
		(layer "In3.Cu")
	)
	(gr_line
		(start 222.051372 -416.80003)
		(end 222.051372 -418.200078)
		(stroke
			(width 0.2)
			(type default)
		)
		(layer "In3.Cu")
	)
	(gr_arc
		(start 222.051372 -407.399998)
		(mid 222.600012 -407.948638)
		(end 223.148652 -407.399998)
		(stroke
			(width 0.2)
			(type default)
		)
		(layer "In3.Cu")
	)
	(gr_line
		(start 222.051372 -405.99995)
		(end 222.051372 -407.399998)
		(stroke
			(width 0.2)
			(type default)
		)
		(layer "In3.Cu")
	)
	(gr_line
		(start 223.148652 -418.200078)
		(end 223.148652 -416.800284)
		(stroke
			(width 0.2)
			(type default)
		)
		(layer "In3.Cu")
	)
	(gr_arc
		(start 223.148652 -416.800284)
		(mid 222.600139 -416.25139)
		(end 222.051372 -416.80003)
		(stroke
			(width 0.2)
			(type default)
		)
		(layer "In3.Cu")
	)
	(gr_line
		(start 223.148652 -407.399998)
		(end 223.148652 -406.000204)
		(stroke
			(width 0.2)
			(type default)
		)
		(layer "In3.Cu")
	)
	(gr_arc
		(start 223.148652 -406.000204)
		(mid 222.600139 -405.45131)
		(end 222.051372 -405.99995)
		(stroke
			(width 0.2)
			(type default)
		)
		(layer "In3.Cu")
	)
	(gr_arc
		(start 235.722922 -121.845578)
		(mid 235.39577 -122.827034)
		(end 236.377226 -123.154186)
		(stroke
			(width 0.2)
			(type default)
		)
		(layer "In3.Cu")
	)
	(gr_line
		(start 235.723938 -65.548002)
		(end 235.725208 -65.550288)
		(stroke
			(width 0.2)
			(type default)
		)
		(layer "In3.Cu")
	)
	(gr_line
		(start 235.724192 -177.848006)
		(end 235.725208 -177.850038)
		(stroke
			(width 0.2)
			(type default)
		)
		(layer "In3.Cu")
	)
	(gr_line
		(start 235.724192 -177.847752)
		(end 235.724192 -177.848006)
		(stroke
			(width 0.2)
			(type default)
		)
		(layer "In3.Cu")
	)
	(gr_line
		(start 235.724192 -173.848014)
		(end 235.725208 -173.850046)
		(stroke
			(width 0.2)
			(type default)
		)
		(layer "In3.Cu")
	)
	(gr_line
		(start 235.724192 -173.84776)
		(end 235.724192 -173.848014)
		(stroke
			(width 0.2)
			(type default)
		)
		(layer "In3.Cu")
	)
	(gr_line
		(start 235.724192 -169.848022)
		(end 235.725208 -169.850054)
		(stroke
			(width 0.2)
			(type default)
		)
		(layer "In3.Cu")
	)
	(gr_line
		(start 235.724192 -169.847768)
		(end 235.724192 -169.848022)
		(stroke
			(width 0.2)
			(type default)
		)
		(layer "In3.Cu")
	)
	(gr_line
		(start 235.724192 -165.84803)
		(end 235.725208 -165.850062)
		(stroke
			(width 0.2)
			(type default)
		)
		(layer "In3.Cu")
	)
	(gr_line
		(start 235.724192 -165.847776)
		(end 235.724192 -165.84803)
		(stroke
			(width 0.2)
			(type default)
		)
		(layer "In3.Cu")
	)
	(gr_line
		(start 235.724192 -137.848086)
		(end 235.725208 -137.850118)
		(stroke
			(width 0.2)
			(type default)
		)
		(layer "In3.Cu")
	)
	(gr_line
		(start 235.724192 -137.847832)
		(end 235.724192 -137.848086)
		(stroke
			(width 0.2)
			(type default)
		)
		(layer "In3.Cu")
	)
	(gr_line
		(start 235.724192 -81.548224)
		(end 235.725208 -81.550256)
		(stroke
			(width 0.2)
			(type default)
		)
		(layer "In3.Cu")
	)
	(gr_line
		(start 235.724192 -81.54797)
		(end 235.724192 -81.548224)
		(stroke
			(width 0.2)
			(type default)
		)
		(layer "In3.Cu")
	)
	(gr_line
		(start 235.724192 -77.548232)
		(end 235.725208 -77.550264)
		(stroke
			(width 0.2)
			(type default)
		)
		(layer "In3.Cu")
	)
	(gr_line
		(start 235.724192 -77.547978)
		(end 235.724192 -77.548232)
		(stroke
			(width 0.2)
			(type default)
		)
		(layer "In3.Cu")
	)
	(gr_line
		(start 235.724192 -73.54824)
		(end 235.725208 -73.550272)
		(stroke
			(width 0.2)
			(type default)
		)
		(layer "In3.Cu")
	)
	(gr_line
		(start 235.724192 -73.547986)
		(end 235.724192 -73.54824)
		(stroke
			(width 0.2)
			(type default)
		)
		(layer "In3.Cu")
	)
	(gr_line
		(start 235.724192 -69.548248)
		(end 235.725208 -69.55028)
		(stroke
			(width 0.2)
			(type default)
		)
		(layer "In3.Cu")
	)
	(gr_line
		(start 235.724192 -69.547994)
		(end 235.724192 -69.548248)
		(stroke
			(width 0.2)
			(type default)
		)
		(layer "In3.Cu")
	)
	(gr_line
		(start 235.724192 -61.548264)
		(end 235.725208 -61.550296)
		(stroke
			(width 0.2)
			(type default)
		)
		(layer "In3.Cu")
	)
	(gr_line
		(start 235.724192 -61.54801)
		(end 235.724192 -61.548264)
		(stroke
			(width 0.2)
			(type default)
		)
		(layer "In3.Cu")
	)
	(gr_line
		(start 235.724192 -57.548272)
		(end 235.725208 -57.550304)
		(stroke
			(width 0.2)
			(type default)
		)
		(layer "In3.Cu")
	)
	(gr_line
		(start 235.724192 -57.548018)
		(end 235.724192 -57.548272)
		(stroke
			(width 0.2)
			(type default)
		)
		(layer "In3.Cu")
	)
	(gr_line
		(start 235.724192 -53.54828)
		(end 235.725208 -53.550312)
		(stroke
			(width 0.2)
			(type default)
		)
		(layer "In3.Cu")
	)
	(gr_line
		(start 235.724192 -53.548026)
		(end 235.724192 -53.54828)
		(stroke
			(width 0.2)
			(type default)
		)
		(layer "In3.Cu")
	)
	(gr_line
		(start 235.724192 -49.548288)
		(end 235.725208 -49.55032)
		(stroke
			(width 0.2)
			(type default)
		)
		(layer "In3.Cu")
	)
	(gr_line
		(start 235.724192 -49.548034)
		(end 235.724192 -49.548288)
		(stroke
			(width 0.2)
			(type default)
		)
		(layer "In3.Cu")
	)
	(gr_line
		(start 235.724192 -45.548296)
		(end 235.725208 -45.550328)
		(stroke
			(width 0.2)
			(type default)
		)
		(layer "In3.Cu")
	)
	(gr_line
		(start 235.724192 -45.548042)
		(end 235.724192 -45.548296)
		(stroke
			(width 0.2)
			(type default)
		)
		(layer "In3.Cu")
	)
	(gr_line
		(start 235.724192 -41.548304)
		(end 235.725208 -41.550336)
		(stroke
			(width 0.2)
			(type default)
		)
		(layer "In3.Cu")
	)
	(gr_line
		(start 235.724192 -41.54805)
		(end 235.724192 -41.548304)
		(stroke
			(width 0.2)
			(type default)
		)
		(layer "In3.Cu")
	)
	(gr_line
		(start 235.724192 -37.548312)
		(end 235.725208 -37.550344)
		(stroke
			(width 0.2)
			(type default)
		)
		(layer "In3.Cu")
	)
	(gr_line
		(start 235.724192 -37.548058)
		(end 235.724192 -37.548312)
		(stroke
			(width 0.2)
			(type default)
		)
		(layer "In3.Cu")
	)
	(gr_line
		(start 235.724192 -17.548352)
		(end 235.725208 -17.550384)
		(stroke
			(width 0.2)
			(type default)
		)
		(layer "In3.Cu")
	)
	(gr_line
		(start 235.724192 -17.548098)
		(end 235.724192 -17.548352)
		(stroke
			(width 0.2)
			(type default)
		)
		(layer "In3.Cu")
	)
	(gr_arc
		(start 235.725208 -177.850038)
		(mid 235.400342 -178.824636)
		(end 236.37494 -179.149502)
		(stroke
			(width 0.2)
			(type default)
		)
		(layer "In3.Cu")
	)
	(gr_arc
		(start 235.725208 -173.850046)
		(mid 235.400342 -174.824644)
		(end 236.37494 -175.14951)
		(stroke
			(width 0.2)
			(type default)
		)
		(layer "In3.Cu")
	)
	(gr_arc
		(start 235.725208 -169.850054)
		(mid 235.400342 -170.824652)
		(end 236.37494 -171.149518)
		(stroke
			(width 0.2)
			(type default)
		)
		(layer "In3.Cu")
	)
	(gr_arc
		(start 235.725208 -165.850062)
		(mid 235.400342 -166.82466)
		(end 236.37494 -167.149526)
		(stroke
			(width 0.2)
			(type default)
		)
		(layer "In3.Cu")
	)
	(gr_arc
		(start 235.725208 -137.850118)
		(mid 235.400342 -138.824716)
		(end 236.37494 -139.149582)
		(stroke
			(width 0.2)
			(type default)
		)
		(layer "In3.Cu")
	)
	(gr_arc
		(start 235.725208 -81.550256)
		(mid 235.400342 -82.524854)
		(end 236.37494 -82.84972)
		(stroke
			(width 0.2)
			(type default)
		)
		(layer "In3.Cu")
	)
	(gr_arc
		(start 235.725208 -77.550264)
		(mid 235.400342 -78.524862)
		(end 236.37494 -78.849728)
		(stroke
			(width 0.2)
			(type default)
		)
		(layer "In3.Cu")
	)
	(gr_arc
		(start 235.725208 -73.550272)
		(mid 235.400342 -74.52487)
		(end 236.37494 -74.849736)
		(stroke
			(width 0.2)
			(type default)
		)
		(layer "In3.Cu")
	)
	(gr_arc
		(start 235.725208 -69.55028)
		(mid 235.400342 -70.524878)
		(end 236.37494 -70.849744)
		(stroke
			(width 0.2)
			(type default)
		)
		(layer "In3.Cu")
	)
	(gr_arc
		(start 235.725208 -65.550288)
		(mid 235.400342 -66.524886)
		(end 236.37494 -66.849752)
		(stroke
			(width 0.2)
			(type default)
		)
		(layer "In3.Cu")
	)
	(gr_arc
		(start 235.725208 -61.550296)
		(mid 235.400342 -62.524894)
		(end 236.37494 -62.84976)
		(stroke
			(width 0.2)
			(type default)
		)
		(layer "In3.Cu")
	)
	(gr_arc
		(start 235.725208 -57.550304)
		(mid 235.400342 -58.524902)
		(end 236.37494 -58.849768)
		(stroke
			(width 0.2)
			(type default)
		)
		(layer "In3.Cu")
	)
	(gr_arc
		(start 235.725208 -53.550312)
		(mid 235.400342 -54.52491)
		(end 236.37494 -54.849776)
		(stroke
			(width 0.2)
			(type default)
		)
		(layer "In3.Cu")
	)
	(gr_arc
		(start 235.725208 -49.55032)
		(mid 235.400342 -50.524918)
		(end 236.37494 -50.849784)
		(stroke
			(width 0.2)
			(type default)
		)
		(layer "In3.Cu")
	)
	(gr_arc
		(start 235.725208 -45.550328)
		(mid 235.400342 -46.524926)
		(end 236.37494 -46.849792)
		(stroke
			(width 0.2)
			(type default)
		)
		(layer "In3.Cu")
	)
	(gr_arc
		(start 235.725208 -41.550336)
		(mid 235.400342 -42.524934)
		(end 236.37494 -42.8498)
		(stroke
			(width 0.2)
			(type default)
		)
		(layer "In3.Cu")
	)
	(gr_arc
		(start 235.725208 -37.550344)
		(mid 235.400342 -38.524942)
		(end 236.37494 -38.849808)
		(stroke
			(width 0.2)
			(type default)
		)
		(layer "In3.Cu")
	)
	(gr_arc
		(start 235.725208 -17.550384)
		(mid 235.400342 -18.524982)
		(end 236.37494 -18.849848)
		(stroke
			(width 0.2)
			(type default)
		)
		(layer "In3.Cu")
	)
	(gr_arc
		(start 235.733844 -161.840164)
		(mid 235.393447 -162.821194)
		(end 236.377226 -163.154106)
		(stroke
			(width 0.2)
			(type default)
		)
		(layer "In3.Cu")
	)
	(gr_arc
		(start 235.733844 -157.840172)
		(mid 235.393447 -158.821202)
		(end 236.377226 -159.154114)
		(stroke
			(width 0.2)
			(type default)
		)
		(layer "In3.Cu")
	)
	(gr_arc
		(start 235.733844 -153.84018)
		(mid 235.393447 -154.82121)
		(end 236.377226 -155.154122)
		(stroke
			(width 0.2)
			(type default)
		)
		(layer "In3.Cu")
	)
	(gr_arc
		(start 235.733844 -149.840188)
		(mid 235.393447 -150.821218)
		(end 236.377226 -151.15413)
		(stroke
			(width 0.2)
			(type default)
		)
		(layer "In3.Cu")
	)
	(gr_arc
		(start 235.733844 -129.840228)
		(mid 235.393447 -130.821258)
		(end 236.377226 -131.15417)
		(stroke
			(width 0.2)
			(type default)
		)
		(layer "In3.Cu")
	)
	(gr_arc
		(start 235.733844 -125.840236)
		(mid 235.393447 -126.821266)
		(end 236.377226 -127.154178)
		(stroke
			(width 0.2)
			(type default)
		)
		(layer "In3.Cu")
	)
	(gr_arc
		(start 235.733844 -117.840252)
		(mid 235.393447 -118.821282)
		(end 236.377226 -119.154194)
		(stroke
			(width 0.2)
			(type default)
		)
		(layer "In3.Cu")
	)
	(gr_arc
		(start 235.733844 -113.84026)
		(mid 235.393447 -114.82129)
		(end 236.377226 -115.154202)
		(stroke
			(width 0.2)
			(type default)
		)
		(layer "In3.Cu")
	)
	(gr_arc
		(start 235.733844 -11.54049)
		(mid 235.393447 -12.52152)
		(end 236.377226 -12.854432)
		(stroke
			(width 0.2)
			(type default)
		)
		(layer "In3.Cu")
	)
	(gr_line
		(start 236.37494 -179.149502)
		(end 236.37621 -179.151788)
		(stroke
			(width 0.2)
			(type default)
		)
		(layer "In3.Cu")
	)
	(gr_line
		(start 236.37494 -175.14951)
		(end 236.37621 -175.151796)
		(stroke
			(width 0.2)
			(type default)
		)
		(layer "In3.Cu")
	)
	(gr_line
		(start 236.37494 -171.149518)
		(end 236.37621 -171.151804)
		(stroke
			(width 0.2)
			(type default)
		)
		(layer "In3.Cu")
	)
	(gr_line
		(start 236.37494 -167.149526)
		(end 236.37621 -167.151812)
		(stroke
			(width 0.2)
			(type default)
		)
		(layer "In3.Cu")
	)
	(gr_line
		(start 236.37494 -139.149582)
		(end 236.37621 -139.151868)
		(stroke
			(width 0.2)
			(type default)
		)
		(layer "In3.Cu")
	)
	(gr_line
		(start 236.37494 -82.84972)
		(end 236.37621 -82.852006)
		(stroke
			(width 0.2)
			(type default)
		)
		(layer "In3.Cu")
	)
	(gr_line
		(start 236.37494 -78.849728)
		(end 236.37621 -78.852014)
		(stroke
			(width 0.2)
			(type default)
		)
		(layer "In3.Cu")
	)
	(gr_line
		(start 236.37494 -74.849736)
		(end 236.37621 -74.852022)
		(stroke
			(width 0.2)
			(type default)
		)
		(layer "In3.Cu")
	)
	(gr_line
		(start 236.37494 -70.849744)
		(end 236.37621 -70.85203)
		(stroke
			(width 0.2)
			(type default)
		)
		(layer "In3.Cu")
	)
	(gr_line
		(start 236.37494 -66.849752)
		(end 236.37621 -66.852038)
		(stroke
			(width 0.2)
			(type default)
		)
		(layer "In3.Cu")
	)
	(gr_line
		(start 236.37494 -62.84976)
		(end 236.37621 -62.852046)
		(stroke
			(width 0.2)
			(type default)
		)
		(layer "In3.Cu")
	)
	(gr_line
		(start 236.37494 -58.849768)
		(end 236.37621 -58.852054)
		(stroke
			(width 0.2)
			(type default)
		)
		(layer "In3.Cu")
	)
	(gr_line
		(start 236.37494 -54.849776)
		(end 236.37621 -54.852062)
		(stroke
			(width 0.2)
			(type default)
		)
		(layer "In3.Cu")
	)
	(gr_line
		(start 236.37494 -50.849784)
		(end 236.37621 -50.85207)
		(stroke
			(width 0.2)
			(type default)
		)
		(layer "In3.Cu")
	)
	(gr_line
		(start 236.37494 -46.849792)
		(end 236.37621 -46.852078)
		(stroke
			(width 0.2)
			(type default)
		)
		(layer "In3.Cu")
	)
	(gr_line
		(start 236.37494 -42.8498)
		(end 236.37621 -42.852086)
		(stroke
			(width 0.2)
			(type default)
		)
		(layer "In3.Cu")
	)
	(gr_line
		(start 236.37494 -38.849808)
		(end 236.37621 -38.852094)
		(stroke
			(width 0.2)
			(type default)
		)
		(layer "In3.Cu")
	)
	(gr_line
		(start 236.37494 -18.849848)
		(end 236.37621 -18.852134)
		(stroke
			(width 0.2)
			(type default)
		)
		(layer "In3.Cu")
	)
	(gr_line
		(start 236.37621 -179.151788)
		(end 238.376206 -178.15179)
		(stroke
			(width 0.2)
			(type default)
		)
		(layer "In3.Cu")
	)
	(gr_line
		(start 236.37621 -175.151796)
		(end 238.376206 -174.151798)
		(stroke
			(width 0.2)
			(type default)
		)
		(layer "In3.Cu")
	)
	(gr_line
		(start 236.37621 -171.151804)
		(end 238.376206 -170.151806)
		(stroke
			(width 0.2)
			(type default)
		)
		(layer "In3.Cu")
	)
	(gr_line
		(start 236.37621 -167.151812)
		(end 238.376206 -166.151814)
		(stroke
			(width 0.2)
			(type default)
		)
		(layer "In3.Cu")
	)
	(gr_line
		(start 236.37621 -139.151868)
		(end 238.376206 -138.15187)
		(stroke
			(width 0.2)
			(type default)
		)
		(layer "In3.Cu")
	)
	(gr_line
		(start 236.37621 -82.852006)
		(end 238.376206 -81.852008)
		(stroke
			(width 0.2)
			(type default)
		)
		(layer "In3.Cu")
	)
	(gr_line
		(start 236.37621 -78.852014)
		(end 238.376206 -77.852016)
		(stroke
			(width 0.2)
			(type default)
		)
		(layer "In3.Cu")
	)
	(gr_line
		(start 236.37621 -74.852022)
		(end 238.376206 -73.852024)
		(stroke
			(width 0.2)
			(type default)
		)
		(layer "In3.Cu")
	)
	(gr_line
		(start 236.37621 -70.85203)
		(end 238.376206 -69.852032)
		(stroke
			(width 0.2)
			(type default)
		)
		(layer "In3.Cu")
	)
	(gr_line
		(start 236.37621 -66.852038)
		(end 238.375952 -65.85204)
		(stroke
			(width 0.2)
			(type default)
		)
		(layer "In3.Cu")
	)
	(gr_line
		(start 236.37621 -62.852046)
		(end 238.376206 -61.852048)
		(stroke
			(width 0.2)
			(type default)
		)
		(layer "In3.Cu")
	)
	(gr_line
		(start 236.37621 -58.852054)
		(end 238.376206 -57.852056)
		(stroke
			(width 0.2)
			(type default)
		)
		(layer "In3.Cu")
	)
	(gr_line
		(start 236.37621 -54.852062)
		(end 238.376206 -53.852064)
		(stroke
			(width 0.2)
			(type default)
		)
		(layer "In3.Cu")
	)
	(gr_line
		(start 236.37621 -50.85207)
		(end 238.376206 -49.852072)
		(stroke
			(width 0.2)
			(type default)
		)
		(layer "In3.Cu")
	)
	(gr_line
		(start 236.37621 -46.852078)
		(end 238.376206 -45.85208)
		(stroke
			(width 0.2)
			(type default)
		)
		(layer "In3.Cu")
	)
	(gr_line
		(start 236.37621 -42.852086)
		(end 238.376206 -41.852088)
		(stroke
			(width 0.2)
			(type default)
		)
		(layer "In3.Cu")
	)
	(gr_line
		(start 236.37621 -38.852094)
		(end 238.376206 -37.852096)
		(stroke
			(width 0.2)
			(type default)
		)
		(layer "In3.Cu")
	)
	(gr_line
		(start 236.37621 -18.852134)
		(end 238.376206 -17.852136)
		(stroke
			(width 0.2)
			(type default)
		)
		(layer "In3.Cu")
	)
	(gr_line
		(start 236.377226 -163.154106)
		(end 238.377222 -162.154108)
		(stroke
			(width 0.2)
			(type default)
		)
		(layer "In3.Cu")
	)
	(gr_line
		(start 236.377226 -159.154114)
		(end 238.377222 -158.154116)
		(stroke
			(width 0.2)
			(type default)
		)
		(layer "In3.Cu")
	)
	(gr_line
		(start 236.377226 -155.154122)
		(end 238.377222 -154.154124)
		(stroke
			(width 0.2)
			(type default)
		)
		(layer "In3.Cu")
	)
	(gr_line
		(start 236.377226 -151.15413)
		(end 238.377222 -150.154132)
		(stroke
			(width 0.2)
			(type default)
		)
		(layer "In3.Cu")
	)
	(gr_line
		(start 236.377226 -131.15417)
		(end 238.377222 -130.154172)
		(stroke
			(width 0.2)
			(type default)
		)
		(layer "In3.Cu")
	)
	(gr_line
		(start 236.377226 -127.154178)
		(end 238.377222 -126.15418)
		(stroke
			(width 0.2)
			(type default)
		)
		(layer "In3.Cu")
	)
	(gr_line
		(start 236.377226 -123.154186)
		(end 238.3663 -122.159522)
		(stroke
			(width 0.2)
			(type default)
		)
		(layer "In3.Cu")
	)
	(gr_line
		(start 236.377226 -119.154194)
		(end 238.377222 -118.154196)
		(stroke
			(width 0.2)
			(type default)
		)
		(layer "In3.Cu")
	)
	(gr_line
		(start 236.377226 -115.154202)
		(end 238.377222 -114.154204)
		(stroke
			(width 0.2)
			(type default)
		)
		(layer "In3.Cu")
	)
	(gr_line
		(start 236.377226 -12.854432)
		(end 238.377222 -11.854434)
		(stroke
			(width 0.2)
			(type default)
		)
		(layer "In3.Cu")
	)
	(gr_line
		(start 237.722918 -160.8455)
		(end 235.733844 -161.840164)
		(stroke
			(width 0.2)
			(type default)
		)
		(layer "In3.Cu")
	)
	(gr_line
		(start 237.722918 -156.845508)
		(end 235.733844 -157.840172)
		(stroke
			(width 0.2)
			(type default)
		)
		(layer "In3.Cu")
	)
	(gr_line
		(start 237.722918 -152.845516)
		(end 235.733844 -153.84018)
		(stroke
			(width 0.2)
			(type default)
		)
		(layer "In3.Cu")
	)
	(gr_line
		(start 237.722918 -148.845524)
		(end 235.733844 -149.840188)
		(stroke
			(width 0.2)
			(type default)
		)
		(layer "In3.Cu")
	)
	(gr_line
		(start 237.722918 -128.845564)
		(end 235.733844 -129.840228)
		(stroke
			(width 0.2)
			(type default)
		)
		(layer "In3.Cu")
	)
	(gr_line
		(start 237.722918 -124.845572)
		(end 235.733844 -125.840236)
		(stroke
			(width 0.2)
			(type default)
		)
		(layer "In3.Cu")
	)
	(gr_line
		(start 237.722918 -120.84558)
		(end 235.722922 -121.845578)
		(stroke
			(width 0.2)
			(type default)
		)
		(layer "In3.Cu")
	)
	(gr_line
		(start 237.722918 -116.845588)
		(end 235.733844 -117.840252)
		(stroke
			(width 0.2)
			(type default)
		)
		(layer "In3.Cu")
	)
	(gr_line
		(start 237.722918 -112.845596)
		(end 235.733844 -113.84026)
		(stroke
			(width 0.2)
			(type default)
		)
		(layer "In3.Cu")
	)
	(gr_line
		(start 237.722918 -10.545826)
		(end 235.733844 -11.54049)
		(stroke
			(width 0.2)
			(type default)
		)
		(layer "In3.Cu")
	)
	(gr_line
		(start 237.723934 -176.847754)
		(end 235.724192 -177.847752)
		(stroke
			(width 0.2)
			(type default)
		)
		(layer "In3.Cu")
	)
	(gr_line
		(start 237.723934 -172.847762)
		(end 235.724192 -173.84776)
		(stroke
			(width 0.2)
			(type default)
		)
		(layer "In3.Cu")
	)
	(gr_line
		(start 237.723934 -168.84777)
		(end 235.724192 -169.847768)
		(stroke
			(width 0.2)
			(type default)
		)
		(layer "In3.Cu")
	)
	(gr_line
		(start 237.723934 -164.847778)
		(end 235.724192 -165.847776)
		(stroke
			(width 0.2)
			(type default)
		)
		(layer "In3.Cu")
	)
	(gr_line
		(start 237.723934 -136.847834)
		(end 235.724192 -137.847832)
		(stroke
			(width 0.2)
			(type default)
		)
		(layer "In3.Cu")
	)
	(gr_line
		(start 237.723934 -80.547972)
		(end 235.724192 -81.54797)
		(stroke
			(width 0.2)
			(type default)
		)
		(layer "In3.Cu")
	)
	(gr_line
		(start 237.723934 -76.54798)
		(end 235.724192 -77.547978)
		(stroke
			(width 0.2)
			(type default)
		)
		(layer "In3.Cu")
	)
	(gr_line
		(start 237.723934 -72.547988)
		(end 235.724192 -73.547986)
		(stroke
			(width 0.2)
			(type default)
		)
		(layer "In3.Cu")
	)
	(gr_line
		(start 237.723934 -68.547996)
		(end 235.724192 -69.547994)
		(stroke
			(width 0.2)
			(type default)
		)
		(layer "In3.Cu")
	)
	(gr_line
		(start 237.723934 -64.548004)
		(end 235.723938 -65.548002)
		(stroke
			(width 0.2)
			(type default)
		)
		(layer "In3.Cu")
	)
	(gr_line
		(start 237.723934 -60.548012)
		(end 235.724192 -61.54801)
		(stroke
			(width 0.2)
			(type default)
		)
		(layer "In3.Cu")
	)
	(gr_line
		(start 237.723934 -56.54802)
		(end 235.724192 -57.548018)
		(stroke
			(width 0.2)
			(type default)
		)
		(layer "In3.Cu")
	)
	(gr_line
		(start 237.723934 -52.548028)
		(end 235.724192 -53.548026)
		(stroke
			(width 0.2)
			(type default)
		)
		(layer "In3.Cu")
	)
	(gr_line
		(start 237.723934 -48.548036)
		(end 235.724192 -49.548034)
		(stroke
			(width 0.2)
			(type default)
		)
		(layer "In3.Cu")
	)
	(gr_line
		(start 237.723934 -44.548044)
		(end 235.724192 -45.548042)
		(stroke
			(width 0.2)
			(type default)
		)
		(layer "In3.Cu")
	)
	(gr_line
		(start 237.723934 -40.548052)
		(end 235.724192 -41.54805)
		(stroke
			(width 0.2)
			(type default)
		)
		(layer "In3.Cu")
	)
	(gr_line
		(start 237.723934 -36.54806)
		(end 235.724192 -37.548058)
		(stroke
			(width 0.2)
			(type default)
		)
		(layer "In3.Cu")
	)
	(gr_line
		(start 237.723934 -16.5481)
		(end 235.724192 -17.548098)
		(stroke
			(width 0.2)
			(type default)
		)
		(layer "In3.Cu")
	)
	(gr_line
		(start 237.725204 -176.85004)
		(end 237.723934 -176.847754)
		(stroke
			(width 0.2)
			(type default)
		)
		(layer "In3.Cu")
	)
	(gr_line
		(start 237.725204 -172.850048)
		(end 237.723934 -172.847762)
		(stroke
			(width 0.2)
			(type default)
		)
		(layer "In3.Cu")
	)
	(gr_line
		(start 237.725204 -168.850056)
		(end 237.723934 -168.84777)
		(stroke
			(width 0.2)
			(type default)
		)
		(layer "In3.Cu")
	)
	(gr_line
		(start 237.725204 -164.850064)
		(end 237.723934 -164.847778)
		(stroke
			(width 0.2)
			(type default)
		)
		(layer "In3.Cu")
	)
	(gr_line
		(start 237.725204 -136.85012)
		(end 237.723934 -136.847834)
		(stroke
			(width 0.2)
			(type default)
		)
		(layer "In3.Cu")
	)
	(gr_line
		(start 237.725204 -80.550258)
		(end 237.723934 -80.547972)
		(stroke
			(width 0.2)
			(type default)
		)
		(layer "In3.Cu")
	)
	(gr_line
		(start 237.725204 -76.550266)
		(end 237.723934 -76.54798)
		(stroke
			(width 0.2)
			(type default)
		)
		(layer "In3.Cu")
	)
	(gr_line
		(start 237.725204 -72.550274)
		(end 237.723934 -72.547988)
		(stroke
			(width 0.2)
			(type default)
		)
		(layer "In3.Cu")
	)
	(gr_line
		(start 237.725204 -68.550282)
		(end 237.723934 -68.547996)
		(stroke
			(width 0.2)
			(type default)
		)
		(layer "In3.Cu")
	)
	(gr_line
		(start 237.725204 -64.55029)
		(end 237.723934 -64.548004)
		(stroke
			(width 0.2)
			(type default)
		)
		(layer "In3.Cu")
	)
	(gr_line
		(start 237.725204 -60.550298)
		(end 237.723934 -60.548012)
		(stroke
			(width 0.2)
			(type default)
		)
		(layer "In3.Cu")
	)
	(gr_line
		(start 237.725204 -56.550306)
		(end 237.723934 -56.54802)
		(stroke
			(width 0.2)
			(type default)
		)
		(layer "In3.Cu")
	)
	(gr_line
		(start 237.725204 -52.550314)
		(end 237.723934 -52.548028)
		(stroke
			(width 0.2)
			(type default)
		)
		(layer "In3.Cu")
	)
	(gr_line
		(start 237.725204 -48.550322)
		(end 237.723934 -48.548036)
		(stroke
			(width 0.2)
			(type default)
		)
		(layer "In3.Cu")
	)
	(gr_line
		(start 237.725204 -44.55033)
		(end 237.723934 -44.548044)
		(stroke
			(width 0.2)
			(type default)
		)
		(layer "In3.Cu")
	)
	(gr_line
		(start 237.725204 -40.550338)
		(end 237.723934 -40.548052)
		(stroke
			(width 0.2)
			(type default)
		)
		(layer "In3.Cu")
	)
	(gr_line
		(start 237.725204 -36.550346)
		(end 237.723934 -36.54806)
		(stroke
			(width 0.2)
			(type default)
		)
		(layer "In3.Cu")
	)
	(gr_line
		(start 237.725204 -16.550386)
		(end 237.723934 -16.5481)
		(stroke
			(width 0.2)
			(type default)
		)
		(layer "In3.Cu")
	)
	(gr_arc
		(start 238.3663 -122.159522)
		(mid 238.706697 -121.178492)
		(end 237.722918 -120.84558)
		(stroke
			(width 0.2)
			(type default)
		)
		(layer "In3.Cu")
	)
	(gr_arc
		(start 238.374936 -178.149504)
		(mid 238.699802 -177.174906)
		(end 237.725204 -176.85004)
		(stroke
			(width 0.2)
			(type default)
		)
		(layer "In3.Cu")
	)
	(gr_arc
		(start 238.374936 -174.149512)
		(mid 238.699802 -173.174914)
		(end 237.725204 -172.850048)
		(stroke
			(width 0.2)
			(type default)
		)
		(layer "In3.Cu")
	)
	(gr_arc
		(start 238.374936 -170.14952)
		(mid 238.699802 -169.174922)
		(end 237.725204 -168.850056)
		(stroke
			(width 0.2)
			(type default)
		)
		(layer "In3.Cu")
	)
	(gr_arc
		(start 238.374936 -166.149528)
		(mid 238.699802 -165.17493)
		(end 237.725204 -164.850064)
		(stroke
			(width 0.2)
			(type default)
		)
		(layer "In3.Cu")
	)
	(gr_arc
		(start 238.374936 -138.149584)
		(mid 238.699802 -137.174986)
		(end 237.725204 -136.85012)
		(stroke
			(width 0.2)
			(type default)
		)
		(layer "In3.Cu")
	)
	(gr_arc
		(start 238.374936 -81.849722)
		(mid 238.699802 -80.875124)
		(end 237.725204 -80.550258)
		(stroke
			(width 0.2)
			(type default)
		)
		(layer "In3.Cu")
	)
	(gr_arc
		(start 238.374936 -77.84973)
		(mid 238.699802 -76.875132)
		(end 237.725204 -76.550266)
		(stroke
			(width 0.2)
			(type default)
		)
		(layer "In3.Cu")
	)
	(gr_arc
		(start 238.374936 -73.849738)
		(mid 238.699802 -72.87514)
		(end 237.725204 -72.550274)
		(stroke
			(width 0.2)
			(type default)
		)
		(layer "In3.Cu")
	)
	(gr_arc
		(start 238.374936 -69.849746)
		(mid 238.699802 -68.875148)
		(end 237.725204 -68.550282)
		(stroke
			(width 0.2)
			(type default)
		)
		(layer "In3.Cu")
	)
	(gr_arc
		(start 238.374936 -65.849754)
		(mid 238.699802 -64.875156)
		(end 237.725204 -64.55029)
		(stroke
			(width 0.2)
			(type default)
		)
		(layer "In3.Cu")
	)
	(gr_arc
		(start 238.374936 -61.849762)
		(mid 238.699802 -60.875164)
		(end 237.725204 -60.550298)
		(stroke
			(width 0.2)
			(type default)
		)
		(layer "In3.Cu")
	)
	(gr_arc
		(start 238.374936 -57.84977)
		(mid 238.699802 -56.875172)
		(end 237.725204 -56.550306)
		(stroke
			(width 0.2)
			(type default)
		)
		(layer "In3.Cu")
	)
	(gr_arc
		(start 238.374936 -53.849778)
		(mid 238.699802 -52.87518)
		(end 237.725204 -52.550314)
		(stroke
			(width 0.2)
			(type default)
		)
		(layer "In3.Cu")
	)
	(gr_arc
		(start 238.374936 -49.849786)
		(mid 238.699802 -48.875188)
		(end 237.725204 -48.550322)
		(stroke
			(width 0.2)
			(type default)
		)
		(layer "In3.Cu")
	)
	(gr_arc
		(start 238.374936 -45.849794)
		(mid 238.699802 -44.875196)
		(end 237.725204 -44.55033)
		(stroke
			(width 0.2)
			(type default)
		)
		(layer "In3.Cu")
	)
	(gr_arc
		(start 238.374936 -41.849802)
		(mid 238.699802 -40.875204)
		(end 237.725204 -40.550338)
		(stroke
			(width 0.2)
			(type default)
		)
		(layer "In3.Cu")
	)
	(gr_arc
		(start 238.374936 -37.84981)
		(mid 238.699802 -36.875212)
		(end 237.725204 -36.550346)
		(stroke
			(width 0.2)
			(type default)
		)
		(layer "In3.Cu")
	)
	(gr_arc
		(start 238.374936 -17.84985)
		(mid 238.699802 -16.875252)
		(end 237.725204 -16.550386)
		(stroke
			(width 0.2)
			(type default)
		)
		(layer "In3.Cu")
	)
	(gr_line
		(start 238.375952 -65.85204)
		(end 238.375952 -65.851786)
		(stroke
			(width 0.2)
			(type default)
		)
		(layer "In3.Cu")
	)
	(gr_line
		(start 238.375952 -65.851786)
		(end 238.374936 -65.849754)
		(stroke
			(width 0.2)
			(type default)
		)
		(layer "In3.Cu")
	)
	(gr_line
		(start 238.376206 -178.15179)
		(end 238.374936 -178.149504)
		(stroke
			(width 0.2)
			(type default)
		)
		(layer "In3.Cu")
	)
	(gr_line
		(start 238.376206 -174.151798)
		(end 238.374936 -174.149512)
		(stroke
			(width 0.2)
			(type default)
		)
		(layer "In3.Cu")
	)
	(gr_line
		(start 238.376206 -170.151806)
		(end 238.374936 -170.14952)
		(stroke
			(width 0.2)
			(type default)
		)
		(layer "In3.Cu")
	)
	(gr_line
		(start 238.376206 -166.151814)
		(end 238.374936 -166.149528)
		(stroke
			(width 0.2)
			(type default)
		)
		(layer "In3.Cu")
	)
	(gr_line
		(start 238.376206 -138.15187)
		(end 238.374936 -138.149584)
		(stroke
			(width 0.2)
			(type default)
		)
		(layer "In3.Cu")
	)
	(gr_line
		(start 238.376206 -81.852008)
		(end 238.374936 -81.849722)
		(stroke
			(width 0.2)
			(type default)
		)
		(layer "In3.Cu")
	)
	(gr_line
		(start 238.376206 -77.852016)
		(end 238.374936 -77.84973)
		(stroke
			(width 0.2)
			(type default)
		)
		(layer "In3.Cu")
	)
	(gr_line
		(start 238.376206 -73.852024)
		(end 238.374936 -73.849738)
		(stroke
			(width 0.2)
			(type default)
		)
		(layer "In3.Cu")
	)
	(gr_line
		(start 238.376206 -69.852032)
		(end 238.374936 -69.849746)
		(stroke
			(width 0.2)
			(type default)
		)
		(layer "In3.Cu")
	)
	(gr_line
		(start 238.376206 -61.852048)
		(end 238.374936 -61.849762)
		(stroke
			(width 0.2)
			(type default)
		)
		(layer "In3.Cu")
	)
	(gr_line
		(start 238.376206 -57.852056)
		(end 238.374936 -57.84977)
		(stroke
			(width 0.2)
			(type default)
		)
		(layer "In3.Cu")
	)
	(gr_line
		(start 238.376206 -53.852064)
		(end 238.374936 -53.849778)
		(stroke
			(width 0.2)
			(type default)
		)
		(layer "In3.Cu")
	)
	(gr_line
		(start 238.376206 -49.852072)
		(end 238.374936 -49.849786)
		(stroke
			(width 0.2)
			(type default)
		)
		(layer "In3.Cu")
	)
	(gr_line
		(start 238.376206 -45.85208)
		(end 238.374936 -45.849794)
		(stroke
			(width 0.2)
			(type default)
		)
		(layer "In3.Cu")
	)
	(gr_line
		(start 238.376206 -41.852088)
		(end 238.374936 -41.849802)
		(stroke
			(width 0.2)
			(type default)
		)
		(layer "In3.Cu")
	)
	(gr_line
		(start 238.376206 -37.852096)
		(end 238.374936 -37.84981)
		(stroke
			(width 0.2)
			(type default)
		)
		(layer "In3.Cu")
	)
	(gr_line
		(start 238.376206 -17.852136)
		(end 238.374936 -17.84985)
		(stroke
			(width 0.2)
			(type default)
		)
		(layer "In3.Cu")
	)
	(gr_arc
		(start 238.377222 -162.154108)
		(mid 238.704374 -161.172652)
		(end 237.722918 -160.8455)
		(stroke
			(width 0.2)
			(type default)
		)
		(layer "In3.Cu")
	)
	(gr_arc
		(start 238.377222 -158.154116)
		(mid 238.704374 -157.17266)
		(end 237.722918 -156.845508)
		(stroke
			(width 0.2)
			(type default)
		)
		(layer "In3.Cu")
	)
	(gr_arc
		(start 238.377222 -154.154124)
		(mid 238.704374 -153.172668)
		(end 237.722918 -152.845516)
		(stroke
			(width 0.2)
			(type default)
		)
		(layer "In3.Cu")
	)
	(gr_arc
		(start 238.377222 -150.154132)
		(mid 238.704374 -149.172676)
		(end 237.722918 -148.845524)
		(stroke
			(width 0.2)
			(type default)
		)
		(layer "In3.Cu")
	)
	(gr_arc
		(start 238.377222 -130.154172)
		(mid 238.704374 -129.172716)
		(end 237.722918 -128.845564)
		(stroke
			(width 0.2)
			(type default)
		)
		(layer "In3.Cu")
	)
	(gr_arc
		(start 238.377222 -126.15418)
		(mid 238.704374 -125.172724)
		(end 237.722918 -124.845572)
		(stroke
			(width 0.2)
			(type default)
		)
		(layer "In3.Cu")
	)
	(gr_arc
		(start 238.377222 -118.154196)
		(mid 238.704374 -117.17274)
		(end 237.722918 -116.845588)
		(stroke
			(width 0.2)
			(type default)
		)
		(layer "In3.Cu")
	)
	(gr_arc
		(start 238.377222 -114.154204)
		(mid 238.704374 -113.172748)
		(end 237.722918 -112.845596)
		(stroke
			(width 0.2)
			(type default)
		)
		(layer "In3.Cu")
	)
	(gr_arc
		(start 238.377222 -11.854434)
		(mid 238.704374 -10.872978)
		(end 237.722918 -10.545826)
		(stroke
			(width 0.2)
			(type default)
		)
		(layer "In3.Cu")
	)
	(gr_line
		(start 240.219484 -128.161034)
		(end 242.21948 -129.161032)
		(stroke
			(width 0.2)
			(type default)
		)
		(layer "In3.Cu")
	)
	(gr_line
		(start 240.219484 -124.161042)
		(end 242.20805 -125.155198)
		(stroke
			(width 0.2)
			(type default)
		)
		(layer "In3.Cu")
	)
	(gr_line
		(start 240.222786 -164.154104)
		(end 242.222782 -165.154102)
		(stroke
			(width 0.2)
			(type default)
		)
		(layer "In3.Cu")
	)
	(gr_line
		(start 240.222786 -160.154112)
		(end 242.222528 -161.15411)
		(stroke
			(width 0.2)
			(type default)
		)
		(layer "In3.Cu")
	)
	(gr_line
		(start 240.222786 -156.15412)
		(end 242.222528 -157.154118)
		(stroke
			(width 0.2)
			(type default)
		)
		(layer "In3.Cu")
	)
	(gr_line
		(start 240.222786 -152.154128)
		(end 242.222782 -153.154126)
		(stroke
			(width 0.2)
			(type default)
		)
		(layer "In3.Cu")
	)
	(gr_line
		(start 240.222786 -120.154192)
		(end 242.222528 -121.15419)
		(stroke
			(width 0.2)
			(type default)
		)
		(layer "In3.Cu")
	)
	(gr_line
		(start 240.222786 -116.1542)
		(end 242.222782 -117.154198)
		(stroke
			(width 0.2)
			(type default)
		)
		(layer "In3.Cu")
	)
	(gr_line
		(start 240.223802 -136.151874)
		(end 242.223798 -137.151872)
		(stroke
			(width 0.2)
			(type default)
		)
		(layer "In3.Cu")
	)
	(gr_line
		(start 240.223802 -108.15193)
		(end 242.223798 -109.151928)
		(stroke
			(width 0.2)
			(type default)
		)
		(layer "In3.Cu")
	)
	(gr_line
		(start 240.223802 -35.8521)
		(end 242.223798 -36.852098)
		(stroke
			(width 0.2)
			(type default)
		)
		(layer "In3.Cu")
	)
	(gr_line
		(start 240.225072 -136.149588)
		(end 240.223802 -136.151874)
		(stroke
			(width 0.2)
			(type default)
		)
		(layer "In3.Cu")
	)
	(gr_line
		(start 240.225072 -108.149644)
		(end 240.223802 -108.15193)
		(stroke
			(width 0.2)
			(type default)
		)
		(layer "In3.Cu")
	)
	(gr_line
		(start 240.236502 -180.126894)
		(end 242.236498 -181.126892)
		(stroke
			(width 0.2)
			(type default)
		)
		(layer "In3.Cu")
	)
	(gr_line
		(start 240.236502 -176.126902)
		(end 242.236498 -177.1269)
		(stroke
			(width 0.2)
			(type default)
		)
		(layer "In3.Cu")
	)
	(gr_line
		(start 240.236502 -172.12691)
		(end 242.236498 -173.126908)
		(stroke
			(width 0.2)
			(type default)
		)
		(layer "In3.Cu")
	)
	(gr_line
		(start 240.236502 -168.126918)
		(end 242.236498 -169.126916)
		(stroke
			(width 0.2)
			(type default)
		)
		(layer "In3.Cu")
	)
	(gr_line
		(start 240.236502 -83.827112)
		(end 242.236498 -84.82711)
		(stroke
			(width 0.2)
			(type default)
		)
		(layer "In3.Cu")
	)
	(gr_line
		(start 240.236502 -79.82712)
		(end 242.228116 -80.8228)
		(stroke
			(width 0.2)
			(type default)
		)
		(layer "In3.Cu")
	)
	(gr_line
		(start 240.236502 -75.827128)
		(end 242.228116 -76.822808)
		(stroke
			(width 0.2)
			(type default)
		)
		(layer "In3.Cu")
	)
	(gr_line
		(start 240.236502 -71.827136)
		(end 242.228116 -72.822816)
		(stroke
			(width 0.2)
			(type default)
		)
		(layer "In3.Cu")
	)
	(gr_line
		(start 240.236502 -67.827144)
		(end 242.236498 -68.827142)
		(stroke
			(width 0.2)
			(type default)
		)
		(layer "In3.Cu")
	)
	(gr_line
		(start 240.236502 -63.827152)
		(end 242.236498 -64.82715)
		(stroke
			(width 0.2)
			(type default)
		)
		(layer "In3.Cu")
	)
	(gr_line
		(start 240.236502 -59.82716)
		(end 242.236498 -60.827158)
		(stroke
			(width 0.2)
			(type default)
		)
		(layer "In3.Cu")
	)
	(gr_line
		(start 240.236502 -55.827168)
		(end 242.236498 -56.827166)
		(stroke
			(width 0.2)
			(type default)
		)
		(layer "In3.Cu")
	)
	(gr_line
		(start 240.236502 -51.827176)
		(end 242.228116 -52.822856)
		(stroke
			(width 0.2)
			(type default)
		)
		(layer "In3.Cu")
	)
	(gr_line
		(start 240.236502 -47.827184)
		(end 242.236498 -48.827182)
		(stroke
			(width 0.2)
			(type default)
		)
		(layer "In3.Cu")
	)
	(gr_line
		(start 240.236502 -43.827192)
		(end 242.236498 -44.82719)
		(stroke
			(width 0.2)
			(type default)
		)
		(layer "In3.Cu")
	)
	(gr_line
		(start 240.236502 -39.8272)
		(end 242.236498 -40.827198)
		(stroke
			(width 0.2)
			(type default)
		)
		(layer "In3.Cu")
	)
	(gr_arc
		(start 240.863374 -78.572868)
		(mid 239.922812 -78.886558)
		(end 240.236502 -79.82712)
		(stroke
			(width 0.2)
			(type default)
		)
		(layer "In3.Cu")
	)
	(gr_arc
		(start 240.863374 -74.572876)
		(mid 239.922812 -74.886566)
		(end 240.236502 -75.827128)
		(stroke
			(width 0.2)
			(type default)
		)
		(layer "In3.Cu")
	)
	(gr_arc
		(start 240.863374 -70.572884)
		(mid 239.922812 -70.886574)
		(end 240.236502 -71.827136)
		(stroke
			(width 0.2)
			(type default)
		)
		(layer "In3.Cu")
	)
	(gr_arc
		(start 240.863374 -50.572924)
		(mid 239.922812 -50.886614)
		(end 240.236502 -51.827176)
		(stroke
			(width 0.2)
			(type default)
		)
		(layer "In3.Cu")
	)
	(gr_arc
		(start 240.871756 -178.87696)
		(mid 239.92498 -179.182145)
		(end 240.236502 -180.126894)
		(stroke
			(width 0.2)
			(type default)
		)
		(layer "In3.Cu")
	)
	(gr_arc
		(start 240.871756 -174.876968)
		(mid 239.92498 -175.182153)
		(end 240.236502 -176.126902)
		(stroke
			(width 0.2)
			(type default)
		)
		(layer "In3.Cu")
	)
	(gr_arc
		(start 240.871756 -170.876976)
		(mid 239.92498 -171.182161)
		(end 240.236502 -172.12691)
		(stroke
			(width 0.2)
			(type default)
		)
		(layer "In3.Cu")
	)
	(gr_arc
		(start 240.871756 -166.876984)
		(mid 239.92498 -167.182169)
		(end 240.236502 -168.126918)
		(stroke
			(width 0.2)
			(type default)
		)
		(layer "In3.Cu")
	)
	(gr_arc
		(start 240.871756 -82.577178)
		(mid 239.92498 -82.882363)
		(end 240.236502 -83.827112)
		(stroke
			(width 0.2)
			(type default)
		)
		(layer "In3.Cu")
	)
	(gr_arc
		(start 240.871756 -66.57721)
		(mid 239.92498 -66.882395)
		(end 240.236502 -67.827144)
		(stroke
			(width 0.2)
			(type default)
		)
		(layer "In3.Cu")
	)
	(gr_arc
		(start 240.871756 -62.577218)
		(mid 239.92498 -62.882403)
		(end 240.236502 -63.827152)
		(stroke
			(width 0.2)
			(type default)
		)
		(layer "In3.Cu")
	)
	(gr_arc
		(start 240.871756 -58.577226)
		(mid 239.92498 -58.882411)
		(end 240.236502 -59.82716)
		(stroke
			(width 0.2)
			(type default)
		)
		(layer "In3.Cu")
	)
	(gr_arc
		(start 240.871756 -54.577234)
		(mid 239.92498 -54.882419)
		(end 240.236502 -55.827168)
		(stroke
			(width 0.2)
			(type default)
		)
		(layer "In3.Cu")
	)
	(gr_arc
		(start 240.871756 -46.57725)
		(mid 239.92498 -46.882435)
		(end 240.236502 -47.827184)
		(stroke
			(width 0.2)
			(type default)
		)
		(layer "In3.Cu")
	)
	(gr_arc
		(start 240.871756 -42.577258)
		(mid 239.92498 -42.882443)
		(end 240.236502 -43.827192)
		(stroke
			(width 0.2)
			(type default)
		)
		(layer "In3.Cu")
	)
	(gr_arc
		(start 240.871756 -38.577266)
		(mid 239.92498 -38.882451)
		(end 240.236502 -39.8272)
		(stroke
			(width 0.2)
			(type default)
		)
		(layer "In3.Cu")
	)
	(gr_arc
		(start 240.874804 -134.850124)
		(mid 239.900206 -135.17499)
		(end 240.225072 -136.149588)
		(stroke
			(width 0.2)
			(type default)
		)
		(layer "In3.Cu")
	)
	(gr_arc
		(start 240.874804 -106.85018)
		(mid 239.900206 -107.175046)
		(end 240.225072 -108.149644)
		(stroke
			(width 0.2)
			(type default)
		)
		(layer "In3.Cu")
	)
	(gr_line
		(start 240.876074 -134.847838)
		(end 240.874804 -134.850124)
		(stroke
			(width 0.2)
			(type default)
		)
		(layer "In3.Cu")
	)
	(gr_line
		(start 240.876074 -106.847894)
		(end 240.874804 -106.85018)
		(stroke
			(width 0.2)
			(type default)
		)
		(layer "In3.Cu")
	)
	(gr_arc
		(start 240.876074 -34.548064)
		(mid 239.89792 -34.873946)
		(end 240.223802 -35.8521)
		(stroke
			(width 0.2)
			(type default)
		)
		(layer "In3.Cu")
	)
	(gr_arc
		(start 240.87709 -158.845504)
		(mid 239.895634 -159.172656)
		(end 240.222786 -160.154112)
		(stroke
			(width 0.2)
			(type default)
		)
		(layer "In3.Cu")
	)
	(gr_arc
		(start 240.87709 -154.845512)
		(mid 239.895634 -155.172664)
		(end 240.222786 -156.15412)
		(stroke
			(width 0.2)
			(type default)
		)
		(layer "In3.Cu")
	)
	(gr_arc
		(start 240.87709 -118.845584)
		(mid 239.895634 -119.172736)
		(end 240.222786 -120.154192)
		(stroke
			(width 0.2)
			(type default)
		)
		(layer "In3.Cu")
	)
	(gr_arc
		(start 240.877344 -162.845496)
		(mid 239.895939 -163.172546)
		(end 240.222786 -164.154104)
		(stroke
			(width 0.2)
			(type default)
		)
		(layer "In3.Cu")
	)
	(gr_arc
		(start 240.877344 -150.84552)
		(mid 239.895939 -151.17257)
		(end 240.222786 -152.154128)
		(stroke
			(width 0.2)
			(type default)
		)
		(layer "In3.Cu")
	)
	(gr_arc
		(start 240.877344 -114.845592)
		(mid 239.895939 -115.172642)
		(end 240.222786 -116.1542)
		(stroke
			(width 0.2)
			(type default)
		)
		(layer "In3.Cu")
	)
	(gr_arc
		(start 240.880392 -122.838718)
		(mid 239.888776 -123.169426)
		(end 240.219484 -124.161042)
		(stroke
			(width 0.2)
			(type default)
		)
		(layer "In3.Cu")
	)
	(gr_arc
		(start 240.891822 -126.844552)
		(mid 239.891674 -127.163691)
		(end 240.219484 -128.161034)
		(stroke
			(width 0.2)
			(type default)
		)
		(layer "In3.Cu")
	)
	(gr_arc
		(start 242.20805 -125.155198)
		(mid 243.208198 -124.836059)
		(end 242.880388 -123.838716)
		(stroke
			(width 0.2)
			(type default)
		)
		(layer "In3.Cu")
	)
	(gr_arc
		(start 242.21948 -129.161032)
		(mid 243.211096 -128.830324)
		(end 242.880388 -127.838708)
		(stroke
			(width 0.2)
			(type default)
		)
		(layer "In3.Cu")
	)
	(gr_arc
		(start 242.222528 -161.15411)
		(mid 243.204289 -160.82711)
		(end 242.877086 -159.845502)
		(stroke
			(width 0.2)
			(type default)
		)
		(layer "In3.Cu")
	)
	(gr_arc
		(start 242.222528 -157.154118)
		(mid 243.204289 -156.827118)
		(end 242.877086 -155.84551)
		(stroke
			(width 0.2)
			(type default)
		)
		(layer "In3.Cu")
	)
	(gr_arc
		(start 242.222528 -121.15419)
		(mid 243.204289 -120.82719)
		(end 242.877086 -119.845582)
		(stroke
			(width 0.2)
			(type default)
		)
		(layer "In3.Cu")
	)
	(gr_arc
		(start 242.222782 -165.154102)
		(mid 243.204238 -164.82695)
		(end 242.877086 -163.845494)
		(stroke
			(width 0.2)
			(type default)
		)
		(layer "In3.Cu")
	)
	(gr_arc
		(start 242.222782 -153.154126)
		(mid 243.204238 -152.826974)
		(end 242.877086 -151.845518)
		(stroke
			(width 0.2)
			(type default)
		)
		(layer "In3.Cu")
	)
	(gr_arc
		(start 242.222782 -117.154198)
		(mid 243.204238 -116.827046)
		(end 242.877086 -115.84559)
		(stroke
			(width 0.2)
			(type default)
		)
		(layer "In3.Cu")
	)
	(gr_line
		(start 242.223798 -137.151872)
		(end 242.224052 -137.151618)
		(stroke
			(width 0.2)
			(type default)
		)
		(layer "In3.Cu")
	)
	(gr_line
		(start 242.223798 -109.151928)
		(end 242.224052 -109.151674)
		(stroke
			(width 0.2)
			(type default)
		)
		(layer "In3.Cu")
	)
	(gr_arc
		(start 242.223798 -36.852098)
		(mid 243.201952 -36.526216)
		(end 242.87607 -35.548062)
		(stroke
			(width 0.2)
			(type default)
		)
		(layer "In3.Cu")
	)
	(gr_line
		(start 242.224052 -137.151618)
		(end 242.225068 -137.149586)
		(stroke
			(width 0.2)
			(type default)
		)
		(layer "In3.Cu")
	)
	(gr_line
		(start 242.224052 -109.151674)
		(end 242.225068 -109.149642)
		(stroke
			(width 0.2)
			(type default)
		)
		(layer "In3.Cu")
	)
	(gr_arc
		(start 242.225068 -137.149586)
		(mid 243.199666 -136.82472)
		(end 242.8748 -135.850122)
		(stroke
			(width 0.2)
			(type default)
		)
		(layer "In3.Cu")
	)
	(gr_arc
		(start 242.225068 -109.149642)
		(mid 243.199666 -108.824776)
		(end 242.8748 -107.850178)
		(stroke
			(width 0.2)
			(type default)
		)
		(layer "In3.Cu")
	)
	(gr_arc
		(start 242.228116 -80.8228)
		(mid 243.174892 -80.517615)
		(end 242.86337 -79.572866)
		(stroke
			(width 0.2)
			(type default)
		)
		(layer "In3.Cu")
	)
	(gr_arc
		(start 242.228116 -76.822808)
		(mid 243.174892 -76.517623)
		(end 242.86337 -75.572874)
		(stroke
			(width 0.2)
			(type default)
		)
		(layer "In3.Cu")
	)
	(gr_arc
		(start 242.228116 -72.822816)
		(mid 243.174892 -72.517631)
		(end 242.86337 -71.572882)
		(stroke
			(width 0.2)
			(type default)
		)
		(layer "In3.Cu")
	)
	(gr_arc
		(start 242.228116 -52.822856)
		(mid 243.174892 -52.517671)
		(end 242.86337 -51.572922)
		(stroke
			(width 0.2)
			(type default)
		)
		(layer "In3.Cu")
	)
	(gr_arc
		(start 242.236498 -181.126892)
		(mid 243.17706 -180.813202)
		(end 242.86337 -179.87264)
		(stroke
			(width 0.2)
			(type default)
		)
		(layer "In3.Cu")
	)
	(gr_arc
		(start 242.236498 -177.1269)
		(mid 243.17706 -176.81321)
		(end 242.86337 -175.872648)
		(stroke
			(width 0.2)
			(type default)
		)
		(layer "In3.Cu")
	)
	(gr_arc
		(start 242.236498 -173.126908)
		(mid 243.17706 -172.813218)
		(end 242.86337 -171.872656)
		(stroke
			(width 0.2)
			(type default)
		)
		(layer "In3.Cu")
	)
	(gr_arc
		(start 242.236498 -169.126916)
		(mid 243.17706 -168.813226)
		(end 242.86337 -167.872664)
		(stroke
			(width 0.2)
			(type default)
		)
		(layer "In3.Cu")
	)
	(gr_arc
		(start 242.236498 -84.82711)
		(mid 243.17706 -84.51342)
		(end 242.86337 -83.572858)
		(stroke
			(width 0.2)
			(type default)
		)
		(layer "In3.Cu")
	)
	(gr_arc
		(start 242.236498 -68.827142)
		(mid 243.17706 -68.513452)
		(end 242.86337 -67.57289)
		(stroke
			(width 0.2)
			(type default)
		)
		(layer "In3.Cu")
	)
	(gr_arc
		(start 242.236498 -64.82715)
		(mid 243.17706 -64.51346)
		(end 242.86337 -63.572898)
		(stroke
			(width 0.2)
			(type default)
		)
		(layer "In3.Cu")
	)
	(gr_arc
		(start 242.236498 -60.827158)
		(mid 243.17706 -60.513468)
		(end 242.86337 -59.572906)
		(stroke
			(width 0.2)
			(type default)
		)
		(layer "In3.Cu")
	)
	(gr_arc
		(start 242.236498 -56.827166)
		(mid 243.17706 -56.513476)
		(end 242.86337 -55.572914)
		(stroke
			(width 0.2)
			(type default)
		)
		(layer "In3.Cu")
	)
	(gr_arc
		(start 242.236498 -48.827182)
		(mid 243.17706 -48.513492)
		(end 242.86337 -47.57293)
		(stroke
			(width 0.2)
			(type default)
		)
		(layer "In3.Cu")
	)
	(gr_arc
		(start 242.236498 -44.82719)
		(mid 243.17706 -44.5135)
		(end 242.86337 -43.572938)
		(stroke
			(width 0.2)
			(type default)
		)
		(layer "In3.Cu")
	)
	(gr_arc
		(start 242.236498 -40.827198)
		(mid 243.17706 -40.513508)
		(end 242.86337 -39.572946)
		(stroke
			(width 0.2)
			(type default)
		)
		(layer "In3.Cu")
	)
	(gr_line
		(start 242.86337 -179.87264)
		(end 240.871756 -178.87696)
		(stroke
			(width 0.2)
			(type default)
		)
		(layer "In3.Cu")
	)
	(gr_line
		(start 242.86337 -175.872648)
		(end 240.871756 -174.876968)
		(stroke
			(width 0.2)
			(type default)
		)
		(layer "In3.Cu")
	)
	(gr_line
		(start 242.86337 -171.872656)
		(end 240.871756 -170.876976)
		(stroke
			(width 0.2)
			(type default)
		)
		(layer "In3.Cu")
	)
	(gr_line
		(start 242.86337 -167.872664)
		(end 240.871756 -166.876984)
		(stroke
			(width 0.2)
			(type default)
		)
		(layer "In3.Cu")
	)
	(gr_line
		(start 242.86337 -83.572858)
		(end 240.871756 -82.577178)
		(stroke
			(width 0.2)
			(type default)
		)
		(layer "In3.Cu")
	)
	(gr_line
		(start 242.86337 -79.572866)
		(end 240.863374 -78.572868)
		(stroke
			(width 0.2)
			(type default)
		)
		(layer "In3.Cu")
	)
	(gr_line
		(start 242.86337 -75.572874)
		(end 240.863374 -74.572876)
		(stroke
			(width 0.2)
			(type default)
		)
		(layer "In3.Cu")
	)
	(gr_line
		(start 242.86337 -71.572882)
		(end 240.863374 -70.572884)
		(stroke
			(width 0.2)
			(type default)
		)
		(layer "In3.Cu")
	)
	(gr_line
		(start 242.86337 -67.57289)
		(end 240.871756 -66.57721)
		(stroke
			(width 0.2)
			(type default)
		)
		(layer "In3.Cu")
	)
	(gr_line
		(start 242.86337 -63.572898)
		(end 240.871756 -62.577218)
		(stroke
			(width 0.2)
			(type default)
		)
		(layer "In3.Cu")
	)
	(gr_line
		(start 242.86337 -59.572906)
		(end 240.871756 -58.577226)
		(stroke
			(width 0.2)
			(type default)
		)
		(layer "In3.Cu")
	)
	(gr_line
		(start 242.86337 -55.572914)
		(end 240.871756 -54.577234)
		(stroke
			(width 0.2)
			(type default)
		)
		(layer "In3.Cu")
	)
	(gr_line
		(start 242.86337 -51.572922)
		(end 240.863374 -50.572924)
		(stroke
			(width 0.2)
			(type default)
		)
		(layer "In3.Cu")
	)
	(gr_line
		(start 242.86337 -47.57293)
		(end 240.871756 -46.57725)
		(stroke
			(width 0.2)
			(type default)
		)
		(layer "In3.Cu")
	)
	(gr_line
		(start 242.86337 -43.572938)
		(end 240.871756 -42.577258)
		(stroke
			(width 0.2)
			(type default)
		)
		(layer "In3.Cu")
	)
	(gr_line
		(start 242.86337 -39.572946)
		(end 240.871756 -38.577266)
		(stroke
			(width 0.2)
			(type default)
		)
		(layer "In3.Cu")
	)
	(gr_line
		(start 242.8748 -135.850122)
		(end 242.87607 -135.847836)
		(stroke
			(width 0.2)
			(type default)
		)
		(layer "In3.Cu")
	)
	(gr_line
		(start 242.8748 -107.850178)
		(end 242.87607 -107.847892)
		(stroke
			(width 0.2)
			(type default)
		)
		(layer "In3.Cu")
	)
	(gr_line
		(start 242.87607 -135.847836)
		(end 240.876074 -134.847838)
		(stroke
			(width 0.2)
			(type default)
		)
		(layer "In3.Cu")
	)
	(gr_line
		(start 242.87607 -107.847892)
		(end 240.876074 -106.847894)
		(stroke
			(width 0.2)
			(type default)
		)
		(layer "In3.Cu")
	)
	(gr_line
		(start 242.87607 -35.548062)
		(end 240.876074 -34.548064)
		(stroke
			(width 0.2)
			(type default)
		)
		(layer "In3.Cu")
	)
	(gr_line
		(start 242.877086 -163.845494)
		(end 240.877344 -162.845496)
		(stroke
			(width 0.2)
			(type default)
		)
		(layer "In3.Cu")
	)
	(gr_line
		(start 242.877086 -159.845502)
		(end 240.87709 -158.845504)
		(stroke
			(width 0.2)
			(type default)
		)
		(layer "In3.Cu")
	)
	(gr_line
		(start 242.877086 -155.84551)
		(end 240.87709 -154.845512)
		(stroke
			(width 0.2)
			(type default)
		)
		(layer "In3.Cu")
	)
	(gr_line
		(start 242.877086 -151.845518)
		(end 240.877344 -150.84552)
		(stroke
			(width 0.2)
			(type default)
		)
		(layer "In3.Cu")
	)
	(gr_line
		(start 242.877086 -119.845582)
		(end 240.87709 -118.845584)
		(stroke
			(width 0.2)
			(type default)
		)
		(layer "In3.Cu")
	)
	(gr_line
		(start 242.877086 -115.84559)
		(end 240.877344 -114.845592)
		(stroke
			(width 0.2)
			(type default)
		)
		(layer "In3.Cu")
	)
	(gr_line
		(start 242.880388 -127.838708)
		(end 240.891822 -126.844552)
		(stroke
			(width 0.2)
			(type default)
		)
		(layer "In3.Cu")
	)
	(gr_line
		(start 242.880388 -123.838716)
		(end 240.880392 -122.838718)
		(stroke
			(width 0.2)
			(type default)
		)
		(layer "In3.Cu")
	)
	(gr_line
		(start 271.9705 -359.885996)
		(end 273.1135 -359.885996)
		(stroke
			(width 0.2)
			(type default)
		)
		(layer "In3.Cu")
	)
	(gr_line
		(start 271.9705 -358.085898)
		(end 273.1135 -358.085898)
		(stroke
			(width 0.2)
			(type default)
		)
		(layer "In3.Cu")
	)
	(gr_line
		(start 271.9705 -356.286054)
		(end 273.1135 -356.286054)
		(stroke
			(width 0.2)
			(type default)
		)
		(layer "In3.Cu")
	)
	(gr_line
		(start 271.9705 -354.485956)
		(end 273.1135 -354.485956)
		(stroke
			(width 0.2)
			(type default)
		)
		(layer "In3.Cu")
	)
	(gr_line
		(start 271.9705 -352.686112)
		(end 273.1135 -352.686112)
		(stroke
			(width 0.2)
			(type default)
		)
		(layer "In3.Cu")
	)
	(gr_line
		(start 271.9705 -350.886014)
		(end 273.1135 -350.886014)
		(stroke
			(width 0.2)
			(type default)
		)
		(layer "In3.Cu")
	)
	(gr_line
		(start 271.9705 -338.28863)
		(end 273.1135 -338.28863)
		(stroke
			(width 0.2)
			(type default)
		)
		(layer "In3.Cu")
	)
	(gr_line
		(start 271.9705 -336.488532)
		(end 273.1135 -336.488532)
		(stroke
			(width 0.2)
			(type default)
		)
		(layer "In3.Cu")
	)
	(gr_line
		(start 271.9705 -334.688434)
		(end 273.1135 -334.688434)
		(stroke
			(width 0.2)
			(type default)
		)
		(layer "In3.Cu")
	)
	(gr_line
		(start 271.9705 -332.88859)
		(end 273.1135 -332.88859)
		(stroke
			(width 0.2)
			(type default)
		)
		(layer "In3.Cu")
	)
	(gr_line
		(start 271.9705 -331.088492)
		(end 273.1135 -331.088492)
		(stroke
			(width 0.2)
			(type default)
		)
		(layer "In3.Cu")
	)
	(gr_line
		(start 271.9705 -329.288648)
		(end 273.1135 -329.288648)
		(stroke
			(width 0.2)
			(type default)
		)
		(layer "In3.Cu")
	)
	(gr_line
		(start 271.9705 -316.68847)
		(end 273.1135 -316.68847)
		(stroke
			(width 0.2)
			(type default)
		)
		(layer "In3.Cu")
	)
	(gr_line
		(start 271.9705 -314.888626)
		(end 273.1135 -314.888626)
		(stroke
			(width 0.2)
			(type default)
		)
		(layer "In3.Cu")
	)
	(gr_line
		(start 271.9705 -313.088528)
		(end 273.1135 -313.088528)
		(stroke
			(width 0.2)
			(type default)
		)
		(layer "In3.Cu")
	)
	(gr_line
		(start 271.9705 -311.28843)
		(end 273.1135 -311.28843)
		(stroke
			(width 0.2)
			(type default)
		)
		(layer "In3.Cu")
	)
	(gr_line
		(start 271.9705 -309.488586)
		(end 273.1135 -309.488586)
		(stroke
			(width 0.2)
			(type default)
		)
		(layer "In3.Cu")
	)
	(gr_line
		(start 271.9705 -307.688488)
		(end 273.1135 -307.688488)
		(stroke
			(width 0.2)
			(type default)
		)
		(layer "In3.Cu")
	)
	(gr_arc
		(start 271.970754 -359.123996)
		(mid 271.5895 -359.504869)
		(end 271.9705 -359.885996)
		(stroke
			(width 0.2)
			(type default)
		)
		(layer "In3.Cu")
	)
	(gr_arc
		(start 271.970754 -357.323898)
		(mid 271.5895 -357.704771)
		(end 271.9705 -358.085898)
		(stroke
			(width 0.2)
			(type default)
		)
		(layer "In3.Cu")
	)
	(gr_arc
		(start 271.970754 -355.524054)
		(mid 271.5895 -355.904927)
		(end 271.9705 -356.286054)
		(stroke
			(width 0.2)
			(type default)
		)
		(layer "In3.Cu")
	)
	(gr_arc
		(start 271.970754 -353.723956)
		(mid 271.5895 -354.104829)
		(end 271.9705 -354.485956)
		(stroke
			(width 0.2)
			(type default)
		)
		(layer "In3.Cu")
	)
	(gr_arc
		(start 271.970754 -351.924112)
		(mid 271.5895 -352.304985)
		(end 271.9705 -352.686112)
		(stroke
			(width 0.2)
			(type default)
		)
		(layer "In3.Cu")
	)
	(gr_arc
		(start 271.970754 -350.124014)
		(mid 271.5895 -350.504887)
		(end 271.9705 -350.886014)
		(stroke
			(width 0.2)
			(type default)
		)
		(layer "In3.Cu")
	)
	(gr_arc
		(start 271.970754 -337.52155)
		(mid 271.58696 -337.904963)
		(end 271.9705 -338.28863)
		(stroke
			(width 0.2)
			(type default)
		)
		(layer "In3.Cu")
	)
	(gr_arc
		(start 271.970754 -335.721452)
		(mid 271.58696 -336.104865)
		(end 271.9705 -336.488532)
		(stroke
			(width 0.2)
			(type default)
		)
		(layer "In3.Cu")
	)
	(gr_arc
		(start 271.970754 -333.921354)
		(mid 271.58696 -334.304767)
		(end 271.9705 -334.688434)
		(stroke
			(width 0.2)
			(type default)
		)
		(layer "In3.Cu")
	)
	(gr_arc
		(start 271.970754 -332.12151)
		(mid 271.58696 -332.504923)
		(end 271.9705 -332.88859)
		(stroke
			(width 0.2)
			(type default)
		)
		(layer "In3.Cu")
	)
	(gr_arc
		(start 271.970754 -330.321412)
		(mid 271.58696 -330.704825)
		(end 271.9705 -331.088492)
		(stroke
			(width 0.2)
			(type default)
		)
		(layer "In3.Cu")
	)
	(gr_arc
		(start 271.970754 -328.521568)
		(mid 271.58696 -328.904981)
		(end 271.9705 -329.288648)
		(stroke
			(width 0.2)
			(type default)
		)
		(layer "In3.Cu")
	)
	(gr_arc
		(start 271.970754 -315.92139)
		(mid 271.58696 -316.304803)
		(end 271.9705 -316.68847)
		(stroke
			(width 0.2)
			(type default)
		)
		(layer "In3.Cu")
	)
	(gr_arc
		(start 271.970754 -314.121546)
		(mid 271.58696 -314.504959)
		(end 271.9705 -314.888626)
		(stroke
			(width 0.2)
			(type default)
		)
		(layer "In3.Cu")
	)
	(gr_arc
		(start 271.970754 -312.321448)
		(mid 271.58696 -312.704861)
		(end 271.9705 -313.088528)
		(stroke
			(width 0.2)
			(type default)
		)
		(layer "In3.Cu")
	)
	(gr_arc
		(start 271.970754 -310.52135)
		(mid 271.58696 -310.904763)
		(end 271.9705 -311.28843)
		(stroke
			(width 0.2)
			(type default)
		)
		(layer "In3.Cu")
	)
	(gr_arc
		(start 271.970754 -308.721506)
		(mid 271.58696 -309.104919)
		(end 271.9705 -309.488586)
		(stroke
			(width 0.2)
			(type default)
		)
		(layer "In3.Cu")
	)
	(gr_arc
		(start 271.970754 -306.921408)
		(mid 271.58696 -307.304821)
		(end 271.9705 -307.688488)
		(stroke
			(width 0.2)
			(type default)
		)
		(layer "In3.Cu")
	)
	(gr_arc
		(start 273.1135 -359.885996)
		(mid 273.4945 -359.504996)
		(end 273.1135 -359.123996)
		(stroke
			(width 0.2)
			(type default)
		)
		(layer "In3.Cu")
	)
	(gr_line
		(start 273.1135 -359.123996)
		(end 271.970754 -359.123996)
		(stroke
			(width 0.2)
			(type default)
		)
		(layer "In3.Cu")
	)
	(gr_arc
		(start 273.1135 -358.085898)
		(mid 273.4945 -357.704898)
		(end 273.1135 -357.323898)
		(stroke
			(width 0.2)
			(type default)
		)
		(layer "In3.Cu")
	)
	(gr_line
		(start 273.1135 -357.323898)
		(end 271.970754 -357.323898)
		(stroke
			(width 0.2)
			(type default)
		)
		(layer "In3.Cu")
	)
	(gr_arc
		(start 273.1135 -356.286054)
		(mid 273.4945 -355.905054)
		(end 273.1135 -355.524054)
		(stroke
			(width 0.2)
			(type default)
		)
		(layer "In3.Cu")
	)
	(gr_line
		(start 273.1135 -355.524054)
		(end 271.970754 -355.524054)
		(stroke
			(width 0.2)
			(type default)
		)
		(layer "In3.Cu")
	)
	(gr_arc
		(start 273.1135 -354.485956)
		(mid 273.4945 -354.104956)
		(end 273.1135 -353.723956)
		(stroke
			(width 0.2)
			(type default)
		)
		(layer "In3.Cu")
	)
	(gr_line
		(start 273.1135 -353.723956)
		(end 271.970754 -353.723956)
		(stroke
			(width 0.2)
			(type default)
		)
		(layer "In3.Cu")
	)
	(gr_arc
		(start 273.1135 -352.686112)
		(mid 273.4945 -352.305112)
		(end 273.1135 -351.924112)
		(stroke
			(width 0.2)
			(type default)
		)
		(layer "In3.Cu")
	)
	(gr_line
		(start 273.1135 -351.924112)
		(end 271.970754 -351.924112)
		(stroke
			(width 0.2)
			(type default)
		)
		(layer "In3.Cu")
	)
	(gr_arc
		(start 273.1135 -350.886014)
		(mid 273.4945 -350.505014)
		(end 273.1135 -350.124014)
		(stroke
			(width 0.2)
			(type default)
		)
		(layer "In3.Cu")
	)
	(gr_line
		(start 273.1135 -350.124014)
		(end 271.970754 -350.124014)
		(stroke
			(width 0.2)
			(type default)
		)
		(layer "In3.Cu")
	)
	(gr_arc
		(start 273.1135 -338.28863)
		(mid 273.49704 -337.90509)
		(end 273.1135 -337.52155)
		(stroke
			(width 0.2)
			(type default)
		)
		(layer "In3.Cu")
	)
	(gr_line
		(start 273.1135 -337.52155)
		(end 271.970754 -337.52155)
		(stroke
			(width 0.2)
			(type default)
		)
		(layer "In3.Cu")
	)
	(gr_arc
		(start 273.1135 -336.488532)
		(mid 273.49704 -336.104992)
		(end 273.1135 -335.721452)
		(stroke
			(width 0.2)
			(type default)
		)
		(layer "In3.Cu")
	)
	(gr_line
		(start 273.1135 -335.721452)
		(end 271.970754 -335.721452)
		(stroke
			(width 0.2)
			(type default)
		)
		(layer "In3.Cu")
	)
	(gr_arc
		(start 273.1135 -334.688434)
		(mid 273.49704 -334.304894)
		(end 273.1135 -333.921354)
		(stroke
			(width 0.2)
			(type default)
		)
		(layer "In3.Cu")
	)
	(gr_line
		(start 273.1135 -333.921354)
		(end 271.970754 -333.921354)
		(stroke
			(width 0.2)
			(type default)
		)
		(layer "In3.Cu")
	)
	(gr_arc
		(start 273.1135 -332.88859)
		(mid 273.49704 -332.50505)
		(end 273.1135 -332.12151)
		(stroke
			(width 0.2)
			(type default)
		)
		(layer "In3.Cu")
	)
	(gr_line
		(start 273.1135 -332.12151)
		(end 271.970754 -332.12151)
		(stroke
			(width 0.2)
			(type default)
		)
		(layer "In3.Cu")
	)
	(gr_arc
		(start 273.1135 -331.088492)
		(mid 273.49704 -330.704952)
		(end 273.1135 -330.321412)
		(stroke
			(width 0.2)
			(type default)
		)
		(layer "In3.Cu")
	)
	(gr_line
		(start 273.1135 -330.321412)
		(end 271.970754 -330.321412)
		(stroke
			(width 0.2)
			(type default)
		)
		(layer "In3.Cu")
	)
	(gr_arc
		(start 273.1135 -329.288648)
		(mid 273.49704 -328.905108)
		(end 273.1135 -328.521568)
		(stroke
			(width 0.2)
			(type default)
		)
		(layer "In3.Cu")
	)
	(gr_line
		(start 273.1135 -328.521568)
		(end 271.970754 -328.521568)
		(stroke
			(width 0.2)
			(type default)
		)
		(layer "In3.Cu")
	)
	(gr_arc
		(start 273.1135 -316.68847)
		(mid 273.49704 -316.30493)
		(end 273.1135 -315.92139)
		(stroke
			(width 0.2)
			(type default)
		)
		(layer "In3.Cu")
	)
	(gr_line
		(start 273.1135 -315.92139)
		(end 271.970754 -315.92139)
		(stroke
			(width 0.2)
			(type default)
		)
		(layer "In3.Cu")
	)
	(gr_arc
		(start 273.1135 -314.888626)
		(mid 273.49704 -314.505086)
		(end 273.1135 -314.121546)
		(stroke
			(width 0.2)
			(type default)
		)
		(layer "In3.Cu")
	)
	(gr_line
		(start 273.1135 -314.121546)
		(end 271.970754 -314.121546)
		(stroke
			(width 0.2)
			(type default)
		)
		(layer "In3.Cu")
	)
	(gr_arc
		(start 273.1135 -313.088528)
		(mid 273.49704 -312.704988)
		(end 273.1135 -312.321448)
		(stroke
			(width 0.2)
			(type default)
		)
		(layer "In3.Cu")
	)
	(gr_line
		(start 273.1135 -312.321448)
		(end 271.970754 -312.321448)
		(stroke
			(width 0.2)
			(type default)
		)
		(layer "In3.Cu")
	)
	(gr_arc
		(start 273.1135 -311.28843)
		(mid 273.49704 -310.90489)
		(end 273.1135 -310.52135)
		(stroke
			(width 0.2)
			(type default)
		)
		(layer "In3.Cu")
	)
	(gr_line
		(start 273.1135 -310.52135)
		(end 271.970754 -310.52135)
		(stroke
			(width 0.2)
			(type default)
		)
		(layer "In3.Cu")
	)
	(gr_arc
		(start 273.1135 -309.488586)
		(mid 273.49704 -309.105046)
		(end 273.1135 -308.721506)
		(stroke
			(width 0.2)
			(type default)
		)
		(layer "In3.Cu")
	)
	(gr_line
		(start 273.1135 -308.721506)
		(end 271.970754 -308.721506)
		(stroke
			(width 0.2)
			(type default)
		)
		(layer "In3.Cu")
	)
	(gr_arc
		(start 273.1135 -307.688488)
		(mid 273.49704 -307.304948)
		(end 273.1135 -306.921408)
		(stroke
			(width 0.2)
			(type default)
		)
		(layer "In3.Cu")
	)
	(gr_line
		(start 273.1135 -306.921408)
		(end 271.970754 -306.921408)
		(stroke
			(width 0.2)
			(type default)
		)
		(layer "In3.Cu")
	)
	(gr_line
		(start 278.23668 -356.453694)
		(end 279.636728 -356.453694)
		(stroke
			(width 0.2)
			(type default)
		)
		(layer "In3.Cu")
	)
	(gr_arc
		(start 278.23668 -355.356414)
		(mid 277.68804 -355.905054)
		(end 278.23668 -356.453694)
		(stroke
			(width 0.2)
			(type default)
		)
		(layer "In3.Cu")
	)
	(gr_line
		(start 278.23668 -352.853752)
		(end 279.636728 -352.853752)
		(stroke
			(width 0.2)
			(type default)
		)
		(layer "In3.Cu")
	)
	(gr_arc
		(start 278.23668 -351.756472)
		(mid 277.68804 -352.305112)
		(end 278.23668 -352.853752)
		(stroke
			(width 0.2)
			(type default)
		)
		(layer "In3.Cu")
	)
	(gr_line
		(start 278.23668 -349.25381)
		(end 279.636728 -349.25381)
		(stroke
			(width 0.2)
			(type default)
		)
		(layer "In3.Cu")
	)
	(gr_arc
		(start 278.23668 -348.15653)
		(mid 277.68804 -348.70517)
		(end 278.23668 -349.25381)
		(stroke
			(width 0.2)
			(type default)
		)
		(layer "In3.Cu")
	)
	(gr_line
		(start 278.23668 -345.653868)
		(end 279.636728 -345.653868)
		(stroke
			(width 0.2)
			(type default)
		)
		(layer "In3.Cu")
	)
	(gr_arc
		(start 278.23668 -344.556588)
		(mid 277.68804 -345.105228)
		(end 278.23668 -345.653868)
		(stroke
			(width 0.2)
			(type default)
		)
		(layer "In3.Cu")
	)
	(gr_line
		(start 278.23668 -342.053672)
		(end 279.636728 -342.053672)
		(stroke
			(width 0.2)
			(type default)
		)
		(layer "In3.Cu")
	)
	(gr_arc
		(start 278.23668 -340.956392)
		(mid 277.68804 -341.505032)
		(end 278.23668 -342.053672)
		(stroke
			(width 0.2)
			(type default)
		)
		(layer "In3.Cu")
	)
	(gr_line
		(start 278.23668 -338.45373)
		(end 279.636728 -338.45373)
		(stroke
			(width 0.2)
			(type default)
		)
		(layer "In3.Cu")
	)
	(gr_arc
		(start 278.23668 -337.35645)
		(mid 277.68804 -337.90509)
		(end 278.23668 -338.45373)
		(stroke
			(width 0.2)
			(type default)
		)
		(layer "In3.Cu")
	)
	(gr_line
		(start 278.23668 -334.853788)
		(end 279.636728 -334.853788)
		(stroke
			(width 0.2)
			(type default)
		)
		(layer "In3.Cu")
	)
	(gr_arc
		(start 278.23668 -333.756508)
		(mid 277.68804 -334.305148)
		(end 278.23668 -334.853788)
		(stroke
			(width 0.2)
			(type default)
		)
		(layer "In3.Cu")
	)
	(gr_line
		(start 278.23668 -331.253846)
		(end 279.636728 -331.253846)
		(stroke
			(width 0.2)
			(type default)
		)
		(layer "In3.Cu")
	)
	(gr_arc
		(start 278.23668 -330.156566)
		(mid 277.68804 -330.705206)
		(end 278.23668 -331.253846)
		(stroke
			(width 0.2)
			(type default)
		)
		(layer "In3.Cu")
	)
	(gr_line
		(start 278.23668 -327.653904)
		(end 279.636728 -327.653904)
		(stroke
			(width 0.2)
			(type default)
		)
		(layer "In3.Cu")
	)
	(gr_arc
		(start 278.23668 -326.556624)
		(mid 277.68804 -327.105264)
		(end 278.23668 -327.653904)
		(stroke
			(width 0.2)
			(type default)
		)
		(layer "In3.Cu")
	)
	(gr_line
		(start 278.23668 -324.053708)
		(end 279.636728 -324.053708)
		(stroke
			(width 0.2)
			(type default)
		)
		(layer "In3.Cu")
	)
	(gr_arc
		(start 278.23668 -322.956428)
		(mid 277.68804 -323.505068)
		(end 278.23668 -324.053708)
		(stroke
			(width 0.2)
			(type default)
		)
		(layer "In3.Cu")
	)
	(gr_line
		(start 278.23668 -320.453766)
		(end 279.636728 -320.453766)
		(stroke
			(width 0.2)
			(type default)
		)
		(layer "In3.Cu")
	)
	(gr_arc
		(start 278.23668 -319.356486)
		(mid 277.68804 -319.905126)
		(end 278.23668 -320.453766)
		(stroke
			(width 0.2)
			(type default)
		)
		(layer "In3.Cu")
	)
	(gr_line
		(start 278.23668 -316.853824)
		(end 279.636728 -316.853824)
		(stroke
			(width 0.2)
			(type default)
		)
		(layer "In3.Cu")
	)
	(gr_arc
		(start 278.23668 -315.756544)
		(mid 277.68804 -316.305184)
		(end 278.23668 -316.853824)
		(stroke
			(width 0.2)
			(type default)
		)
		(layer "In3.Cu")
	)
	(gr_line
		(start 278.23668 -313.253882)
		(end 279.636728 -313.253882)
		(stroke
			(width 0.2)
			(type default)
		)
		(layer "In3.Cu")
	)
	(gr_arc
		(start 278.23668 -312.156602)
		(mid 277.68804 -312.705242)
		(end 278.23668 -313.253882)
		(stroke
			(width 0.2)
			(type default)
		)
		(layer "In3.Cu")
	)
	(gr_line
		(start 278.23668 -309.653686)
		(end 279.636728 -309.653686)
		(stroke
			(width 0.2)
			(type default)
		)
		(layer "In3.Cu")
	)
	(gr_arc
		(start 278.23668 -308.556406)
		(mid 277.68804 -309.105046)
		(end 278.23668 -309.653686)
		(stroke
			(width 0.2)
			(type default)
		)
		(layer "In3.Cu")
	)
	(gr_line
		(start 278.23668 -306.053744)
		(end 279.636728 -306.053744)
		(stroke
			(width 0.2)
			(type default)
		)
		(layer "In3.Cu")
	)
	(gr_arc
		(start 278.23668 -304.956464)
		(mid 277.68804 -305.505104)
		(end 278.23668 -306.053744)
		(stroke
			(width 0.2)
			(type default)
		)
		(layer "In3.Cu")
	)
	(gr_line
		(start 278.23668 -302.453802)
		(end 279.636728 -302.453802)
		(stroke
			(width 0.2)
			(type default)
		)
		(layer "In3.Cu")
	)
	(gr_arc
		(start 278.23668 -301.356522)
		(mid 277.68804 -301.905162)
		(end 278.23668 -302.453802)
		(stroke
			(width 0.2)
			(type default)
		)
		(layer "In3.Cu")
	)
	(gr_line
		(start 278.23668 -298.85386)
		(end 279.636728 -298.85386)
		(stroke
			(width 0.2)
			(type default)
		)
		(layer "In3.Cu")
	)
	(gr_arc
		(start 278.23668 -297.75658)
		(mid 277.68804 -298.30522)
		(end 278.23668 -298.85386)
		(stroke
			(width 0.2)
			(type default)
		)
		(layer "In3.Cu")
	)
	(gr_line
		(start 278.23668 -295.253918)
		(end 279.636728 -295.253918)
		(stroke
			(width 0.2)
			(type default)
		)
		(layer "In3.Cu")
	)
	(gr_arc
		(start 278.23668 -294.156638)
		(mid 277.68804 -294.705278)
		(end 278.23668 -295.253918)
		(stroke
			(width 0.2)
			(type default)
		)
		(layer "In3.Cu")
	)
	(gr_line
		(start 278.23668 -262.453374)
		(end 279.636728 -262.453374)
		(stroke
			(width 0.2)
			(type default)
		)
		(layer "In3.Cu")
	)
	(gr_arc
		(start 278.23668 -261.351014)
		(mid 277.6855 -261.902194)
		(end 278.23668 -262.453374)
		(stroke
			(width 0.2)
			(type default)
		)
		(layer "In3.Cu")
	)
	(gr_line
		(start 278.23668 -258.853432)
		(end 279.636728 -258.853432)
		(stroke
			(width 0.2)
			(type default)
		)
		(layer "In3.Cu")
	)
	(gr_arc
		(start 278.23668 -257.751072)
		(mid 277.6855 -258.302252)
		(end 278.23668 -258.853432)
		(stroke
			(width 0.2)
			(type default)
		)
		(layer "In3.Cu")
	)
	(gr_line
		(start 278.23668 -255.25349)
		(end 279.636728 -255.25349)
		(stroke
			(width 0.2)
			(type default)
		)
		(layer "In3.Cu")
	)
	(gr_arc
		(start 278.23668 -254.15113)
		(mid 277.6855 -254.70231)
		(end 278.23668 -255.25349)
		(stroke
			(width 0.2)
			(type default)
		)
		(layer "In3.Cu")
	)
	(gr_line
		(start 278.23668 -251.653548)
		(end 279.636728 -251.653548)
		(stroke
			(width 0.2)
			(type default)
		)
		(layer "In3.Cu")
	)
	(gr_arc
		(start 278.23668 -250.551188)
		(mid 277.6855 -251.102368)
		(end 278.23668 -251.653548)
		(stroke
			(width 0.2)
			(type default)
		)
		(layer "In3.Cu")
	)
	(gr_line
		(start 278.236934 -355.356414)
		(end 278.23668 -355.356414)
		(stroke
			(width 0.2)
			(type default)
		)
		(layer "In3.Cu")
	)
	(gr_line
		(start 278.236934 -351.756472)
		(end 278.23668 -351.756472)
		(stroke
			(width 0.2)
			(type default)
		)
		(layer "In3.Cu")
	)
	(gr_line
		(start 278.236934 -348.15653)
		(end 278.23668 -348.15653)
		(stroke
			(width 0.2)
			(type default)
		)
		(layer "In3.Cu")
	)
	(gr_line
		(start 278.236934 -344.556588)
		(end 278.23668 -344.556588)
		(stroke
			(width 0.2)
			(type default)
		)
		(layer "In3.Cu")
	)
	(gr_line
		(start 278.236934 -340.956392)
		(end 278.23668 -340.956392)
		(stroke
			(width 0.2)
			(type default)
		)
		(layer "In3.Cu")
	)
	(gr_line
		(start 278.236934 -337.35645)
		(end 278.23668 -337.35645)
		(stroke
			(width 0.2)
			(type default)
		)
		(layer "In3.Cu")
	)
	(gr_line
		(start 278.236934 -333.756508)
		(end 278.23668 -333.756508)
		(stroke
			(width 0.2)
			(type default)
		)
		(layer "In3.Cu")
	)
	(gr_line
		(start 278.236934 -330.156566)
		(end 278.23668 -330.156566)
		(stroke
			(width 0.2)
			(type default)
		)
		(layer "In3.Cu")
	)
	(gr_line
		(start 278.236934 -326.556624)
		(end 278.23668 -326.556624)
		(stroke
			(width 0.2)
			(type default)
		)
		(layer "In3.Cu")
	)
	(gr_line
		(start 278.236934 -322.956428)
		(end 278.23668 -322.956428)
		(stroke
			(width 0.2)
			(type default)
		)
		(layer "In3.Cu")
	)
	(gr_line
		(start 278.236934 -319.356486)
		(end 278.23668 -319.356486)
		(stroke
			(width 0.2)
			(type default)
		)
		(layer "In3.Cu")
	)
	(gr_line
		(start 278.236934 -315.756544)
		(end 278.23668 -315.756544)
		(stroke
			(width 0.2)
			(type default)
		)
		(layer "In3.Cu")
	)
	(gr_line
		(start 278.236934 -312.156602)
		(end 278.23668 -312.156602)
		(stroke
			(width 0.2)
			(type default)
		)
		(layer "In3.Cu")
	)
	(gr_line
		(start 278.236934 -308.556406)
		(end 278.23668 -308.556406)
		(stroke
			(width 0.2)
			(type default)
		)
		(layer "In3.Cu")
	)
	(gr_line
		(start 278.236934 -304.956464)
		(end 278.23668 -304.956464)
		(stroke
			(width 0.2)
			(type default)
		)
		(layer "In3.Cu")
	)
	(gr_line
		(start 278.236934 -301.356522)
		(end 278.23668 -301.356522)
		(stroke
			(width 0.2)
			(type default)
		)
		(layer "In3.Cu")
	)
	(gr_line
		(start 278.236934 -297.75658)
		(end 278.23668 -297.75658)
		(stroke
			(width 0.2)
			(type default)
		)
		(layer "In3.Cu")
	)
	(gr_line
		(start 278.236934 -294.156638)
		(end 278.23668 -294.156638)
		(stroke
			(width 0.2)
			(type default)
		)
		(layer "In3.Cu")
	)
	(gr_line
		(start 278.236934 -261.351014)
		(end 278.23668 -261.351014)
		(stroke
			(width 0.2)
			(type default)
		)
		(layer "In3.Cu")
	)
	(gr_line
		(start 278.236934 -257.751072)
		(end 278.23668 -257.751072)
		(stroke
			(width 0.2)
			(type default)
		)
		(layer "In3.Cu")
	)
	(gr_line
		(start 278.236934 -254.15113)
		(end 278.23668 -254.15113)
		(stroke
			(width 0.2)
			(type default)
		)
		(layer "In3.Cu")
	)
	(gr_line
		(start 278.236934 -250.551188)
		(end 278.23668 -250.551188)
		(stroke
			(width 0.2)
			(type default)
		)
		(layer "In3.Cu")
	)
	(gr_line
		(start 278.424132 -177.848006)
		(end 278.425148 -177.850038)
		(stroke
			(width 0.2)
			(type default)
		)
		(layer "In3.Cu")
	)
	(gr_line
		(start 278.424132 -177.847752)
		(end 278.424132 -177.848006)
		(stroke
			(width 0.2)
			(type default)
		)
		(layer "In3.Cu")
	)
	(gr_line
		(start 278.424132 -173.848014)
		(end 278.425148 -173.850046)
		(stroke
			(width 0.2)
			(type default)
		)
		(layer "In3.Cu")
	)
	(gr_line
		(start 278.424132 -173.84776)
		(end 278.424132 -173.848014)
		(stroke
			(width 0.2)
			(type default)
		)
		(layer "In3.Cu")
	)
	(gr_line
		(start 278.424132 -169.848022)
		(end 278.425148 -169.850054)
		(stroke
			(width 0.2)
			(type default)
		)
		(layer "In3.Cu")
	)
	(gr_line
		(start 278.424132 -169.847768)
		(end 278.424132 -169.848022)
		(stroke
			(width 0.2)
			(type default)
		)
		(layer "In3.Cu")
	)
	(gr_line
		(start 278.424132 -165.84803)
		(end 278.425148 -165.850062)
		(stroke
			(width 0.2)
			(type default)
		)
		(layer "In3.Cu")
	)
	(gr_line
		(start 278.424132 -165.847776)
		(end 278.424132 -165.84803)
		(stroke
			(width 0.2)
			(type default)
		)
		(layer "In3.Cu")
	)
	(gr_line
		(start 278.424132 -137.848086)
		(end 278.425148 -137.850118)
		(stroke
			(width 0.2)
			(type default)
		)
		(layer "In3.Cu")
	)
	(gr_line
		(start 278.424132 -137.847832)
		(end 278.424132 -137.848086)
		(stroke
			(width 0.2)
			(type default)
		)
		(layer "In3.Cu")
	)
	(gr_line
		(start 278.424132 -81.548224)
		(end 278.425148 -81.550256)
		(stroke
			(width 0.2)
			(type default)
		)
		(layer "In3.Cu")
	)
	(gr_line
		(start 278.424132 -81.54797)
		(end 278.424132 -81.548224)
		(stroke
			(width 0.2)
			(type default)
		)
		(layer "In3.Cu")
	)
	(gr_line
		(start 278.424132 -77.548232)
		(end 278.425148 -77.550264)
		(stroke
			(width 0.2)
			(type default)
		)
		(layer "In3.Cu")
	)
	(gr_line
		(start 278.424132 -77.547978)
		(end 278.424132 -77.548232)
		(stroke
			(width 0.2)
			(type default)
		)
		(layer "In3.Cu")
	)
	(gr_line
		(start 278.424132 -73.54824)
		(end 278.425148 -73.550272)
		(stroke
			(width 0.2)
			(type default)
		)
		(layer "In3.Cu")
	)
	(gr_line
		(start 278.424132 -73.547986)
		(end 278.424132 -73.54824)
		(stroke
			(width 0.2)
			(type default)
		)
		(layer "In3.Cu")
	)
	(gr_line
		(start 278.424132 -69.548248)
		(end 278.425148 -69.55028)
		(stroke
			(width 0.2)
			(type default)
		)
		(layer "In3.Cu")
	)
	(gr_line
		(start 278.424132 -69.547994)
		(end 278.424132 -69.548248)
		(stroke
			(width 0.2)
			(type default)
		)
		(layer "In3.Cu")
	)
	(gr_line
		(start 278.424132 -65.548256)
		(end 278.425148 -65.550288)
		(stroke
			(width 0.2)
			(type default)
		)
		(layer "In3.Cu")
	)
	(gr_line
		(start 278.424132 -65.548002)
		(end 278.424132 -65.548256)
		(stroke
			(width 0.2)
			(type default)
		)
		(layer "In3.Cu")
	)
	(gr_line
		(start 278.424132 -61.548264)
		(end 278.425148 -61.550296)
		(stroke
			(width 0.2)
			(type default)
		)
		(layer "In3.Cu")
	)
	(gr_line
		(start 278.424132 -61.54801)
		(end 278.424132 -61.548264)
		(stroke
			(width 0.2)
			(type default)
		)
		(layer "In3.Cu")
	)
	(gr_line
		(start 278.424132 -57.548272)
		(end 278.425148 -57.550304)
		(stroke
			(width 0.2)
			(type default)
		)
		(layer "In3.Cu")
	)
	(gr_line
		(start 278.424132 -57.548018)
		(end 278.424132 -57.548272)
		(stroke
			(width 0.2)
			(type default)
		)
		(layer "In3.Cu")
	)
	(gr_line
		(start 278.424132 -53.54828)
		(end 278.425148 -53.550312)
		(stroke
			(width 0.2)
			(type default)
		)
		(layer "In3.Cu")
	)
	(gr_line
		(start 278.424132 -53.548026)
		(end 278.424132 -53.54828)
		(stroke
			(width 0.2)
			(type default)
		)
		(layer "In3.Cu")
	)
	(gr_line
		(start 278.424132 -49.548288)
		(end 278.425148 -49.55032)
		(stroke
			(width 0.2)
			(type default)
		)
		(layer "In3.Cu")
	)
	(gr_line
		(start 278.424132 -49.548034)
		(end 278.424132 -49.548288)
		(stroke
			(width 0.2)
			(type default)
		)
		(layer "In3.Cu")
	)
	(gr_line
		(start 278.424132 -45.548296)
		(end 278.425148 -45.550328)
		(stroke
			(width 0.2)
			(type default)
		)
		(layer "In3.Cu")
	)
	(gr_line
		(start 278.424132 -45.548042)
		(end 278.424132 -45.548296)
		(stroke
			(width 0.2)
			(type default)
		)
		(layer "In3.Cu")
	)
	(gr_line
		(start 278.424132 -41.548304)
		(end 278.425148 -41.550336)
		(stroke
			(width 0.2)
			(type default)
		)
		(layer "In3.Cu")
	)
	(gr_line
		(start 278.424132 -41.54805)
		(end 278.424132 -41.548304)
		(stroke
			(width 0.2)
			(type default)
		)
		(layer "In3.Cu")
	)
	(gr_line
		(start 278.424132 -37.548312)
		(end 278.425148 -37.550344)
		(stroke
			(width 0.2)
			(type default)
		)
		(layer "In3.Cu")
	)
	(gr_line
		(start 278.424132 -37.548058)
		(end 278.424132 -37.548312)
		(stroke
			(width 0.2)
			(type default)
		)
		(layer "In3.Cu")
	)
	(gr_line
		(start 278.424132 -17.548352)
		(end 278.425148 -17.550384)
		(stroke
			(width 0.2)
			(type default)
		)
		(layer "In3.Cu")
	)
	(gr_line
		(start 278.424132 -17.548098)
		(end 278.424132 -17.548352)
		(stroke
			(width 0.2)
			(type default)
		)
		(layer "In3.Cu")
	)
	(gr_arc
		(start 278.425148 -177.850038)
		(mid 278.100282 -178.824636)
		(end 279.07488 -179.149502)
		(stroke
			(width 0.2)
			(type default)
		)
		(layer "In3.Cu")
	)
	(gr_arc
		(start 278.425148 -173.850046)
		(mid 278.100282 -174.824644)
		(end 279.07488 -175.14951)
		(stroke
			(width 0.2)
			(type default)
		)
		(layer "In3.Cu")
	)
	(gr_arc
		(start 278.425148 -169.850054)
		(mid 278.100282 -170.824652)
		(end 279.07488 -171.149518)
		(stroke
			(width 0.2)
			(type default)
		)
		(layer "In3.Cu")
	)
	(gr_arc
		(start 278.425148 -165.850062)
		(mid 278.100282 -166.82466)
		(end 279.07488 -167.149526)
		(stroke
			(width 0.2)
			(type default)
		)
		(layer "In3.Cu")
	)
	(gr_arc
		(start 278.425148 -137.850118)
		(mid 278.100282 -138.824716)
		(end 279.07488 -139.149582)
		(stroke
			(width 0.2)
			(type default)
		)
		(layer "In3.Cu")
	)
	(gr_arc
		(start 278.425148 -81.550256)
		(mid 278.100282 -82.524854)
		(end 279.07488 -82.84972)
		(stroke
			(width 0.2)
			(type default)
		)
		(layer "In3.Cu")
	)
	(gr_arc
		(start 278.425148 -77.550264)
		(mid 278.100282 -78.524862)
		(end 279.07488 -78.849728)
		(stroke
			(width 0.2)
			(type default)
		)
		(layer "In3.Cu")
	)
	(gr_arc
		(start 278.425148 -73.550272)
		(mid 278.100282 -74.52487)
		(end 279.07488 -74.849736)
		(stroke
			(width 0.2)
			(type default)
		)
		(layer "In3.Cu")
	)
	(gr_arc
		(start 278.425148 -69.55028)
		(mid 278.100282 -70.524878)
		(end 279.07488 -70.849744)
		(stroke
			(width 0.2)
			(type default)
		)
		(layer "In3.Cu")
	)
	(gr_arc
		(start 278.425148 -65.550288)
		(mid 278.100282 -66.524886)
		(end 279.07488 -66.849752)
		(stroke
			(width 0.2)
			(type default)
		)
		(layer "In3.Cu")
	)
	(gr_arc
		(start 278.425148 -61.550296)
		(mid 278.100282 -62.524894)
		(end 279.07488 -62.84976)
		(stroke
			(width 0.2)
			(type default)
		)
		(layer "In3.Cu")
	)
	(gr_arc
		(start 278.425148 -57.550304)
		(mid 278.100282 -58.524902)
		(end 279.07488 -58.849768)
		(stroke
			(width 0.2)
			(type default)
		)
		(layer "In3.Cu")
	)
	(gr_arc
		(start 278.425148 -53.550312)
		(mid 278.100282 -54.52491)
		(end 279.07488 -54.849776)
		(stroke
			(width 0.2)
			(type default)
		)
		(layer "In3.Cu")
	)
	(gr_arc
		(start 278.425148 -49.55032)
		(mid 278.100282 -50.524918)
		(end 279.07488 -50.849784)
		(stroke
			(width 0.2)
			(type default)
		)
		(layer "In3.Cu")
	)
	(gr_arc
		(start 278.425148 -45.550328)
		(mid 278.100282 -46.524926)
		(end 279.07488 -46.849792)
		(stroke
			(width 0.2)
			(type default)
		)
		(layer "In3.Cu")
	)
	(gr_arc
		(start 278.425148 -41.550336)
		(mid 278.100282 -42.524934)
		(end 279.07488 -42.8498)
		(stroke
			(width 0.2)
			(type default)
		)
		(layer "In3.Cu")
	)
	(gr_arc
		(start 278.425148 -37.550344)
		(mid 278.100282 -38.524942)
		(end 279.07488 -38.849808)
		(stroke
			(width 0.2)
			(type default)
		)
		(layer "In3.Cu")
	)
	(gr_arc
		(start 278.425148 -17.550384)
		(mid 278.100282 -18.524982)
		(end 279.07488 -18.849848)
		(stroke
			(width 0.2)
			(type default)
		)
		(layer "In3.Cu")
	)
	(gr_arc
		(start 278.426418 -161.852356)
		(mid 278.102619 -162.8235)
		(end 279.073864 -163.147248)
		(stroke
			(width 0.2)
			(type default)
		)
		(layer "In3.Cu")
	)
	(gr_line
		(start 278.426418 -161.852102)
		(end 278.426418 -161.852356)
		(stroke
			(width 0.2)
			(type default)
		)
		(layer "In3.Cu")
	)
	(gr_arc
		(start 278.426418 -157.852364)
		(mid 278.102619 -158.823508)
		(end 279.073864 -159.147256)
		(stroke
			(width 0.2)
			(type default)
		)
		(layer "In3.Cu")
	)
	(gr_line
		(start 278.426418 -157.85211)
		(end 278.426418 -157.852364)
		(stroke
			(width 0.2)
			(type default)
		)
		(layer "In3.Cu")
	)
	(gr_arc
		(start 278.426418 -153.852372)
		(mid 278.102619 -154.823516)
		(end 279.073864 -155.147264)
		(stroke
			(width 0.2)
			(type default)
		)
		(layer "In3.Cu")
	)
	(gr_line
		(start 278.426418 -153.852118)
		(end 278.426418 -153.852372)
		(stroke
			(width 0.2)
			(type default)
		)
		(layer "In3.Cu")
	)
	(gr_arc
		(start 278.426418 -149.85238)
		(mid 278.102619 -150.823524)
		(end 279.073864 -151.147272)
		(stroke
			(width 0.2)
			(type default)
		)
		(layer "In3.Cu")
	)
	(gr_line
		(start 278.426418 -149.852126)
		(end 278.426418 -149.85238)
		(stroke
			(width 0.2)
			(type default)
		)
		(layer "In3.Cu")
	)
	(gr_arc
		(start 278.426418 -129.85242)
		(mid 278.102619 -130.823564)
		(end 279.073864 -131.147312)
		(stroke
			(width 0.2)
			(type default)
		)
		(layer "In3.Cu")
	)
	(gr_line
		(start 278.426418 -129.852166)
		(end 278.426418 -129.85242)
		(stroke
			(width 0.2)
			(type default)
		)
		(layer "In3.Cu")
	)
	(gr_arc
		(start 278.426418 -125.852428)
		(mid 278.102619 -126.823572)
		(end 279.073864 -127.14732)
		(stroke
			(width 0.2)
			(type default)
		)
		(layer "In3.Cu")
	)
	(gr_line
		(start 278.426418 -125.852174)
		(end 278.426418 -125.852428)
		(stroke
			(width 0.2)
			(type default)
		)
		(layer "In3.Cu")
	)
	(gr_arc
		(start 278.426418 -121.852436)
		(mid 278.102619 -122.82358)
		(end 279.073864 -123.147328)
		(stroke
			(width 0.2)
			(type default)
		)
		(layer "In3.Cu")
	)
	(gr_line
		(start 278.426418 -121.852182)
		(end 278.426418 -121.852436)
		(stroke
			(width 0.2)
			(type default)
		)
		(layer "In3.Cu")
	)
	(gr_arc
		(start 278.426418 -117.852444)
		(mid 278.102619 -118.823588)
		(end 279.073864 -119.147336)
		(stroke
			(width 0.2)
			(type default)
		)
		(layer "In3.Cu")
	)
	(gr_line
		(start 278.426418 -117.85219)
		(end 278.426418 -117.852444)
		(stroke
			(width 0.2)
			(type default)
		)
		(layer "In3.Cu")
	)
	(gr_arc
		(start 278.433784 -11.54049)
		(mid 278.093387 -12.52152)
		(end 279.077166 -12.854432)
		(stroke
			(width 0.2)
			(type default)
		)
		(layer "In3.Cu")
	)
	(gr_arc
		(start 278.44496 -113.868708)
		(mid 278.120865 -114.809139)
		(end 279.06345 -115.127024)
		(stroke
			(width 0.2)
			(type default)
		)
		(layer "In3.Cu")
	)
	(gr_line
		(start 279.06345 -115.127024)
		(end 281.063446 -114.127026)
		(stroke
			(width 0.2)
			(type default)
		)
		(layer "In3.Cu")
	)
	(gr_line
		(start 279.073864 -163.147248)
		(end 281.07386 -162.14725)
		(stroke
			(width 0.2)
			(type default)
		)
		(layer "In3.Cu")
	)
	(gr_line
		(start 279.073864 -159.147256)
		(end 281.07386 -158.147258)
		(stroke
			(width 0.2)
			(type default)
		)
		(layer "In3.Cu")
	)
	(gr_line
		(start 279.073864 -155.147264)
		(end 281.07386 -154.147266)
		(stroke
			(width 0.2)
			(type default)
		)
		(layer "In3.Cu")
	)
	(gr_line
		(start 279.073864 -151.147272)
		(end 281.07386 -150.147274)
		(stroke
			(width 0.2)
			(type default)
		)
		(layer "In3.Cu")
	)
	(gr_line
		(start 279.073864 -131.147312)
		(end 281.07386 -130.147314)
		(stroke
			(width 0.2)
			(type default)
		)
		(layer "In3.Cu")
	)
	(gr_line
		(start 279.073864 -127.14732)
		(end 281.07386 -126.147322)
		(stroke
			(width 0.2)
			(type default)
		)
		(layer "In3.Cu")
	)
	(gr_line
		(start 279.073864 -123.147328)
		(end 281.07386 -122.14733)
		(stroke
			(width 0.2)
			(type default)
		)
		(layer "In3.Cu")
	)
	(gr_line
		(start 279.073864 -119.147336)
		(end 281.07386 -118.147338)
		(stroke
			(width 0.2)
			(type default)
		)
		(layer "In3.Cu")
	)
	(gr_line
		(start 279.07488 -179.149502)
		(end 279.07615 -179.151788)
		(stroke
			(width 0.2)
			(type default)
		)
		(layer "In3.Cu")
	)
	(gr_line
		(start 279.07488 -175.14951)
		(end 279.07615 -175.151796)
		(stroke
			(width 0.2)
			(type default)
		)
		(layer "In3.Cu")
	)
	(gr_line
		(start 279.07488 -171.149518)
		(end 279.07615 -171.151804)
		(stroke
			(width 0.2)
			(type default)
		)
		(layer "In3.Cu")
	)
	(gr_line
		(start 279.07488 -167.149526)
		(end 279.07615 -167.151812)
		(stroke
			(width 0.2)
			(type default)
		)
		(layer "In3.Cu")
	)
	(gr_line
		(start 279.07488 -139.149582)
		(end 279.07615 -139.151868)
		(stroke
			(width 0.2)
			(type default)
		)
		(layer "In3.Cu")
	)
	(gr_line
		(start 279.07488 -82.84972)
		(end 279.07615 -82.852006)
		(stroke
			(width 0.2)
			(type default)
		)
		(layer "In3.Cu")
	)
	(gr_line
		(start 279.07488 -78.849728)
		(end 279.07615 -78.852014)
		(stroke
			(width 0.2)
			(type default)
		)
		(layer "In3.Cu")
	)
	(gr_line
		(start 279.07488 -74.849736)
		(end 279.07615 -74.852022)
		(stroke
			(width 0.2)
			(type default)
		)
		(layer "In3.Cu")
	)
	(gr_line
		(start 279.07488 -70.849744)
		(end 279.07615 -70.85203)
		(stroke
			(width 0.2)
			(type default)
		)
		(layer "In3.Cu")
	)
	(gr_line
		(start 279.07488 -66.849752)
		(end 279.07615 -66.852038)
		(stroke
			(width 0.2)
			(type default)
		)
		(layer "In3.Cu")
	)
	(gr_line
		(start 279.07488 -62.84976)
		(end 279.07615 -62.852046)
		(stroke
			(width 0.2)
			(type default)
		)
		(layer "In3.Cu")
	)
	(gr_line
		(start 279.07488 -58.849768)
		(end 279.07615 -58.852054)
		(stroke
			(width 0.2)
			(type default)
		)
		(layer "In3.Cu")
	)
	(gr_line
		(start 279.07488 -54.849776)
		(end 279.07615 -54.852062)
		(stroke
			(width 0.2)
			(type default)
		)
		(layer "In3.Cu")
	)
	(gr_line
		(start 279.07488 -50.849784)
		(end 279.07615 -50.85207)
		(stroke
			(width 0.2)
			(type default)
		)
		(layer "In3.Cu")
	)
	(gr_line
		(start 279.07488 -46.849792)
		(end 279.07615 -46.852078)
		(stroke
			(width 0.2)
			(type default)
		)
		(layer "In3.Cu")
	)
	(gr_line
		(start 279.07488 -42.8498)
		(end 279.07615 -42.852086)
		(stroke
			(width 0.2)
			(type default)
		)
		(layer "In3.Cu")
	)
	(gr_line
		(start 279.07488 -38.849808)
		(end 279.07615 -38.852094)
		(stroke
			(width 0.2)
			(type default)
		)
		(layer "In3.Cu")
	)
	(gr_line
		(start 279.07488 -18.849848)
		(end 279.07615 -18.852134)
		(stroke
			(width 0.2)
			(type default)
		)
		(layer "In3.Cu")
	)
	(gr_line
		(start 279.07615 -179.151788)
		(end 281.076146 -178.15179)
		(stroke
			(width 0.2)
			(type default)
		)
		(layer "In3.Cu")
	)
	(gr_line
		(start 279.07615 -175.151796)
		(end 281.076146 -174.151798)
		(stroke
			(width 0.2)
			(type default)
		)
		(layer "In3.Cu")
	)
	(gr_line
		(start 279.07615 -171.151804)
		(end 281.076146 -170.151806)
		(stroke
			(width 0.2)
			(type default)
		)
		(layer "In3.Cu")
	)
	(gr_line
		(start 279.07615 -167.151812)
		(end 281.076146 -166.151814)
		(stroke
			(width 0.2)
			(type default)
		)
		(layer "In3.Cu")
	)
	(gr_line
		(start 279.07615 -139.151868)
		(end 281.076146 -138.15187)
		(stroke
			(width 0.2)
			(type default)
		)
		(layer "In3.Cu")
	)
	(gr_line
		(start 279.07615 -82.852006)
		(end 281.076146 -81.852008)
		(stroke
			(width 0.2)
			(type default)
		)
		(layer "In3.Cu")
	)
	(gr_line
		(start 279.07615 -78.852014)
		(end 281.076146 -77.852016)
		(stroke
			(width 0.2)
			(type default)
		)
		(layer "In3.Cu")
	)
	(gr_line
		(start 279.07615 -74.852022)
		(end 281.076146 -73.852024)
		(stroke
			(width 0.2)
			(type default)
		)
		(layer "In3.Cu")
	)
	(gr_line
		(start 279.07615 -70.85203)
		(end 281.076146 -69.852032)
		(stroke
			(width 0.2)
			(type default)
		)
		(layer "In3.Cu")
	)
	(gr_line
		(start 279.07615 -66.852038)
		(end 281.076146 -65.85204)
		(stroke
			(width 0.2)
			(type default)
		)
		(layer "In3.Cu")
	)
	(gr_line
		(start 279.07615 -62.852046)
		(end 281.076146 -61.852048)
		(stroke
			(width 0.2)
			(type default)
		)
		(layer "In3.Cu")
	)
	(gr_line
		(start 279.07615 -58.852054)
		(end 281.076146 -57.852056)
		(stroke
			(width 0.2)
			(type default)
		)
		(layer "In3.Cu")
	)
	(gr_line
		(start 279.07615 -54.852062)
		(end 281.076146 -53.852064)
		(stroke
			(width 0.2)
			(type default)
		)
		(layer "In3.Cu")
	)
	(gr_line
		(start 279.07615 -50.85207)
		(end 281.076146 -49.852072)
		(stroke
			(width 0.2)
			(type default)
		)
		(layer "In3.Cu")
	)
	(gr_line
		(start 279.07615 -46.852078)
		(end 281.076146 -45.85208)
		(stroke
			(width 0.2)
			(type default)
		)
		(layer "In3.Cu")
	)
	(gr_line
		(start 279.07615 -42.852086)
		(end 281.076146 -41.852088)
		(stroke
			(width 0.2)
			(type default)
		)
		(layer "In3.Cu")
	)
	(gr_line
		(start 279.07615 -38.852094)
		(end 281.076146 -37.852096)
		(stroke
			(width 0.2)
			(type default)
		)
		(layer "In3.Cu")
	)
	(gr_line
		(start 279.07615 -18.852134)
		(end 281.076146 -17.852136)
		(stroke
			(width 0.2)
			(type default)
		)
		(layer "In3.Cu")
	)
	(gr_line
		(start 279.077166 -12.854432)
		(end 281.077162 -11.854434)
		(stroke
			(width 0.2)
			(type default)
		)
		(layer "In3.Cu")
	)
	(gr_line
		(start 279.236678 -358.253792)
		(end 280.636726 -358.253792)
		(stroke
			(width 0.2)
			(type default)
		)
		(layer "In3.Cu")
	)
	(gr_arc
		(start 279.236678 -357.156512)
		(mid 278.688038 -357.705152)
		(end 279.236678 -358.253792)
		(stroke
			(width 0.2)
			(type default)
		)
		(layer "In3.Cu")
	)
	(gr_line
		(start 279.236678 -354.65385)
		(end 280.636726 -354.65385)
		(stroke
			(width 0.2)
			(type default)
		)
		(layer "In3.Cu")
	)
	(gr_arc
		(start 279.236678 -353.55657)
		(mid 278.688038 -354.10521)
		(end 279.236678 -354.65385)
		(stroke
			(width 0.2)
			(type default)
		)
		(layer "In3.Cu")
	)
	(gr_line
		(start 279.236678 -351.053908)
		(end 280.636726 -351.053908)
		(stroke
			(width 0.2)
			(type default)
		)
		(layer "In3.Cu")
	)
	(gr_arc
		(start 279.236678 -349.956628)
		(mid 278.688038 -350.505268)
		(end 279.236678 -351.053908)
		(stroke
			(width 0.2)
			(type default)
		)
		(layer "In3.Cu")
	)
	(gr_line
		(start 279.236678 -347.453712)
		(end 280.636726 -347.453712)
		(stroke
			(width 0.2)
			(type default)
		)
		(layer "In3.Cu")
	)
	(gr_arc
		(start 279.236678 -346.356432)
		(mid 278.688038 -346.905072)
		(end 279.236678 -347.453712)
		(stroke
			(width 0.2)
			(type default)
		)
		(layer "In3.Cu")
	)
	(gr_line
		(start 279.236678 -343.85377)
		(end 280.636726 -343.85377)
		(stroke
			(width 0.2)
			(type default)
		)
		(layer "In3.Cu")
	)
	(gr_arc
		(start 279.236678 -342.75649)
		(mid 278.688038 -343.30513)
		(end 279.236678 -343.85377)
		(stroke
			(width 0.2)
			(type default)
		)
		(layer "In3.Cu")
	)
	(gr_line
		(start 279.236678 -340.253828)
		(end 280.636726 -340.253828)
		(stroke
			(width 0.2)
			(type default)
		)
		(layer "In3.Cu")
	)
	(gr_arc
		(start 279.236678 -339.156548)
		(mid 278.688038 -339.705188)
		(end 279.236678 -340.253828)
		(stroke
			(width 0.2)
			(type default)
		)
		(layer "In3.Cu")
	)
	(gr_line
		(start 279.236678 -336.653886)
		(end 280.636726 -336.653886)
		(stroke
			(width 0.2)
			(type default)
		)
		(layer "In3.Cu")
	)
	(gr_arc
		(start 279.236678 -335.556606)
		(mid 278.688038 -336.105246)
		(end 279.236678 -336.653886)
		(stroke
			(width 0.2)
			(type default)
		)
		(layer "In3.Cu")
	)
	(gr_line
		(start 279.236678 -333.05369)
		(end 280.636726 -333.05369)
		(stroke
			(width 0.2)
			(type default)
		)
		(layer "In3.Cu")
	)
	(gr_arc
		(start 279.236678 -331.95641)
		(mid 278.688038 -332.50505)
		(end 279.236678 -333.05369)
		(stroke
			(width 0.2)
			(type default)
		)
		(layer "In3.Cu")
	)
	(gr_line
		(start 279.236678 -329.453748)
		(end 280.636726 -329.453748)
		(stroke
			(width 0.2)
			(type default)
		)
		(layer "In3.Cu")
	)
	(gr_arc
		(start 279.236678 -328.356468)
		(mid 278.688038 -328.905108)
		(end 279.236678 -329.453748)
		(stroke
			(width 0.2)
			(type default)
		)
		(layer "In3.Cu")
	)
	(gr_line
		(start 279.236678 -325.853806)
		(end 280.636726 -325.853806)
		(stroke
			(width 0.2)
			(type default)
		)
		(layer "In3.Cu")
	)
	(gr_arc
		(start 279.236678 -324.756526)
		(mid 278.688038 -325.305166)
		(end 279.236678 -325.853806)
		(stroke
			(width 0.2)
			(type default)
		)
		(layer "In3.Cu")
	)
	(gr_line
		(start 279.236678 -322.253864)
		(end 280.636726 -322.253864)
		(stroke
			(width 0.2)
			(type default)
		)
		(layer "In3.Cu")
	)
	(gr_arc
		(start 279.236678 -321.156584)
		(mid 278.688038 -321.705224)
		(end 279.236678 -322.253864)
		(stroke
			(width 0.2)
			(type default)
		)
		(layer "In3.Cu")
	)
	(gr_line
		(start 279.236678 -318.653668)
		(end 280.636726 -318.653668)
		(stroke
			(width 0.2)
			(type default)
		)
		(layer "In3.Cu")
	)
	(gr_arc
		(start 279.236678 -317.556388)
		(mid 278.688038 -318.105028)
		(end 279.236678 -318.653668)
		(stroke
			(width 0.2)
			(type default)
		)
		(layer "In3.Cu")
	)
	(gr_line
		(start 279.236678 -315.053726)
		(end 280.636726 -315.053726)
		(stroke
			(width 0.2)
			(type default)
		)
		(layer "In3.Cu")
	)
	(gr_arc
		(start 279.236678 -313.956446)
		(mid 278.688038 -314.505086)
		(end 279.236678 -315.053726)
		(stroke
			(width 0.2)
			(type default)
		)
		(layer "In3.Cu")
	)
	(gr_line
		(start 279.236678 -311.453784)
		(end 280.636726 -311.453784)
		(stroke
			(width 0.2)
			(type default)
		)
		(layer "In3.Cu")
	)
	(gr_arc
		(start 279.236678 -310.356504)
		(mid 278.688038 -310.905144)
		(end 279.236678 -311.453784)
		(stroke
			(width 0.2)
			(type default)
		)
		(layer "In3.Cu")
	)
	(gr_line
		(start 279.236678 -307.853842)
		(end 280.636726 -307.853842)
		(stroke
			(width 0.2)
			(type default)
		)
		(layer "In3.Cu")
	)
	(gr_arc
		(start 279.236678 -306.756562)
		(mid 278.688038 -307.305202)
		(end 279.236678 -307.853842)
		(stroke
			(width 0.2)
			(type default)
		)
		(layer "In3.Cu")
	)
	(gr_line
		(start 279.236678 -304.2539)
		(end 280.636726 -304.2539)
		(stroke
			(width 0.2)
			(type default)
		)
		(layer "In3.Cu")
	)
	(gr_arc
		(start 279.236678 -303.15662)
		(mid 278.688038 -303.70526)
		(end 279.236678 -304.2539)
		(stroke
			(width 0.2)
			(type default)
		)
		(layer "In3.Cu")
	)
	(gr_line
		(start 279.236678 -300.653704)
		(end 280.636726 -300.653704)
		(stroke
			(width 0.2)
			(type default)
		)
		(layer "In3.Cu")
	)
	(gr_arc
		(start 279.236678 -299.556424)
		(mid 278.688038 -300.105064)
		(end 279.236678 -300.653704)
		(stroke
			(width 0.2)
			(type default)
		)
		(layer "In3.Cu")
	)
	(gr_line
		(start 279.236678 -297.053762)
		(end 280.636726 -297.053762)
		(stroke
			(width 0.2)
			(type default)
		)
		(layer "In3.Cu")
	)
	(gr_arc
		(start 279.236678 -295.956482)
		(mid 278.688038 -296.505122)
		(end 279.236678 -297.053762)
		(stroke
			(width 0.2)
			(type default)
		)
		(layer "In3.Cu")
	)
	(gr_line
		(start 279.236678 -264.253472)
		(end 280.636726 -264.253472)
		(stroke
			(width 0.2)
			(type default)
		)
		(layer "In3.Cu")
	)
	(gr_arc
		(start 279.236678 -263.151112)
		(mid 278.685498 -263.702292)
		(end 279.236678 -264.253472)
		(stroke
			(width 0.2)
			(type default)
		)
		(layer "In3.Cu")
	)
	(gr_line
		(start 279.236678 -260.65353)
		(end 280.636726 -260.65353)
		(stroke
			(width 0.2)
			(type default)
		)
		(layer "In3.Cu")
	)
	(gr_arc
		(start 279.236678 -259.55117)
		(mid 278.685498 -260.10235)
		(end 279.236678 -260.65353)
		(stroke
			(width 0.2)
			(type default)
		)
		(layer "In3.Cu")
	)
	(gr_line
		(start 279.236678 -257.053588)
		(end 280.636726 -257.053588)
		(stroke
			(width 0.2)
			(type default)
		)
		(layer "In3.Cu")
	)
	(gr_arc
		(start 279.236678 -255.951228)
		(mid 278.685498 -256.502408)
		(end 279.236678 -257.053588)
		(stroke
			(width 0.2)
			(type default)
		)
		(layer "In3.Cu")
	)
	(gr_line
		(start 279.236678 -253.453392)
		(end 280.636726 -253.453392)
		(stroke
			(width 0.2)
			(type default)
		)
		(layer "In3.Cu")
	)
	(gr_arc
		(start 279.236678 -252.351032)
		(mid 278.685498 -252.902212)
		(end 279.236678 -253.453392)
		(stroke
			(width 0.2)
			(type default)
		)
		(layer "In3.Cu")
	)
	(gr_line
		(start 279.236932 -357.156512)
		(end 279.236678 -357.156512)
		(stroke
			(width 0.2)
			(type default)
		)
		(layer "In3.Cu")
	)
	(gr_line
		(start 279.236932 -353.55657)
		(end 279.236678 -353.55657)
		(stroke
			(width 0.2)
			(type default)
		)
		(layer "In3.Cu")
	)
	(gr_line
		(start 279.236932 -349.956628)
		(end 279.236678 -349.956628)
		(stroke
			(width 0.2)
			(type default)
		)
		(layer "In3.Cu")
	)
	(gr_line
		(start 279.236932 -346.356432)
		(end 279.236678 -346.356432)
		(stroke
			(width 0.2)
			(type default)
		)
		(layer "In3.Cu")
	)
	(gr_line
		(start 279.236932 -342.75649)
		(end 279.236678 -342.75649)
		(stroke
			(width 0.2)
			(type default)
		)
		(layer "In3.Cu")
	)
	(gr_line
		(start 279.236932 -339.156548)
		(end 279.236678 -339.156548)
		(stroke
			(width 0.2)
			(type default)
		)
		(layer "In3.Cu")
	)
	(gr_line
		(start 279.236932 -335.556606)
		(end 279.236678 -335.556606)
		(stroke
			(width 0.2)
			(type default)
		)
		(layer "In3.Cu")
	)
	(gr_line
		(start 279.236932 -331.95641)
		(end 279.236678 -331.95641)
		(stroke
			(width 0.2)
			(type default)
		)
		(layer "In3.Cu")
	)
	(gr_line
		(start 279.236932 -328.356468)
		(end 279.236678 -328.356468)
		(stroke
			(width 0.2)
			(type default)
		)
		(layer "In3.Cu")
	)
	(gr_line
		(start 279.236932 -324.756526)
		(end 279.236678 -324.756526)
		(stroke
			(width 0.2)
			(type default)
		)
		(layer "In3.Cu")
	)
	(gr_line
		(start 279.236932 -321.156584)
		(end 279.236678 -321.156584)
		(stroke
			(width 0.2)
			(type default)
		)
		(layer "In3.Cu")
	)
	(gr_line
		(start 279.236932 -317.556388)
		(end 279.236678 -317.556388)
		(stroke
			(width 0.2)
			(type default)
		)
		(layer "In3.Cu")
	)
	(gr_line
		(start 279.236932 -313.956446)
		(end 279.236678 -313.956446)
		(stroke
			(width 0.2)
			(type default)
		)
		(layer "In3.Cu")
	)
	(gr_line
		(start 279.236932 -310.356504)
		(end 279.236678 -310.356504)
		(stroke
			(width 0.2)
			(type default)
		)
		(layer "In3.Cu")
	)
	(gr_line
		(start 279.236932 -306.756562)
		(end 279.236678 -306.756562)
		(stroke
			(width 0.2)
			(type default)
		)
		(layer "In3.Cu")
	)
	(gr_line
		(start 279.236932 -303.15662)
		(end 279.236678 -303.15662)
		(stroke
			(width 0.2)
			(type default)
		)
		(layer "In3.Cu")
	)
	(gr_line
		(start 279.236932 -299.556424)
		(end 279.236678 -299.556424)
		(stroke
			(width 0.2)
			(type default)
		)
		(layer "In3.Cu")
	)
	(gr_line
		(start 279.236932 -295.956482)
		(end 279.236678 -295.956482)
		(stroke
			(width 0.2)
			(type default)
		)
		(layer "In3.Cu")
	)
	(gr_line
		(start 279.236932 -263.151112)
		(end 279.236678 -263.151112)
		(stroke
			(width 0.2)
			(type default)
		)
		(layer "In3.Cu")
	)
	(gr_line
		(start 279.236932 -259.55117)
		(end 279.236678 -259.55117)
		(stroke
			(width 0.2)
			(type default)
		)
		(layer "In3.Cu")
	)
	(gr_line
		(start 279.236932 -255.951228)
		(end 279.236678 -255.951228)
		(stroke
			(width 0.2)
			(type default)
		)
		(layer "In3.Cu")
	)
	(gr_line
		(start 279.236932 -252.351032)
		(end 279.236678 -252.351032)
		(stroke
			(width 0.2)
			(type default)
		)
		(layer "In3.Cu")
	)
	(gr_arc
		(start 279.636728 -356.453694)
		(mid 280.185368 -355.905054)
		(end 279.636728 -355.356414)
		(stroke
			(width 0.2)
			(type default)
		)
		(layer "In3.Cu")
	)
	(gr_line
		(start 279.636728 -355.356414)
		(end 278.236934 -355.356414)
		(stroke
			(width 0.2)
			(type default)
		)
		(layer "In3.Cu")
	)
	(gr_arc
		(start 279.636728 -352.853752)
		(mid 280.185368 -352.305112)
		(end 279.636728 -351.756472)
		(stroke
			(width 0.2)
			(type default)
		)
		(layer "In3.Cu")
	)
	(gr_line
		(start 279.636728 -351.756472)
		(end 278.236934 -351.756472)
		(stroke
			(width 0.2)
			(type default)
		)
		(layer "In3.Cu")
	)
	(gr_arc
		(start 279.636728 -349.25381)
		(mid 280.185368 -348.70517)
		(end 279.636728 -348.15653)
		(stroke
			(width 0.2)
			(type default)
		)
		(layer "In3.Cu")
	)
	(gr_line
		(start 279.636728 -348.15653)
		(end 278.236934 -348.15653)
		(stroke
			(width 0.2)
			(type default)
		)
		(layer "In3.Cu")
	)
	(gr_arc
		(start 279.636728 -345.653868)
		(mid 280.185368 -345.105228)
		(end 279.636728 -344.556588)
		(stroke
			(width 0.2)
			(type default)
		)
		(layer "In3.Cu")
	)
	(gr_line
		(start 279.636728 -344.556588)
		(end 278.236934 -344.556588)
		(stroke
			(width 0.2)
			(type default)
		)
		(layer "In3.Cu")
	)
	(gr_arc
		(start 279.636728 -342.053672)
		(mid 280.185368 -341.505032)
		(end 279.636728 -340.956392)
		(stroke
			(width 0.2)
			(type default)
		)
		(layer "In3.Cu")
	)
	(gr_line
		(start 279.636728 -340.956392)
		(end 278.236934 -340.956392)
		(stroke
			(width 0.2)
			(type default)
		)
		(layer "In3.Cu")
	)
	(gr_arc
		(start 279.636728 -338.45373)
		(mid 280.185368 -337.90509)
		(end 279.636728 -337.35645)
		(stroke
			(width 0.2)
			(type default)
		)
		(layer "In3.Cu")
	)
	(gr_line
		(start 279.636728 -337.35645)
		(end 278.236934 -337.35645)
		(stroke
			(width 0.2)
			(type default)
		)
		(layer "In3.Cu")
	)
	(gr_arc
		(start 279.636728 -334.853788)
		(mid 280.185368 -334.305148)
		(end 279.636728 -333.756508)
		(stroke
			(width 0.2)
			(type default)
		)
		(layer "In3.Cu")
	)
	(gr_line
		(start 279.636728 -333.756508)
		(end 278.236934 -333.756508)
		(stroke
			(width 0.2)
			(type default)
		)
		(layer "In3.Cu")
	)
	(gr_arc
		(start 279.636728 -331.253846)
		(mid 280.185368 -330.705206)
		(end 279.636728 -330.156566)
		(stroke
			(width 0.2)
			(type default)
		)
		(layer "In3.Cu")
	)
	(gr_line
		(start 279.636728 -330.156566)
		(end 278.236934 -330.156566)
		(stroke
			(width 0.2)
			(type default)
		)
		(layer "In3.Cu")
	)
	(gr_arc
		(start 279.636728 -327.653904)
		(mid 280.185368 -327.105264)
		(end 279.636728 -326.556624)
		(stroke
			(width 0.2)
			(type default)
		)
		(layer "In3.Cu")
	)
	(gr_line
		(start 279.636728 -326.556624)
		(end 278.236934 -326.556624)
		(stroke
			(width 0.2)
			(type default)
		)
		(layer "In3.Cu")
	)
	(gr_arc
		(start 279.636728 -324.053708)
		(mid 280.185368 -323.505068)
		(end 279.636728 -322.956428)
		(stroke
			(width 0.2)
			(type default)
		)
		(layer "In3.Cu")
	)
	(gr_line
		(start 279.636728 -322.956428)
		(end 278.236934 -322.956428)
		(stroke
			(width 0.2)
			(type default)
		)
		(layer "In3.Cu")
	)
	(gr_arc
		(start 279.636728 -320.453766)
		(mid 280.185368 -319.905126)
		(end 279.636728 -319.356486)
		(stroke
			(width 0.2)
			(type default)
		)
		(layer "In3.Cu")
	)
	(gr_line
		(start 279.636728 -319.356486)
		(end 278.236934 -319.356486)
		(stroke
			(width 0.2)
			(type default)
		)
		(layer "In3.Cu")
	)
	(gr_arc
		(start 279.636728 -316.853824)
		(mid 280.185368 -316.305184)
		(end 279.636728 -315.756544)
		(stroke
			(width 0.2)
			(type default)
		)
		(layer "In3.Cu")
	)
	(gr_line
		(start 279.636728 -315.756544)
		(end 278.236934 -315.756544)
		(stroke
			(width 0.2)
			(type default)
		)
		(layer "In3.Cu")
	)
	(gr_arc
		(start 279.636728 -313.253882)
		(mid 280.185368 -312.705242)
		(end 279.636728 -312.156602)
		(stroke
			(width 0.2)
			(type default)
		)
		(layer "In3.Cu")
	)
	(gr_line
		(start 279.636728 -312.156602)
		(end 278.236934 -312.156602)
		(stroke
			(width 0.2)
			(type default)
		)
		(layer "In3.Cu")
	)
	(gr_arc
		(start 279.636728 -309.653686)
		(mid 280.185368 -309.105046)
		(end 279.636728 -308.556406)
		(stroke
			(width 0.2)
			(type default)
		)
		(layer "In3.Cu")
	)
	(gr_line
		(start 279.636728 -308.556406)
		(end 278.236934 -308.556406)
		(stroke
			(width 0.2)
			(type default)
		)
		(layer "In3.Cu")
	)
	(gr_arc
		(start 279.636728 -306.053744)
		(mid 280.185368 -305.505104)
		(end 279.636728 -304.956464)
		(stroke
			(width 0.2)
			(type default)
		)
		(layer "In3.Cu")
	)
	(gr_line
		(start 279.636728 -304.956464)
		(end 278.236934 -304.956464)
		(stroke
			(width 0.2)
			(type default)
		)
		(layer "In3.Cu")
	)
	(gr_arc
		(start 279.636728 -302.453802)
		(mid 280.185368 -301.905162)
		(end 279.636728 -301.356522)
		(stroke
			(width 0.2)
			(type default)
		)
		(layer "In3.Cu")
	)
	(gr_line
		(start 279.636728 -301.356522)
		(end 278.236934 -301.356522)
		(stroke
			(width 0.2)
			(type default)
		)
		(layer "In3.Cu")
	)
	(gr_arc
		(start 279.636728 -298.85386)
		(mid 280.185368 -298.30522)
		(end 279.636728 -297.75658)
		(stroke
			(width 0.2)
			(type default)
		)
		(layer "In3.Cu")
	)
	(gr_line
		(start 279.636728 -297.75658)
		(end 278.236934 -297.75658)
		(stroke
			(width 0.2)
			(type default)
		)
		(layer "In3.Cu")
	)
	(gr_arc
		(start 279.636728 -295.253918)
		(mid 280.185368 -294.705278)
		(end 279.636728 -294.156638)
		(stroke
			(width 0.2)
			(type default)
		)
		(layer "In3.Cu")
	)
	(gr_line
		(start 279.636728 -294.156638)
		(end 278.236934 -294.156638)
		(stroke
			(width 0.2)
			(type default)
		)
		(layer "In3.Cu")
	)
	(gr_arc
		(start 279.636728 -262.453374)
		(mid 280.187908 -261.902194)
		(end 279.636728 -261.351014)
		(stroke
			(width 0.2)
			(type default)
		)
		(layer "In3.Cu")
	)
	(gr_line
		(start 279.636728 -261.351014)
		(end 278.236934 -261.351014)
		(stroke
			(width 0.2)
			(type default)
		)
		(layer "In3.Cu")
	)
	(gr_arc
		(start 279.636728 -258.853432)
		(mid 280.187908 -258.302252)
		(end 279.636728 -257.751072)
		(stroke
			(width 0.2)
			(type default)
		)
		(layer "In3.Cu")
	)
	(gr_line
		(start 279.636728 -257.751072)
		(end 278.236934 -257.751072)
		(stroke
			(width 0.2)
			(type default)
		)
		(layer "In3.Cu")
	)
	(gr_arc
		(start 279.636728 -255.25349)
		(mid 280.187908 -254.70231)
		(end 279.636728 -254.15113)
		(stroke
			(width 0.2)
			(type default)
		)
		(layer "In3.Cu")
	)
	(gr_line
		(start 279.636728 -254.15113)
		(end 278.236934 -254.15113)
		(stroke
			(width 0.2)
			(type default)
		)
		(layer "In3.Cu")
	)
	(gr_arc
		(start 279.636728 -251.653548)
		(mid 280.187908 -251.102368)
		(end 279.636728 -250.551188)
		(stroke
			(width 0.2)
			(type default)
		)
		(layer "In3.Cu")
	)
	(gr_line
		(start 279.636728 -250.551188)
		(end 278.236934 -250.551188)
		(stroke
			(width 0.2)
			(type default)
		)
		(layer "In3.Cu")
	)
	(gr_line
		(start 280.422858 -10.545826)
		(end 278.433784 -11.54049)
		(stroke
			(width 0.2)
			(type default)
		)
		(layer "In3.Cu")
	)
	(gr_line
		(start 280.423874 -176.847754)
		(end 278.424132 -177.847752)
		(stroke
			(width 0.2)
			(type default)
		)
		(layer "In3.Cu")
	)
	(gr_line
		(start 280.423874 -172.847762)
		(end 278.424132 -173.84776)
		(stroke
			(width 0.2)
			(type default)
		)
		(layer "In3.Cu")
	)
	(gr_line
		(start 280.423874 -168.84777)
		(end 278.424132 -169.847768)
		(stroke
			(width 0.2)
			(type default)
		)
		(layer "In3.Cu")
	)
	(gr_line
		(start 280.423874 -164.847778)
		(end 278.424132 -165.847776)
		(stroke
			(width 0.2)
			(type default)
		)
		(layer "In3.Cu")
	)
	(gr_line
		(start 280.423874 -136.847834)
		(end 278.424132 -137.847832)
		(stroke
			(width 0.2)
			(type default)
		)
		(layer "In3.Cu")
	)
	(gr_line
		(start 280.423874 -80.547972)
		(end 278.424132 -81.54797)
		(stroke
			(width 0.2)
			(type default)
		)
		(layer "In3.Cu")
	)
	(gr_line
		(start 280.423874 -76.54798)
		(end 278.424132 -77.547978)
		(stroke
			(width 0.2)
			(type default)
		)
		(layer "In3.Cu")
	)
	(gr_line
		(start 280.423874 -72.547988)
		(end 278.424132 -73.547986)
		(stroke
			(width 0.2)
			(type default)
		)
		(layer "In3.Cu")
	)
	(gr_line
		(start 280.423874 -68.547996)
		(end 278.424132 -69.547994)
		(stroke
			(width 0.2)
			(type default)
		)
		(layer "In3.Cu")
	)
	(gr_line
		(start 280.423874 -64.548004)
		(end 278.424132 -65.548002)
		(stroke
			(width 0.2)
			(type default)
		)
		(layer "In3.Cu")
	)
	(gr_line
		(start 280.423874 -60.548012)
		(end 278.424132 -61.54801)
		(stroke
			(width 0.2)
			(type default)
		)
		(layer "In3.Cu")
	)
	(gr_line
		(start 280.423874 -56.54802)
		(end 278.424132 -57.548018)
		(stroke
			(width 0.2)
			(type default)
		)
		(layer "In3.Cu")
	)
	(gr_line
		(start 280.423874 -52.548028)
		(end 278.424132 -53.548026)
		(stroke
			(width 0.2)
			(type default)
		)
		(layer "In3.Cu")
	)
	(gr_line
		(start 280.423874 -48.548036)
		(end 278.424132 -49.548034)
		(stroke
			(width 0.2)
			(type default)
		)
		(layer "In3.Cu")
	)
	(gr_line
		(start 280.423874 -44.548044)
		(end 278.424132 -45.548042)
		(stroke
			(width 0.2)
			(type default)
		)
		(layer "In3.Cu")
	)
	(gr_line
		(start 280.423874 -40.548052)
		(end 278.424132 -41.54805)
		(stroke
			(width 0.2)
			(type default)
		)
		(layer "In3.Cu")
	)
	(gr_line
		(start 280.423874 -36.54806)
		(end 278.424132 -37.548058)
		(stroke
			(width 0.2)
			(type default)
		)
		(layer "In3.Cu")
	)
	(gr_line
		(start 280.423874 -16.5481)
		(end 278.424132 -17.548098)
		(stroke
			(width 0.2)
			(type default)
		)
		(layer "In3.Cu")
	)
	(gr_line
		(start 280.425144 -176.85004)
		(end 280.423874 -176.847754)
		(stroke
			(width 0.2)
			(type default)
		)
		(layer "In3.Cu")
	)
	(gr_line
		(start 280.425144 -172.850048)
		(end 280.423874 -172.847762)
		(stroke
			(width 0.2)
			(type default)
		)
		(layer "In3.Cu")
	)
	(gr_line
		(start 280.425144 -168.850056)
		(end 280.423874 -168.84777)
		(stroke
			(width 0.2)
			(type default)
		)
		(layer "In3.Cu")
	)
	(gr_line
		(start 280.425144 -164.850064)
		(end 280.423874 -164.847778)
		(stroke
			(width 0.2)
			(type default)
		)
		(layer "In3.Cu")
	)
	(gr_line
		(start 280.425144 -136.85012)
		(end 280.423874 -136.847834)
		(stroke
			(width 0.2)
			(type default)
		)
		(layer "In3.Cu")
	)
	(gr_line
		(start 280.425144 -80.550258)
		(end 280.423874 -80.547972)
		(stroke
			(width 0.2)
			(type default)
		)
		(layer "In3.Cu")
	)
	(gr_line
		(start 280.425144 -76.550266)
		(end 280.423874 -76.54798)
		(stroke
			(width 0.2)
			(type default)
		)
		(layer "In3.Cu")
	)
	(gr_line
		(start 280.425144 -72.550274)
		(end 280.423874 -72.547988)
		(stroke
			(width 0.2)
			(type default)
		)
		(layer "In3.Cu")
	)
	(gr_line
		(start 280.425144 -68.550282)
		(end 280.423874 -68.547996)
		(stroke
			(width 0.2)
			(type default)
		)
		(layer "In3.Cu")
	)
	(gr_line
		(start 280.425144 -64.55029)
		(end 280.423874 -64.548004)
		(stroke
			(width 0.2)
			(type default)
		)
		(layer "In3.Cu")
	)
	(gr_line
		(start 280.425144 -60.550298)
		(end 280.423874 -60.548012)
		(stroke
			(width 0.2)
			(type default)
		)
		(layer "In3.Cu")
	)
	(gr_line
		(start 280.425144 -56.550306)
		(end 280.423874 -56.54802)
		(stroke
			(width 0.2)
			(type default)
		)
		(layer "In3.Cu")
	)
	(gr_line
		(start 280.425144 -52.550314)
		(end 280.423874 -52.548028)
		(stroke
			(width 0.2)
			(type default)
		)
		(layer "In3.Cu")
	)
	(gr_line
		(start 280.425144 -48.550322)
		(end 280.423874 -48.548036)
		(stroke
			(width 0.2)
			(type default)
		)
		(layer "In3.Cu")
	)
	(gr_line
		(start 280.425144 -44.55033)
		(end 280.423874 -44.548044)
		(stroke
			(width 0.2)
			(type default)
		)
		(layer "In3.Cu")
	)
	(gr_line
		(start 280.425144 -40.550338)
		(end 280.423874 -40.548052)
		(stroke
			(width 0.2)
			(type default)
		)
		(layer "In3.Cu")
	)
	(gr_line
		(start 280.425144 -36.550346)
		(end 280.423874 -36.54806)
		(stroke
			(width 0.2)
			(type default)
		)
		(layer "In3.Cu")
	)
	(gr_line
		(start 280.425144 -16.550386)
		(end 280.423874 -16.5481)
		(stroke
			(width 0.2)
			(type default)
		)
		(layer "In3.Cu")
	)
	(gr_line
		(start 280.42616 -160.852358)
		(end 278.426418 -161.852102)
		(stroke
			(width 0.2)
			(type default)
		)
		(layer "In3.Cu")
	)
	(gr_line
		(start 280.42616 -156.852366)
		(end 278.426418 -157.85211)
		(stroke
			(width 0.2)
			(type default)
		)
		(layer "In3.Cu")
	)
	(gr_line
		(start 280.42616 -152.852374)
		(end 278.426418 -153.852118)
		(stroke
			(width 0.2)
			(type default)
		)
		(layer "In3.Cu")
	)
	(gr_line
		(start 280.42616 -148.852382)
		(end 278.426418 -149.852126)
		(stroke
			(width 0.2)
			(type default)
		)
		(layer "In3.Cu")
	)
	(gr_line
		(start 280.42616 -128.852422)
		(end 278.426418 -129.852166)
		(stroke
			(width 0.2)
			(type default)
		)
		(layer "In3.Cu")
	)
	(gr_line
		(start 280.42616 -124.85243)
		(end 278.426418 -125.852174)
		(stroke
			(width 0.2)
			(type default)
		)
		(layer "In3.Cu")
	)
	(gr_line
		(start 280.42616 -120.852438)
		(end 278.426418 -121.852182)
		(stroke
			(width 0.2)
			(type default)
		)
		(layer "In3.Cu")
	)
	(gr_line
		(start 280.42616 -116.852446)
		(end 278.426418 -117.85219)
		(stroke
			(width 0.2)
			(type default)
		)
		(layer "In3.Cu")
	)
	(gr_line
		(start 280.436574 -112.872774)
		(end 278.44496 -113.868708)
		(stroke
			(width 0.2)
			(type default)
		)
		(layer "In3.Cu")
	)
	(gr_arc
		(start 280.636726 -358.253792)
		(mid 281.185366 -357.705152)
		(end 280.636726 -357.156512)
		(stroke
			(width 0.2)
			(type default)
		)
		(layer "In3.Cu")
	)
	(gr_line
		(start 280.636726 -357.156512)
		(end 279.236932 -357.156512)
		(stroke
			(width 0.2)
			(type default)
		)
		(layer "In3.Cu")
	)
	(gr_arc
		(start 280.636726 -354.65385)
		(mid 281.185366 -354.10521)
		(end 280.636726 -353.55657)
		(stroke
			(width 0.2)
			(type default)
		)
		(layer "In3.Cu")
	)
	(gr_line
		(start 280.636726 -353.55657)
		(end 279.236932 -353.55657)
		(stroke
			(width 0.2)
			(type default)
		)
		(layer "In3.Cu")
	)
	(gr_arc
		(start 280.636726 -351.053908)
		(mid 281.185366 -350.505268)
		(end 280.636726 -349.956628)
		(stroke
			(width 0.2)
			(type default)
		)
		(layer "In3.Cu")
	)
	(gr_line
		(start 280.636726 -349.956628)
		(end 279.236932 -349.956628)
		(stroke
			(width 0.2)
			(type default)
		)
		(layer "In3.Cu")
	)
	(gr_arc
		(start 280.636726 -347.453712)
		(mid 281.185366 -346.905072)
		(end 280.636726 -346.356432)
		(stroke
			(width 0.2)
			(type default)
		)
		(layer "In3.Cu")
	)
	(gr_line
		(start 280.636726 -346.356432)
		(end 279.236932 -346.356432)
		(stroke
			(width 0.2)
			(type default)
		)
		(layer "In3.Cu")
	)
	(gr_arc
		(start 280.636726 -343.85377)
		(mid 281.185366 -343.30513)
		(end 280.636726 -342.75649)
		(stroke
			(width 0.2)
			(type default)
		)
		(layer "In3.Cu")
	)
	(gr_line
		(start 280.636726 -342.75649)
		(end 279.236932 -342.75649)
		(stroke
			(width 0.2)
			(type default)
		)
		(layer "In3.Cu")
	)
	(gr_arc
		(start 280.636726 -340.253828)
		(mid 281.185366 -339.705188)
		(end 280.636726 -339.156548)
		(stroke
			(width 0.2)
			(type default)
		)
		(layer "In3.Cu")
	)
	(gr_line
		(start 280.636726 -339.156548)
		(end 279.236932 -339.156548)
		(stroke
			(width 0.2)
			(type default)
		)
		(layer "In3.Cu")
	)
	(gr_arc
		(start 280.636726 -336.653886)
		(mid 281.185366 -336.105246)
		(end 280.636726 -335.556606)
		(stroke
			(width 0.2)
			(type default)
		)
		(layer "In3.Cu")
	)
	(gr_line
		(start 280.636726 -335.556606)
		(end 279.236932 -335.556606)
		(stroke
			(width 0.2)
			(type default)
		)
		(layer "In3.Cu")
	)
	(gr_arc
		(start 280.636726 -333.05369)
		(mid 281.185366 -332.50505)
		(end 280.636726 -331.95641)
		(stroke
			(width 0.2)
			(type default)
		)
		(layer "In3.Cu")
	)
	(gr_line
		(start 280.636726 -331.95641)
		(end 279.236932 -331.95641)
		(stroke
			(width 0.2)
			(type default)
		)
		(layer "In3.Cu")
	)
	(gr_arc
		(start 280.636726 -329.453748)
		(mid 281.185366 -328.905108)
		(end 280.636726 -328.356468)
		(stroke
			(width 0.2)
			(type default)
		)
		(layer "In3.Cu")
	)
	(gr_line
		(start 280.636726 -328.356468)
		(end 279.236932 -328.356468)
		(stroke
			(width 0.2)
			(type default)
		)
		(layer "In3.Cu")
	)
	(gr_arc
		(start 280.636726 -325.853806)
		(mid 281.185366 -325.305166)
		(end 280.636726 -324.756526)
		(stroke
			(width 0.2)
			(type default)
		)
		(layer "In3.Cu")
	)
	(gr_line
		(start 280.636726 -324.756526)
		(end 279.236932 -324.756526)
		(stroke
			(width 0.2)
			(type default)
		)
		(layer "In3.Cu")
	)
	(gr_arc
		(start 280.636726 -322.253864)
		(mid 281.185366 -321.705224)
		(end 280.636726 -321.156584)
		(stroke
			(width 0.2)
			(type default)
		)
		(layer "In3.Cu")
	)
	(gr_line
		(start 280.636726 -321.156584)
		(end 279.236932 -321.156584)
		(stroke
			(width 0.2)
			(type default)
		)
		(layer "In3.Cu")
	)
	(gr_arc
		(start 280.636726 -318.653668)
		(mid 281.185366 -318.105028)
		(end 280.636726 -317.556388)
		(stroke
			(width 0.2)
			(type default)
		)
		(layer "In3.Cu")
	)
	(gr_line
		(start 280.636726 -317.556388)
		(end 279.236932 -317.556388)
		(stroke
			(width 0.2)
			(type default)
		)
		(layer "In3.Cu")
	)
	(gr_arc
		(start 280.636726 -315.053726)
		(mid 281.185366 -314.505086)
		(end 280.636726 -313.956446)
		(stroke
			(width 0.2)
			(type default)
		)
		(layer "In3.Cu")
	)
	(gr_line
		(start 280.636726 -313.956446)
		(end 279.236932 -313.956446)
		(stroke
			(width 0.2)
			(type default)
		)
		(layer "In3.Cu")
	)
	(gr_arc
		(start 280.636726 -311.453784)
		(mid 281.185366 -310.905144)
		(end 280.636726 -310.356504)
		(stroke
			(width 0.2)
			(type default)
		)
		(layer "In3.Cu")
	)
	(gr_line
		(start 280.636726 -310.356504)
		(end 279.236932 -310.356504)
		(stroke
			(width 0.2)
			(type default)
		)
		(layer "In3.Cu")
	)
	(gr_arc
		(start 280.636726 -307.853842)
		(mid 281.185366 -307.305202)
		(end 280.636726 -306.756562)
		(stroke
			(width 0.2)
			(type default)
		)
		(layer "In3.Cu")
	)
	(gr_line
		(start 280.636726 -306.756562)
		(end 279.236932 -306.756562)
		(stroke
			(width 0.2)
			(type default)
		)
		(layer "In3.Cu")
	)
	(gr_arc
		(start 280.636726 -304.2539)
		(mid 281.185366 -303.70526)
		(end 280.636726 -303.15662)
		(stroke
			(width 0.2)
			(type default)
		)
		(layer "In3.Cu")
	)
	(gr_line
		(start 280.636726 -303.15662)
		(end 279.236932 -303.15662)
		(stroke
			(width 0.2)
			(type default)
		)
		(layer "In3.Cu")
	)
	(gr_arc
		(start 280.636726 -300.653704)
		(mid 281.185366 -300.105064)
		(end 280.636726 -299.556424)
		(stroke
			(width 0.2)
			(type default)
		)
		(layer "In3.Cu")
	)
	(gr_line
		(start 280.636726 -299.556424)
		(end 279.236932 -299.556424)
		(stroke
			(width 0.2)
			(type default)
		)
		(layer "In3.Cu")
	)
	(gr_arc
		(start 280.636726 -297.053762)
		(mid 281.185366 -296.505122)
		(end 280.636726 -295.956482)
		(stroke
			(width 0.2)
			(type default)
		)
		(layer "In3.Cu")
	)
	(gr_line
		(start 280.636726 -295.956482)
		(end 279.236932 -295.956482)
		(stroke
			(width 0.2)
			(type default)
		)
		(layer "In3.Cu")
	)
	(gr_arc
		(start 280.636726 -264.253472)
		(mid 281.187906 -263.702292)
		(end 280.636726 -263.151112)
		(stroke
			(width 0.2)
			(type default)
		)
		(layer "In3.Cu")
	)
	(gr_line
		(start 280.636726 -263.151112)
		(end 279.236932 -263.151112)
		(stroke
			(width 0.2)
			(type default)
		)
		(layer "In3.Cu")
	)
	(gr_arc
		(start 280.636726 -260.65353)
		(mid 281.187906 -260.10235)
		(end 280.636726 -259.55117)
		(stroke
			(width 0.2)
			(type default)
		)
		(layer "In3.Cu")
	)
	(gr_line
		(start 280.636726 -259.55117)
		(end 279.236932 -259.55117)
		(stroke
			(width 0.2)
			(type default)
		)
		(layer "In3.Cu")
	)
	(gr_arc
		(start 280.636726 -257.053588)
		(mid 281.187906 -256.502408)
		(end 280.636726 -255.951228)
		(stroke
			(width 0.2)
			(type default)
		)
		(layer "In3.Cu")
	)
	(gr_line
		(start 280.636726 -255.951228)
		(end 279.236932 -255.951228)
		(stroke
			(width 0.2)
			(type default)
		)
		(layer "In3.Cu")
	)
	(gr_arc
		(start 280.636726 -253.453392)
		(mid 281.187906 -252.902212)
		(end 280.636726 -252.351032)
		(stroke
			(width 0.2)
			(type default)
		)
		(layer "In3.Cu")
	)
	(gr_line
		(start 280.636726 -252.351032)
		(end 279.236932 -252.351032)
		(stroke
			(width 0.2)
			(type default)
		)
		(layer "In3.Cu")
	)
	(gr_arc
		(start 281.063446 -114.127026)
		(mid 281.377136 -113.186464)
		(end 280.436574 -112.872774)
		(stroke
			(width 0.2)
			(type default)
		)
		(layer "In3.Cu")
	)
	(gr_arc
		(start 281.07386 -162.14725)
		(mid 281.397456 -161.175954)
		(end 280.42616 -160.852358)
		(stroke
			(width 0.2)
			(type default)
		)
		(layer "In3.Cu")
	)
	(gr_arc
		(start 281.07386 -158.147258)
		(mid 281.397456 -157.175962)
		(end 280.42616 -156.852366)
		(stroke
			(width 0.2)
			(type default)
		)
		(layer "In3.Cu")
	)
	(gr_arc
		(start 281.07386 -154.147266)
		(mid 281.397456 -153.17597)
		(end 280.42616 -152.852374)
		(stroke
			(width 0.2)
			(type default)
		)
		(layer "In3.Cu")
	)
	(gr_arc
		(start 281.07386 -150.147274)
		(mid 281.397456 -149.175978)
		(end 280.42616 -148.852382)
		(stroke
			(width 0.2)
			(type default)
		)
		(layer "In3.Cu")
	)
	(gr_arc
		(start 281.07386 -130.147314)
		(mid 281.397456 -129.176018)
		(end 280.42616 -128.852422)
		(stroke
			(width 0.2)
			(type default)
		)
		(layer "In3.Cu")
	)
	(gr_arc
		(start 281.07386 -126.147322)
		(mid 281.397456 -125.176026)
		(end 280.42616 -124.85243)
		(stroke
			(width 0.2)
			(type default)
		)
		(layer "In3.Cu")
	)
	(gr_arc
		(start 281.07386 -122.14733)
		(mid 281.397456 -121.176034)
		(end 280.42616 -120.852438)
		(stroke
			(width 0.2)
			(type default)
		)
		(layer "In3.Cu")
	)
	(gr_arc
		(start 281.07386 -118.147338)
		(mid 281.397456 -117.176042)
		(end 280.42616 -116.852446)
		(stroke
			(width 0.2)
			(type default)
		)
		(layer "In3.Cu")
	)
	(gr_arc
		(start 281.074876 -178.149504)
		(mid 281.399742 -177.174906)
		(end 280.425144 -176.85004)
		(stroke
			(width 0.2)
			(type default)
		)
		(layer "In3.Cu")
	)
	(gr_arc
		(start 281.074876 -174.149512)
		(mid 281.399742 -173.174914)
		(end 280.425144 -172.850048)
		(stroke
			(width 0.2)
			(type default)
		)
		(layer "In3.Cu")
	)
	(gr_arc
		(start 281.074876 -170.14952)
		(mid 281.399742 -169.174922)
		(end 280.425144 -168.850056)
		(stroke
			(width 0.2)
			(type default)
		)
		(layer "In3.Cu")
	)
	(gr_arc
		(start 281.074876 -166.149528)
		(mid 281.399742 -165.17493)
		(end 280.425144 -164.850064)
		(stroke
			(width 0.2)
			(type default)
		)
		(layer "In3.Cu")
	)
	(gr_arc
		(start 281.074876 -138.149584)
		(mid 281.399742 -137.174986)
		(end 280.425144 -136.85012)
		(stroke
			(width 0.2)
			(type default)
		)
		(layer "In3.Cu")
	)
	(gr_arc
		(start 281.074876 -81.849722)
		(mid 281.399742 -80.875124)
		(end 280.425144 -80.550258)
		(stroke
			(width 0.2)
			(type default)
		)
		(layer "In3.Cu")
	)
	(gr_arc
		(start 281.074876 -77.84973)
		(mid 281.399742 -76.875132)
		(end 280.425144 -76.550266)
		(stroke
			(width 0.2)
			(type default)
		)
		(layer "In3.Cu")
	)
	(gr_arc
		(start 281.074876 -73.849738)
		(mid 281.399742 -72.87514)
		(end 280.425144 -72.550274)
		(stroke
			(width 0.2)
			(type default)
		)
		(layer "In3.Cu")
	)
	(gr_arc
		(start 281.074876 -69.849746)
		(mid 281.399742 -68.875148)
		(end 280.425144 -68.550282)
		(stroke
			(width 0.2)
			(type default)
		)
		(layer "In3.Cu")
	)
	(gr_arc
		(start 281.074876 -65.849754)
		(mid 281.399742 -64.875156)
		(end 280.425144 -64.55029)
		(stroke
			(width 0.2)
			(type default)
		)
		(layer "In3.Cu")
	)
	(gr_arc
		(start 281.074876 -61.849762)
		(mid 281.399742 -60.875164)
		(end 280.425144 -60.550298)
		(stroke
			(width 0.2)
			(type default)
		)
		(layer "In3.Cu")
	)
	(gr_arc
		(start 281.074876 -57.84977)
		(mid 281.399742 -56.875172)
		(end 280.425144 -56.550306)
		(stroke
			(width 0.2)
			(type default)
		)
		(layer "In3.Cu")
	)
	(gr_arc
		(start 281.074876 -53.849778)
		(mid 281.399742 -52.87518)
		(end 280.425144 -52.550314)
		(stroke
			(width 0.2)
			(type default)
		)
		(layer "In3.Cu")
	)
	(gr_arc
		(start 281.074876 -49.849786)
		(mid 281.399742 -48.875188)
		(end 280.425144 -48.550322)
		(stroke
			(width 0.2)
			(type default)
		)
		(layer "In3.Cu")
	)
	(gr_arc
		(start 281.074876 -45.849794)
		(mid 281.399742 -44.875196)
		(end 280.425144 -44.55033)
		(stroke
			(width 0.2)
			(type default)
		)
		(layer "In3.Cu")
	)
	(gr_arc
		(start 281.074876 -41.849802)
		(mid 281.399742 -40.875204)
		(end 280.425144 -40.550338)
		(stroke
			(width 0.2)
			(type default)
		)
		(layer "In3.Cu")
	)
	(gr_arc
		(start 281.074876 -37.84981)
		(mid 281.399742 -36.875212)
		(end 280.425144 -36.550346)
		(stroke
			(width 0.2)
			(type default)
		)
		(layer "In3.Cu")
	)
	(gr_arc
		(start 281.074876 -17.84985)
		(mid 281.399742 -16.875252)
		(end 280.425144 -16.550386)
		(stroke
			(width 0.2)
			(type default)
		)
		(layer "In3.Cu")
	)
	(gr_line
		(start 281.076146 -178.15179)
		(end 281.074876 -178.149504)
		(stroke
			(width 0.2)
			(type default)
		)
		(layer "In3.Cu")
	)
	(gr_line
		(start 281.076146 -174.151798)
		(end 281.074876 -174.149512)
		(stroke
			(width 0.2)
			(type default)
		)
		(layer "In3.Cu")
	)
	(gr_line
		(start 281.076146 -170.151806)
		(end 281.074876 -170.14952)
		(stroke
			(width 0.2)
			(type default)
		)
		(layer "In3.Cu")
	)
	(gr_line
		(start 281.076146 -166.151814)
		(end 281.074876 -166.149528)
		(stroke
			(width 0.2)
			(type default)
		)
		(layer "In3.Cu")
	)
	(gr_line
		(start 281.076146 -138.15187)
		(end 281.074876 -138.149584)
		(stroke
			(width 0.2)
			(type default)
		)
		(layer "In3.Cu")
	)
	(gr_line
		(start 281.076146 -81.852008)
		(end 281.074876 -81.849722)
		(stroke
			(width 0.2)
			(type default)
		)
		(layer "In3.Cu")
	)
	(gr_line
		(start 281.076146 -77.852016)
		(end 281.074876 -77.84973)
		(stroke
			(width 0.2)
			(type default)
		)
		(layer "In3.Cu")
	)
	(gr_line
		(start 281.076146 -73.852024)
		(end 281.074876 -73.849738)
		(stroke
			(width 0.2)
			(type default)
		)
		(layer "In3.Cu")
	)
	(gr_line
		(start 281.076146 -69.852032)
		(end 281.074876 -69.849746)
		(stroke
			(width 0.2)
			(type default)
		)
		(layer "In3.Cu")
	)
	(gr_line
		(start 281.076146 -65.85204)
		(end 281.074876 -65.849754)
		(stroke
			(width 0.2)
			(type default)
		)
		(layer "In3.Cu")
	)
	(gr_line
		(start 281.076146 -61.852048)
		(end 281.074876 -61.849762)
		(stroke
			(width 0.2)
			(type default)
		)
		(layer "In3.Cu")
	)
	(gr_line
		(start 281.076146 -57.852056)
		(end 281.074876 -57.84977)
		(stroke
			(width 0.2)
			(type default)
		)
		(layer "In3.Cu")
	)
	(gr_line
		(start 281.076146 -53.852064)
		(end 281.074876 -53.849778)
		(stroke
			(width 0.2)
			(type default)
		)
		(layer "In3.Cu")
	)
	(gr_line
		(start 281.076146 -49.852072)
		(end 281.074876 -49.849786)
		(stroke
			(width 0.2)
			(type default)
		)
		(layer "In3.Cu")
	)
	(gr_line
		(start 281.076146 -45.85208)
		(end 281.074876 -45.849794)
		(stroke
			(width 0.2)
			(type default)
		)
		(layer "In3.Cu")
	)
	(gr_line
		(start 281.076146 -41.852088)
		(end 281.074876 -41.849802)
		(stroke
			(width 0.2)
			(type default)
		)
		(layer "In3.Cu")
	)
	(gr_line
		(start 281.076146 -37.852096)
		(end 281.074876 -37.84981)
		(stroke
			(width 0.2)
			(type default)
		)
		(layer "In3.Cu")
	)
	(gr_line
		(start 281.076146 -17.852136)
		(end 281.074876 -17.84985)
		(stroke
			(width 0.2)
			(type default)
		)
		(layer "In3.Cu")
	)
	(gr_arc
		(start 281.077162 -11.854434)
		(mid 281.404314 -10.872978)
		(end 280.422858 -10.545826)
		(stroke
			(width 0.2)
			(type default)
		)
		(layer "In3.Cu")
	)
	(gr_line
		(start 282.83662 -264.250932)
		(end 284.236668 -264.250932)
		(stroke
			(width 0.2)
			(type default)
		)
		(layer "In3.Cu")
	)
	(gr_arc
		(start 282.83662 -263.153652)
		(mid 282.28798 -263.702292)
		(end 282.83662 -264.250932)
		(stroke
			(width 0.2)
			(type default)
		)
		(layer "In3.Cu")
	)
	(gr_line
		(start 282.922726 -35.854386)
		(end 284.922468 -36.854384)
		(stroke
			(width 0.2)
			(type default)
		)
		(layer "In3.Cu")
	)
	(gr_line
		(start 282.923742 -136.151874)
		(end 284.923738 -137.151872)
		(stroke
			(width 0.2)
			(type default)
		)
		(layer "In3.Cu")
	)
	(gr_line
		(start 282.923742 -108.15193)
		(end 284.923738 -109.151928)
		(stroke
			(width 0.2)
			(type default)
		)
		(layer "In3.Cu")
	)
	(gr_line
		(start 282.925012 -136.149588)
		(end 282.923742 -136.151874)
		(stroke
			(width 0.2)
			(type default)
		)
		(layer "In3.Cu")
	)
	(gr_line
		(start 282.936442 -180.126894)
		(end 284.928056 -181.122574)
		(stroke
			(width 0.2)
			(type default)
		)
		(layer "In3.Cu")
	)
	(gr_line
		(start 282.936442 -176.126902)
		(end 284.928056 -177.122582)
		(stroke
			(width 0.2)
			(type default)
		)
		(layer "In3.Cu")
	)
	(gr_line
		(start 282.936442 -172.12691)
		(end 284.928056 -173.12259)
		(stroke
			(width 0.2)
			(type default)
		)
		(layer "In3.Cu")
	)
	(gr_line
		(start 282.936442 -168.126918)
		(end 284.928056 -169.122598)
		(stroke
			(width 0.2)
			(type default)
		)
		(layer "In3.Cu")
	)
	(gr_line
		(start 282.936442 -164.126926)
		(end 284.928056 -165.122606)
		(stroke
			(width 0.2)
			(type default)
		)
		(layer "In3.Cu")
	)
	(gr_line
		(start 282.936442 -160.126934)
		(end 284.936438 -161.126932)
		(stroke
			(width 0.2)
			(type default)
		)
		(layer "In3.Cu")
	)
	(gr_line
		(start 282.936442 -156.126942)
		(end 284.928056 -157.122622)
		(stroke
			(width 0.2)
			(type default)
		)
		(layer "In3.Cu")
	)
	(gr_line
		(start 282.936442 -152.12695)
		(end 284.928056 -153.12263)
		(stroke
			(width 0.2)
			(type default)
		)
		(layer "In3.Cu")
	)
	(gr_line
		(start 282.936442 -128.126998)
		(end 284.928056 -129.122678)
		(stroke
			(width 0.2)
			(type default)
		)
		(layer "In3.Cu")
	)
	(gr_line
		(start 282.936442 -124.127006)
		(end 284.928056 -125.122686)
		(stroke
			(width 0.2)
			(type default)
		)
		(layer "In3.Cu")
	)
	(gr_line
		(start 282.936442 -120.127014)
		(end 284.928056 -121.122694)
		(stroke
			(width 0.2)
			(type default)
		)
		(layer "In3.Cu")
	)
	(gr_line
		(start 282.936442 -116.127022)
		(end 284.928056 -117.122702)
		(stroke
			(width 0.2)
			(type default)
		)
		(layer "In3.Cu")
	)
	(gr_line
		(start 282.936442 -83.827112)
		(end 284.928056 -84.822792)
		(stroke
			(width 0.2)
			(type default)
		)
		(layer "In3.Cu")
	)
	(gr_line
		(start 282.936442 -79.82712)
		(end 284.928056 -80.8228)
		(stroke
			(width 0.2)
			(type default)
		)
		(layer "In3.Cu")
	)
	(gr_line
		(start 282.936442 -75.827128)
		(end 284.928056 -76.822808)
		(stroke
			(width 0.2)
			(type default)
		)
		(layer "In3.Cu")
	)
	(gr_line
		(start 282.936442 -71.827136)
		(end 284.928056 -72.822816)
		(stroke
			(width 0.2)
			(type default)
		)
		(layer "In3.Cu")
	)
	(gr_line
		(start 282.936442 -67.827144)
		(end 284.928056 -68.822824)
		(stroke
			(width 0.2)
			(type default)
		)
		(layer "In3.Cu")
	)
	(gr_line
		(start 282.936442 -63.827152)
		(end 284.928056 -64.822832)
		(stroke
			(width 0.2)
			(type default)
		)
		(layer "In3.Cu")
	)
	(gr_line
		(start 282.936442 -59.82716)
		(end 284.928056 -60.82284)
		(stroke
			(width 0.2)
			(type default)
		)
		(layer "In3.Cu")
	)
	(gr_line
		(start 282.936442 -55.827168)
		(end 284.928056 -56.822848)
		(stroke
			(width 0.2)
			(type default)
		)
		(layer "In3.Cu")
	)
	(gr_line
		(start 282.936442 -51.827176)
		(end 284.928056 -52.822856)
		(stroke
			(width 0.2)
			(type default)
		)
		(layer "In3.Cu")
	)
	(gr_line
		(start 282.936442 -47.827184)
		(end 284.928056 -48.822864)
		(stroke
			(width 0.2)
			(type default)
		)
		(layer "In3.Cu")
	)
	(gr_line
		(start 282.936442 -43.827192)
		(end 284.928056 -44.822872)
		(stroke
			(width 0.2)
			(type default)
		)
		(layer "In3.Cu")
	)
	(gr_line
		(start 282.936442 -39.8272)
		(end 284.928056 -40.82288)
		(stroke
			(width 0.2)
			(type default)
		)
		(layer "In3.Cu")
	)
	(gr_arc
		(start 283.563314 -178.872642)
		(mid 282.622752 -179.186332)
		(end 282.936442 -180.126894)
		(stroke
			(width 0.2)
			(type default)
		)
		(layer "In3.Cu")
	)
	(gr_arc
		(start 283.563314 -174.87265)
		(mid 282.622752 -175.18634)
		(end 282.936442 -176.126902)
		(stroke
			(width 0.2)
			(type default)
		)
		(layer "In3.Cu")
	)
	(gr_arc
		(start 283.563314 -170.872658)
		(mid 282.622752 -171.186348)
		(end 282.936442 -172.12691)
		(stroke
			(width 0.2)
			(type default)
		)
		(layer "In3.Cu")
	)
	(gr_arc
		(start 283.563314 -166.872666)
		(mid 282.622752 -167.186356)
		(end 282.936442 -168.126918)
		(stroke
			(width 0.2)
			(type default)
		)
		(layer "In3.Cu")
	)
	(gr_arc
		(start 283.563314 -162.872674)
		(mid 282.622752 -163.186364)
		(end 282.936442 -164.126926)
		(stroke
			(width 0.2)
			(type default)
		)
		(layer "In3.Cu")
	)
	(gr_arc
		(start 283.563314 -154.87269)
		(mid 282.622752 -155.18638)
		(end 282.936442 -156.126942)
		(stroke
			(width 0.2)
			(type default)
		)
		(layer "In3.Cu")
	)
	(gr_arc
		(start 283.563314 -150.872698)
		(mid 282.622752 -151.186388)
		(end 282.936442 -152.12695)
		(stroke
			(width 0.2)
			(type default)
		)
		(layer "In3.Cu")
	)
	(gr_arc
		(start 283.563314 -126.872746)
		(mid 282.622752 -127.186436)
		(end 282.936442 -128.126998)
		(stroke
			(width 0.2)
			(type default)
		)
		(layer "In3.Cu")
	)
	(gr_arc
		(start 283.563314 -122.872754)
		(mid 282.622752 -123.186444)
		(end 282.936442 -124.127006)
		(stroke
			(width 0.2)
			(type default)
		)
		(layer "In3.Cu")
	)
	(gr_arc
		(start 283.563314 -118.872762)
		(mid 282.622752 -119.186452)
		(end 282.936442 -120.127014)
		(stroke
			(width 0.2)
			(type default)
		)
		(layer "In3.Cu")
	)
	(gr_arc
		(start 283.563314 -114.87277)
		(mid 282.622752 -115.18646)
		(end 282.936442 -116.127022)
		(stroke
			(width 0.2)
			(type default)
		)
		(layer "In3.Cu")
	)
	(gr_arc
		(start 283.563314 -82.57286)
		(mid 282.622752 -82.88655)
		(end 282.936442 -83.827112)
		(stroke
			(width 0.2)
			(type default)
		)
		(layer "In3.Cu")
	)
	(gr_arc
		(start 283.563314 -78.572868)
		(mid 282.622752 -78.886558)
		(end 282.936442 -79.82712)
		(stroke
			(width 0.2)
			(type default)
		)
		(layer "In3.Cu")
	)
	(gr_arc
		(start 283.563314 -74.572876)
		(mid 282.622752 -74.886566)
		(end 282.936442 -75.827128)
		(stroke
			(width 0.2)
			(type default)
		)
		(layer "In3.Cu")
	)
	(gr_arc
		(start 283.563314 -70.572884)
		(mid 282.622752 -70.886574)
		(end 282.936442 -71.827136)
		(stroke
			(width 0.2)
			(type default)
		)
		(layer "In3.Cu")
	)
	(gr_arc
		(start 283.563314 -66.572892)
		(mid 282.622752 -66.886582)
		(end 282.936442 -67.827144)
		(stroke
			(width 0.2)
			(type default)
		)
		(layer "In3.Cu")
	)
	(gr_arc
		(start 283.563314 -62.5729)
		(mid 282.622752 -62.88659)
		(end 282.936442 -63.827152)
		(stroke
			(width 0.2)
			(type default)
		)
		(layer "In3.Cu")
	)
	(gr_arc
		(start 283.563314 -58.572908)
		(mid 282.622752 -58.886598)
		(end 282.936442 -59.82716)
		(stroke
			(width 0.2)
			(type default)
		)
		(layer "In3.Cu")
	)
	(gr_arc
		(start 283.563314 -54.572916)
		(mid 282.622752 -54.886606)
		(end 282.936442 -55.827168)
		(stroke
			(width 0.2)
			(type default)
		)
		(layer "In3.Cu")
	)
	(gr_arc
		(start 283.563314 -50.572924)
		(mid 282.622752 -50.886614)
		(end 282.936442 -51.827176)
		(stroke
			(width 0.2)
			(type default)
		)
		(layer "In3.Cu")
	)
	(gr_arc
		(start 283.563314 -46.572932)
		(mid 282.622752 -46.886622)
		(end 282.936442 -47.827184)
		(stroke
			(width 0.2)
			(type default)
		)
		(layer "In3.Cu")
	)
	(gr_arc
		(start 283.563314 -42.57294)
		(mid 282.622752 -42.88663)
		(end 282.936442 -43.827192)
		(stroke
			(width 0.2)
			(type default)
		)
		(layer "In3.Cu")
	)
	(gr_arc
		(start 283.563314 -38.572948)
		(mid 282.622752 -38.886638)
		(end 282.936442 -39.8272)
		(stroke
			(width 0.2)
			(type default)
		)
		(layer "In3.Cu")
	)
	(gr_arc
		(start 283.571696 -158.877)
		(mid 282.62492 -159.182185)
		(end 282.936442 -160.126934)
		(stroke
			(width 0.2)
			(type default)
		)
		(layer "In3.Cu")
	)
	(gr_arc
		(start 283.574744 -134.850124)
		(mid 282.600146 -135.17499)
		(end 282.925012 -136.149588)
		(stroke
			(width 0.2)
			(type default)
		)
		(layer "In3.Cu")
	)
	(gr_line
		(start 283.576014 -134.847838)
		(end 283.574744 -134.850124)
		(stroke
			(width 0.2)
			(type default)
		)
		(layer "In3.Cu")
	)
	(gr_arc
		(start 283.576014 -106.847894)
		(mid 282.59786 -107.173776)
		(end 282.923742 -108.15193)
		(stroke
			(width 0.2)
			(type default)
		)
		(layer "In3.Cu")
	)
	(gr_arc
		(start 283.57703 -34.545778)
		(mid 282.595574 -34.87293)
		(end 282.922726 -35.854386)
		(stroke
			(width 0.2)
			(type default)
		)
		(layer "In3.Cu")
	)
	(gr_arc
		(start 284.236668 -264.250932)
		(mid 284.785308 -263.702292)
		(end 284.236668 -263.153652)
		(stroke
			(width 0.2)
			(type default)
		)
		(layer "In3.Cu")
	)
	(gr_line
		(start 284.236668 -263.153652)
		(end 282.83662 -263.153652)
		(stroke
			(width 0.2)
			(type default)
		)
		(layer "In3.Cu")
	)
	(gr_arc
		(start 284.922468 -36.854384)
		(mid 285.904229 -36.527384)
		(end 285.577026 -35.545776)
		(stroke
			(width 0.2)
			(type default)
		)
		(layer "In3.Cu")
	)
	(gr_line
		(start 284.923738 -137.151872)
		(end 284.923992 -137.151618)
		(stroke
			(width 0.2)
			(type default)
		)
		(layer "In3.Cu")
	)
	(gr_arc
		(start 284.923738 -109.151928)
		(mid 285.901892 -108.826046)
		(end 285.57601 -107.847892)
		(stroke
			(width 0.2)
			(type default)
		)
		(layer "In3.Cu")
	)
	(gr_line
		(start 284.923992 -137.151618)
		(end 284.925008 -137.149586)
		(stroke
			(width 0.2)
			(type default)
		)
		(layer "In3.Cu")
	)
	(gr_arc
		(start 284.925008 -137.149586)
		(mid 285.899606 -136.82472)
		(end 285.57474 -135.850122)
		(stroke
			(width 0.2)
			(type default)
		)
		(layer "In3.Cu")
	)
	(gr_arc
		(start 284.928056 -181.122574)
		(mid 285.874832 -180.817389)
		(end 285.56331 -179.87264)
		(stroke
			(width 0.2)
			(type default)
		)
		(layer "In3.Cu")
	)
	(gr_arc
		(start 284.928056 -177.122582)
		(mid 285.874832 -176.817397)
		(end 285.56331 -175.872648)
		(stroke
			(width 0.2)
			(type default)
		)
		(layer "In3.Cu")
	)
	(gr_arc
		(start 284.928056 -173.12259)
		(mid 285.874832 -172.817405)
		(end 285.56331 -171.872656)
		(stroke
			(width 0.2)
			(type default)
		)
		(layer "In3.Cu")
	)
	(gr_arc
		(start 284.928056 -169.122598)
		(mid 285.874832 -168.817413)
		(end 285.56331 -167.872664)
		(stroke
			(width 0.2)
			(type default)
		)
		(layer "In3.Cu")
	)
	(gr_arc
		(start 284.928056 -165.122606)
		(mid 285.874832 -164.817421)
		(end 285.56331 -163.872672)
		(stroke
			(width 0.2)
			(type default)
		)
		(layer "In3.Cu")
	)
	(gr_arc
		(start 284.928056 -157.122622)
		(mid 285.874832 -156.817437)
		(end 285.56331 -155.872688)
		(stroke
			(width 0.2)
			(type default)
		)
		(layer "In3.Cu")
	)
	(gr_arc
		(start 284.928056 -153.12263)
		(mid 285.874832 -152.817445)
		(end 285.56331 -151.872696)
		(stroke
			(width 0.2)
			(type default)
		)
		(layer "In3.Cu")
	)
	(gr_arc
		(start 284.928056 -129.122678)
		(mid 285.874832 -128.817493)
		(end 285.56331 -127.872744)
		(stroke
			(width 0.2)
			(type default)
		)
		(layer "In3.Cu")
	)
	(gr_arc
		(start 284.928056 -125.122686)
		(mid 285.874832 -124.817501)
		(end 285.56331 -123.872752)
		(stroke
			(width 0.2)
			(type default)
		)
		(layer "In3.Cu")
	)
	(gr_arc
		(start 284.928056 -121.122694)
		(mid 285.874832 -120.817509)
		(end 285.56331 -119.87276)
		(stroke
			(width 0.2)
			(type default)
		)
		(layer "In3.Cu")
	)
	(gr_arc
		(start 284.928056 -117.122702)
		(mid 285.874832 -116.817517)
		(end 285.56331 -115.872768)
		(stroke
			(width 0.2)
			(type default)
		)
		(layer "In3.Cu")
	)
	(gr_arc
		(start 284.928056 -84.822792)
		(mid 285.874832 -84.517607)
		(end 285.56331 -83.572858)
		(stroke
			(width 0.2)
			(type default)
		)
		(layer "In3.Cu")
	)
	(gr_arc
		(start 284.928056 -80.8228)
		(mid 285.874832 -80.517615)
		(end 285.56331 -79.572866)
		(stroke
			(width 0.2)
			(type default)
		)
		(layer "In3.Cu")
	)
	(gr_arc
		(start 284.928056 -76.822808)
		(mid 285.874832 -76.517623)
		(end 285.56331 -75.572874)
		(stroke
			(width 0.2)
			(type default)
		)
		(layer "In3.Cu")
	)
	(gr_arc
		(start 284.928056 -72.822816)
		(mid 285.874832 -72.517631)
		(end 285.56331 -71.572882)
		(stroke
			(width 0.2)
			(type default)
		)
		(layer "In3.Cu")
	)
	(gr_arc
		(start 284.928056 -68.822824)
		(mid 285.874832 -68.517639)
		(end 285.56331 -67.57289)
		(stroke
			(width 0.2)
			(type default)
		)
		(layer "In3.Cu")
	)
	(gr_arc
		(start 284.928056 -64.822832)
		(mid 285.874832 -64.517647)
		(end 285.56331 -63.572898)
		(stroke
			(width 0.2)
			(type default)
		)
		(layer "In3.Cu")
	)
	(gr_arc
		(start 284.928056 -60.82284)
		(mid 285.874832 -60.517655)
		(end 285.56331 -59.572906)
		(stroke
			(width 0.2)
			(type default)
		)
		(layer "In3.Cu")
	)
	(gr_arc
		(start 284.928056 -56.822848)
		(mid 285.874832 -56.517663)
		(end 285.56331 -55.572914)
		(stroke
			(width 0.2)
			(type default)
		)
		(layer "In3.Cu")
	)
	(gr_arc
		(start 284.928056 -52.822856)
		(mid 285.874832 -52.517671)
		(end 285.56331 -51.572922)
		(stroke
			(width 0.2)
			(type default)
		)
		(layer "In3.Cu")
	)
	(gr_arc
		(start 284.928056 -48.822864)
		(mid 285.874832 -48.517679)
		(end 285.56331 -47.57293)
		(stroke
			(width 0.2)
			(type default)
		)
		(layer "In3.Cu")
	)
	(gr_arc
		(start 284.928056 -44.822872)
		(mid 285.874832 -44.517687)
		(end 285.56331 -43.572938)
		(stroke
			(width 0.2)
			(type default)
		)
		(layer "In3.Cu")
	)
	(gr_arc
		(start 284.928056 -40.82288)
		(mid 285.874832 -40.517695)
		(end 285.56331 -39.572946)
		(stroke
			(width 0.2)
			(type default)
		)
		(layer "In3.Cu")
	)
	(gr_arc
		(start 284.936438 -161.126932)
		(mid 285.877 -160.813242)
		(end 285.56331 -159.87268)
		(stroke
			(width 0.2)
			(type default)
		)
		(layer "In3.Cu")
	)
	(gr_line
		(start 285.436564 -356.456234)
		(end 286.836612 -356.456234)
		(stroke
			(width 0.2)
			(type default)
		)
		(layer "In3.Cu")
	)
	(gr_arc
		(start 285.436564 -355.353874)
		(mid 284.885384 -355.905054)
		(end 285.436564 -356.456234)
		(stroke
			(width 0.2)
			(type default)
		)
		(layer "In3.Cu")
	)
	(gr_line
		(start 285.436564 -352.856292)
		(end 286.836612 -352.856292)
		(stroke
			(width 0.2)
			(type default)
		)
		(layer "In3.Cu")
	)
	(gr_arc
		(start 285.436564 -351.753932)
		(mid 284.885384 -352.305112)
		(end 285.436564 -352.856292)
		(stroke
			(width 0.2)
			(type default)
		)
		(layer "In3.Cu")
	)
	(gr_line
		(start 285.436564 -349.25635)
		(end 286.836612 -349.25635)
		(stroke
			(width 0.2)
			(type default)
		)
		(layer "In3.Cu")
	)
	(gr_arc
		(start 285.436564 -348.15399)
		(mid 284.885384 -348.70517)
		(end 285.436564 -349.25635)
		(stroke
			(width 0.2)
			(type default)
		)
		(layer "In3.Cu")
	)
	(gr_line
		(start 285.436564 -345.653868)
		(end 286.836612 -345.653868)
		(stroke
			(width 0.2)
			(type default)
		)
		(layer "In3.Cu")
	)
	(gr_arc
		(start 285.436564 -344.556588)
		(mid 284.887924 -345.105228)
		(end 285.436564 -345.653868)
		(stroke
			(width 0.2)
			(type default)
		)
		(layer "In3.Cu")
	)
	(gr_line
		(start 285.436564 -342.053672)
		(end 286.836612 -342.053672)
		(stroke
			(width 0.2)
			(type default)
		)
		(layer "In3.Cu")
	)
	(gr_arc
		(start 285.436564 -340.956392)
		(mid 284.887924 -341.505032)
		(end 285.436564 -342.053672)
		(stroke
			(width 0.2)
			(type default)
		)
		(layer "In3.Cu")
	)
	(gr_line
		(start 285.436564 -338.45373)
		(end 286.836612 -338.45373)
		(stroke
			(width 0.2)
			(type default)
		)
		(layer "In3.Cu")
	)
	(gr_arc
		(start 285.436564 -337.35645)
		(mid 284.887924 -337.90509)
		(end 285.436564 -338.45373)
		(stroke
			(width 0.2)
			(type default)
		)
		(layer "In3.Cu")
	)
	(gr_line
		(start 285.436564 -334.856328)
		(end 286.836612 -334.856328)
		(stroke
			(width 0.2)
			(type default)
		)
		(layer "In3.Cu")
	)
	(gr_arc
		(start 285.436564 -333.753968)
		(mid 284.885384 -334.305148)
		(end 285.436564 -334.856328)
		(stroke
			(width 0.2)
			(type default)
		)
		(layer "In3.Cu")
	)
	(gr_line
		(start 285.436564 -331.256386)
		(end 286.836612 -331.256386)
		(stroke
			(width 0.2)
			(type default)
		)
		(layer "In3.Cu")
	)
	(gr_arc
		(start 285.436564 -330.154026)
		(mid 284.885384 -330.705206)
		(end 285.436564 -331.256386)
		(stroke
			(width 0.2)
			(type default)
		)
		(layer "In3.Cu")
	)
	(gr_line
		(start 285.436564 -327.656444)
		(end 286.836612 -327.656444)
		(stroke
			(width 0.2)
			(type default)
		)
		(layer "In3.Cu")
	)
	(gr_arc
		(start 285.436564 -326.554084)
		(mid 284.885384 -327.105264)
		(end 285.436564 -327.656444)
		(stroke
			(width 0.2)
			(type default)
		)
		(layer "In3.Cu")
	)
	(gr_line
		(start 285.436564 -324.053708)
		(end 286.836612 -324.053708)
		(stroke
			(width 0.2)
			(type default)
		)
		(layer "In3.Cu")
	)
	(gr_arc
		(start 285.436564 -322.956428)
		(mid 284.887924 -323.505068)
		(end 285.436564 -324.053708)
		(stroke
			(width 0.2)
			(type default)
		)
		(layer "In3.Cu")
	)
	(gr_line
		(start 285.436564 -320.453766)
		(end 286.836612 -320.453766)
		(stroke
			(width 0.2)
			(type default)
		)
		(layer "In3.Cu")
	)
	(gr_arc
		(start 285.436564 -319.356486)
		(mid 284.887924 -319.905126)
		(end 285.436564 -320.453766)
		(stroke
			(width 0.2)
			(type default)
		)
		(layer "In3.Cu")
	)
	(gr_line
		(start 285.436564 -316.853824)
		(end 286.836612 -316.853824)
		(stroke
			(width 0.2)
			(type default)
		)
		(layer "In3.Cu")
	)
	(gr_arc
		(start 285.436564 -315.756544)
		(mid 284.887924 -316.305184)
		(end 285.436564 -316.853824)
		(stroke
			(width 0.2)
			(type default)
		)
		(layer "In3.Cu")
	)
	(gr_line
		(start 285.436564 -313.256422)
		(end 286.836612 -313.256422)
		(stroke
			(width 0.2)
			(type default)
		)
		(layer "In3.Cu")
	)
	(gr_arc
		(start 285.436564 -312.154062)
		(mid 284.885384 -312.705242)
		(end 285.436564 -313.256422)
		(stroke
			(width 0.2)
			(type default)
		)
		(layer "In3.Cu")
	)
	(gr_line
		(start 285.436564 -309.656226)
		(end 286.836612 -309.656226)
		(stroke
			(width 0.2)
			(type default)
		)
		(layer "In3.Cu")
	)
	(gr_arc
		(start 285.436564 -308.553866)
		(mid 284.885384 -309.105046)
		(end 285.436564 -309.656226)
		(stroke
			(width 0.2)
			(type default)
		)
		(layer "In3.Cu")
	)
	(gr_line
		(start 285.436564 -306.056284)
		(end 286.836612 -306.056284)
		(stroke
			(width 0.2)
			(type default)
		)
		(layer "In3.Cu")
	)
	(gr_arc
		(start 285.436564 -304.953924)
		(mid 284.885384 -305.505104)
		(end 285.436564 -306.056284)
		(stroke
			(width 0.2)
			(type default)
		)
		(layer "In3.Cu")
	)
	(gr_line
		(start 285.436564 -302.453802)
		(end 286.836612 -302.453802)
		(stroke
			(width 0.2)
			(type default)
		)
		(layer "In3.Cu")
	)
	(gr_arc
		(start 285.436564 -301.356522)
		(mid 284.887924 -301.905162)
		(end 285.436564 -302.453802)
		(stroke
			(width 0.2)
			(type default)
		)
		(layer "In3.Cu")
	)
	(gr_line
		(start 285.436564 -298.85386)
		(end 286.836612 -298.85386)
		(stroke
			(width 0.2)
			(type default)
		)
		(layer "In3.Cu")
	)
	(gr_arc
		(start 285.436564 -297.75658)
		(mid 284.887924 -298.30522)
		(end 285.436564 -298.85386)
		(stroke
			(width 0.2)
			(type default)
		)
		(layer "In3.Cu")
	)
	(gr_line
		(start 285.436564 -295.256458)
		(end 286.836612 -295.256458)
		(stroke
			(width 0.2)
			(type default)
		)
		(layer "In3.Cu")
	)
	(gr_arc
		(start 285.436564 -294.154098)
		(mid 284.885384 -294.705278)
		(end 285.436564 -295.256458)
		(stroke
			(width 0.2)
			(type default)
		)
		(layer "In3.Cu")
	)
	(gr_line
		(start 285.436564 -262.453374)
		(end 286.836612 -262.453374)
		(stroke
			(width 0.2)
			(type default)
		)
		(layer "In3.Cu")
	)
	(gr_arc
		(start 285.436564 -261.351014)
		(mid 284.885384 -261.902194)
		(end 285.436564 -262.453374)
		(stroke
			(width 0.2)
			(type default)
		)
		(layer "In3.Cu")
	)
	(gr_line
		(start 285.436564 -258.853432)
		(end 286.836612 -258.853432)
		(stroke
			(width 0.2)
			(type default)
		)
		(layer "In3.Cu")
	)
	(gr_arc
		(start 285.436564 -257.751072)
		(mid 284.885384 -258.302252)
		(end 285.436564 -258.853432)
		(stroke
			(width 0.2)
			(type default)
		)
		(layer "In3.Cu")
	)
	(gr_line
		(start 285.436564 -255.25349)
		(end 286.836612 -255.25349)
		(stroke
			(width 0.2)
			(type default)
		)
		(layer "In3.Cu")
	)
	(gr_arc
		(start 285.436564 -254.15113)
		(mid 284.885384 -254.70231)
		(end 285.436564 -255.25349)
		(stroke
			(width 0.2)
			(type default)
		)
		(layer "In3.Cu")
	)
	(gr_line
		(start 285.436564 -251.653548)
		(end 286.836612 -251.653548)
		(stroke
			(width 0.2)
			(type default)
		)
		(layer "In3.Cu")
	)
	(gr_arc
		(start 285.436564 -250.551188)
		(mid 284.885384 -251.102368)
		(end 285.436564 -251.653548)
		(stroke
			(width 0.2)
			(type default)
		)
		(layer "In3.Cu")
	)
	(gr_line
		(start 285.436818 -355.353874)
		(end 285.436564 -355.353874)
		(stroke
			(width 0.2)
			(type default)
		)
		(layer "In3.Cu")
	)
	(gr_line
		(start 285.436818 -351.753932)
		(end 285.436564 -351.753932)
		(stroke
			(width 0.2)
			(type default)
		)
		(layer "In3.Cu")
	)
	(gr_line
		(start 285.436818 -348.15399)
		(end 285.436564 -348.15399)
		(stroke
			(width 0.2)
			(type default)
		)
		(layer "In3.Cu")
	)
	(gr_line
		(start 285.436818 -344.556588)
		(end 285.436564 -344.556588)
		(stroke
			(width 0.2)
			(type default)
		)
		(layer "In3.Cu")
	)
	(gr_line
		(start 285.436818 -340.956392)
		(end 285.436564 -340.956392)
		(stroke
			(width 0.2)
			(type default)
		)
		(layer "In3.Cu")
	)
	(gr_line
		(start 285.436818 -337.35645)
		(end 285.436564 -337.35645)
		(stroke
			(width 0.2)
			(type default)
		)
		(layer "In3.Cu")
	)
	(gr_line
		(start 285.436818 -333.753968)
		(end 285.436564 -333.753968)
		(stroke
			(width 0.2)
			(type default)
		)
		(layer "In3.Cu")
	)
	(gr_line
		(start 285.436818 -330.154026)
		(end 285.436564 -330.154026)
		(stroke
			(width 0.2)
			(type default)
		)
		(layer "In3.Cu")
	)
	(gr_line
		(start 285.436818 -326.554084)
		(end 285.436564 -326.554084)
		(stroke
			(width 0.2)
			(type default)
		)
		(layer "In3.Cu")
	)
	(gr_line
		(start 285.436818 -322.956428)
		(end 285.436564 -322.956428)
		(stroke
			(width 0.2)
			(type default)
		)
		(layer "In3.Cu")
	)
	(gr_line
		(start 285.436818 -319.356486)
		(end 285.436564 -319.356486)
		(stroke
			(width 0.2)
			(type default)
		)
		(layer "In3.Cu")
	)
	(gr_line
		(start 285.436818 -315.756544)
		(end 285.436564 -315.756544)
		(stroke
			(width 0.2)
			(type default)
		)
		(layer "In3.Cu")
	)
	(gr_line
		(start 285.436818 -312.154062)
		(end 285.436564 -312.154062)
		(stroke
			(width 0.2)
			(type default)
		)
		(layer "In3.Cu")
	)
	(gr_line
		(start 285.436818 -308.553866)
		(end 285.436564 -308.553866)
		(stroke
			(width 0.2)
			(type default)
		)
		(layer "In3.Cu")
	)
	(gr_line
		(start 285.436818 -304.953924)
		(end 285.436564 -304.953924)
		(stroke
			(width 0.2)
			(type default)
		)
		(layer "In3.Cu")
	)
	(gr_line
		(start 285.436818 -301.356522)
		(end 285.436564 -301.356522)
		(stroke
			(width 0.2)
			(type default)
		)
		(layer "In3.Cu")
	)
	(gr_line
		(start 285.436818 -297.75658)
		(end 285.436564 -297.75658)
		(stroke
			(width 0.2)
			(type default)
		)
		(layer "In3.Cu")
	)
	(gr_line
		(start 285.436818 -294.154098)
		(end 285.436564 -294.154098)
		(stroke
			(width 0.2)
			(type default)
		)
		(layer "In3.Cu")
	)
	(gr_line
		(start 285.436818 -261.351014)
		(end 285.436564 -261.351014)
		(stroke
			(width 0.2)
			(type default)
		)
		(layer "In3.Cu")
	)
	(gr_line
		(start 285.436818 -257.751072)
		(end 285.436564 -257.751072)
		(stroke
			(width 0.2)
			(type default)
		)
		(layer "In3.Cu")
	)
	(gr_line
		(start 285.436818 -254.15113)
		(end 285.436564 -254.15113)
		(stroke
			(width 0.2)
			(type default)
		)
		(layer "In3.Cu")
	)
	(gr_line
		(start 285.436818 -250.551188)
		(end 285.436564 -250.551188)
		(stroke
			(width 0.2)
			(type default)
		)
		(layer "In3.Cu")
	)
	(gr_line
		(start 285.56331 -179.87264)
		(end 283.563314 -178.872642)
		(stroke
			(width 0.2)
			(type default)
		)
		(layer "In3.Cu")
	)
	(gr_line
		(start 285.56331 -175.872648)
		(end 283.563314 -174.87265)
		(stroke
			(width 0.2)
			(type default)
		)
		(layer "In3.Cu")
	)
	(gr_line
		(start 285.56331 -171.872656)
		(end 283.563314 -170.872658)
		(stroke
			(width 0.2)
			(type default)
		)
		(layer "In3.Cu")
	)
	(gr_line
		(start 285.56331 -167.872664)
		(end 283.563314 -166.872666)
		(stroke
			(width 0.2)
			(type default)
		)
		(layer "In3.Cu")
	)
	(gr_line
		(start 285.56331 -163.872672)
		(end 283.563314 -162.872674)
		(stroke
			(width 0.2)
			(type default)
		)
		(layer "In3.Cu")
	)
	(gr_line
		(start 285.56331 -159.87268)
		(end 283.571696 -158.877)
		(stroke
			(width 0.2)
			(type default)
		)
		(layer "In3.Cu")
	)
	(gr_line
		(start 285.56331 -155.872688)
		(end 283.563314 -154.87269)
		(stroke
			(width 0.2)
			(type default)
		)
		(layer "In3.Cu")
	)
	(gr_line
		(start 285.56331 -151.872696)
		(end 283.563314 -150.872698)
		(stroke
			(width 0.2)
			(type default)
		)
		(layer "In3.Cu")
	)
	(gr_line
		(start 285.56331 -127.872744)
		(end 283.563314 -126.872746)
		(stroke
			(width 0.2)
			(type default)
		)
		(layer "In3.Cu")
	)
	(gr_line
		(start 285.56331 -123.872752)
		(end 283.563314 -122.872754)
		(stroke
			(width 0.2)
			(type default)
		)
		(layer "In3.Cu")
	)
	(gr_line
		(start 285.56331 -119.87276)
		(end 283.563314 -118.872762)
		(stroke
			(width 0.2)
			(type default)
		)
		(layer "In3.Cu")
	)
	(gr_line
		(start 285.56331 -115.872768)
		(end 283.563314 -114.87277)
		(stroke
			(width 0.2)
			(type default)
		)
		(layer "In3.Cu")
	)
	(gr_line
		(start 285.56331 -83.572858)
		(end 283.563314 -82.57286)
		(stroke
			(width 0.2)
			(type default)
		)
		(layer "In3.Cu")
	)
	(gr_line
		(start 285.56331 -79.572866)
		(end 283.563314 -78.572868)
		(stroke
			(width 0.2)
			(type default)
		)
		(layer "In3.Cu")
	)
	(gr_line
		(start 285.56331 -75.572874)
		(end 283.563314 -74.572876)
		(stroke
			(width 0.2)
			(type default)
		)
		(layer "In3.Cu")
	)
	(gr_line
		(start 285.56331 -71.572882)
		(end 283.563314 -70.572884)
		(stroke
			(width 0.2)
			(type default)
		)
		(layer "In3.Cu")
	)
	(gr_line
		(start 285.56331 -67.57289)
		(end 283.563314 -66.572892)
		(stroke
			(width 0.2)
			(type default)
		)
		(layer "In3.Cu")
	)
	(gr_line
		(start 285.56331 -63.572898)
		(end 283.563314 -62.5729)
		(stroke
			(width 0.2)
			(type default)
		)
		(layer "In3.Cu")
	)
	(gr_line
		(start 285.56331 -59.572906)
		(end 283.563314 -58.572908)
		(stroke
			(width 0.2)
			(type default)
		)
		(layer "In3.Cu")
	)
	(gr_line
		(start 285.56331 -55.572914)
		(end 283.563314 -54.572916)
		(stroke
			(width 0.2)
			(type default)
		)
		(layer "In3.Cu")
	)
	(gr_line
		(start 285.56331 -51.572922)
		(end 283.563314 -50.572924)
		(stroke
			(width 0.2)
			(type default)
		)
		(layer "In3.Cu")
	)
	(gr_line
		(start 285.56331 -47.57293)
		(end 283.563314 -46.572932)
		(stroke
			(width 0.2)
			(type default)
		)
		(layer "In3.Cu")
	)
	(gr_line
		(start 285.56331 -43.572938)
		(end 283.563314 -42.57294)
		(stroke
			(width 0.2)
			(type default)
		)
		(layer "In3.Cu")
	)
	(gr_line
		(start 285.56331 -39.572946)
		(end 283.563314 -38.572948)
		(stroke
			(width 0.2)
			(type default)
		)
		(layer "In3.Cu")
	)
	(gr_line
		(start 285.57474 -135.850122)
		(end 285.57601 -135.847836)
		(stroke
			(width 0.2)
			(type default)
		)
		(layer "In3.Cu")
	)
	(gr_line
		(start 285.57601 -135.847836)
		(end 283.576014 -134.847838)
		(stroke
			(width 0.2)
			(type default)
		)
		(layer "In3.Cu")
	)
	(gr_line
		(start 285.57601 -107.847892)
		(end 283.576014 -106.847894)
		(stroke
			(width 0.2)
			(type default)
		)
		(layer "In3.Cu")
	)
	(gr_line
		(start 285.577026 -35.545776)
		(end 283.57703 -34.545778)
		(stroke
			(width 0.2)
			(type default)
		)
		(layer "In3.Cu")
	)
	(gr_line
		(start 286.436562 -358.256332)
		(end 287.83661 -358.256332)
		(stroke
			(width 0.2)
			(type default)
		)
		(layer "In3.Cu")
	)
	(gr_arc
		(start 286.436562 -357.153972)
		(mid 285.885382 -357.705152)
		(end 286.436562 -358.256332)
		(stroke
			(width 0.2)
			(type default)
		)
		(layer "In3.Cu")
	)
	(gr_line
		(start 286.436562 -354.65639)
		(end 287.83661 -354.65639)
		(stroke
			(width 0.2)
			(type default)
		)
		(layer "In3.Cu")
	)
	(gr_arc
		(start 286.436562 -353.55403)
		(mid 285.885382 -354.10521)
		(end 286.436562 -354.65639)
		(stroke
			(width 0.2)
			(type default)
		)
		(layer "In3.Cu")
	)
	(gr_line
		(start 286.436562 -351.056448)
		(end 287.83661 -351.056448)
		(stroke
			(width 0.2)
			(type default)
		)
		(layer "In3.Cu")
	)
	(gr_arc
		(start 286.436562 -349.954088)
		(mid 285.885382 -350.505268)
		(end 286.436562 -351.056448)
		(stroke
			(width 0.2)
			(type default)
		)
		(layer "In3.Cu")
	)
	(gr_line
		(start 286.436562 -347.453712)
		(end 287.83661 -347.453712)
		(stroke
			(width 0.2)
			(type default)
		)
		(layer "In3.Cu")
	)
	(gr_arc
		(start 286.436562 -346.356432)
		(mid 285.887922 -346.905072)
		(end 286.436562 -347.453712)
		(stroke
			(width 0.2)
			(type default)
		)
		(layer "In3.Cu")
	)
	(gr_line
		(start 286.436562 -343.85377)
		(end 287.83661 -343.85377)
		(stroke
			(width 0.2)
			(type default)
		)
		(layer "In3.Cu")
	)
	(gr_arc
		(start 286.436562 -342.75649)
		(mid 285.887922 -343.30513)
		(end 286.436562 -343.85377)
		(stroke
			(width 0.2)
			(type default)
		)
		(layer "In3.Cu")
	)
	(gr_line
		(start 286.436562 -340.253828)
		(end 287.83661 -340.253828)
		(stroke
			(width 0.2)
			(type default)
		)
		(layer "In3.Cu")
	)
	(gr_arc
		(start 286.436562 -339.156548)
		(mid 285.887922 -339.705188)
		(end 286.436562 -340.253828)
		(stroke
			(width 0.2)
			(type default)
		)
		(layer "In3.Cu")
	)
	(gr_line
		(start 286.436562 -336.656426)
		(end 287.83661 -336.656426)
		(stroke
			(width 0.2)
			(type default)
		)
		(layer "In3.Cu")
	)
	(gr_arc
		(start 286.436562 -335.554066)
		(mid 285.885382 -336.105246)
		(end 286.436562 -336.656426)
		(stroke
			(width 0.2)
			(type default)
		)
		(layer "In3.Cu")
	)
	(gr_line
		(start 286.436562 -333.05623)
		(end 287.83661 -333.05623)
		(stroke
			(width 0.2)
			(type default)
		)
		(layer "In3.Cu")
	)
	(gr_arc
		(start 286.436562 -331.95387)
		(mid 285.885382 -332.50505)
		(end 286.436562 -333.05623)
		(stroke
			(width 0.2)
			(type default)
		)
		(layer "In3.Cu")
	)
	(gr_line
		(start 286.436562 -329.456288)
		(end 287.83661 -329.456288)
		(stroke
			(width 0.2)
			(type default)
		)
		(layer "In3.Cu")
	)
	(gr_arc
		(start 286.436562 -328.353928)
		(mid 285.885382 -328.905108)
		(end 286.436562 -329.456288)
		(stroke
			(width 0.2)
			(type default)
		)
		(layer "In3.Cu")
	)
	(gr_line
		(start 286.436562 -325.853806)
		(end 287.83661 -325.853806)
		(stroke
			(width 0.2)
			(type default)
		)
		(layer "In3.Cu")
	)
	(gr_arc
		(start 286.436562 -324.756526)
		(mid 285.887922 -325.305166)
		(end 286.436562 -325.853806)
		(stroke
			(width 0.2)
			(type default)
		)
		(layer "In3.Cu")
	)
	(gr_line
		(start 286.436562 -322.253864)
		(end 287.83661 -322.253864)
		(stroke
			(width 0.2)
			(type default)
		)
		(layer "In3.Cu")
	)
	(gr_arc
		(start 286.436562 -321.156584)
		(mid 285.887922 -321.705224)
		(end 286.436562 -322.253864)
		(stroke
			(width 0.2)
			(type default)
		)
		(layer "In3.Cu")
	)
	(gr_line
		(start 286.436562 -318.653668)
		(end 287.83661 -318.653668)
		(stroke
			(width 0.2)
			(type default)
		)
		(layer "In3.Cu")
	)
	(gr_arc
		(start 286.436562 -317.556388)
		(mid 285.887922 -318.105028)
		(end 286.436562 -318.653668)
		(stroke
			(width 0.2)
			(type default)
		)
		(layer "In3.Cu")
	)
	(gr_line
		(start 286.436562 -315.056266)
		(end 287.83661 -315.056266)
		(stroke
			(width 0.2)
			(type default)
		)
		(layer "In3.Cu")
	)
	(gr_arc
		(start 286.436562 -313.953906)
		(mid 285.885382 -314.505086)
		(end 286.436562 -315.056266)
		(stroke
			(width 0.2)
			(type default)
		)
		(layer "In3.Cu")
	)
	(gr_line
		(start 286.436562 -311.456324)
		(end 287.83661 -311.456324)
		(stroke
			(width 0.2)
			(type default)
		)
		(layer "In3.Cu")
	)
	(gr_arc
		(start 286.436562 -310.353964)
		(mid 285.885382 -310.905144)
		(end 286.436562 -311.456324)
		(stroke
			(width 0.2)
			(type default)
		)
		(layer "In3.Cu")
	)
	(gr_line
		(start 286.436562 -307.856382)
		(end 287.83661 -307.856382)
		(stroke
			(width 0.2)
			(type default)
		)
		(layer "In3.Cu")
	)
	(gr_arc
		(start 286.436562 -306.754022)
		(mid 285.885382 -307.305202)
		(end 286.436562 -307.856382)
		(stroke
			(width 0.2)
			(type default)
		)
		(layer "In3.Cu")
	)
	(gr_line
		(start 286.436562 -304.2539)
		(end 287.83661 -304.2539)
		(stroke
			(width 0.2)
			(type default)
		)
		(layer "In3.Cu")
	)
	(gr_arc
		(start 286.436562 -303.15662)
		(mid 285.887922 -303.70526)
		(end 286.436562 -304.2539)
		(stroke
			(width 0.2)
			(type default)
		)
		(layer "In3.Cu")
	)
	(gr_line
		(start 286.436562 -300.653704)
		(end 287.83661 -300.653704)
		(stroke
			(width 0.2)
			(type default)
		)
		(layer "In3.Cu")
	)
	(gr_arc
		(start 286.436562 -299.556424)
		(mid 285.887922 -300.105064)
		(end 286.436562 -300.653704)
		(stroke
			(width 0.2)
			(type default)
		)
		(layer "In3.Cu")
	)
	(gr_line
		(start 286.436562 -297.056302)
		(end 287.83661 -297.056302)
		(stroke
			(width 0.2)
			(type default)
		)
		(layer "In3.Cu")
	)
	(gr_arc
		(start 286.436562 -295.953942)
		(mid 285.885382 -296.505122)
		(end 286.436562 -297.056302)
		(stroke
			(width 0.2)
			(type default)
		)
		(layer "In3.Cu")
	)
	(gr_line
		(start 286.436562 -264.253472)
		(end 287.83661 -264.253472)
		(stroke
			(width 0.2)
			(type default)
		)
		(layer "In3.Cu")
	)
	(gr_arc
		(start 286.436562 -263.151112)
		(mid 285.885382 -263.702292)
		(end 286.436562 -264.253472)
		(stroke
			(width 0.2)
			(type default)
		)
		(layer "In3.Cu")
	)
	(gr_line
		(start 286.436562 -260.65353)
		(end 287.83661 -260.65353)
		(stroke
			(width 0.2)
			(type default)
		)
		(layer "In3.Cu")
	)
	(gr_arc
		(start 286.436562 -259.55117)
		(mid 285.885382 -260.10235)
		(end 286.436562 -260.65353)
		(stroke
			(width 0.2)
			(type default)
		)
		(layer "In3.Cu")
	)
	(gr_line
		(start 286.436562 -257.053588)
		(end 287.83661 -257.053588)
		(stroke
			(width 0.2)
			(type default)
		)
		(layer "In3.Cu")
	)
	(gr_arc
		(start 286.436562 -255.951228)
		(mid 285.885382 -256.502408)
		(end 286.436562 -257.053588)
		(stroke
			(width 0.2)
			(type default)
		)
		(layer "In3.Cu")
	)
	(gr_line
		(start 286.436562 -253.453392)
		(end 287.83661 -253.453392)
		(stroke
			(width 0.2)
			(type default)
		)
		(layer "In3.Cu")
	)
	(gr_arc
		(start 286.436562 -252.351032)
		(mid 285.885382 -252.902212)
		(end 286.436562 -253.453392)
		(stroke
			(width 0.2)
			(type default)
		)
		(layer "In3.Cu")
	)
	(gr_line
		(start 286.436816 -357.153972)
		(end 286.436562 -357.153972)
		(stroke
			(width 0.2)
			(type default)
		)
		(layer "In3.Cu")
	)
	(gr_line
		(start 286.436816 -353.55403)
		(end 286.436562 -353.55403)
		(stroke
			(width 0.2)
			(type default)
		)
		(layer "In3.Cu")
	)
	(gr_line
		(start 286.436816 -349.954088)
		(end 286.436562 -349.954088)
		(stroke
			(width 0.2)
			(type default)
		)
		(layer "In3.Cu")
	)
	(gr_line
		(start 286.436816 -346.356432)
		(end 286.436562 -346.356432)
		(stroke
			(width 0.2)
			(type default)
		)
		(layer "In3.Cu")
	)
	(gr_line
		(start 286.436816 -342.75649)
		(end 286.436562 -342.75649)
		(stroke
			(width 0.2)
			(type default)
		)
		(layer "In3.Cu")
	)
	(gr_line
		(start 286.436816 -339.156548)
		(end 286.436562 -339.156548)
		(stroke
			(width 0.2)
			(type default)
		)
		(layer "In3.Cu")
	)
	(gr_line
		(start 286.436816 -335.554066)
		(end 286.436562 -335.554066)
		(stroke
			(width 0.2)
			(type default)
		)
		(layer "In3.Cu")
	)
	(gr_line
		(start 286.436816 -331.95387)
		(end 286.436562 -331.95387)
		(stroke
			(width 0.2)
			(type default)
		)
		(layer "In3.Cu")
	)
	(gr_line
		(start 286.436816 -328.353928)
		(end 286.436562 -328.353928)
		(stroke
			(width 0.2)
			(type default)
		)
		(layer "In3.Cu")
	)
	(gr_line
		(start 286.436816 -324.756526)
		(end 286.436562 -324.756526)
		(stroke
			(width 0.2)
			(type default)
		)
		(layer "In3.Cu")
	)
	(gr_line
		(start 286.436816 -321.156584)
		(end 286.436562 -321.156584)
		(stroke
			(width 0.2)
			(type default)
		)
		(layer "In3.Cu")
	)
	(gr_line
		(start 286.436816 -317.556388)
		(end 286.436562 -317.556388)
		(stroke
			(width 0.2)
			(type default)
		)
		(layer "In3.Cu")
	)
	(gr_line
		(start 286.436816 -313.953906)
		(end 286.436562 -313.953906)
		(stroke
			(width 0.2)
			(type default)
		)
		(layer "In3.Cu")
	)
	(gr_line
		(start 286.436816 -310.353964)
		(end 286.436562 -310.353964)
		(stroke
			(width 0.2)
			(type default)
		)
		(layer "In3.Cu")
	)
	(gr_line
		(start 286.436816 -306.754022)
		(end 286.436562 -306.754022)
		(stroke
			(width 0.2)
			(type default)
		)
		(layer "In3.Cu")
	)
	(gr_line
		(start 286.436816 -303.15662)
		(end 286.436562 -303.15662)
		(stroke
			(width 0.2)
			(type default)
		)
		(layer "In3.Cu")
	)
	(gr_line
		(start 286.436816 -299.556424)
		(end 286.436562 -299.556424)
		(stroke
			(width 0.2)
			(type default)
		)
		(layer "In3.Cu")
	)
	(gr_line
		(start 286.436816 -295.953942)
		(end 286.436562 -295.953942)
		(stroke
			(width 0.2)
			(type default)
		)
		(layer "In3.Cu")
	)
	(gr_line
		(start 286.436816 -263.151112)
		(end 286.436562 -263.151112)
		(stroke
			(width 0.2)
			(type default)
		)
		(layer "In3.Cu")
	)
	(gr_line
		(start 286.436816 -259.55117)
		(end 286.436562 -259.55117)
		(stroke
			(width 0.2)
			(type default)
		)
		(layer "In3.Cu")
	)
	(gr_line
		(start 286.436816 -255.951228)
		(end 286.436562 -255.951228)
		(stroke
			(width 0.2)
			(type default)
		)
		(layer "In3.Cu")
	)
	(gr_line
		(start 286.436816 -252.351032)
		(end 286.436562 -252.351032)
		(stroke
			(width 0.2)
			(type default)
		)
		(layer "In3.Cu")
	)
	(gr_arc
		(start 286.836612 -356.456234)
		(mid 287.387792 -355.905054)
		(end 286.836612 -355.353874)
		(stroke
			(width 0.2)
			(type default)
		)
		(layer "In3.Cu")
	)
	(gr_line
		(start 286.836612 -355.353874)
		(end 285.436818 -355.353874)
		(stroke
			(width 0.2)
			(type default)
		)
		(layer "In3.Cu")
	)
	(gr_arc
		(start 286.836612 -352.856292)
		(mid 287.387792 -352.305112)
		(end 286.836612 -351.753932)
		(stroke
			(width 0.2)
			(type default)
		)
		(layer "In3.Cu")
	)
	(gr_line
		(start 286.836612 -351.753932)
		(end 285.436818 -351.753932)
		(stroke
			(width 0.2)
			(type default)
		)
		(layer "In3.Cu")
	)
	(gr_arc
		(start 286.836612 -349.25635)
		(mid 287.387792 -348.70517)
		(end 286.836612 -348.15399)
		(stroke
			(width 0.2)
			(type default)
		)
		(layer "In3.Cu")
	)
	(gr_line
		(start 286.836612 -348.15399)
		(end 285.436818 -348.15399)
		(stroke
			(width 0.2)
			(type default)
		)
		(layer "In3.Cu")
	)
	(gr_arc
		(start 286.836612 -345.653868)
		(mid 287.385252 -345.105228)
		(end 286.836612 -344.556588)
		(stroke
			(width 0.2)
			(type default)
		)
		(layer "In3.Cu")
	)
	(gr_line
		(start 286.836612 -344.556588)
		(end 285.436818 -344.556588)
		(stroke
			(width 0.2)
			(type default)
		)
		(layer "In3.Cu")
	)
	(gr_arc
		(start 286.836612 -342.053672)
		(mid 287.385252 -341.505032)
		(end 286.836612 -340.956392)
		(stroke
			(width 0.2)
			(type default)
		)
		(layer "In3.Cu")
	)
	(gr_line
		(start 286.836612 -340.956392)
		(end 285.436818 -340.956392)
		(stroke
			(width 0.2)
			(type default)
		)
		(layer "In3.Cu")
	)
	(gr_arc
		(start 286.836612 -338.45373)
		(mid 287.385252 -337.90509)
		(end 286.836612 -337.35645)
		(stroke
			(width 0.2)
			(type default)
		)
		(layer "In3.Cu")
	)
	(gr_line
		(start 286.836612 -337.35645)
		(end 285.436818 -337.35645)
		(stroke
			(width 0.2)
			(type default)
		)
		(layer "In3.Cu")
	)
	(gr_arc
		(start 286.836612 -334.856328)
		(mid 287.387792 -334.305148)
		(end 286.836612 -333.753968)
		(stroke
			(width 0.2)
			(type default)
		)
		(layer "In3.Cu")
	)
	(gr_line
		(start 286.836612 -333.753968)
		(end 285.436818 -333.753968)
		(stroke
			(width 0.2)
			(type default)
		)
		(layer "In3.Cu")
	)
	(gr_arc
		(start 286.836612 -331.256386)
		(mid 287.387792 -330.705206)
		(end 286.836612 -330.154026)
		(stroke
			(width 0.2)
			(type default)
		)
		(layer "In3.Cu")
	)
	(gr_line
		(start 286.836612 -330.154026)
		(end 285.436818 -330.154026)
		(stroke
			(width 0.2)
			(type default)
		)
		(layer "In3.Cu")
	)
	(gr_arc
		(start 286.836612 -327.656444)
		(mid 287.387792 -327.105264)
		(end 286.836612 -326.554084)
		(stroke
			(width 0.2)
			(type default)
		)
		(layer "In3.Cu")
	)
	(gr_line
		(start 286.836612 -326.554084)
		(end 285.436818 -326.554084)
		(stroke
			(width 0.2)
			(type default)
		)
		(layer "In3.Cu")
	)
	(gr_arc
		(start 286.836612 -324.053708)
		(mid 287.385252 -323.505068)
		(end 286.836612 -322.956428)
		(stroke
			(width 0.2)
			(type default)
		)
		(layer "In3.Cu")
	)
	(gr_line
		(start 286.836612 -322.956428)
		(end 285.436818 -322.956428)
		(stroke
			(width 0.2)
			(type default)
		)
		(layer "In3.Cu")
	)
	(gr_arc
		(start 286.836612 -320.453766)
		(mid 287.385252 -319.905126)
		(end 286.836612 -319.356486)
		(stroke
			(width 0.2)
			(type default)
		)
		(layer "In3.Cu")
	)
	(gr_line
		(start 286.836612 -319.356486)
		(end 285.436818 -319.356486)
		(stroke
			(width 0.2)
			(type default)
		)
		(layer "In3.Cu")
	)
	(gr_arc
		(start 286.836612 -316.853824)
		(mid 287.385252 -316.305184)
		(end 286.836612 -315.756544)
		(stroke
			(width 0.2)
			(type default)
		)
		(layer "In3.Cu")
	)
	(gr_line
		(start 286.836612 -315.756544)
		(end 285.436818 -315.756544)
		(stroke
			(width 0.2)
			(type default)
		)
		(layer "In3.Cu")
	)
	(gr_arc
		(start 286.836612 -313.256422)
		(mid 287.387792 -312.705242)
		(end 286.836612 -312.154062)
		(stroke
			(width 0.2)
			(type default)
		)
		(layer "In3.Cu")
	)
	(gr_line
		(start 286.836612 -312.154062)
		(end 285.436818 -312.154062)
		(stroke
			(width 0.2)
			(type default)
		)
		(layer "In3.Cu")
	)
	(gr_arc
		(start 286.836612 -309.656226)
		(mid 287.387792 -309.105046)
		(end 286.836612 -308.553866)
		(stroke
			(width 0.2)
			(type default)
		)
		(layer "In3.Cu")
	)
	(gr_line
		(start 286.836612 -308.553866)
		(end 285.436818 -308.553866)
		(stroke
			(width 0.2)
			(type default)
		)
		(layer "In3.Cu")
	)
	(gr_arc
		(start 286.836612 -306.056284)
		(mid 287.387792 -305.505104)
		(end 286.836612 -304.953924)
		(stroke
			(width 0.2)
			(type default)
		)
		(layer "In3.Cu")
	)
	(gr_line
		(start 286.836612 -304.953924)
		(end 285.436818 -304.953924)
		(stroke
			(width 0.2)
			(type default)
		)
		(layer "In3.Cu")
	)
	(gr_arc
		(start 286.836612 -302.453802)
		(mid 287.385252 -301.905162)
		(end 286.836612 -301.356522)
		(stroke
			(width 0.2)
			(type default)
		)
		(layer "In3.Cu")
	)
	(gr_line
		(start 286.836612 -301.356522)
		(end 285.436818 -301.356522)
		(stroke
			(width 0.2)
			(type default)
		)
		(layer "In3.Cu")
	)
	(gr_arc
		(start 286.836612 -298.85386)
		(mid 287.385252 -298.30522)
		(end 286.836612 -297.75658)
		(stroke
			(width 0.2)
			(type default)
		)
		(layer "In3.Cu")
	)
	(gr_line
		(start 286.836612 -297.75658)
		(end 285.436818 -297.75658)
		(stroke
			(width 0.2)
			(type default)
		)
		(layer "In3.Cu")
	)
	(gr_arc
		(start 286.836612 -295.256458)
		(mid 287.387792 -294.705278)
		(end 286.836612 -294.154098)
		(stroke
			(width 0.2)
			(type default)
		)
		(layer "In3.Cu")
	)
	(gr_line
		(start 286.836612 -294.154098)
		(end 285.436818 -294.154098)
		(stroke
			(width 0.2)
			(type default)
		)
		(layer "In3.Cu")
	)
	(gr_arc
		(start 286.836612 -262.453374)
		(mid 287.387792 -261.902194)
		(end 286.836612 -261.351014)
		(stroke
			(width 0.2)
			(type default)
		)
		(layer "In3.Cu")
	)
	(gr_line
		(start 286.836612 -261.351014)
		(end 285.436818 -261.351014)
		(stroke
			(width 0.2)
			(type default)
		)
		(layer "In3.Cu")
	)
	(gr_arc
		(start 286.836612 -258.853432)
		(mid 287.387792 -258.302252)
		(end 286.836612 -257.751072)
		(stroke
			(width 0.2)
			(type default)
		)
		(layer "In3.Cu")
	)
	(gr_line
		(start 286.836612 -257.751072)
		(end 285.436818 -257.751072)
		(stroke
			(width 0.2)
			(type default)
		)
		(layer "In3.Cu")
	)
	(gr_arc
		(start 286.836612 -255.25349)
		(mid 287.387792 -254.70231)
		(end 286.836612 -254.15113)
		(stroke
			(width 0.2)
			(type default)
		)
		(layer "In3.Cu")
	)
	(gr_line
		(start 286.836612 -254.15113)
		(end 285.436818 -254.15113)
		(stroke
			(width 0.2)
			(type default)
		)
		(layer "In3.Cu")
	)
	(gr_arc
		(start 286.836612 -251.653548)
		(mid 287.387792 -251.102368)
		(end 286.836612 -250.551188)
		(stroke
			(width 0.2)
			(type default)
		)
		(layer "In3.Cu")
	)
	(gr_line
		(start 286.836612 -250.551188)
		(end 285.436818 -250.551188)
		(stroke
			(width 0.2)
			(type default)
		)
		(layer "In3.Cu")
	)
	(gr_arc
		(start 287.83661 -358.256332)
		(mid 288.38779 -357.705152)
		(end 287.83661 -357.153972)
		(stroke
			(width 0.2)
			(type default)
		)
		(layer "In3.Cu")
	)
	(gr_line
		(start 287.83661 -357.153972)
		(end 286.436816 -357.153972)
		(stroke
			(width 0.2)
			(type default)
		)
		(layer "In3.Cu")
	)
	(gr_arc
		(start 287.83661 -354.65639)
		(mid 288.38779 -354.10521)
		(end 287.83661 -353.55403)
		(stroke
			(width 0.2)
			(type default)
		)
		(layer "In3.Cu")
	)
	(gr_line
		(start 287.83661 -353.55403)
		(end 286.436816 -353.55403)
		(stroke
			(width 0.2)
			(type default)
		)
		(layer "In3.Cu")
	)
	(gr_arc
		(start 287.83661 -351.056448)
		(mid 288.38779 -350.505268)
		(end 287.83661 -349.954088)
		(stroke
			(width 0.2)
			(type default)
		)
		(layer "In3.Cu")
	)
	(gr_line
		(start 287.83661 -349.954088)
		(end 286.436816 -349.954088)
		(stroke
			(width 0.2)
			(type default)
		)
		(layer "In3.Cu")
	)
	(gr_arc
		(start 287.83661 -347.453712)
		(mid 288.38525 -346.905072)
		(end 287.83661 -346.356432)
		(stroke
			(width 0.2)
			(type default)
		)
		(layer "In3.Cu")
	)
	(gr_line
		(start 287.83661 -346.356432)
		(end 286.436816 -346.356432)
		(stroke
			(width 0.2)
			(type default)
		)
		(layer "In3.Cu")
	)
	(gr_arc
		(start 287.83661 -343.85377)
		(mid 288.38525 -343.30513)
		(end 287.83661 -342.75649)
		(stroke
			(width 0.2)
			(type default)
		)
		(layer "In3.Cu")
	)
	(gr_line
		(start 287.83661 -342.75649)
		(end 286.436816 -342.75649)
		(stroke
			(width 0.2)
			(type default)
		)
		(layer "In3.Cu")
	)
	(gr_arc
		(start 287.83661 -340.253828)
		(mid 288.38525 -339.705188)
		(end 287.83661 -339.156548)
		(stroke
			(width 0.2)
			(type default)
		)
		(layer "In3.Cu")
	)
	(gr_line
		(start 287.83661 -339.156548)
		(end 286.436816 -339.156548)
		(stroke
			(width 0.2)
			(type default)
		)
		(layer "In3.Cu")
	)
	(gr_arc
		(start 287.83661 -336.656426)
		(mid 288.38779 -336.105246)
		(end 287.83661 -335.554066)
		(stroke
			(width 0.2)
			(type default)
		)
		(layer "In3.Cu")
	)
	(gr_line
		(start 287.83661 -335.554066)
		(end 286.436816 -335.554066)
		(stroke
			(width 0.2)
			(type default)
		)
		(layer "In3.Cu")
	)
	(gr_arc
		(start 287.83661 -333.05623)
		(mid 288.38779 -332.50505)
		(end 287.83661 -331.95387)
		(stroke
			(width 0.2)
			(type default)
		)
		(layer "In3.Cu")
	)
	(gr_line
		(start 287.83661 -331.95387)
		(end 286.436816 -331.95387)
		(stroke
			(width 0.2)
			(type default)
		)
		(layer "In3.Cu")
	)
	(gr_arc
		(start 287.83661 -329.456288)
		(mid 288.38779 -328.905108)
		(end 287.83661 -328.353928)
		(stroke
			(width 0.2)
			(type default)
		)
		(layer "In3.Cu")
	)
	(gr_line
		(start 287.83661 -328.353928)
		(end 286.436816 -328.353928)
		(stroke
			(width 0.2)
			(type default)
		)
		(layer "In3.Cu")
	)
	(gr_arc
		(start 287.83661 -325.853806)
		(mid 288.38525 -325.305166)
		(end 287.83661 -324.756526)
		(stroke
			(width 0.2)
			(type default)
		)
		(layer "In3.Cu")
	)
	(gr_line
		(start 287.83661 -324.756526)
		(end 286.436816 -324.756526)
		(stroke
			(width 0.2)
			(type default)
		)
		(layer "In3.Cu")
	)
	(gr_arc
		(start 287.83661 -322.253864)
		(mid 288.38525 -321.705224)
		(end 287.83661 -321.156584)
		(stroke
			(width 0.2)
			(type default)
		)
		(layer "In3.Cu")
	)
	(gr_line
		(start 287.83661 -321.156584)
		(end 286.436816 -321.156584)
		(stroke
			(width 0.2)
			(type default)
		)
		(layer "In3.Cu")
	)
	(gr_arc
		(start 287.83661 -318.653668)
		(mid 288.38525 -318.105028)
		(end 287.83661 -317.556388)
		(stroke
			(width 0.2)
			(type default)
		)
		(layer "In3.Cu")
	)
	(gr_line
		(start 287.83661 -317.556388)
		(end 286.436816 -317.556388)
		(stroke
			(width 0.2)
			(type default)
		)
		(layer "In3.Cu")
	)
	(gr_arc
		(start 287.83661 -315.056266)
		(mid 288.38779 -314.505086)
		(end 287.83661 -313.953906)
		(stroke
			(width 0.2)
			(type default)
		)
		(layer "In3.Cu")
	)
	(gr_line
		(start 287.83661 -313.953906)
		(end 286.436816 -313.953906)
		(stroke
			(width 0.2)
			(type default)
		)
		(layer "In3.Cu")
	)
	(gr_arc
		(start 287.83661 -311.456324)
		(mid 288.38779 -310.905144)
		(end 287.83661 -310.353964)
		(stroke
			(width 0.2)
			(type default)
		)
		(layer "In3.Cu")
	)
	(gr_line
		(start 287.83661 -310.353964)
		(end 286.436816 -310.353964)
		(stroke
			(width 0.2)
			(type default)
		)
		(layer "In3.Cu")
	)
	(gr_arc
		(start 287.83661 -307.856382)
		(mid 288.38779 -307.305202)
		(end 287.83661 -306.754022)
		(stroke
			(width 0.2)
			(type default)
		)
		(layer "In3.Cu")
	)
	(gr_line
		(start 287.83661 -306.754022)
		(end 286.436816 -306.754022)
		(stroke
			(width 0.2)
			(type default)
		)
		(layer "In3.Cu")
	)
	(gr_arc
		(start 287.83661 -304.2539)
		(mid 288.38525 -303.70526)
		(end 287.83661 -303.15662)
		(stroke
			(width 0.2)
			(type default)
		)
		(layer "In3.Cu")
	)
	(gr_line
		(start 287.83661 -303.15662)
		(end 286.436816 -303.15662)
		(stroke
			(width 0.2)
			(type default)
		)
		(layer "In3.Cu")
	)
	(gr_arc
		(start 287.83661 -300.653704)
		(mid 288.38525 -300.105064)
		(end 287.83661 -299.556424)
		(stroke
			(width 0.2)
			(type default)
		)
		(layer "In3.Cu")
	)
	(gr_line
		(start 287.83661 -299.556424)
		(end 286.436816 -299.556424)
		(stroke
			(width 0.2)
			(type default)
		)
		(layer "In3.Cu")
	)
	(gr_arc
		(start 287.83661 -297.056302)
		(mid 288.38779 -296.505122)
		(end 287.83661 -295.953942)
		(stroke
			(width 0.2)
			(type default)
		)
		(layer "In3.Cu")
	)
	(gr_line
		(start 287.83661 -295.953942)
		(end 286.436816 -295.953942)
		(stroke
			(width 0.2)
			(type default)
		)
		(layer "In3.Cu")
	)
	(gr_arc
		(start 287.83661 -264.253472)
		(mid 288.38779 -263.702292)
		(end 287.83661 -263.151112)
		(stroke
			(width 0.2)
			(type default)
		)
		(layer "In3.Cu")
	)
	(gr_line
		(start 287.83661 -263.151112)
		(end 286.436816 -263.151112)
		(stroke
			(width 0.2)
			(type default)
		)
		(layer "In3.Cu")
	)
	(gr_arc
		(start 287.83661 -260.65353)
		(mid 288.38779 -260.10235)
		(end 287.83661 -259.55117)
		(stroke
			(width 0.2)
			(type default)
		)
		(layer "In3.Cu")
	)
	(gr_line
		(start 287.83661 -259.55117)
		(end 286.436816 -259.55117)
		(stroke
			(width 0.2)
			(type default)
		)
		(layer "In3.Cu")
	)
	(gr_arc
		(start 287.83661 -257.053588)
		(mid 288.38779 -256.502408)
		(end 287.83661 -255.951228)
		(stroke
			(width 0.2)
			(type default)
		)
		(layer "In3.Cu")
	)
	(gr_line
		(start 287.83661 -255.951228)
		(end 286.436816 -255.951228)
		(stroke
			(width 0.2)
			(type default)
		)
		(layer "In3.Cu")
	)
	(gr_arc
		(start 287.83661 -253.453392)
		(mid 288.38779 -252.902212)
		(end 287.83661 -252.351032)
		(stroke
			(width 0.2)
			(type default)
		)
		(layer "In3.Cu")
	)
	(gr_line
		(start 287.83661 -252.351032)
		(end 286.436816 -252.351032)
		(stroke
			(width 0.2)
			(type default)
		)
		(layer "In3.Cu")
	)
	(gr_arc
		(start 295.699942 -373.000016)
		(mid 295.992835 -373.707121)
		(end 296.69994 -374.000014)
		(stroke
			(width 1.524)
			(type default)
		)
		(layer "In3.Cu")
	)
	(gr_line
		(start 295.699942 -350.19996)
		(end 295.699942 -373.000016)
		(stroke
			(width 1.524)
			(type default)
		)
		(layer "In3.Cu")
	)
	(gr_line
		(start 296.69994 -374.000014)
		(end 308.99989 -374.000014)
		(stroke
			(width 1.524)
			(type default)
		)
		(layer "In3.Cu")
	)
	(gr_arc
		(start 296.69994 -349.199962)
		(mid 295.992835 -349.492855)
		(end 295.699942 -350.19996)
		(stroke
			(width 1.524)
			(type default)
		)
		(layer "In3.Cu")
	)
	(gr_arc
		(start 299.999908 0.999998)
		(mid 300.292801 0.292893)
		(end 300.999906 0)
		(stroke
			(width 1.524)
			(type default)
		)
		(layer "In3.Cu")
	)
	(gr_arc
		(start 299.999908 37.800026)
		(mid 299.707007 38.507118)
		(end 298.99991 38.800024)
		(stroke
			(width 1.524)
			(type default)
		)
		(layer "In3.Cu")
	)
	(gr_line
		(start 299.999908 37.800026)
		(end 299.999908 0.999998)
		(stroke
			(width 1.524)
			(type default)
		)
		(layer "In3.Cu")
	)
	(gr_line
		(start 300.999906 0)
		(end 347.000068 0)
		(stroke
			(width 1.524)
			(type default)
		)
		(layer "In3.Cu")
	)
	(gr_line
		(start 308.99989 -421.200072)
		(end 201.000106 -421.200072)
		(stroke
			(width 1.524)
			(type default)
		)
		(layer "In3.Cu")
	)
	(gr_arc
		(start 308.99989 -421.200072)
		(mid 309.706993 -420.907181)
		(end 309.999888 -420.200074)
		(stroke
			(width 1.524)
			(type default)
		)
		(layer "In3.Cu")
	)
	(gr_arc
		(start 309.999888 -375.000012)
		(mid 309.706999 -374.292902)
		(end 308.99989 -374.000014)
		(stroke
			(width 1.524)
			(type default)
		)
		(layer "In3.Cu")
	)
	(gr_line
		(start 309.999888 -375.000012)
		(end 309.999888 -420.200074)
		(stroke
			(width 1.524)
			(type default)
		)
		(layer "In3.Cu")
	)
	(gr_line
		(start 319.2145 -43.008042)
		(end 320.3575 -43.008042)
		(stroke
			(width 0.2)
			(type default)
		)
		(layer "In3.Cu")
	)
	(gr_arc
		(start 319.214754 -42.246042)
		(mid 318.8335 -42.626915)
		(end 319.2145 -43.008042)
		(stroke
			(width 0.2)
			(type default)
		)
		(layer "In3.Cu")
	)
	(gr_arc
		(start 319.56756 -274.511516)
		(mid 319.9892 -274.933156)
		(end 320.41084 -274.511516)
		(stroke
			(width 0.2)
			(type default)
		)
		(layer "In3.Cu")
	)
	(gr_line
		(start 319.56756 -273.368516)
		(end 319.56756 -274.511516)
		(stroke
			(width 0.2)
			(type default)
		)
		(layer "In3.Cu")
	)
	(gr_arc
		(start 319.6082 -159.511238)
		(mid 319.989073 -159.892492)
		(end 320.3702 -159.511492)
		(stroke
			(width 0.2)
			(type default)
		)
		(layer "In3.Cu")
	)
	(gr_line
		(start 319.6082 -158.368492)
		(end 319.6082 -159.511238)
		(stroke
			(width 0.2)
			(type default)
		)
		(layer "In3.Cu")
	)
	(gr_arc
		(start 320.3575 -43.008042)
		(mid 320.7385 -42.627042)
		(end 320.3575 -42.246042)
		(stroke
			(width 0.2)
			(type default)
		)
		(layer "In3.Cu")
	)
	(gr_line
		(start 320.3575 -42.246042)
		(end 319.214754 -42.246042)
		(stroke
			(width 0.2)
			(type default)
		)
		(layer "In3.Cu")
	)
	(gr_line
		(start 320.3702 -159.511492)
		(end 320.3702 -158.368492)
		(stroke
			(width 0.2)
			(type default)
		)
		(layer "In3.Cu")
	)
	(gr_arc
		(start 320.3702 -158.368492)
		(mid 319.9892 -157.987492)
		(end 319.6082 -158.368492)
		(stroke
			(width 0.2)
			(type default)
		)
		(layer "In3.Cu")
	)
	(gr_line
		(start 320.41084 -274.511516)
		(end 320.41084 -273.36877)
		(stroke
			(width 0.2)
			(type default)
		)
		(layer "In3.Cu")
	)
	(gr_arc
		(start 320.41084 -273.36877)
		(mid 319.989327 -272.946876)
		(end 319.56756 -273.368516)
		(stroke
			(width 0.2)
			(type default)
		)
		(layer "In3.Cu")
	)
	(gr_line
		(start 322.6816 -46.818042)
		(end 323.824346 -46.818042)
		(stroke
			(width 0.2)
			(type default)
		)
		(layer "In3.Cu")
	)
	(gr_arc
		(start 322.6816 -46.056042)
		(mid 322.3006 -46.437042)
		(end 322.6816 -46.818042)
		(stroke
			(width 0.2)
			(type default)
		)
		(layer "In3.Cu")
	)
	(gr_arc
		(start 323.824346 -46.818042)
		(mid 324.2056 -46.437169)
		(end 323.8246 -46.056042)
		(stroke
			(width 0.2)
			(type default)
		)
		(layer "In3.Cu")
	)
	(gr_line
		(start 323.8246 -46.056042)
		(end 322.6816 -46.056042)
		(stroke
			(width 0.2)
			(type default)
		)
		(layer "In3.Cu")
	)
	(gr_arc
		(start 324.358 -278.321516)
		(mid 324.739 -278.702516)
		(end 325.12 -278.321516)
		(stroke
			(width 0.2)
			(type default)
		)
		(layer "In3.Cu")
	)
	(gr_line
		(start 324.358 -277.178516)
		(end 324.358 -278.321516)
		(stroke
			(width 0.2)
			(type default)
		)
		(layer "In3.Cu")
	)
	(gr_arc
		(start 324.358 -163.321492)
		(mid 324.739 -163.702492)
		(end 325.12 -163.321492)
		(stroke
			(width 0.2)
			(type default)
		)
		(layer "In3.Cu")
	)
	(gr_line
		(start 324.358 -162.178492)
		(end 324.358 -163.321492)
		(stroke
			(width 0.2)
			(type default)
		)
		(layer "In3.Cu")
	)
	(gr_line
		(start 325.12 -278.321516)
		(end 325.12 -277.17877)
		(stroke
			(width 0.2)
			(type default)
		)
		(layer "In3.Cu")
	)
	(gr_arc
		(start 325.12 -277.17877)
		(mid 324.739127 -276.797516)
		(end 324.358 -277.178516)
		(stroke
			(width 0.2)
			(type default)
		)
		(layer "In3.Cu")
	)
	(gr_line
		(start 325.12 -163.321492)
		(end 325.12 -162.178746)
		(stroke
			(width 0.2)
			(type default)
		)
		(layer "In3.Cu")
	)
	(gr_arc
		(start 325.12 -162.178746)
		(mid 324.739127 -161.797492)
		(end 324.358 -162.178492)
		(stroke
			(width 0.2)
			(type default)
		)
		(layer "In3.Cu")
	)
	(gr_arc
		(start 348.000066 -13.999972)
		(mid 348.292959 -14.707077)
		(end 349.000064 -14.99997)
		(stroke
			(width 1.524)
			(type default)
		)
		(layer "In3.Cu")
	)
	(gr_arc
		(start 348.000066 -0.999998)
		(mid 347.707171 -0.292905)
		(end 347.000068 0)
		(stroke
			(width 1.524)
			(type default)
		)
		(layer "In3.Cu")
	)
	(gr_line
		(start 348.000066 -0.999998)
		(end 348.000066 -13.999972)
		(stroke
			(width 1.524)
			(type default)
		)
		(layer "In3.Cu")
	)
	(gr_line
		(start 349.000064 -14.99997)
		(end 394.999972 -14.99997)
		(stroke
			(width 1.524)
			(type default)
		)
		(layer "In3.Cu")
	)
	(gr_line
		(start 350.764602 -43.013122)
		(end 351.907602 -43.013122)
		(stroke
			(width 0.2)
			(type default)
		)
		(layer "In3.Cu")
	)
	(gr_arc
		(start 350.764856 -42.240962)
		(mid 350.378522 -42.626915)
		(end 350.764602 -43.013122)
		(stroke
			(width 0.2)
			(type default)
		)
		(layer "In3.Cu")
	)
	(gr_arc
		(start 351.158302 -274.511262)
		(mid 351.539175 -274.892516)
		(end 351.920302 -274.511516)
		(stroke
			(width 0.2)
			(type default)
		)
		(layer "In3.Cu")
	)
	(gr_line
		(start 351.158302 -273.368516)
		(end 351.158302 -274.511262)
		(stroke
			(width 0.2)
			(type default)
		)
		(layer "In3.Cu")
	)
	(gr_arc
		(start 351.158302 -159.511238)
		(mid 351.539175 -159.892492)
		(end 351.920302 -159.511492)
		(stroke
			(width 0.2)
			(type default)
		)
		(layer "In3.Cu")
	)
	(gr_line
		(start 351.158302 -158.368492)
		(end 351.158302 -159.511238)
		(stroke
			(width 0.2)
			(type default)
		)
		(layer "In3.Cu")
	)
	(gr_arc
		(start 351.907602 -43.013122)
		(mid 352.293682 -42.627042)
		(end 351.907602 -42.240962)
		(stroke
			(width 0.2)
			(type default)
		)
		(layer "In3.Cu")
	)
	(gr_line
		(start 351.907602 -42.240962)
		(end 350.764856 -42.240962)
		(stroke
			(width 0.2)
			(type default)
		)
		(layer "In3.Cu")
	)
	(gr_line
		(start 351.920302 -274.511516)
		(end 351.920302 -273.368516)
		(stroke
			(width 0.2)
			(type default)
		)
		(layer "In3.Cu")
	)
	(gr_arc
		(start 351.920302 -273.368516)
		(mid 351.539302 -272.987516)
		(end 351.158302 -273.368516)
		(stroke
			(width 0.2)
			(type default)
		)
		(layer "In3.Cu")
	)
	(gr_line
		(start 351.920302 -159.511492)
		(end 351.920302 -158.368492)
		(stroke
			(width 0.2)
			(type default)
		)
		(layer "In3.Cu")
	)
	(gr_arc
		(start 351.920302 -158.368492)
		(mid 351.539302 -157.987492)
		(end 351.158302 -158.368492)
		(stroke
			(width 0.2)
			(type default)
		)
		(layer "In3.Cu")
	)
	(gr_arc
		(start 354.601272 -22.350222)
		(mid 355.149912 -22.898862)
		(end 355.698552 -22.350222)
		(stroke
			(width 0.2)
			(type default)
		)
		(layer "In3.Cu")
	)
	(gr_line
		(start 354.601272 -20.950174)
		(end 354.601272 -22.350222)
		(stroke
			(width 0.2)
			(type default)
		)
		(layer "In3.Cu")
	)
	(gr_arc
		(start 354.601272 -18.750026)
		(mid 355.149912 -19.298666)
		(end 355.698552 -18.750026)
		(stroke
			(width 0.2)
			(type default)
		)
		(layer "In3.Cu")
	)
	(gr_line
		(start 354.601272 -17.349978)
		(end 354.601272 -18.750026)
		(stroke
			(width 0.2)
			(type default)
		)
		(layer "In3.Cu")
	)
	(gr_line
		(start 355.698552 -22.350222)
		(end 355.698552 -20.950428)
		(stroke
			(width 0.2)
			(type default)
		)
		(layer "In3.Cu")
	)
	(gr_arc
		(start 355.698552 -20.950428)
		(mid 355.150039 -20.401534)
		(end 354.601272 -20.950174)
		(stroke
			(width 0.2)
			(type default)
		)
		(layer "In3.Cu")
	)
	(gr_line
		(start 355.698552 -18.750026)
		(end 355.698552 -17.350232)
		(stroke
			(width 0.2)
			(type default)
		)
		(layer "In3.Cu")
	)
	(gr_arc
		(start 355.698552 -17.350232)
		(mid 355.150039 -16.801338)
		(end 354.601272 -17.349978)
		(stroke
			(width 0.2)
			(type default)
		)
		(layer "In3.Cu")
	)
	(gr_arc
		(start 355.903022 -48.321468)
		(mid 356.289102 -48.707548)
		(end 356.675182 -48.321468)
		(stroke
			(width 0.2)
			(type default)
		)
		(layer "In3.Cu")
	)
	(gr_line
		(start 355.903022 -47.178468)
		(end 355.903022 -48.321468)
		(stroke
			(width 0.2)
			(type default)
		)
		(layer "In3.Cu")
	)
	(gr_arc
		(start 355.908102 -278.321516)
		(mid 356.289102 -278.702516)
		(end 356.670102 -278.321516)
		(stroke
			(width 0.2)
			(type default)
		)
		(layer "In3.Cu")
	)
	(gr_line
		(start 355.908102 -277.178516)
		(end 355.908102 -278.321516)
		(stroke
			(width 0.2)
			(type default)
		)
		(layer "In3.Cu")
	)
	(gr_arc
		(start 355.908102 -163.321492)
		(mid 356.289102 -163.702492)
		(end 356.670102 -163.321492)
		(stroke
			(width 0.2)
			(type default)
		)
		(layer "In3.Cu")
	)
	(gr_line
		(start 355.908102 -162.178492)
		(end 355.908102 -163.321492)
		(stroke
			(width 0.2)
			(type default)
		)
		(layer "In3.Cu")
	)
	(gr_arc
		(start 356.40137 -23.35022)
		(mid 356.95001 -23.89886)
		(end 357.49865 -23.35022)
		(stroke
			(width 0.2)
			(type default)
		)
		(layer "In3.Cu")
	)
	(gr_line
		(start 356.40137 -21.950172)
		(end 356.40137 -23.35022)
		(stroke
			(width 0.2)
			(type default)
		)
		(layer "In3.Cu")
	)
	(gr_arc
		(start 356.40137 -19.750024)
		(mid 356.95001 -20.298664)
		(end 357.49865 -19.750024)
		(stroke
			(width 0.2)
			(type default)
		)
		(layer "In3.Cu")
	)
	(gr_line
		(start 356.40137 -18.35023)
		(end 356.40137 -19.750024)
		(stroke
			(width 0.2)
			(type default)
		)
		(layer "In3.Cu")
	)
	(gr_line
		(start 356.670102 -278.321516)
		(end 356.670102 -277.17877)
		(stroke
			(width 0.2)
			(type default)
		)
		(layer "In3.Cu")
	)
	(gr_arc
		(start 356.670102 -277.17877)
		(mid 356.289229 -276.797516)
		(end 355.908102 -277.178516)
		(stroke
			(width 0.2)
			(type default)
		)
		(layer "In3.Cu")
	)
	(gr_line
		(start 356.670102 -163.321492)
		(end 356.670102 -162.178746)
		(stroke
			(width 0.2)
			(type default)
		)
		(layer "In3.Cu")
	)
	(gr_arc
		(start 356.670102 -162.178746)
		(mid 356.289229 -161.797492)
		(end 355.908102 -162.178492)
		(stroke
			(width 0.2)
			(type default)
		)
		(layer "In3.Cu")
	)
	(gr_line
		(start 356.675182 -48.321468)
		(end 356.675182 -47.178722)
		(stroke
			(width 0.2)
			(type default)
		)
		(layer "In3.Cu")
	)
	(gr_arc
		(start 356.675182 -47.178722)
		(mid 356.289229 -46.792388)
		(end 355.903022 -47.178468)
		(stroke
			(width 0.2)
			(type default)
		)
		(layer "In3.Cu")
	)
	(gr_line
		(start 357.49865 -23.35022)
		(end 357.49865 -21.950426)
		(stroke
			(width 0.2)
			(type default)
		)
		(layer "In3.Cu")
	)
	(gr_arc
		(start 357.49865 -21.950426)
		(mid 356.950137 -21.401532)
		(end 356.40137 -21.950172)
		(stroke
			(width 0.2)
			(type default)
		)
		(layer "In3.Cu")
	)
	(gr_line
		(start 357.49865 -19.750024)
		(end 357.49865 -18.350484)
		(stroke
			(width 0.2)
			(type default)
		)
		(layer "In3.Cu")
	)
	(gr_arc
		(start 357.49865 -18.350484)
		(mid 356.950137 -17.80159)
		(end 356.40137 -18.35023)
		(stroke
			(width 0.2)
			(type default)
		)
		(layer "In3.Cu")
	)
	(gr_arc
		(start 358.201468 -22.350222)
		(mid 358.750108 -22.898862)
		(end 359.298748 -22.350222)
		(stroke
			(width 0.2)
			(type default)
		)
		(layer "In3.Cu")
	)
	(gr_line
		(start 358.201468 -20.950174)
		(end 358.201468 -22.350222)
		(stroke
			(width 0.2)
			(type default)
		)
		(layer "In3.Cu")
	)
	(gr_arc
		(start 358.201468 -18.750026)
		(mid 358.750108 -19.298666)
		(end 359.298748 -18.750026)
		(stroke
			(width 0.2)
			(type default)
		)
		(layer "In3.Cu")
	)
	(gr_line
		(start 358.201468 -17.349978)
		(end 358.201468 -18.750026)
		(stroke
			(width 0.2)
			(type default)
		)
		(layer "In3.Cu")
	)
	(gr_line
		(start 359.298748 -22.350222)
		(end 359.298748 -20.950428)
		(stroke
			(width 0.2)
			(type default)
		)
		(layer "In3.Cu")
	)
	(gr_arc
		(start 359.298748 -20.950428)
		(mid 358.750235 -20.401534)
		(end 358.201468 -20.950174)
		(stroke
			(width 0.2)
			(type default)
		)
		(layer "In3.Cu")
	)
	(gr_line
		(start 359.298748 -18.750026)
		(end 359.298748 -17.350232)
		(stroke
			(width 0.2)
			(type default)
		)
		(layer "In3.Cu")
	)
	(gr_arc
		(start 359.298748 -17.350232)
		(mid 358.750235 -16.801338)
		(end 358.201468 -17.349978)
		(stroke
			(width 0.2)
			(type default)
		)
		(layer "In3.Cu")
	)
	(gr_arc
		(start 360.001312 -23.35022)
		(mid 360.549952 -23.89886)
		(end 361.098592 -23.35022)
		(stroke
			(width 0.2)
			(type default)
		)
		(layer "In3.Cu")
	)
	(gr_line
		(start 360.001312 -21.950172)
		(end 360.001312 -23.35022)
		(stroke
			(width 0.2)
			(type default)
		)
		(layer "In3.Cu")
	)
	(gr_arc
		(start 360.001312 -19.750024)
		(mid 360.549952 -20.298664)
		(end 361.098592 -19.750024)
		(stroke
			(width 0.2)
			(type default)
		)
		(layer "In3.Cu")
	)
	(gr_line
		(start 360.001312 -18.35023)
		(end 360.001312 -19.750024)
		(stroke
			(width 0.2)
			(type default)
		)
		(layer "In3.Cu")
	)
	(gr_line
		(start 361.098592 -23.35022)
		(end 361.098592 -21.950426)
		(stroke
			(width 0.2)
			(type default)
		)
		(layer "In3.Cu")
	)
	(gr_arc
		(start 361.098592 -21.950426)
		(mid 360.550079 -21.401532)
		(end 360.001312 -21.950172)
		(stroke
			(width 0.2)
			(type default)
		)
		(layer "In3.Cu")
	)
	(gr_line
		(start 361.098592 -19.750024)
		(end 361.098592 -18.350484)
		(stroke
			(width 0.2)
			(type default)
		)
		(layer "In3.Cu")
	)
	(gr_arc
		(start 361.098592 -18.350484)
		(mid 360.550079 -17.80159)
		(end 360.001312 -18.35023)
		(stroke
			(width 0.2)
			(type default)
		)
		(layer "In3.Cu")
	)
	(gr_arc
		(start 361.80141 -29.550106)
		(mid 362.35005 -30.098746)
		(end 362.89869 -29.550106)
		(stroke
			(width 0.2)
			(type default)
		)
		(layer "In3.Cu")
	)
	(gr_line
		(start 361.80141 -28.150058)
		(end 361.80141 -29.550106)
		(stroke
			(width 0.2)
			(type default)
		)
		(layer "In3.Cu")
	)
	(gr_arc
		(start 361.80141 -22.350222)
		(mid 362.35005 -22.898862)
		(end 362.89869 -22.350222)
		(stroke
			(width 0.2)
			(type default)
		)
		(layer "In3.Cu")
	)
	(gr_line
		(start 361.80141 -20.950174)
		(end 361.80141 -22.350222)
		(stroke
			(width 0.2)
			(type default)
		)
		(layer "In3.Cu")
	)
	(gr_arc
		(start 361.80141 -18.750026)
		(mid 362.35005 -19.298666)
		(end 362.89869 -18.750026)
		(stroke
			(width 0.2)
			(type default)
		)
		(layer "In3.Cu")
	)
	(gr_line
		(start 361.80141 -17.349978)
		(end 361.80141 -18.750026)
		(stroke
			(width 0.2)
			(type default)
		)
		(layer "In3.Cu")
	)
	(gr_line
		(start 362.89869 -29.550106)
		(end 362.89869 -28.150312)
		(stroke
			(width 0.2)
			(type default)
		)
		(layer "In3.Cu")
	)
	(gr_arc
		(start 362.89869 -28.150312)
		(mid 362.350177 -27.601418)
		(end 361.80141 -28.150058)
		(stroke
			(width 0.2)
			(type default)
		)
		(layer "In3.Cu")
	)
	(gr_line
		(start 362.89869 -22.350222)
		(end 362.89869 -20.950428)
		(stroke
			(width 0.2)
			(type default)
		)
		(layer "In3.Cu")
	)
	(gr_arc
		(start 362.89869 -20.950428)
		(mid 362.350177 -20.401534)
		(end 361.80141 -20.950174)
		(stroke
			(width 0.2)
			(type default)
		)
		(layer "In3.Cu")
	)
	(gr_line
		(start 362.89869 -18.750026)
		(end 362.89869 -17.350232)
		(stroke
			(width 0.2)
			(type default)
		)
		(layer "In3.Cu")
	)
	(gr_arc
		(start 362.89869 -17.350232)
		(mid 362.350177 -16.801338)
		(end 361.80141 -17.349978)
		(stroke
			(width 0.2)
			(type default)
		)
		(layer "In3.Cu")
	)
	(gr_arc
		(start 363.601254 -23.35022)
		(mid 364.149894 -23.89886)
		(end 364.698534 -23.35022)
		(stroke
			(width 0.2)
			(type default)
		)
		(layer "In3.Cu")
	)
	(gr_line
		(start 363.601254 -21.950172)
		(end 363.601254 -23.35022)
		(stroke
			(width 0.2)
			(type default)
		)
		(layer "In3.Cu")
	)
	(gr_arc
		(start 363.601254 -19.750024)
		(mid 364.149894 -20.298664)
		(end 364.698534 -19.750024)
		(stroke
			(width 0.2)
			(type default)
		)
		(layer "In3.Cu")
	)
	(gr_line
		(start 363.601254 -18.35023)
		(end 363.601254 -19.750024)
		(stroke
			(width 0.2)
			(type default)
		)
		(layer "In3.Cu")
	)
	(gr_line
		(start 364.698534 -23.35022)
		(end 364.698534 -21.950426)
		(stroke
			(width 0.2)
			(type default)
		)
		(layer "In3.Cu")
	)
	(gr_arc
		(start 364.698534 -21.950426)
		(mid 364.150021 -21.401532)
		(end 363.601254 -21.950172)
		(stroke
			(width 0.2)
			(type default)
		)
		(layer "In3.Cu")
	)
	(gr_line
		(start 364.698534 -19.750024)
		(end 364.698534 -18.350484)
		(stroke
			(width 0.2)
			(type default)
		)
		(layer "In3.Cu")
	)
	(gr_arc
		(start 364.698534 -18.350484)
		(mid 364.150021 -17.80159)
		(end 363.601254 -18.35023)
		(stroke
			(width 0.2)
			(type default)
		)
		(layer "In3.Cu")
	)
	(gr_arc
		(start 365.401352 -22.350222)
		(mid 365.949992 -22.898862)
		(end 366.498632 -22.350222)
		(stroke
			(width 0.2)
			(type default)
		)
		(layer "In3.Cu")
	)
	(gr_line
		(start 365.401352 -20.950174)
		(end 365.401352 -22.350222)
		(stroke
			(width 0.2)
			(type default)
		)
		(layer "In3.Cu")
	)
	(gr_arc
		(start 365.401352 -18.750026)
		(mid 365.949992 -19.298666)
		(end 366.498632 -18.750026)
		(stroke
			(width 0.2)
			(type default)
		)
		(layer "In3.Cu")
	)
	(gr_line
		(start 365.401352 -17.349978)
		(end 365.401352 -18.750026)
		(stroke
			(width 0.2)
			(type default)
		)
		(layer "In3.Cu")
	)
	(gr_line
		(start 366.498632 -22.350222)
		(end 366.498632 -20.950428)
		(stroke
			(width 0.2)
			(type default)
		)
		(layer "In3.Cu")
	)
	(gr_arc
		(start 366.498632 -20.950428)
		(mid 365.950119 -20.401534)
		(end 365.401352 -20.950174)
		(stroke
			(width 0.2)
			(type default)
		)
		(layer "In3.Cu")
	)
	(gr_line
		(start 366.498632 -18.750026)
		(end 366.498632 -17.350232)
		(stroke
			(width 0.2)
			(type default)
		)
		(layer "In3.Cu")
	)
	(gr_arc
		(start 366.498632 -17.350232)
		(mid 365.950119 -16.801338)
		(end 365.401352 -17.349978)
		(stroke
			(width 0.2)
			(type default)
		)
		(layer "In3.Cu")
	)
	(gr_arc
		(start 367.19891 -30.54985)
		(mid 367.749963 -31.101284)
		(end 368.30127 -30.550104)
		(stroke
			(width 0.2)
			(type default)
		)
		(layer "In3.Cu")
	)
	(gr_line
		(start 367.19891 -29.150056)
		(end 367.19891 -30.54985)
		(stroke
			(width 0.2)
			(type default)
		)
		(layer "In3.Cu")
	)
	(gr_arc
		(start 367.20145 -23.35022)
		(mid 367.75009 -23.89886)
		(end 368.29873 -23.35022)
		(stroke
			(width 0.2)
			(type default)
		)
		(layer "In3.Cu")
	)
	(gr_line
		(start 367.20145 -21.950172)
		(end 367.20145 -23.35022)
		(stroke
			(width 0.2)
			(type default)
		)
		(layer "In3.Cu")
	)
	(gr_arc
		(start 367.20145 -19.750024)
		(mid 367.75009 -20.298664)
		(end 368.29873 -19.750024)
		(stroke
			(width 0.2)
			(type default)
		)
		(layer "In3.Cu")
	)
	(gr_line
		(start 367.20145 -18.35023)
		(end 367.20145 -19.750024)
		(stroke
			(width 0.2)
			(type default)
		)
		(layer "In3.Cu")
	)
	(gr_line
		(start 368.29873 -23.35022)
		(end 368.29873 -21.950426)
		(stroke
			(width 0.2)
			(type default)
		)
		(layer "In3.Cu")
	)
	(gr_arc
		(start 368.29873 -21.950426)
		(mid 367.750217 -21.401532)
		(end 367.20145 -21.950172)
		(stroke
			(width 0.2)
			(type default)
		)
		(layer "In3.Cu")
	)
	(gr_line
		(start 368.29873 -19.750024)
		(end 368.29873 -18.350484)
		(stroke
			(width 0.2)
			(type default)
		)
		(layer "In3.Cu")
	)
	(gr_arc
		(start 368.29873 -18.350484)
		(mid 367.750217 -17.80159)
		(end 367.20145 -18.35023)
		(stroke
			(width 0.2)
			(type default)
		)
		(layer "In3.Cu")
	)
	(gr_line
		(start 368.30127 -30.550104)
		(end 368.30127 -29.150056)
		(stroke
			(width 0.2)
			(type default)
		)
		(layer "In3.Cu")
	)
	(gr_arc
		(start 368.30127 -29.150056)
		(mid 367.75009 -28.598876)
		(end 367.19891 -29.150056)
		(stroke
			(width 0.2)
			(type default)
		)
		(layer "In3.Cu")
	)
	(gr_arc
		(start 376.201432 -22.350222)
		(mid 376.750072 -22.898862)
		(end 377.298712 -22.350222)
		(stroke
			(width 0.2)
			(type default)
		)
		(layer "In3.Cu")
	)
	(gr_line
		(start 376.201432 -20.950174)
		(end 376.201432 -22.350222)
		(stroke
			(width 0.2)
			(type default)
		)
		(layer "In3.Cu")
	)
	(gr_arc
		(start 376.201432 -18.750026)
		(mid 376.750072 -19.298666)
		(end 377.298712 -18.750026)
		(stroke
			(width 0.2)
			(type default)
		)
		(layer "In3.Cu")
	)
	(gr_line
		(start 376.201432 -17.349978)
		(end 376.201432 -18.750026)
		(stroke
			(width 0.2)
			(type default)
		)
		(layer "In3.Cu")
	)
	(gr_line
		(start 377.298712 -22.350222)
		(end 377.298712 -20.950428)
		(stroke
			(width 0.2)
			(type default)
		)
		(layer "In3.Cu")
	)
	(gr_arc
		(start 377.298712 -20.950428)
		(mid 376.750199 -20.401534)
		(end 376.201432 -20.950174)
		(stroke
			(width 0.2)
			(type default)
		)
		(layer "In3.Cu")
	)
	(gr_line
		(start 377.298712 -18.750026)
		(end 377.298712 -17.350232)
		(stroke
			(width 0.2)
			(type default)
		)
		(layer "In3.Cu")
	)
	(gr_arc
		(start 377.298712 -17.350232)
		(mid 376.750199 -16.801338)
		(end 376.201432 -17.349978)
		(stroke
			(width 0.2)
			(type default)
		)
		(layer "In3.Cu")
	)
	(gr_arc
		(start 378.001276 -23.35022)
		(mid 378.549916 -23.89886)
		(end 379.098556 -23.35022)
		(stroke
			(width 0.2)
			(type default)
		)
		(layer "In3.Cu")
	)
	(gr_line
		(start 378.001276 -21.950172)
		(end 378.001276 -23.35022)
		(stroke
			(width 0.2)
			(type default)
		)
		(layer "In3.Cu")
	)
	(gr_arc
		(start 378.001276 -19.750024)
		(mid 378.549916 -20.298664)
		(end 379.098556 -19.750024)
		(stroke
			(width 0.2)
			(type default)
		)
		(layer "In3.Cu")
	)
	(gr_line
		(start 378.001276 -18.35023)
		(end 378.001276 -19.750024)
		(stroke
			(width 0.2)
			(type default)
		)
		(layer "In3.Cu")
	)
	(gr_line
		(start 379.098556 -23.35022)
		(end 379.098556 -21.950426)
		(stroke
			(width 0.2)
			(type default)
		)
		(layer "In3.Cu")
	)
	(gr_arc
		(start 379.098556 -21.950426)
		(mid 378.550043 -21.401532)
		(end 378.001276 -21.950172)
		(stroke
			(width 0.2)
			(type default)
		)
		(layer "In3.Cu")
	)
	(gr_line
		(start 379.098556 -19.750024)
		(end 379.098556 -18.350484)
		(stroke
			(width 0.2)
			(type default)
		)
		(layer "In3.Cu")
	)
	(gr_arc
		(start 379.098556 -18.350484)
		(mid 378.550043 -17.80159)
		(end 378.001276 -18.35023)
		(stroke
			(width 0.2)
			(type default)
		)
		(layer "In3.Cu")
	)
	(gr_arc
		(start 379.801374 -22.350222)
		(mid 380.350014 -22.898862)
		(end 380.898654 -22.350222)
		(stroke
			(width 0.2)
			(type default)
		)
		(layer "In3.Cu")
	)
	(gr_line
		(start 379.801374 -20.950174)
		(end 379.801374 -22.350222)
		(stroke
			(width 0.2)
			(type default)
		)
		(layer "In3.Cu")
	)
	(gr_arc
		(start 379.801374 -18.750026)
		(mid 380.350014 -19.298666)
		(end 380.898654 -18.750026)
		(stroke
			(width 0.2)
			(type default)
		)
		(layer "In3.Cu")
	)
	(gr_line
		(start 379.801374 -17.349978)
		(end 379.801374 -18.750026)
		(stroke
			(width 0.2)
			(type default)
		)
		(layer "In3.Cu")
	)
	(gr_line
		(start 380.898654 -22.350222)
		(end 380.898654 -20.950428)
		(stroke
			(width 0.2)
			(type default)
		)
		(layer "In3.Cu")
	)
	(gr_arc
		(start 380.898654 -20.950428)
		(mid 380.350141 -20.401534)
		(end 379.801374 -20.950174)
		(stroke
			(width 0.2)
			(type default)
		)
		(layer "In3.Cu")
	)
	(gr_line
		(start 380.898654 -18.750026)
		(end 380.898654 -17.350232)
		(stroke
			(width 0.2)
			(type default)
		)
		(layer "In3.Cu")
	)
	(gr_arc
		(start 380.898654 -17.350232)
		(mid 380.350141 -16.801338)
		(end 379.801374 -17.349978)
		(stroke
			(width 0.2)
			(type default)
		)
		(layer "In3.Cu")
	)
	(gr_arc
		(start 381.598932 -30.550104)
		(mid 382.150112 -31.101284)
		(end 382.701292 -30.550104)
		(stroke
			(width 0.2)
			(type default)
		)
		(layer "In3.Cu")
	)
	(gr_line
		(start 381.598932 -29.150056)
		(end 381.598932 -30.550104)
		(stroke
			(width 0.2)
			(type default)
		)
		(layer "In3.Cu")
	)
	(gr_arc
		(start 381.601472 -23.35022)
		(mid 382.150112 -23.89886)
		(end 382.698752 -23.35022)
		(stroke
			(width 0.2)
			(type default)
		)
		(layer "In3.Cu")
	)
	(gr_line
		(start 381.601472 -21.950172)
		(end 381.601472 -23.35022)
		(stroke
			(width 0.2)
			(type default)
		)
		(layer "In3.Cu")
	)
	(gr_arc
		(start 381.601472 -19.750024)
		(mid 382.150112 -20.298664)
		(end 382.698752 -19.750024)
		(stroke
			(width 0.2)
			(type default)
		)
		(layer "In3.Cu")
	)
	(gr_line
		(start 381.601472 -18.35023)
		(end 381.601472 -19.750024)
		(stroke
			(width 0.2)
			(type default)
		)
		(layer "In3.Cu")
	)
	(gr_line
		(start 382.698752 -23.35022)
		(end 382.698752 -21.950426)
		(stroke
			(width 0.2)
			(type default)
		)
		(layer "In3.Cu")
	)
	(gr_arc
		(start 382.698752 -21.950426)
		(mid 382.150239 -21.401532)
		(end 381.601472 -21.950172)
		(stroke
			(width 0.2)
			(type default)
		)
		(layer "In3.Cu")
	)
	(gr_line
		(start 382.698752 -19.750024)
		(end 382.698752 -18.350484)
		(stroke
			(width 0.2)
			(type default)
		)
		(layer "In3.Cu")
	)
	(gr_arc
		(start 382.698752 -18.350484)
		(mid 382.150239 -17.80159)
		(end 381.601472 -18.35023)
		(stroke
			(width 0.2)
			(type default)
		)
		(layer "In3.Cu")
	)
	(gr_line
		(start 382.701292 -30.550104)
		(end 382.701292 -29.15031)
		(stroke
			(width 0.2)
			(type default)
		)
		(layer "In3.Cu")
	)
	(gr_arc
		(start 382.701292 -29.15031)
		(mid 382.150239 -28.598876)
		(end 381.598932 -29.150056)
		(stroke
			(width 0.2)
			(type default)
		)
		(layer "In3.Cu")
	)
	(gr_arc
		(start 382.70815 -274.511262)
		(mid 383.089023 -274.892516)
		(end 383.47015 -274.511516)
		(stroke
			(width 0.2)
			(type default)
		)
		(layer "In3.Cu")
	)
	(gr_line
		(start 382.70815 -273.368516)
		(end 382.70815 -274.511262)
		(stroke
			(width 0.2)
			(type default)
		)
		(layer "In3.Cu")
	)
	(gr_arc
		(start 382.70815 -159.511238)
		(mid 383.089023 -159.892492)
		(end 383.47015 -159.511492)
		(stroke
			(width 0.2)
			(type default)
		)
		(layer "In3.Cu")
	)
	(gr_line
		(start 382.70815 -158.368492)
		(end 382.70815 -159.511238)
		(stroke
			(width 0.2)
			(type default)
		)
		(layer "In3.Cu")
	)
	(gr_line
		(start 382.7653 -46.5328)
		(end 383.908046 -46.5328)
		(stroke
			(width 0.2)
			(type default)
		)
		(layer "In3.Cu")
	)
	(gr_arc
		(start 382.7653 -45.7708)
		(mid 382.3843 -46.1518)
		(end 382.7653 -46.5328)
		(stroke
			(width 0.2)
			(type default)
		)
		(layer "In3.Cu")
	)
	(gr_arc
		(start 383.401316 -22.350222)
		(mid 383.949956 -22.898862)
		(end 384.498596 -22.350222)
		(stroke
			(width 0.2)
			(type default)
		)
		(layer "In3.Cu")
	)
	(gr_line
		(start 383.401316 -20.950174)
		(end 383.401316 -22.350222)
		(stroke
			(width 0.2)
			(type default)
		)
		(layer "In3.Cu")
	)
	(gr_arc
		(start 383.401316 -18.750026)
		(mid 383.949956 -19.298666)
		(end 384.498596 -18.750026)
		(stroke
			(width 0.2)
			(type default)
		)
		(layer "In3.Cu")
	)
	(gr_line
		(start 383.401316 -17.349978)
		(end 383.401316 -18.750026)
		(stroke
			(width 0.2)
			(type default)
		)
		(layer "In3.Cu")
	)
	(gr_line
		(start 383.47015 -274.511516)
		(end 383.47015 -273.368516)
		(stroke
			(width 0.2)
			(type default)
		)
		(layer "In3.Cu")
	)
	(gr_arc
		(start 383.47015 -273.368516)
		(mid 383.08915 -272.987516)
		(end 382.70815 -273.368516)
		(stroke
			(width 0.2)
			(type default)
		)
		(layer "In3.Cu")
	)
	(gr_line
		(start 383.47015 -159.511492)
		(end 383.47015 -158.368492)
		(stroke
			(width 0.2)
			(type default)
		)
		(layer "In3.Cu")
	)
	(gr_arc
		(start 383.47015 -158.368492)
		(mid 383.08915 -157.987492)
		(end 382.70815 -158.368492)
		(stroke
			(width 0.2)
			(type default)
		)
		(layer "In3.Cu")
	)
	(gr_arc
		(start 383.908046 -46.5328)
		(mid 384.2893 -46.151927)
		(end 383.9083 -45.7708)
		(stroke
			(width 0.2)
			(type default)
		)
		(layer "In3.Cu")
	)
	(gr_line
		(start 383.9083 -45.7708)
		(end 382.7653 -45.7708)
		(stroke
			(width 0.2)
			(type default)
		)
		(layer "In3.Cu")
	)
	(gr_line
		(start 384.498596 -22.350222)
		(end 384.498596 -20.950428)
		(stroke
			(width 0.2)
			(type default)
		)
		(layer "In3.Cu")
	)
	(gr_arc
		(start 384.498596 -20.950428)
		(mid 383.950083 -20.401534)
		(end 383.401316 -20.950174)
		(stroke
			(width 0.2)
			(type default)
		)
		(layer "In3.Cu")
	)
	(gr_line
		(start 384.498596 -18.750026)
		(end 384.498596 -17.350232)
		(stroke
			(width 0.2)
			(type default)
		)
		(layer "In3.Cu")
	)
	(gr_arc
		(start 384.498596 -17.350232)
		(mid 383.950083 -16.801338)
		(end 383.401316 -17.349978)
		(stroke
			(width 0.2)
			(type default)
		)
		(layer "In3.Cu")
	)
	(gr_arc
		(start 385.201414 -23.35022)
		(mid 385.750054 -23.89886)
		(end 386.298694 -23.35022)
		(stroke
			(width 0.2)
			(type default)
		)
		(layer "In3.Cu")
	)
	(gr_line
		(start 385.201414 -21.950172)
		(end 385.201414 -23.35022)
		(stroke
			(width 0.2)
			(type default)
		)
		(layer "In3.Cu")
	)
	(gr_arc
		(start 385.201414 -19.750024)
		(mid 385.750054 -20.298664)
		(end 386.298694 -19.750024)
		(stroke
			(width 0.2)
			(type default)
		)
		(layer "In3.Cu")
	)
	(gr_line
		(start 385.201414 -18.35023)
		(end 385.201414 -19.750024)
		(stroke
			(width 0.2)
			(type default)
		)
		(layer "In3.Cu")
	)
	(gr_line
		(start 386.298694 -23.35022)
		(end 386.298694 -21.950426)
		(stroke
			(width 0.2)
			(type default)
		)
		(layer "In3.Cu")
	)
	(gr_arc
		(start 386.298694 -21.950426)
		(mid 385.750181 -21.401532)
		(end 385.201414 -21.950172)
		(stroke
			(width 0.2)
			(type default)
		)
		(layer "In3.Cu")
	)
	(gr_line
		(start 386.298694 -19.750024)
		(end 386.298694 -18.350484)
		(stroke
			(width 0.2)
			(type default)
		)
		(layer "In3.Cu")
	)
	(gr_arc
		(start 386.298694 -18.350484)
		(mid 385.750181 -17.80159)
		(end 385.201414 -18.35023)
		(stroke
			(width 0.2)
			(type default)
		)
		(layer "In3.Cu")
	)
	(gr_arc
		(start 387.001258 -22.350222)
		(mid 387.549898 -22.898862)
		(end 388.098538 -22.350222)
		(stroke
			(width 0.2)
			(type default)
		)
		(layer "In3.Cu")
	)
	(gr_line
		(start 387.001258 -20.950174)
		(end 387.001258 -22.350222)
		(stroke
			(width 0.2)
			(type default)
		)
		(layer "In3.Cu")
	)
	(gr_arc
		(start 387.001258 -18.750026)
		(mid 387.549898 -19.298666)
		(end 388.098538 -18.750026)
		(stroke
			(width 0.2)
			(type default)
		)
		(layer "In3.Cu")
	)
	(gr_line
		(start 387.001258 -17.349978)
		(end 387.001258 -18.750026)
		(stroke
			(width 0.2)
			(type default)
		)
		(layer "In3.Cu")
	)
	(gr_arc
		(start 387.45795 -278.321516)
		(mid 387.83895 -278.702516)
		(end 388.21995 -278.321516)
		(stroke
			(width 0.2)
			(type default)
		)
		(layer "In3.Cu")
	)
	(gr_line
		(start 387.45795 -277.178516)
		(end 387.45795 -278.321516)
		(stroke
			(width 0.2)
			(type default)
		)
		(layer "In3.Cu")
	)
	(gr_arc
		(start 387.45795 -163.321492)
		(mid 387.83895 -163.702492)
		(end 388.21995 -163.321492)
		(stroke
			(width 0.2)
			(type default)
		)
		(layer "In3.Cu")
	)
	(gr_line
		(start 387.45795 -162.178492)
		(end 387.45795 -163.321492)
		(stroke
			(width 0.2)
			(type default)
		)
		(layer "In3.Cu")
	)
	(gr_arc
		(start 387.45795 -48.321468)
		(mid 387.83895 -48.702468)
		(end 388.21995 -48.321468)
		(stroke
			(width 0.2)
			(type default)
		)
		(layer "In3.Cu")
	)
	(gr_line
		(start 387.45795 -47.178468)
		(end 387.45795 -48.321468)
		(stroke
			(width 0.2)
			(type default)
		)
		(layer "In3.Cu")
	)
	(gr_line
		(start 388.098538 -22.350222)
		(end 388.098538 -20.950428)
		(stroke
			(width 0.2)
			(type default)
		)
		(layer "In3.Cu")
	)
	(gr_arc
		(start 388.098538 -20.950428)
		(mid 387.550025 -20.401534)
		(end 387.001258 -20.950174)
		(stroke
			(width 0.2)
			(type default)
		)
		(layer "In3.Cu")
	)
	(gr_line
		(start 388.098538 -18.750026)
		(end 388.098538 -17.350232)
		(stroke
			(width 0.2)
			(type default)
		)
		(layer "In3.Cu")
	)
	(gr_arc
		(start 388.098538 -17.350232)
		(mid 387.550025 -16.801338)
		(end 387.001258 -17.349978)
		(stroke
			(width 0.2)
			(type default)
		)
		(layer "In3.Cu")
	)
	(gr_line
		(start 388.21995 -278.321516)
		(end 388.21995 -277.17877)
		(stroke
			(width 0.2)
			(type default)
		)
		(layer "In3.Cu")
	)
	(gr_arc
		(start 388.21995 -277.17877)
		(mid 387.839077 -276.797516)
		(end 387.45795 -277.178516)
		(stroke
			(width 0.2)
			(type default)
		)
		(layer "In3.Cu")
	)
	(gr_line
		(start 388.21995 -163.321492)
		(end 388.21995 -162.178746)
		(stroke
			(width 0.2)
			(type default)
		)
		(layer "In3.Cu")
	)
	(gr_arc
		(start 388.21995 -162.178746)
		(mid 387.839077 -161.797492)
		(end 387.45795 -162.178492)
		(stroke
			(width 0.2)
			(type default)
		)
		(layer "In3.Cu")
	)
	(gr_line
		(start 388.21995 -48.321468)
		(end 388.21995 -47.178722)
		(stroke
			(width 0.2)
			(type default)
		)
		(layer "In3.Cu")
	)
	(gr_arc
		(start 388.21995 -47.178722)
		(mid 387.839077 -46.797468)
		(end 387.45795 -47.178468)
		(stroke
			(width 0.2)
			(type default)
		)
		(layer "In3.Cu")
	)
	(gr_arc
		(start 388.801356 -30.550104)
		(mid 389.349996 -31.098744)
		(end 389.898636 -30.550104)
		(stroke
			(width 0.2)
			(type default)
		)
		(layer "In3.Cu")
	)
	(gr_line
		(start 388.801356 -29.150056)
		(end 388.801356 -30.550104)
		(stroke
			(width 0.2)
			(type default)
		)
		(layer "In3.Cu")
	)
	(gr_arc
		(start 388.801356 -23.35022)
		(mid 389.349996 -23.89886)
		(end 389.898636 -23.35022)
		(stroke
			(width 0.2)
			(type default)
		)
		(layer "In3.Cu")
	)
	(gr_line
		(start 388.801356 -21.950172)
		(end 388.801356 -23.35022)
		(stroke
			(width 0.2)
			(type default)
		)
		(layer "In3.Cu")
	)
	(gr_arc
		(start 388.801356 -19.750024)
		(mid 389.349996 -20.298664)
		(end 389.898636 -19.750024)
		(stroke
			(width 0.2)
			(type default)
		)
		(layer "In3.Cu")
	)
	(gr_line
		(start 388.801356 -18.35023)
		(end 388.801356 -19.750024)
		(stroke
			(width 0.2)
			(type default)
		)
		(layer "In3.Cu")
	)
	(gr_line
		(start 389.898636 -30.550104)
		(end 389.898636 -29.15031)
		(stroke
			(width 0.2)
			(type default)
		)
		(layer "In3.Cu")
	)
	(gr_arc
		(start 389.898636 -29.15031)
		(mid 389.350123 -28.601416)
		(end 388.801356 -29.150056)
		(stroke
			(width 0.2)
			(type default)
		)
		(layer "In3.Cu")
	)
	(gr_line
		(start 389.898636 -23.35022)
		(end 389.898636 -21.950426)
		(stroke
			(width 0.2)
			(type default)
		)
		(layer "In3.Cu")
	)
	(gr_arc
		(start 389.898636 -21.950426)
		(mid 389.350123 -21.401532)
		(end 388.801356 -21.950172)
		(stroke
			(width 0.2)
			(type default)
		)
		(layer "In3.Cu")
	)
	(gr_line
		(start 389.898636 -19.750024)
		(end 389.898636 -18.350484)
		(stroke
			(width 0.2)
			(type default)
		)
		(layer "In3.Cu")
	)
	(gr_arc
		(start 389.898636 -18.350484)
		(mid 389.350123 -17.80159)
		(end 388.801356 -18.35023)
		(stroke
			(width 0.2)
			(type default)
		)
		(layer "In3.Cu")
	)
	(gr_arc
		(start 394.999972 -14.99997)
		(mid 395.707077 -14.707077)
		(end 395.99997 -13.999972)
		(stroke
			(width 1.524)
			(type default)
		)
		(layer "In3.Cu")
	)
	(gr_line
		(start 395.99997 -13.999972)
		(end 395.99997 -0.999998)
		(stroke
			(width 1.524)
			(type default)
		)
		(layer "In3.Cu")
	)
	(gr_arc
		(start 396.999968 0)
		(mid 396.292883 -0.292904)
		(end 395.99997 -0.999998)
		(stroke
			(width 1.524)
			(type default)
		)
		(layer "In3.Cu")
	)
	(gr_line
		(start 396.999968 0)
		(end 490.450124 0)
		(stroke
			(width 1.524)
			(type default)
		)
		(layer "In3.Cu")
	)
	(gr_arc
		(start 414.258252 -274.511262)
		(mid 414.639125 -274.892516)
		(end 415.020252 -274.511516)
		(stroke
			(width 0.2)
			(type default)
		)
		(layer "In3.Cu")
	)
	(gr_line
		(start 414.258252 -273.368516)
		(end 414.258252 -274.511262)
		(stroke
			(width 0.2)
			(type default)
		)
		(layer "In3.Cu")
	)
	(gr_arc
		(start 414.258252 -159.511238)
		(mid 414.639125 -159.892492)
		(end 415.020252 -159.511492)
		(stroke
			(width 0.2)
			(type default)
		)
		(layer "In3.Cu")
	)
	(gr_line
		(start 414.258252 -158.368492)
		(end 414.258252 -159.511238)
		(stroke
			(width 0.2)
			(type default)
		)
		(layer "In3.Cu")
	)
	(gr_arc
		(start 414.258252 -44.511214)
		(mid 414.639125 -44.892468)
		(end 415.020252 -44.511468)
		(stroke
			(width 0.2)
			(type default)
		)
		(layer "In3.Cu")
	)
	(gr_line
		(start 414.258252 -43.368468)
		(end 414.258252 -44.511214)
		(stroke
			(width 0.2)
			(type default)
		)
		(layer "In3.Cu")
	)
	(gr_line
		(start 415.020252 -274.511516)
		(end 415.020252 -273.368516)
		(stroke
			(width 0.2)
			(type default)
		)
		(layer "In3.Cu")
	)
	(gr_arc
		(start 415.020252 -273.368516)
		(mid 414.639252 -272.987516)
		(end 414.258252 -273.368516)
		(stroke
			(width 0.2)
			(type default)
		)
		(layer "In3.Cu")
	)
	(gr_line
		(start 415.020252 -159.511492)
		(end 415.020252 -158.368492)
		(stroke
			(width 0.2)
			(type default)
		)
		(layer "In3.Cu")
	)
	(gr_arc
		(start 415.020252 -158.368492)
		(mid 414.639252 -157.987492)
		(end 414.258252 -158.368492)
		(stroke
			(width 0.2)
			(type default)
		)
		(layer "In3.Cu")
	)
	(gr_line
		(start 415.020252 -44.511468)
		(end 415.020252 -43.368468)
		(stroke
			(width 0.2)
			(type default)
		)
		(layer "In3.Cu")
	)
	(gr_arc
		(start 415.020252 -43.368468)
		(mid 414.639252 -42.987468)
		(end 414.258252 -43.368468)
		(stroke
			(width 0.2)
			(type default)
		)
		(layer "In3.Cu")
	)
	(gr_arc
		(start 419.008052 -278.321516)
		(mid 419.389052 -278.702516)
		(end 419.770052 -278.321516)
		(stroke
			(width 0.2)
			(type default)
		)
		(layer "In3.Cu")
	)
	(gr_line
		(start 419.008052 -277.178516)
		(end 419.008052 -278.321516)
		(stroke
			(width 0.2)
			(type default)
		)
		(layer "In3.Cu")
	)
	(gr_arc
		(start 419.008052 -163.321492)
		(mid 419.389052 -163.702492)
		(end 419.770052 -163.321492)
		(stroke
			(width 0.2)
			(type default)
		)
		(layer "In3.Cu")
	)
	(gr_line
		(start 419.008052 -162.178492)
		(end 419.008052 -163.321492)
		(stroke
			(width 0.2)
			(type default)
		)
		(layer "In3.Cu")
	)
	(gr_arc
		(start 419.008052 -48.321468)
		(mid 419.389052 -48.702468)
		(end 419.770052 -48.321468)
		(stroke
			(width 0.2)
			(type default)
		)
		(layer "In3.Cu")
	)
	(gr_line
		(start 419.008052 -47.178468)
		(end 419.008052 -48.321468)
		(stroke
			(width 0.2)
			(type default)
		)
		(layer "In3.Cu")
	)
	(gr_line
		(start 419.770052 -278.321516)
		(end 419.770052 -277.17877)
		(stroke
			(width 0.2)
			(type default)
		)
		(layer "In3.Cu")
	)
	(gr_arc
		(start 419.770052 -277.17877)
		(mid 419.389179 -276.797516)
		(end 419.008052 -277.178516)
		(stroke
			(width 0.2)
			(type default)
		)
		(layer "In3.Cu")
	)
	(gr_line
		(start 419.770052 -163.321492)
		(end 419.770052 -162.178746)
		(stroke
			(width 0.2)
			(type default)
		)
		(layer "In3.Cu")
	)
	(gr_arc
		(start 419.770052 -162.178746)
		(mid 419.389179 -161.797492)
		(end 419.008052 -162.178492)
		(stroke
			(width 0.2)
			(type default)
		)
		(layer "In3.Cu")
	)
	(gr_line
		(start 419.770052 -48.321468)
		(end 419.770052 -47.178722)
		(stroke
			(width 0.2)
			(type default)
		)
		(layer "In3.Cu")
	)
	(gr_arc
		(start 419.770052 -47.178722)
		(mid 419.389179 -46.797468)
		(end 419.008052 -47.178468)
		(stroke
			(width 0.2)
			(type default)
		)
		(layer "In3.Cu")
	)
	(gr_arc
		(start 437.8579 -163.321492)
		(mid 438.2389 -163.702492)
		(end 438.6199 -163.321492)
		(stroke
			(width 0.2)
			(type default)
		)
		(layer "In3.Cu")
	)
	(gr_line
		(start 437.8579 -162.178492)
		(end 437.8579 -163.321492)
		(stroke
			(width 0.2)
			(type default)
		)
		(layer "In3.Cu")
	)
	(gr_line
		(start 438.6199 -163.321492)
		(end 438.6199 -162.178746)
		(stroke
			(width 0.2)
			(type default)
		)
		(layer "In3.Cu")
	)
	(gr_arc
		(start 438.6199 -162.178746)
		(mid 438.239027 -161.797492)
		(end 437.8579 -162.178492)
		(stroke
			(width 0.2)
			(type default)
		)
		(layer "In3.Cu")
	)
	(gr_arc
		(start 439.4581 -159.511238)
		(mid 439.838973 -159.892492)
		(end 440.2201 -159.511492)
		(stroke
			(width 0.2)
			(type default)
		)
		(layer "In3.Cu")
	)
	(gr_line
		(start 439.4581 -158.368492)
		(end 439.4581 -159.511238)
		(stroke
			(width 0.2)
			(type default)
		)
		(layer "In3.Cu")
	)
	(gr_line
		(start 440.2201 -159.511492)
		(end 440.2201 -158.368492)
		(stroke
			(width 0.2)
			(type default)
		)
		(layer "In3.Cu")
	)
	(gr_arc
		(start 440.2201 -158.368492)
		(mid 439.8391 -157.987492)
		(end 439.4581 -158.368492)
		(stroke
			(width 0.2)
			(type default)
		)
		(layer "In3.Cu")
	)
	(gr_arc
		(start 445.8081 -274.511262)
		(mid 446.188973 -274.892516)
		(end 446.5701 -274.511516)
		(stroke
			(width 0.2)
			(type default)
		)
		(layer "In3.Cu")
	)
	(gr_line
		(start 445.8081 -273.368516)
		(end 445.8081 -274.511262)
		(stroke
			(width 0.2)
			(type default)
		)
		(layer "In3.Cu")
	)
	(gr_arc
		(start 445.8081 -44.511214)
		(mid 446.188973 -44.892468)
		(end 446.5701 -44.511468)
		(stroke
			(width 0.2)
			(type default)
		)
		(layer "In3.Cu")
	)
	(gr_line
		(start 445.8081 -43.368468)
		(end 445.8081 -44.511214)
		(stroke
			(width 0.2)
			(type default)
		)
		(layer "In3.Cu")
	)
	(gr_line
		(start 446.5701 -274.511516)
		(end 446.5701 -273.368516)
		(stroke
			(width 0.2)
			(type default)
		)
		(layer "In3.Cu")
	)
	(gr_arc
		(start 446.5701 -273.368516)
		(mid 446.1891 -272.987516)
		(end 445.8081 -273.368516)
		(stroke
			(width 0.2)
			(type default)
		)
		(layer "In3.Cu")
	)
	(gr_line
		(start 446.5701 -44.511468)
		(end 446.5701 -43.368468)
		(stroke
			(width 0.2)
			(type default)
		)
		(layer "In3.Cu")
	)
	(gr_arc
		(start 446.5701 -43.368468)
		(mid 446.1891 -42.987468)
		(end 445.8081 -43.368468)
		(stroke
			(width 0.2)
			(type default)
		)
		(layer "In3.Cu")
	)
	(gr_arc
		(start 450.5579 -278.321516)
		(mid 450.9389 -278.702516)
		(end 451.3199 -278.321516)
		(stroke
			(width 0.2)
			(type default)
		)
		(layer "In3.Cu")
	)
	(gr_line
		(start 450.5579 -277.178516)
		(end 450.5579 -278.321516)
		(stroke
			(width 0.2)
			(type default)
		)
		(layer "In3.Cu")
	)
	(gr_arc
		(start 450.5579 -48.321468)
		(mid 450.9389 -48.702468)
		(end 451.3199 -48.321468)
		(stroke
			(width 0.2)
			(type default)
		)
		(layer "In3.Cu")
	)
	(gr_line
		(start 450.5579 -47.178468)
		(end 450.5579 -48.321468)
		(stroke
			(width 0.2)
			(type default)
		)
		(layer "In3.Cu")
	)
	(gr_line
		(start 451.3199 -278.321516)
		(end 451.3199 -277.17877)
		(stroke
			(width 0.2)
			(type default)
		)
		(layer "In3.Cu")
	)
	(gr_arc
		(start 451.3199 -277.17877)
		(mid 450.939027 -276.797516)
		(end 450.5579 -277.178516)
		(stroke
			(width 0.2)
			(type default)
		)
		(layer "In3.Cu")
	)
	(gr_line
		(start 451.3199 -48.321468)
		(end 451.3199 -47.178722)
		(stroke
			(width 0.2)
			(type default)
		)
		(layer "In3.Cu")
	)
	(gr_arc
		(start 451.3199 -47.178722)
		(mid 450.939027 -46.797468)
		(end 450.5579 -47.178468)
		(stroke
			(width 0.2)
			(type default)
		)
		(layer "In3.Cu")
	)
	(gr_arc
		(start 477.358202 -274.511262)
		(mid 477.739075 -274.892516)
		(end 478.120202 -274.511516)
		(stroke
			(width 0.2)
			(type default)
		)
		(layer "In3.Cu")
	)
	(gr_line
		(start 477.358202 -273.368516)
		(end 477.358202 -274.511262)
		(stroke
			(width 0.2)
			(type default)
		)
		(layer "In3.Cu")
	)
	(gr_arc
		(start 477.358202 -159.511238)
		(mid 477.739075 -159.892492)
		(end 478.120202 -159.511492)
		(stroke
			(width 0.2)
			(type default)
		)
		(layer "In3.Cu")
	)
	(gr_line
		(start 477.358202 -158.368492)
		(end 477.358202 -159.511238)
		(stroke
			(width 0.2)
			(type default)
		)
		(layer "In3.Cu")
	)
	(gr_arc
		(start 477.358202 -44.511214)
		(mid 477.739075 -44.892468)
		(end 478.120202 -44.511468)
		(stroke
			(width 0.2)
			(type default)
		)
		(layer "In3.Cu")
	)
	(gr_line
		(start 477.358202 -43.368468)
		(end 477.358202 -44.511214)
		(stroke
			(width 0.2)
			(type default)
		)
		(layer "In3.Cu")
	)
	(gr_line
		(start 478.120202 -274.511516)
		(end 478.120202 -273.368516)
		(stroke
			(width 0.2)
			(type default)
		)
		(layer "In3.Cu")
	)
	(gr_arc
		(start 478.120202 -273.368516)
		(mid 477.739202 -272.987516)
		(end 477.358202 -273.368516)
		(stroke
			(width 0.2)
			(type default)
		)
		(layer "In3.Cu")
	)
	(gr_line
		(start 478.120202 -159.511492)
		(end 478.120202 -158.368492)
		(stroke
			(width 0.2)
			(type default)
		)
		(layer "In3.Cu")
	)
	(gr_arc
		(start 478.120202 -158.368492)
		(mid 477.739202 -157.987492)
		(end 477.358202 -158.368492)
		(stroke
			(width 0.2)
			(type default)
		)
		(layer "In3.Cu")
	)
	(gr_line
		(start 478.120202 -44.511468)
		(end 478.120202 -43.368468)
		(stroke
			(width 0.2)
			(type default)
		)
		(layer "In3.Cu")
	)
	(gr_arc
		(start 478.120202 -43.368468)
		(mid 477.739202 -42.987468)
		(end 477.358202 -43.368468)
		(stroke
			(width 0.2)
			(type default)
		)
		(layer "In3.Cu")
	)
	(gr_arc
		(start 482.108002 -278.321516)
		(mid 482.489002 -278.702516)
		(end 482.870002 -278.321516)
		(stroke
			(width 0.2)
			(type default)
		)
		(layer "In3.Cu")
	)
	(gr_line
		(start 482.108002 -277.178516)
		(end 482.108002 -278.321516)
		(stroke
			(width 0.2)
			(type default)
		)
		(layer "In3.Cu")
	)
	(gr_arc
		(start 482.108002 -163.321492)
		(mid 482.489002 -163.702492)
		(end 482.870002 -163.321492)
		(stroke
			(width 0.2)
			(type default)
		)
		(layer "In3.Cu")
	)
	(gr_line
		(start 482.108002 -162.178492)
		(end 482.108002 -163.321492)
		(stroke
			(width 0.2)
			(type default)
		)
		(layer "In3.Cu")
	)
	(gr_arc
		(start 482.108002 -48.321468)
		(mid 482.489002 -48.702468)
		(end 482.870002 -48.321468)
		(stroke
			(width 0.2)
			(type default)
		)
		(layer "In3.Cu")
	)
	(gr_line
		(start 482.108002 -47.178468)
		(end 482.108002 -48.321468)
		(stroke
			(width 0.2)
			(type default)
		)
		(layer "In3.Cu")
	)
	(gr_line
		(start 482.870002 -278.321516)
		(end 482.870002 -277.17877)
		(stroke
			(width 0.2)
			(type default)
		)
		(layer "In3.Cu")
	)
	(gr_arc
		(start 482.870002 -277.17877)
		(mid 482.489129 -276.797516)
		(end 482.108002 -277.178516)
		(stroke
			(width 0.2)
			(type default)
		)
		(layer "In3.Cu")
	)
	(gr_line
		(start 482.870002 -163.321492)
		(end 482.870002 -162.178746)
		(stroke
			(width 0.2)
			(type default)
		)
		(layer "In3.Cu")
	)
	(gr_arc
		(start 482.870002 -162.178746)
		(mid 482.489129 -161.797492)
		(end 482.108002 -162.178492)
		(stroke
			(width 0.2)
			(type default)
		)
		(layer "In3.Cu")
	)
	(gr_line
		(start 482.870002 -48.321468)
		(end 482.870002 -47.178722)
		(stroke
			(width 0.2)
			(type default)
		)
		(layer "In3.Cu")
	)
	(gr_arc
		(start 482.870002 -47.178722)
		(mid 482.489129 -46.797468)
		(end 482.108002 -47.178468)
		(stroke
			(width 0.2)
			(type default)
		)
		(layer "In3.Cu")
	)
	(gr_line
		(start 490.450124 -349.199962)
		(end 296.69994 -349.199962)
		(stroke
			(width 1.524)
			(type default)
		)
		(layer "In3.Cu")
	)
	(gr_arc
		(start 490.450124 -349.199962)
		(mid 491.157201 -348.907059)
		(end 491.450122 -348.199964)
		(stroke
			(width 1.524)
			(type default)
		)
		(layer "In3.Cu")
	)
	(gr_arc
		(start 491.450122 -0.999998)
		(mid 491.15723 -0.292885)
		(end 490.450124 0)
		(stroke
			(width 1.524)
			(type default)
		)
		(layer "In3.Cu")
	)
	(gr_line
		(start 491.450122 -0.999998)
		(end 491.450122 -348.199964)
		(stroke
			(width 1.524)
			(type default)
		)
		(layer "In3.Cu")
	)
	(gr_line
		(start 0 -348.199964)
		(end 0 -0.999998)
		(stroke
			(width 2.54)
			(type default)
		)
		(layer "In5.Cu")
	)
	(gr_arc
		(start 0 -348.199964)
		(mid 0.292894 -348.907067)
		(end 0.999998 -349.199962)
		(stroke
			(width 2.54)
			(type default)
		)
		(layer "In5.Cu")
	)
	(gr_arc
		(start 0.999998 0)
		(mid 0.292893 -0.292893)
		(end 0 -0.999998)
		(stroke
			(width 2.54)
			(type default)
		)
		(layer "In5.Cu")
	)
	(gr_line
		(start 0.999998 0)
		(end 101.000052 0)
		(stroke
			(width 2.54)
			(type default)
		)
		(layer "In5.Cu")
	)
	(gr_arc
		(start 32.127952 -278.321516)
		(mid 32.508952 -278.702516)
		(end 32.889952 -278.321516)
		(stroke
			(width 0.2)
			(type default)
		)
		(layer "In5.Cu")
	)
	(gr_line
		(start 32.127952 -277.178516)
		(end 32.127952 -278.321516)
		(stroke
			(width 0.2)
			(type default)
		)
		(layer "In5.Cu")
	)
	(gr_arc
		(start 32.127952 -163.321492)
		(mid 32.508952 -163.702492)
		(end 32.889952 -163.321492)
		(stroke
			(width 0.2)
			(type default)
		)
		(layer "In5.Cu")
	)
	(gr_line
		(start 32.127952 -162.178492)
		(end 32.127952 -163.321492)
		(stroke
			(width 0.2)
			(type default)
		)
		(layer "In5.Cu")
	)
	(gr_arc
		(start 32.127952 -48.321468)
		(mid 32.508952 -48.702468)
		(end 32.889952 -48.321468)
		(stroke
			(width 0.2)
			(type default)
		)
		(layer "In5.Cu")
	)
	(gr_line
		(start 32.127952 -47.178468)
		(end 32.127952 -48.321468)
		(stroke
			(width 0.2)
			(type default)
		)
		(layer "In5.Cu")
	)
	(gr_line
		(start 32.889952 -278.321516)
		(end 32.889952 -277.17877)
		(stroke
			(width 0.2)
			(type default)
		)
		(layer "In5.Cu")
	)
	(gr_arc
		(start 32.889952 -277.17877)
		(mid 32.509079 -276.797516)
		(end 32.127952 -277.178516)
		(stroke
			(width 0.2)
			(type default)
		)
		(layer "In5.Cu")
	)
	(gr_line
		(start 32.889952 -163.321492)
		(end 32.889952 -162.178746)
		(stroke
			(width 0.2)
			(type default)
		)
		(layer "In5.Cu")
	)
	(gr_arc
		(start 32.889952 -162.178746)
		(mid 32.509079 -161.797492)
		(end 32.127952 -162.178492)
		(stroke
			(width 0.2)
			(type default)
		)
		(layer "In5.Cu")
	)
	(gr_line
		(start 32.889952 -48.321468)
		(end 32.889952 -47.178722)
		(stroke
			(width 0.2)
			(type default)
		)
		(layer "In5.Cu")
	)
	(gr_arc
		(start 32.889952 -47.178722)
		(mid 32.509079 -46.797468)
		(end 32.127952 -47.178468)
		(stroke
			(width 0.2)
			(type default)
		)
		(layer "In5.Cu")
	)
	(gr_arc
		(start 63.6778 -278.321516)
		(mid 64.0588 -278.702516)
		(end 64.4398 -278.321516)
		(stroke
			(width 0.2)
			(type default)
		)
		(layer "In5.Cu")
	)
	(gr_line
		(start 63.6778 -277.178516)
		(end 63.6778 -278.321516)
		(stroke
			(width 0.2)
			(type default)
		)
		(layer "In5.Cu")
	)
	(gr_arc
		(start 63.6778 -163.321492)
		(mid 64.0588 -163.702492)
		(end 64.4398 -163.321492)
		(stroke
			(width 0.2)
			(type default)
		)
		(layer "In5.Cu")
	)
	(gr_line
		(start 63.6778 -162.178492)
		(end 63.6778 -163.321492)
		(stroke
			(width 0.2)
			(type default)
		)
		(layer "In5.Cu")
	)
	(gr_arc
		(start 63.6778 -48.321468)
		(mid 64.0588 -48.702468)
		(end 64.4398 -48.321468)
		(stroke
			(width 0.2)
			(type default)
		)
		(layer "In5.Cu")
	)
	(gr_line
		(start 63.6778 -47.178468)
		(end 63.6778 -48.321468)
		(stroke
			(width 0.2)
			(type default)
		)
		(layer "In5.Cu")
	)
	(gr_line
		(start 64.4398 -278.321516)
		(end 64.4398 -277.17877)
		(stroke
			(width 0.2)
			(type default)
		)
		(layer "In5.Cu")
	)
	(gr_arc
		(start 64.4398 -277.17877)
		(mid 64.058927 -276.797516)
		(end 63.6778 -277.178516)
		(stroke
			(width 0.2)
			(type default)
		)
		(layer "In5.Cu")
	)
	(gr_line
		(start 64.4398 -163.321492)
		(end 64.4398 -162.178746)
		(stroke
			(width 0.2)
			(type default)
		)
		(layer "In5.Cu")
	)
	(gr_arc
		(start 64.4398 -162.178746)
		(mid 64.058927 -161.797492)
		(end 63.6778 -162.178492)
		(stroke
			(width 0.2)
			(type default)
		)
		(layer "In5.Cu")
	)
	(gr_line
		(start 64.4398 -48.321468)
		(end 64.4398 -47.178722)
		(stroke
			(width 0.2)
			(type default)
		)
		(layer "In5.Cu")
	)
	(gr_arc
		(start 64.4398 -47.178722)
		(mid 64.058927 -46.797468)
		(end 63.6778 -47.178468)
		(stroke
			(width 0.2)
			(type default)
		)
		(layer "In5.Cu")
	)
	(gr_arc
		(start 95.227902 -278.321516)
		(mid 95.608902 -278.702516)
		(end 95.989902 -278.321516)
		(stroke
			(width 0.2)
			(type default)
		)
		(layer "In5.Cu")
	)
	(gr_line
		(start 95.227902 -277.178516)
		(end 95.227902 -278.321516)
		(stroke
			(width 0.2)
			(type default)
		)
		(layer "In5.Cu")
	)
	(gr_arc
		(start 95.227902 -163.321492)
		(mid 95.608902 -163.702492)
		(end 95.989902 -163.321492)
		(stroke
			(width 0.2)
			(type default)
		)
		(layer "In5.Cu")
	)
	(gr_line
		(start 95.227902 -162.178492)
		(end 95.227902 -163.321492)
		(stroke
			(width 0.2)
			(type default)
		)
		(layer "In5.Cu")
	)
	(gr_arc
		(start 95.227902 -48.321468)
		(mid 95.608902 -48.702468)
		(end 95.989902 -48.321468)
		(stroke
			(width 0.2)
			(type default)
		)
		(layer "In5.Cu")
	)
	(gr_line
		(start 95.227902 -47.178468)
		(end 95.227902 -48.321468)
		(stroke
			(width 0.2)
			(type default)
		)
		(layer "In5.Cu")
	)
	(gr_line
		(start 95.989902 -278.321516)
		(end 95.989902 -277.17877)
		(stroke
			(width 0.2)
			(type default)
		)
		(layer "In5.Cu")
	)
	(gr_arc
		(start 95.989902 -277.17877)
		(mid 95.609029 -276.797516)
		(end 95.227902 -277.178516)
		(stroke
			(width 0.2)
			(type default)
		)
		(layer "In5.Cu")
	)
	(gr_line
		(start 95.989902 -163.321492)
		(end 95.989902 -162.178746)
		(stroke
			(width 0.2)
			(type default)
		)
		(layer "In5.Cu")
	)
	(gr_arc
		(start 95.989902 -162.178746)
		(mid 95.609029 -161.797492)
		(end 95.227902 -162.178492)
		(stroke
			(width 0.2)
			(type default)
		)
		(layer "In5.Cu")
	)
	(gr_line
		(start 95.989902 -48.321468)
		(end 95.989902 -47.178722)
		(stroke
			(width 0.2)
			(type default)
		)
		(layer "In5.Cu")
	)
	(gr_arc
		(start 95.989902 -47.178722)
		(mid 95.609029 -46.797468)
		(end 95.227902 -47.178468)
		(stroke
			(width 0.2)
			(type default)
		)
		(layer "In5.Cu")
	)
	(gr_arc
		(start 102.00005 -13.999972)
		(mid 102.292943 -14.707077)
		(end 103.000048 -14.99997)
		(stroke
			(width 2.54)
			(type default)
		)
		(layer "In5.Cu")
	)
	(gr_arc
		(start 102.00005 -0.999998)
		(mid 101.707154 -0.292911)
		(end 101.000052 0)
		(stroke
			(width 2.54)
			(type default)
		)
		(layer "In5.Cu")
	)
	(gr_line
		(start 102.00005 -0.999998)
		(end 102.00005 -13.999972)
		(stroke
			(width 2.54)
			(type default)
		)
		(layer "In5.Cu")
	)
	(gr_line
		(start 103.000048 -14.99997)
		(end 148.999956 -14.99997)
		(stroke
			(width 2.54)
			(type default)
		)
		(layer "In5.Cu")
	)
	(gr_line
		(start 103.205788 -35.438842)
		(end 103.205788 -15.174976)
		(stroke
			(width 0.381)
			(type default)
		)
		(layer "In5.Cu")
	)
	(gr_line
		(start 103.205788 -15.174976)
		(end 104.380792 -13.999972)
		(stroke
			(width 0.381)
			(type default)
		)
		(layer "In5.Cu")
	)
	(gr_line
		(start 103.77551 -36.008564)
		(end 103.205788 -35.438842)
		(stroke
			(width 0.381)
			(type default)
		)
		(layer "In5.Cu")
	)
	(gr_line
		(start 104.380792 -13.999972)
		(end 107.00004 -13.999972)
		(stroke
			(width 0.381)
			(type default)
		)
		(layer "In5.Cu")
	)
	(gr_arc
		(start 108.601256 -22.350222)
		(mid 109.149896 -22.898862)
		(end 109.698536 -22.350222)
		(stroke
			(width 0.2)
			(type default)
		)
		(layer "In5.Cu")
	)
	(gr_line
		(start 108.601256 -20.950174)
		(end 108.601256 -22.350222)
		(stroke
			(width 0.2)
			(type default)
		)
		(layer "In5.Cu")
	)
	(gr_arc
		(start 108.601256 -18.750026)
		(mid 109.149896 -19.298666)
		(end 109.698536 -18.750026)
		(stroke
			(width 0.2)
			(type default)
		)
		(layer "In5.Cu")
	)
	(gr_line
		(start 108.601256 -17.349978)
		(end 108.601256 -18.750026)
		(stroke
			(width 0.2)
			(type default)
		)
		(layer "In5.Cu")
	)
	(gr_line
		(start 109.698536 -22.350222)
		(end 109.698536 -20.950428)
		(stroke
			(width 0.2)
			(type default)
		)
		(layer "In5.Cu")
	)
	(gr_arc
		(start 109.698536 -20.950428)
		(mid 109.150023 -20.401534)
		(end 108.601256 -20.950174)
		(stroke
			(width 0.2)
			(type default)
		)
		(layer "In5.Cu")
	)
	(gr_line
		(start 109.698536 -18.750026)
		(end 109.698536 -17.350232)
		(stroke
			(width 0.2)
			(type default)
		)
		(layer "In5.Cu")
	)
	(gr_arc
		(start 109.698536 -17.350232)
		(mid 109.150023 -16.801338)
		(end 108.601256 -17.349978)
		(stroke
			(width 0.2)
			(type default)
		)
		(layer "In5.Cu")
	)
	(gr_arc
		(start 110.401354 -23.35022)
		(mid 110.949994 -23.89886)
		(end 111.498634 -23.35022)
		(stroke
			(width 0.2)
			(type default)
		)
		(layer "In5.Cu")
	)
	(gr_line
		(start 110.401354 -21.950172)
		(end 110.401354 -23.35022)
		(stroke
			(width 0.2)
			(type default)
		)
		(layer "In5.Cu")
	)
	(gr_arc
		(start 110.401354 -19.750024)
		(mid 110.949994 -20.298664)
		(end 111.498634 -19.750024)
		(stroke
			(width 0.2)
			(type default)
		)
		(layer "In5.Cu")
	)
	(gr_line
		(start 110.401354 -18.35023)
		(end 110.401354 -19.750024)
		(stroke
			(width 0.2)
			(type default)
		)
		(layer "In5.Cu")
	)
	(gr_line
		(start 111.498634 -23.35022)
		(end 111.498634 -21.950426)
		(stroke
			(width 0.2)
			(type default)
		)
		(layer "In5.Cu")
	)
	(gr_arc
		(start 111.498634 -21.950426)
		(mid 110.950121 -21.401532)
		(end 110.401354 -21.950172)
		(stroke
			(width 0.2)
			(type default)
		)
		(layer "In5.Cu")
	)
	(gr_line
		(start 111.498634 -19.750024)
		(end 111.498634 -18.350484)
		(stroke
			(width 0.2)
			(type default)
		)
		(layer "In5.Cu")
	)
	(gr_arc
		(start 111.498634 -18.350484)
		(mid 110.950121 -17.80159)
		(end 110.401354 -18.35023)
		(stroke
			(width 0.2)
			(type default)
		)
		(layer "In5.Cu")
	)
	(gr_arc
		(start 112.201452 -22.350222)
		(mid 112.750092 -22.898862)
		(end 113.298732 -22.350222)
		(stroke
			(width 0.2)
			(type default)
		)
		(layer "In5.Cu")
	)
	(gr_line
		(start 112.201452 -20.950174)
		(end 112.201452 -22.350222)
		(stroke
			(width 0.2)
			(type default)
		)
		(layer "In5.Cu")
	)
	(gr_arc
		(start 112.201452 -18.750026)
		(mid 112.750092 -19.298666)
		(end 113.298732 -18.750026)
		(stroke
			(width 0.2)
			(type default)
		)
		(layer "In5.Cu")
	)
	(gr_line
		(start 112.201452 -17.349978)
		(end 112.201452 -18.750026)
		(stroke
			(width 0.2)
			(type default)
		)
		(layer "In5.Cu")
	)
	(gr_line
		(start 113.298732 -22.350222)
		(end 113.298732 -20.950428)
		(stroke
			(width 0.2)
			(type default)
		)
		(layer "In5.Cu")
	)
	(gr_arc
		(start 113.298732 -20.950428)
		(mid 112.750219 -20.401534)
		(end 112.201452 -20.950174)
		(stroke
			(width 0.2)
			(type default)
		)
		(layer "In5.Cu")
	)
	(gr_line
		(start 113.298732 -18.750026)
		(end 113.298732 -17.350232)
		(stroke
			(width 0.2)
			(type default)
		)
		(layer "In5.Cu")
	)
	(gr_arc
		(start 113.298732 -17.350232)
		(mid 112.750219 -16.801338)
		(end 112.201452 -17.349978)
		(stroke
			(width 0.2)
			(type default)
		)
		(layer "In5.Cu")
	)
	(gr_arc
		(start 114.001296 -23.35022)
		(mid 114.549936 -23.89886)
		(end 115.098576 -23.35022)
		(stroke
			(width 0.2)
			(type default)
		)
		(layer "In5.Cu")
	)
	(gr_line
		(start 114.001296 -21.950172)
		(end 114.001296 -23.35022)
		(stroke
			(width 0.2)
			(type default)
		)
		(layer "In5.Cu")
	)
	(gr_arc
		(start 114.001296 -19.750024)
		(mid 114.549936 -20.298664)
		(end 115.098576 -19.750024)
		(stroke
			(width 0.2)
			(type default)
		)
		(layer "In5.Cu")
	)
	(gr_line
		(start 114.001296 -18.35023)
		(end 114.001296 -19.750024)
		(stroke
			(width 0.2)
			(type default)
		)
		(layer "In5.Cu")
	)
	(gr_line
		(start 115.098576 -23.35022)
		(end 115.098576 -21.950426)
		(stroke
			(width 0.2)
			(type default)
		)
		(layer "In5.Cu")
	)
	(gr_arc
		(start 115.098576 -21.950426)
		(mid 114.550063 -21.401532)
		(end 114.001296 -21.950172)
		(stroke
			(width 0.2)
			(type default)
		)
		(layer "In5.Cu")
	)
	(gr_line
		(start 115.098576 -19.750024)
		(end 115.098576 -18.350484)
		(stroke
			(width 0.2)
			(type default)
		)
		(layer "In5.Cu")
	)
	(gr_arc
		(start 115.098576 -18.350484)
		(mid 114.550063 -17.80159)
		(end 114.001296 -18.35023)
		(stroke
			(width 0.2)
			(type default)
		)
		(layer "In5.Cu")
	)
	(gr_arc
		(start 115.801394 -29.550106)
		(mid 116.350034 -30.098746)
		(end 116.898674 -29.550106)
		(stroke
			(width 0.2)
			(type default)
		)
		(layer "In5.Cu")
	)
	(gr_line
		(start 115.801394 -28.150058)
		(end 115.801394 -29.550106)
		(stroke
			(width 0.2)
			(type default)
		)
		(layer "In5.Cu")
	)
	(gr_arc
		(start 115.801394 -22.350222)
		(mid 116.350034 -22.898862)
		(end 116.898674 -22.350222)
		(stroke
			(width 0.2)
			(type default)
		)
		(layer "In5.Cu")
	)
	(gr_line
		(start 115.801394 -20.950174)
		(end 115.801394 -22.350222)
		(stroke
			(width 0.2)
			(type default)
		)
		(layer "In5.Cu")
	)
	(gr_arc
		(start 115.801394 -18.750026)
		(mid 116.350034 -19.298666)
		(end 116.898674 -18.750026)
		(stroke
			(width 0.2)
			(type default)
		)
		(layer "In5.Cu")
	)
	(gr_line
		(start 115.801394 -17.349978)
		(end 115.801394 -18.750026)
		(stroke
			(width 0.2)
			(type default)
		)
		(layer "In5.Cu")
	)
	(gr_line
		(start 116.898674 -29.550106)
		(end 116.898674 -28.150312)
		(stroke
			(width 0.2)
			(type default)
		)
		(layer "In5.Cu")
	)
	(gr_arc
		(start 116.898674 -28.150312)
		(mid 116.350161 -27.601418)
		(end 115.801394 -28.150058)
		(stroke
			(width 0.2)
			(type default)
		)
		(layer "In5.Cu")
	)
	(gr_line
		(start 116.898674 -22.350222)
		(end 116.898674 -20.950428)
		(stroke
			(width 0.2)
			(type default)
		)
		(layer "In5.Cu")
	)
	(gr_arc
		(start 116.898674 -20.950428)
		(mid 116.350161 -20.401534)
		(end 115.801394 -20.950174)
		(stroke
			(width 0.2)
			(type default)
		)
		(layer "In5.Cu")
	)
	(gr_line
		(start 116.898674 -18.750026)
		(end 116.898674 -17.350232)
		(stroke
			(width 0.2)
			(type default)
		)
		(layer "In5.Cu")
	)
	(gr_arc
		(start 116.898674 -17.350232)
		(mid 116.350161 -16.801338)
		(end 115.801394 -17.349978)
		(stroke
			(width 0.2)
			(type default)
		)
		(layer "In5.Cu")
	)
	(gr_arc
		(start 117.601238 -23.35022)
		(mid 118.149878 -23.89886)
		(end 118.698518 -23.35022)
		(stroke
			(width 0.2)
			(type default)
		)
		(layer "In5.Cu")
	)
	(gr_line
		(start 117.601238 -21.950172)
		(end 117.601238 -23.35022)
		(stroke
			(width 0.2)
			(type default)
		)
		(layer "In5.Cu")
	)
	(gr_arc
		(start 117.601238 -19.750024)
		(mid 118.149878 -20.298664)
		(end 118.698518 -19.750024)
		(stroke
			(width 0.2)
			(type default)
		)
		(layer "In5.Cu")
	)
	(gr_line
		(start 117.601238 -18.35023)
		(end 117.601238 -19.750024)
		(stroke
			(width 0.2)
			(type default)
		)
		(layer "In5.Cu")
	)
	(gr_line
		(start 118.698518 -23.35022)
		(end 118.698518 -21.950426)
		(stroke
			(width 0.2)
			(type default)
		)
		(layer "In5.Cu")
	)
	(gr_arc
		(start 118.698518 -21.950426)
		(mid 118.150005 -21.401532)
		(end 117.601238 -21.950172)
		(stroke
			(width 0.2)
			(type default)
		)
		(layer "In5.Cu")
	)
	(gr_line
		(start 118.698518 -19.750024)
		(end 118.698518 -18.350484)
		(stroke
			(width 0.2)
			(type default)
		)
		(layer "In5.Cu")
	)
	(gr_arc
		(start 118.698518 -18.350484)
		(mid 118.150005 -17.80159)
		(end 117.601238 -18.35023)
		(stroke
			(width 0.2)
			(type default)
		)
		(layer "In5.Cu")
	)
	(gr_arc
		(start 119.401336 -22.350222)
		(mid 119.949976 -22.898862)
		(end 120.498616 -22.350222)
		(stroke
			(width 0.2)
			(type default)
		)
		(layer "In5.Cu")
	)
	(gr_line
		(start 119.401336 -20.950174)
		(end 119.401336 -22.350222)
		(stroke
			(width 0.2)
			(type default)
		)
		(layer "In5.Cu")
	)
	(gr_arc
		(start 119.401336 -18.750026)
		(mid 119.949976 -19.298666)
		(end 120.498616 -18.750026)
		(stroke
			(width 0.2)
			(type default)
		)
		(layer "In5.Cu")
	)
	(gr_line
		(start 119.401336 -17.349978)
		(end 119.401336 -18.750026)
		(stroke
			(width 0.2)
			(type default)
		)
		(layer "In5.Cu")
	)
	(gr_line
		(start 120.498616 -22.350222)
		(end 120.498616 -20.950428)
		(stroke
			(width 0.2)
			(type default)
		)
		(layer "In5.Cu")
	)
	(gr_arc
		(start 120.498616 -20.950428)
		(mid 119.950103 -20.401534)
		(end 119.401336 -20.950174)
		(stroke
			(width 0.2)
			(type default)
		)
		(layer "In5.Cu")
	)
	(gr_line
		(start 120.498616 -18.750026)
		(end 120.498616 -17.350232)
		(stroke
			(width 0.2)
			(type default)
		)
		(layer "In5.Cu")
	)
	(gr_arc
		(start 120.498616 -17.350232)
		(mid 119.950103 -16.801338)
		(end 119.401336 -17.349978)
		(stroke
			(width 0.2)
			(type default)
		)
		(layer "In5.Cu")
	)
	(gr_arc
		(start 121.198894 -30.54985)
		(mid 121.749947 -31.101284)
		(end 122.301254 -30.550104)
		(stroke
			(width 0.2)
			(type default)
		)
		(layer "In5.Cu")
	)
	(gr_line
		(start 121.198894 -29.150056)
		(end 121.198894 -30.54985)
		(stroke
			(width 0.2)
			(type default)
		)
		(layer "In5.Cu")
	)
	(gr_arc
		(start 121.201434 -23.35022)
		(mid 121.750074 -23.89886)
		(end 122.298714 -23.35022)
		(stroke
			(width 0.2)
			(type default)
		)
		(layer "In5.Cu")
	)
	(gr_line
		(start 121.201434 -21.950172)
		(end 121.201434 -23.35022)
		(stroke
			(width 0.2)
			(type default)
		)
		(layer "In5.Cu")
	)
	(gr_arc
		(start 121.201434 -19.750024)
		(mid 121.750074 -20.298664)
		(end 122.298714 -19.750024)
		(stroke
			(width 0.2)
			(type default)
		)
		(layer "In5.Cu")
	)
	(gr_line
		(start 121.201434 -18.35023)
		(end 121.201434 -19.750024)
		(stroke
			(width 0.2)
			(type default)
		)
		(layer "In5.Cu")
	)
	(gr_line
		(start 122.298714 -23.35022)
		(end 122.298714 -21.950426)
		(stroke
			(width 0.2)
			(type default)
		)
		(layer "In5.Cu")
	)
	(gr_arc
		(start 122.298714 -21.950426)
		(mid 121.750201 -21.401532)
		(end 121.201434 -21.950172)
		(stroke
			(width 0.2)
			(type default)
		)
		(layer "In5.Cu")
	)
	(gr_line
		(start 122.298714 -19.750024)
		(end 122.298714 -18.350484)
		(stroke
			(width 0.2)
			(type default)
		)
		(layer "In5.Cu")
	)
	(gr_arc
		(start 122.298714 -18.350484)
		(mid 121.750201 -17.80159)
		(end 121.201434 -18.35023)
		(stroke
			(width 0.2)
			(type default)
		)
		(layer "In5.Cu")
	)
	(gr_line
		(start 122.301254 -30.550104)
		(end 122.301254 -29.150056)
		(stroke
			(width 0.2)
			(type default)
		)
		(layer "In5.Cu")
	)
	(gr_arc
		(start 122.301254 -29.150056)
		(mid 121.750074 -28.598876)
		(end 121.198894 -29.150056)
		(stroke
			(width 0.2)
			(type default)
		)
		(layer "In5.Cu")
	)
	(gr_line
		(start 123.857766 -36.008564)
		(end 103.77551 -36.008564)
		(stroke
			(width 0.381)
			(type default)
		)
		(layer "In5.Cu")
	)
	(gr_line
		(start 124.556774 -35.309556)
		(end 123.857766 -36.008564)
		(stroke
			(width 0.381)
			(type default)
		)
		(layer "In5.Cu")
	)
	(gr_line
		(start 124.556774 -24.802338)
		(end 124.556774 -35.309556)
		(stroke
			(width 0.381)
			(type default)
		)
		(layer "In5.Cu")
	)
	(gr_line
		(start 126.29515 -23.063962)
		(end 124.556774 -24.802338)
		(stroke
			(width 0.381)
			(type default)
		)
		(layer "In5.Cu")
	)
	(gr_line
		(start 126.29515 -23.063962)
		(end 125.514354 -23.844758)
		(stroke
			(width 0.381)
			(type default)
		)
		(layer "In5.Cu")
	)
	(gr_arc
		(start 126.77775 -278.321516)
		(mid 127.15875 -278.702516)
		(end 127.53975 -278.321516)
		(stroke
			(width 0.2)
			(type default)
		)
		(layer "In5.Cu")
	)
	(gr_line
		(start 126.77775 -277.178516)
		(end 126.77775 -278.321516)
		(stroke
			(width 0.2)
			(type default)
		)
		(layer "In5.Cu")
	)
	(gr_arc
		(start 126.77775 -163.321492)
		(mid 127.15875 -163.702492)
		(end 127.53975 -163.321492)
		(stroke
			(width 0.2)
			(type default)
		)
		(layer "In5.Cu")
	)
	(gr_line
		(start 126.77775 -162.178492)
		(end 126.77775 -163.321492)
		(stroke
			(width 0.2)
			(type default)
		)
		(layer "In5.Cu")
	)
	(gr_arc
		(start 126.77775 -48.321468)
		(mid 127.15875 -48.702468)
		(end 127.53975 -48.321468)
		(stroke
			(width 0.2)
			(type default)
		)
		(layer "In5.Cu")
	)
	(gr_line
		(start 126.77775 -47.178468)
		(end 126.77775 -48.321468)
		(stroke
			(width 0.2)
			(type default)
		)
		(layer "In5.Cu")
	)
	(gr_line
		(start 127.53975 -278.321516)
		(end 127.53975 -277.17877)
		(stroke
			(width 0.2)
			(type default)
		)
		(layer "In5.Cu")
	)
	(gr_arc
		(start 127.53975 -277.17877)
		(mid 127.158877 -276.797516)
		(end 126.77775 -277.178516)
		(stroke
			(width 0.2)
			(type default)
		)
		(layer "In5.Cu")
	)
	(gr_line
		(start 127.53975 -163.321492)
		(end 127.53975 -162.178746)
		(stroke
			(width 0.2)
			(type default)
		)
		(layer "In5.Cu")
	)
	(gr_arc
		(start 127.53975 -162.178746)
		(mid 127.158877 -161.797492)
		(end 126.77775 -162.178492)
		(stroke
			(width 0.2)
			(type default)
		)
		(layer "In5.Cu")
	)
	(gr_line
		(start 127.53975 -48.321468)
		(end 127.53975 -47.178722)
		(stroke
			(width 0.2)
			(type default)
		)
		(layer "In5.Cu")
	)
	(gr_arc
		(start 127.53975 -47.178722)
		(mid 127.158877 -46.797468)
		(end 126.77775 -47.178468)
		(stroke
			(width 0.2)
			(type default)
		)
		(layer "In5.Cu")
	)
	(gr_arc
		(start 130.201416 -22.350222)
		(mid 130.750056 -22.898862)
		(end 131.298696 -22.350222)
		(stroke
			(width 0.2)
			(type default)
		)
		(layer "In5.Cu")
	)
	(gr_line
		(start 130.201416 -20.950174)
		(end 130.201416 -22.350222)
		(stroke
			(width 0.2)
			(type default)
		)
		(layer "In5.Cu")
	)
	(gr_arc
		(start 130.201416 -18.750026)
		(mid 130.750056 -19.298666)
		(end 131.298696 -18.750026)
		(stroke
			(width 0.2)
			(type default)
		)
		(layer "In5.Cu")
	)
	(gr_line
		(start 130.201416 -17.349978)
		(end 130.201416 -18.750026)
		(stroke
			(width 0.2)
			(type default)
		)
		(layer "In5.Cu")
	)
	(gr_line
		(start 130.97129 -23.063962)
		(end 126.29515 -23.063962)
		(stroke
			(width 0.381)
			(type default)
		)
		(layer "In5.Cu")
	)
	(gr_line
		(start 131.298696 -22.350222)
		(end 131.298696 -20.950428)
		(stroke
			(width 0.2)
			(type default)
		)
		(layer "In5.Cu")
	)
	(gr_arc
		(start 131.298696 -20.950428)
		(mid 130.750183 -20.401534)
		(end 130.201416 -20.950174)
		(stroke
			(width 0.2)
			(type default)
		)
		(layer "In5.Cu")
	)
	(gr_line
		(start 131.298696 -18.750026)
		(end 131.298696 -17.350232)
		(stroke
			(width 0.2)
			(type default)
		)
		(layer "In5.Cu")
	)
	(gr_arc
		(start 131.298696 -17.350232)
		(mid 130.750183 -16.801338)
		(end 130.201416 -17.349978)
		(stroke
			(width 0.2)
			(type default)
		)
		(layer "In5.Cu")
	)
	(gr_line
		(start 131.981448 -24.07412)
		(end 130.97129 -23.063962)
		(stroke
			(width 0.381)
			(type default)
		)
		(layer "In5.Cu")
	)
	(gr_arc
		(start 132.00126 -23.35022)
		(mid 132.5499 -23.89886)
		(end 133.09854 -23.35022)
		(stroke
			(width 0.2)
			(type default)
		)
		(layer "In5.Cu")
	)
	(gr_line
		(start 132.00126 -21.950172)
		(end 132.00126 -23.35022)
		(stroke
			(width 0.2)
			(type default)
		)
		(layer "In5.Cu")
	)
	(gr_arc
		(start 132.00126 -19.74977)
		(mid 132.549773 -20.298664)
		(end 133.09854 -19.750024)
		(stroke
			(width 0.2)
			(type default)
		)
		(layer "In5.Cu")
	)
	(gr_line
		(start 132.00126 -18.35023)
		(end 132.00126 -19.74977)
		(stroke
			(width 0.2)
			(type default)
		)
		(layer "In5.Cu")
	)
	(gr_line
		(start 132.675884 -24.07412)
		(end 131.981448 -24.07412)
		(stroke
			(width 0.381)
			(type default)
		)
		(layer "In5.Cu")
	)
	(gr_line
		(start 133.09854 -23.35022)
		(end 133.09854 -21.950426)
		(stroke
			(width 0.2)
			(type default)
		)
		(layer "In5.Cu")
	)
	(gr_arc
		(start 133.09854 -21.950426)
		(mid 132.550027 -21.401532)
		(end 132.00126 -21.950172)
		(stroke
			(width 0.2)
			(type default)
		)
		(layer "In5.Cu")
	)
	(gr_line
		(start 133.09854 -19.750024)
		(end 133.09854 -18.35023)
		(stroke
			(width 0.2)
			(type default)
		)
		(layer "In5.Cu")
	)
	(gr_arc
		(start 133.09854 -18.35023)
		(mid 132.5499 -17.80159)
		(end 132.00126 -18.35023)
		(stroke
			(width 0.2)
			(type default)
		)
		(layer "In5.Cu")
	)
	(gr_line
		(start 133.65353 -35.315652)
		(end 133.65353 -25.051766)
		(stroke
			(width 0.381)
			(type default)
		)
		(layer "In5.Cu")
	)
	(gr_line
		(start 133.65353 -25.051766)
		(end 132.675884 -24.07412)
		(stroke
			(width 0.381)
			(type default)
		)
		(layer "In5.Cu")
	)
	(gr_arc
		(start 133.801358 -22.350222)
		(mid 134.349998 -22.898862)
		(end 134.898638 -22.350222)
		(stroke
			(width 0.2)
			(type default)
		)
		(layer "In5.Cu")
	)
	(gr_line
		(start 133.801358 -20.950174)
		(end 133.801358 -22.350222)
		(stroke
			(width 0.2)
			(type default)
		)
		(layer "In5.Cu")
	)
	(gr_arc
		(start 133.801358 -18.750026)
		(mid 134.349998 -19.298666)
		(end 134.898638 -18.750026)
		(stroke
			(width 0.2)
			(type default)
		)
		(layer "In5.Cu")
	)
	(gr_line
		(start 133.801358 -17.349978)
		(end 133.801358 -18.750026)
		(stroke
			(width 0.2)
			(type default)
		)
		(layer "In5.Cu")
	)
	(gr_line
		(start 134.346442 -36.008564)
		(end 133.65353 -35.315652)
		(stroke
			(width 0.381)
			(type default)
		)
		(layer "In5.Cu")
	)
	(gr_line
		(start 134.898638 -22.350222)
		(end 134.898638 -20.950428)
		(stroke
			(width 0.2)
			(type default)
		)
		(layer "In5.Cu")
	)
	(gr_arc
		(start 134.898638 -20.950428)
		(mid 134.350125 -20.401534)
		(end 133.801358 -20.950174)
		(stroke
			(width 0.2)
			(type default)
		)
		(layer "In5.Cu")
	)
	(gr_line
		(start 134.898638 -18.750026)
		(end 134.898638 -17.350232)
		(stroke
			(width 0.2)
			(type default)
		)
		(layer "In5.Cu")
	)
	(gr_arc
		(start 134.898638 -17.350232)
		(mid 134.350125 -16.801338)
		(end 133.801358 -17.349978)
		(stroke
			(width 0.2)
			(type default)
		)
		(layer "In5.Cu")
	)
	(gr_arc
		(start 135.601456 -30.550104)
		(mid 136.150096 -31.098744)
		(end 136.698736 -30.550104)
		(stroke
			(width 0.2)
			(type default)
		)
		(layer "In5.Cu")
	)
	(gr_line
		(start 135.601456 -29.150056)
		(end 135.601456 -30.550104)
		(stroke
			(width 0.2)
			(type default)
		)
		(layer "In5.Cu")
	)
	(gr_arc
		(start 135.601456 -23.35022)
		(mid 136.150096 -23.89886)
		(end 136.698736 -23.35022)
		(stroke
			(width 0.2)
			(type default)
		)
		(layer "In5.Cu")
	)
	(gr_line
		(start 135.601456 -21.950172)
		(end 135.601456 -23.35022)
		(stroke
			(width 0.2)
			(type default)
		)
		(layer "In5.Cu")
	)
	(gr_arc
		(start 135.601456 -19.750024)
		(mid 136.150096 -20.298664)
		(end 136.698736 -19.750024)
		(stroke
			(width 0.2)
			(type default)
		)
		(layer "In5.Cu")
	)
	(gr_line
		(start 135.601456 -18.35023)
		(end 135.601456 -19.750024)
		(stroke
			(width 0.2)
			(type default)
		)
		(layer "In5.Cu")
	)
	(gr_line
		(start 136.698736 -30.550104)
		(end 136.698736 -29.15031)
		(stroke
			(width 0.2)
			(type default)
		)
		(layer "In5.Cu")
	)
	(gr_arc
		(start 136.698736 -29.15031)
		(mid 136.150223 -28.601416)
		(end 135.601456 -29.150056)
		(stroke
			(width 0.2)
			(type default)
		)
		(layer "In5.Cu")
	)
	(gr_line
		(start 136.698736 -23.35022)
		(end 136.698736 -21.950426)
		(stroke
			(width 0.2)
			(type default)
		)
		(layer "In5.Cu")
	)
	(gr_arc
		(start 136.698736 -21.950426)
		(mid 136.150223 -21.401532)
		(end 135.601456 -21.950172)
		(stroke
			(width 0.2)
			(type default)
		)
		(layer "In5.Cu")
	)
	(gr_line
		(start 136.698736 -19.750024)
		(end 136.698736 -18.350484)
		(stroke
			(width 0.2)
			(type default)
		)
		(layer "In5.Cu")
	)
	(gr_arc
		(start 136.698736 -18.350484)
		(mid 136.150223 -17.80159)
		(end 135.601456 -18.35023)
		(stroke
			(width 0.2)
			(type default)
		)
		(layer "In5.Cu")
	)
	(gr_arc
		(start 137.4013 -22.350222)
		(mid 137.94994 -22.898862)
		(end 138.49858 -22.350222)
		(stroke
			(width 0.2)
			(type default)
		)
		(layer "In5.Cu")
	)
	(gr_line
		(start 137.4013 -20.950174)
		(end 137.4013 -22.350222)
		(stroke
			(width 0.2)
			(type default)
		)
		(layer "In5.Cu")
	)
	(gr_arc
		(start 137.4013 -18.750026)
		(mid 137.94994 -19.298666)
		(end 138.49858 -18.750026)
		(stroke
			(width 0.2)
			(type default)
		)
		(layer "In5.Cu")
	)
	(gr_line
		(start 137.4013 -17.349978)
		(end 137.4013 -18.750026)
		(stroke
			(width 0.2)
			(type default)
		)
		(layer "In5.Cu")
	)
	(gr_line
		(start 138.49858 -22.350222)
		(end 138.49858 -20.950428)
		(stroke
			(width 0.2)
			(type default)
		)
		(layer "In5.Cu")
	)
	(gr_arc
		(start 138.49858 -20.950428)
		(mid 137.950067 -20.401534)
		(end 137.4013 -20.950174)
		(stroke
			(width 0.2)
			(type default)
		)
		(layer "In5.Cu")
	)
	(gr_line
		(start 138.49858 -18.750026)
		(end 138.49858 -17.350232)
		(stroke
			(width 0.2)
			(type default)
		)
		(layer "In5.Cu")
	)
	(gr_arc
		(start 138.49858 -17.350232)
		(mid 137.950067 -16.801338)
		(end 137.4013 -17.349978)
		(stroke
			(width 0.2)
			(type default)
		)
		(layer "In5.Cu")
	)
	(gr_arc
		(start 139.201398 -23.35022)
		(mid 139.750038 -23.89886)
		(end 140.298678 -23.35022)
		(stroke
			(width 0.2)
			(type default)
		)
		(layer "In5.Cu")
	)
	(gr_line
		(start 139.201398 -21.950172)
		(end 139.201398 -23.35022)
		(stroke
			(width 0.2)
			(type default)
		)
		(layer "In5.Cu")
	)
	(gr_arc
		(start 139.201398 -19.750024)
		(mid 139.750038 -20.298664)
		(end 140.298678 -19.750024)
		(stroke
			(width 0.2)
			(type default)
		)
		(layer "In5.Cu")
	)
	(gr_line
		(start 139.201398 -18.35023)
		(end 139.201398 -19.750024)
		(stroke
			(width 0.2)
			(type default)
		)
		(layer "In5.Cu")
	)
	(gr_line
		(start 140.298678 -23.35022)
		(end 140.298678 -21.950426)
		(stroke
			(width 0.2)
			(type default)
		)
		(layer "In5.Cu")
	)
	(gr_arc
		(start 140.298678 -21.950426)
		(mid 139.750165 -21.401532)
		(end 139.201398 -21.950172)
		(stroke
			(width 0.2)
			(type default)
		)
		(layer "In5.Cu")
	)
	(gr_line
		(start 140.298678 -19.750024)
		(end 140.298678 -18.350484)
		(stroke
			(width 0.2)
			(type default)
		)
		(layer "In5.Cu")
	)
	(gr_arc
		(start 140.298678 -18.350484)
		(mid 139.750165 -17.80159)
		(end 139.201398 -18.35023)
		(stroke
			(width 0.2)
			(type default)
		)
		(layer "In5.Cu")
	)
	(gr_arc
		(start 141.001242 -22.350222)
		(mid 141.549882 -22.898862)
		(end 142.098522 -22.350222)
		(stroke
			(width 0.2)
			(type default)
		)
		(layer "In5.Cu")
	)
	(gr_line
		(start 141.001242 -20.950174)
		(end 141.001242 -22.350222)
		(stroke
			(width 0.2)
			(type default)
		)
		(layer "In5.Cu")
	)
	(gr_arc
		(start 141.001242 -18.750026)
		(mid 141.549882 -19.298666)
		(end 142.098522 -18.750026)
		(stroke
			(width 0.2)
			(type default)
		)
		(layer "In5.Cu")
	)
	(gr_line
		(start 141.001242 -17.349978)
		(end 141.001242 -18.750026)
		(stroke
			(width 0.2)
			(type default)
		)
		(layer "In5.Cu")
	)
	(gr_line
		(start 142.098522 -22.350222)
		(end 142.098522 -20.950428)
		(stroke
			(width 0.2)
			(type default)
		)
		(layer "In5.Cu")
	)
	(gr_arc
		(start 142.098522 -20.950428)
		(mid 141.550009 -20.401534)
		(end 141.001242 -20.950174)
		(stroke
			(width 0.2)
			(type default)
		)
		(layer "In5.Cu")
	)
	(gr_line
		(start 142.098522 -18.750026)
		(end 142.098522 -17.350232)
		(stroke
			(width 0.2)
			(type default)
		)
		(layer "In5.Cu")
	)
	(gr_arc
		(start 142.098522 -17.350232)
		(mid 141.550009 -16.801338)
		(end 141.001242 -17.349978)
		(stroke
			(width 0.2)
			(type default)
		)
		(layer "In5.Cu")
	)
	(gr_arc
		(start 142.80134 -30.550104)
		(mid 143.34998 -31.098744)
		(end 143.89862 -30.550104)
		(stroke
			(width 0.2)
			(type default)
		)
		(layer "In5.Cu")
	)
	(gr_line
		(start 142.80134 -29.150056)
		(end 142.80134 -30.550104)
		(stroke
			(width 0.2)
			(type default)
		)
		(layer "In5.Cu")
	)
	(gr_arc
		(start 142.80134 -23.35022)
		(mid 143.34998 -23.89886)
		(end 143.89862 -23.35022)
		(stroke
			(width 0.2)
			(type default)
		)
		(layer "In5.Cu")
	)
	(gr_line
		(start 142.80134 -21.950172)
		(end 142.80134 -23.35022)
		(stroke
			(width 0.2)
			(type default)
		)
		(layer "In5.Cu")
	)
	(gr_arc
		(start 142.80134 -19.750024)
		(mid 143.34998 -20.298664)
		(end 143.89862 -19.750024)
		(stroke
			(width 0.2)
			(type default)
		)
		(layer "In5.Cu")
	)
	(gr_line
		(start 142.80134 -18.35023)
		(end 142.80134 -19.750024)
		(stroke
			(width 0.2)
			(type default)
		)
		(layer "In5.Cu")
	)
	(gr_line
		(start 143.89862 -30.550104)
		(end 143.89862 -29.15031)
		(stroke
			(width 0.2)
			(type default)
		)
		(layer "In5.Cu")
	)
	(gr_arc
		(start 143.89862 -29.15031)
		(mid 143.350107 -28.601416)
		(end 142.80134 -29.150056)
		(stroke
			(width 0.2)
			(type default)
		)
		(layer "In5.Cu")
	)
	(gr_line
		(start 143.89862 -23.35022)
		(end 143.89862 -21.950426)
		(stroke
			(width 0.2)
			(type default)
		)
		(layer "In5.Cu")
	)
	(gr_arc
		(start 143.89862 -21.950426)
		(mid 143.350107 -21.401532)
		(end 142.80134 -21.950172)
		(stroke
			(width 0.2)
			(type default)
		)
		(layer "In5.Cu")
	)
	(gr_line
		(start 143.89862 -19.750024)
		(end 143.89862 -18.350484)
		(stroke
			(width 0.2)
			(type default)
		)
		(layer "In5.Cu")
	)
	(gr_arc
		(start 143.89862 -18.350484)
		(mid 143.350107 -17.80159)
		(end 142.80134 -18.35023)
		(stroke
			(width 0.2)
			(type default)
		)
		(layer "In5.Cu")
	)
	(gr_line
		(start 144.999964 -13.999972)
		(end 148.744686 -13.999972)
		(stroke
			(width 0.381)
			(type default)
		)
		(layer "In5.Cu")
	)
	(gr_line
		(start 148.744686 -13.999972)
		(end 149.324314 -14.5796)
		(stroke
			(width 0.381)
			(type default)
		)
		(layer "In5.Cu")
	)
	(gr_line
		(start 148.7678 -36.008564)
		(end 134.346442 -36.008564)
		(stroke
			(width 0.381)
			(type default)
		)
		(layer "In5.Cu")
	)
	(gr_arc
		(start 148.999956 -14.99997)
		(mid 149.707061 -14.707077)
		(end 149.999954 -13.999972)
		(stroke
			(width 2.54)
			(type default)
		)
		(layer "In5.Cu")
	)
	(gr_line
		(start 149.324314 -35.45205)
		(end 148.7678 -36.008564)
		(stroke
			(width 0.381)
			(type default)
		)
		(layer "In5.Cu")
	)
	(gr_line
		(start 149.324314 -14.5796)
		(end 149.324314 -35.45205)
		(stroke
			(width 0.381)
			(type default)
		)
		(layer "In5.Cu")
	)
	(gr_line
		(start 149.999954 -13.999972)
		(end 149.999954 -0.999998)
		(stroke
			(width 2.54)
			(type default)
		)
		(layer "In5.Cu")
	)
	(gr_arc
		(start 150.999952 0)
		(mid 150.292877 -0.292909)
		(end 149.999954 -0.999998)
		(stroke
			(width 2.54)
			(type default)
		)
		(layer "In5.Cu")
	)
	(gr_line
		(start 150.999952 0)
		(end 199.00011 0)
		(stroke
			(width 2.54)
			(type default)
		)
		(layer "In5.Cu")
	)
	(gr_arc
		(start 158.327852 -278.321516)
		(mid 158.708852 -278.702516)
		(end 159.089852 -278.321516)
		(stroke
			(width 0.2)
			(type default)
		)
		(layer "In5.Cu")
	)
	(gr_line
		(start 158.327852 -277.178516)
		(end 158.327852 -278.321516)
		(stroke
			(width 0.2)
			(type default)
		)
		(layer "In5.Cu")
	)
	(gr_arc
		(start 158.327852 -163.321492)
		(mid 158.708852 -163.702492)
		(end 159.089852 -163.321492)
		(stroke
			(width 0.2)
			(type default)
		)
		(layer "In5.Cu")
	)
	(gr_line
		(start 158.327852 -162.178492)
		(end 158.327852 -163.321492)
		(stroke
			(width 0.2)
			(type default)
		)
		(layer "In5.Cu")
	)
	(gr_arc
		(start 158.327852 -48.321468)
		(mid 158.708852 -48.702468)
		(end 159.089852 -48.321468)
		(stroke
			(width 0.2)
			(type default)
		)
		(layer "In5.Cu")
	)
	(gr_line
		(start 158.327852 -47.178468)
		(end 158.327852 -48.321468)
		(stroke
			(width 0.2)
			(type default)
		)
		(layer "In5.Cu")
	)
	(gr_line
		(start 158.87446 -155.75407)
		(end 159.554926 -156.434536)
		(stroke
			(width 0.381)
			(type default)
		)
		(layer "In5.Cu")
	)
	(gr_line
		(start 158.87446 -132.397754)
		(end 158.87446 -155.75407)
		(stroke
			(width 0.381)
			(type default)
		)
		(layer "In5.Cu")
	)
	(gr_line
		(start 159.089852 -278.321516)
		(end 159.089852 -277.17877)
		(stroke
			(width 0.2)
			(type default)
		)
		(layer "In5.Cu")
	)
	(gr_arc
		(start 159.089852 -277.17877)
		(mid 158.708979 -276.797516)
		(end 158.327852 -277.178516)
		(stroke
			(width 0.2)
			(type default)
		)
		(layer "In5.Cu")
	)
	(gr_line
		(start 159.089852 -163.321492)
		(end 159.089852 -162.178746)
		(stroke
			(width 0.2)
			(type default)
		)
		(layer "In5.Cu")
	)
	(gr_arc
		(start 159.089852 -162.178746)
		(mid 158.708979 -161.797492)
		(end 158.327852 -162.178492)
		(stroke
			(width 0.2)
			(type default)
		)
		(layer "In5.Cu")
	)
	(gr_line
		(start 159.089852 -48.321468)
		(end 159.089852 -47.178722)
		(stroke
			(width 0.2)
			(type default)
		)
		(layer "In5.Cu")
	)
	(gr_arc
		(start 159.089852 -47.178722)
		(mid 158.708979 -46.797468)
		(end 158.327852 -47.178468)
		(stroke
			(width 0.2)
			(type default)
		)
		(layer "In5.Cu")
	)
	(gr_line
		(start 159.486092 -131.786122)
		(end 158.87446 -132.397754)
		(stroke
			(width 0.381)
			(type default)
		)
		(layer "In5.Cu")
	)
	(gr_line
		(start 159.554926 -156.434536)
		(end 174.02048 -156.434536)
		(stroke
			(width 0.381)
			(type default)
		)
		(layer "In5.Cu")
	)
	(gr_line
		(start 174.02048 -156.434536)
		(end 174.361856 -156.09316)
		(stroke
			(width 0.381)
			(type default)
		)
		(layer "In5.Cu")
	)
	(gr_line
		(start 174.361856 -156.09316)
		(end 174.361856 -149.916642)
		(stroke
			(width 0.381)
			(type default)
		)
		(layer "In5.Cu")
	)
	(gr_line
		(start 174.361856 -149.916642)
		(end 175.221646 -149.056852)
		(stroke
			(width 0.381)
			(type default)
		)
		(layer "In5.Cu")
	)
	(gr_line
		(start 175.221646 -149.056852)
		(end 182.90286 -149.056852)
		(stroke
			(width 0.381)
			(type default)
		)
		(layer "In5.Cu")
	)
	(gr_line
		(start 181.926992 -131.786122)
		(end 159.486092 -131.786122)
		(stroke
			(width 0.381)
			(type default)
		)
		(layer "In5.Cu")
	)
	(gr_line
		(start 182.90286 -149.056852)
		(end 183.365902 -149.519894)
		(stroke
			(width 0.381)
			(type default)
		)
		(layer "In5.Cu")
	)
	(gr_line
		(start 183.3626 -130.350514)
		(end 181.926992 -131.786122)
		(stroke
			(width 0.381)
			(type default)
		)
		(layer "In5.Cu")
	)
	(gr_line
		(start 183.3626 -91.1606)
		(end 183.3626 -130.350514)
		(stroke
			(width 0.381)
			(type default)
		)
		(layer "In5.Cu")
	)
	(gr_line
		(start 183.365902 -155.86964)
		(end 183.930798 -156.434536)
		(stroke
			(width 0.381)
			(type default)
		)
		(layer "In5.Cu")
	)
	(gr_line
		(start 183.365902 -149.519894)
		(end 183.365902 -155.86964)
		(stroke
			(width 0.381)
			(type default)
		)
		(layer "In5.Cu")
	)
	(gr_line
		(start 183.930798 -156.434536)
		(end 209.698336 -156.434536)
		(stroke
			(width 0.381)
			(type default)
		)
		(layer "In5.Cu")
	)
	(gr_line
		(start 188.0616 -86.4616)
		(end 183.3626 -91.1606)
		(stroke
			(width 0.381)
			(type default)
		)
		(layer "In5.Cu")
	)
	(gr_line
		(start 189.6999 -349.199962)
		(end 0.999998 -349.199962)
		(stroke
			(width 2.54)
			(type default)
		)
		(layer "In5.Cu")
	)
	(gr_arc
		(start 189.877954 -278.321516)
		(mid 190.258954 -278.702516)
		(end 190.639954 -278.321516)
		(stroke
			(width 0.2)
			(type default)
		)
		(layer "In5.Cu")
	)
	(gr_line
		(start 189.877954 -277.178516)
		(end 189.877954 -278.321516)
		(stroke
			(width 0.2)
			(type default)
		)
		(layer "In5.Cu")
	)
	(gr_arc
		(start 189.877954 -163.321492)
		(mid 190.258954 -163.702492)
		(end 190.639954 -163.321492)
		(stroke
			(width 0.2)
			(type default)
		)
		(layer "In5.Cu")
	)
	(gr_line
		(start 189.877954 -162.178492)
		(end 189.877954 -163.321492)
		(stroke
			(width 0.2)
			(type default)
		)
		(layer "In5.Cu")
	)
	(gr_arc
		(start 189.877954 -48.321468)
		(mid 190.258954 -48.702468)
		(end 190.639954 -48.321468)
		(stroke
			(width 0.2)
			(type default)
		)
		(layer "In5.Cu")
	)
	(gr_line
		(start 189.877954 -47.178468)
		(end 189.877954 -48.321468)
		(stroke
			(width 0.2)
			(type default)
		)
		(layer "In5.Cu")
	)
	(gr_line
		(start 190.639954 -278.321516)
		(end 190.639954 -277.17877)
		(stroke
			(width 0.2)
			(type default)
		)
		(layer "In5.Cu")
	)
	(gr_arc
		(start 190.639954 -277.17877)
		(mid 190.259081 -276.797516)
		(end 189.877954 -277.178516)
		(stroke
			(width 0.2)
			(type default)
		)
		(layer "In5.Cu")
	)
	(gr_line
		(start 190.639954 -163.321492)
		(end 190.639954 -162.178746)
		(stroke
			(width 0.2)
			(type default)
		)
		(layer "In5.Cu")
	)
	(gr_arc
		(start 190.639954 -162.178746)
		(mid 190.259081 -161.797492)
		(end 189.877954 -162.178492)
		(stroke
			(width 0.2)
			(type default)
		)
		(layer "In5.Cu")
	)
	(gr_line
		(start 190.639954 -48.321468)
		(end 190.639954 -47.178722)
		(stroke
			(width 0.2)
			(type default)
		)
		(layer "In5.Cu")
	)
	(gr_arc
		(start 190.639954 -47.178722)
		(mid 190.259081 -46.797468)
		(end 189.877954 -47.178468)
		(stroke
			(width 0.2)
			(type default)
		)
		(layer "In5.Cu")
	)
	(gr_line
		(start 190.699898 -372.000018)
		(end 190.699898 -350.19996)
		(stroke
			(width 2.54)
			(type default)
		)
		(layer "In5.Cu")
	)
	(gr_arc
		(start 190.699898 -372.000018)
		(mid 190.992797 -372.707113)
		(end 191.699896 -373.000016)
		(stroke
			(width 2.54)
			(type default)
		)
		(layer "In5.Cu")
	)
	(gr_arc
		(start 190.699898 -350.19996)
		(mid 190.407005 -349.492855)
		(end 189.6999 -349.199962)
		(stroke
			(width 2.54)
			(type default)
		)
		(layer "In5.Cu")
	)
	(gr_line
		(start 199.00011 -373.000016)
		(end 191.699896 -373.000016)
		(stroke
			(width 2.54)
			(type default)
		)
		(layer "In5.Cu")
	)
	(gr_arc
		(start 199.00011 0)
		(mid 199.707215 0.292893)
		(end 200.000108 0.999998)
		(stroke
			(width 2.54)
			(type default)
		)
		(layer "In5.Cu")
	)
	(gr_line
		(start 200.000108 -420.200074)
		(end 200.000108 -374.000014)
		(stroke
			(width 2.54)
			(type default)
		)
		(layer "In5.Cu")
	)
	(gr_arc
		(start 200.000108 -420.200074)
		(mid 200.292992 -420.907194)
		(end 201.000106 -421.200072)
		(stroke
			(width 2.54)
			(type default)
		)
		(layer "In5.Cu")
	)
	(gr_arc
		(start 200.000108 -374.000014)
		(mid 199.707215 -373.292909)
		(end 199.00011 -373.000016)
		(stroke
			(width 2.54)
			(type default)
		)
		(layer "In5.Cu")
	)
	(gr_arc
		(start 201.000106 1.999996)
		(mid 200.292997 1.707105)
		(end 200.000108 0.999998)
		(stroke
			(width 2.54)
			(type default)
		)
		(layer "In5.Cu")
	)
	(gr_line
		(start 201.000106 1.999996)
		(end 219.00007 1.999996)
		(stroke
			(width 2.54)
			(type default)
		)
		(layer "In5.Cu")
	)
	(gr_line
		(start 208.2546 -86.4616)
		(end 188.0616 -86.4616)
		(stroke
			(width 0.381)
			(type default)
		)
		(layer "In5.Cu")
	)
	(gr_arc
		(start 209.451448 -415.600134)
		(mid 210.000088 -416.148774)
		(end 210.548728 -415.600134)
		(stroke
			(width 0.2)
			(type default)
		)
		(layer "In5.Cu")
	)
	(gr_line
		(start 209.451448 -414.200086)
		(end 209.451448 -415.600134)
		(stroke
			(width 0.2)
			(type default)
		)
		(layer "In5.Cu")
	)
	(gr_arc
		(start 209.451448 -412.000192)
		(mid 210.000088 -412.548832)
		(end 210.548728 -412.000192)
		(stroke
			(width 0.2)
			(type default)
		)
		(layer "In5.Cu")
	)
	(gr_line
		(start 209.451448 -410.600144)
		(end 209.451448 -412.000192)
		(stroke
			(width 0.2)
			(type default)
		)
		(layer "In5.Cu")
	)
	(gr_arc
		(start 209.451448 -408.399996)
		(mid 210.000088 -408.948636)
		(end 210.548728 -408.399996)
		(stroke
			(width 0.2)
			(type default)
		)
		(layer "In5.Cu")
	)
	(gr_line
		(start 209.451448 -407.000202)
		(end 209.451448 -408.399996)
		(stroke
			(width 0.2)
			(type default)
		)
		(layer "In5.Cu")
	)
	(gr_circle
		(center 209.698336 -156.43479)
		(end 209.69859 -156.43479)
		(stroke
			(width 0.381)
			(type default)
		)
		(fill no)
		(layer "In5.Cu")
	)
	(gr_line
		(start 209.698336 -156.434536)
		(end 212.0646 -158.8008)
		(stroke
			(width 0.381)
			(type default)
		)
		(layer "In5.Cu")
	)
	(gr_line
		(start 210.548728 -415.600134)
		(end 210.548728 -414.20034)
		(stroke
			(width 0.2)
			(type default)
		)
		(layer "In5.Cu")
	)
	(gr_arc
		(start 210.548728 -414.20034)
		(mid 210.000215 -413.651446)
		(end 209.451448 -414.200086)
		(stroke
			(width 0.2)
			(type default)
		)
		(layer "In5.Cu")
	)
	(gr_line
		(start 210.548728 -412.000192)
		(end 210.548728 -410.600398)
		(stroke
			(width 0.2)
			(type default)
		)
		(layer "In5.Cu")
	)
	(gr_arc
		(start 210.548728 -410.600398)
		(mid 210.000215 -410.051504)
		(end 209.451448 -410.600144)
		(stroke
			(width 0.2)
			(type default)
		)
		(layer "In5.Cu")
	)
	(gr_line
		(start 210.548728 -408.399996)
		(end 210.548728 -407.000456)
		(stroke
			(width 0.2)
			(type default)
		)
		(layer "In5.Cu")
	)
	(gr_arc
		(start 210.548728 -407.000456)
		(mid 210.000215 -406.451562)
		(end 209.451448 -407.000202)
		(stroke
			(width 0.2)
			(type default)
		)
		(layer "In5.Cu")
	)
	(gr_arc
		(start 211.251546 -418.200078)
		(mid 211.800186 -418.748718)
		(end 212.348826 -418.200078)
		(stroke
			(width 0.2)
			(type default)
		)
		(layer "In5.Cu")
	)
	(gr_line
		(start 211.251546 -416.80003)
		(end 211.251546 -418.200078)
		(stroke
			(width 0.2)
			(type default)
		)
		(layer "In5.Cu")
	)
	(gr_arc
		(start 211.251546 -407.399998)
		(mid 211.800186 -407.948638)
		(end 212.348826 -407.399998)
		(stroke
			(width 0.2)
			(type default)
		)
		(layer "In5.Cu")
	)
	(gr_line
		(start 211.251546 -405.99995)
		(end 211.251546 -407.399998)
		(stroke
			(width 0.2)
			(type default)
		)
		(layer "In5.Cu")
	)
	(gr_line
		(start 212.0646 -190.4746)
		(end 219.4306 -197.8406)
		(stroke
			(width 0.381)
			(type default)
		)
		(layer "In5.Cu")
	)
	(gr_line
		(start 212.0646 -158.8008)
		(end 212.0646 -190.4746)
		(stroke
			(width 0.381)
			(type default)
		)
		(layer "In5.Cu")
	)
	(gr_line
		(start 212.348826 -418.200078)
		(end 212.348826 -416.800284)
		(stroke
			(width 0.2)
			(type default)
		)
		(layer "In5.Cu")
	)
	(gr_arc
		(start 212.348826 -416.800284)
		(mid 211.800313 -416.25139)
		(end 211.251546 -416.80003)
		(stroke
			(width 0.2)
			(type default)
		)
		(layer "In5.Cu")
	)
	(gr_line
		(start 212.348826 -407.399998)
		(end 212.348826 -406.000204)
		(stroke
			(width 0.2)
			(type default)
		)
		(layer "In5.Cu")
	)
	(gr_arc
		(start 212.348826 -406.000204)
		(mid 211.800313 -405.45131)
		(end 211.251546 -405.99995)
		(stroke
			(width 0.2)
			(type default)
		)
		(layer "In5.Cu")
	)
	(gr_arc
		(start 213.05139 -415.600134)
		(mid 213.60003 -416.148774)
		(end 214.14867 -415.600134)
		(stroke
			(width 0.2)
			(type default)
		)
		(layer "In5.Cu")
	)
	(gr_line
		(start 213.05139 -414.200086)
		(end 213.05139 -415.600134)
		(stroke
			(width 0.2)
			(type default)
		)
		(layer "In5.Cu")
	)
	(gr_arc
		(start 213.05139 -408.399996)
		(mid 213.60003 -408.948636)
		(end 214.14867 -408.399996)
		(stroke
			(width 0.2)
			(type default)
		)
		(layer "In5.Cu")
	)
	(gr_line
		(start 213.05139 -407.000202)
		(end 213.05139 -408.399996)
		(stroke
			(width 0.2)
			(type default)
		)
		(layer "In5.Cu")
	)
	(gr_line
		(start 213.9442 -80.772)
		(end 208.2546 -86.4616)
		(stroke
			(width 0.381)
			(type default)
		)
		(layer "In5.Cu")
	)
	(gr_line
		(start 213.9442 -11.866372)
		(end 213.9442 -80.772)
		(stroke
			(width 0.381)
			(type default)
		)
		(layer "In5.Cu")
	)
	(gr_line
		(start 214.14867 -415.600134)
		(end 214.14867 -414.20034)
		(stroke
			(width 0.2)
			(type default)
		)
		(layer "In5.Cu")
	)
	(gr_arc
		(start 214.14867 -414.20034)
		(mid 213.600157 -413.651446)
		(end 213.05139 -414.200086)
		(stroke
			(width 0.2)
			(type default)
		)
		(layer "In5.Cu")
	)
	(gr_line
		(start 214.14867 -408.399996)
		(end 214.14867 -407.000456)
		(stroke
			(width 0.2)
			(type default)
		)
		(layer "In5.Cu")
	)
	(gr_arc
		(start 214.14867 -407.000456)
		(mid 213.600157 -406.451562)
		(end 213.05139 -407.000202)
		(stroke
			(width 0.2)
			(type default)
		)
		(layer "In5.Cu")
	)
	(gr_arc
		(start 214.851488 -418.200078)
		(mid 215.400128 -418.748718)
		(end 215.948768 -418.200078)
		(stroke
			(width 0.2)
			(type default)
		)
		(layer "In5.Cu")
	)
	(gr_line
		(start 214.851488 -416.80003)
		(end 214.851488 -418.200078)
		(stroke
			(width 0.2)
			(type default)
		)
		(layer "In5.Cu")
	)
	(gr_arc
		(start 214.851488 -407.399998)
		(mid 215.400128 -407.948638)
		(end 215.948768 -407.399998)
		(stroke
			(width 0.2)
			(type default)
		)
		(layer "In5.Cu")
	)
	(gr_line
		(start 214.851488 -405.99995)
		(end 214.851488 -407.399998)
		(stroke
			(width 0.2)
			(type default)
		)
		(layer "In5.Cu")
	)
	(gr_line
		(start 215.948768 -418.200078)
		(end 215.948768 -416.800284)
		(stroke
			(width 0.2)
			(type default)
		)
		(layer "In5.Cu")
	)
	(gr_arc
		(start 215.948768 -416.800284)
		(mid 215.400255 -416.25139)
		(end 214.851488 -416.80003)
		(stroke
			(width 0.2)
			(type default)
		)
		(layer "In5.Cu")
	)
	(gr_line
		(start 215.948768 -407.399998)
		(end 215.948768 -406.000204)
		(stroke
			(width 0.2)
			(type default)
		)
		(layer "In5.Cu")
	)
	(gr_arc
		(start 215.948768 -406.000204)
		(mid 215.400255 -405.45131)
		(end 214.851488 -405.99995)
		(stroke
			(width 0.2)
			(type default)
		)
		(layer "In5.Cu")
	)
	(gr_arc
		(start 216.651332 -415.600134)
		(mid 217.199972 -416.148774)
		(end 217.748612 -415.600134)
		(stroke
			(width 0.2)
			(type default)
		)
		(layer "In5.Cu")
	)
	(gr_line
		(start 216.651332 -414.200086)
		(end 216.651332 -415.600134)
		(stroke
			(width 0.2)
			(type default)
		)
		(layer "In5.Cu")
	)
	(gr_arc
		(start 216.651332 -408.399996)
		(mid 217.199972 -408.948636)
		(end 217.748612 -408.399996)
		(stroke
			(width 0.2)
			(type default)
		)
		(layer "In5.Cu")
	)
	(gr_line
		(start 216.651332 -407.000202)
		(end 216.651332 -408.399996)
		(stroke
			(width 0.2)
			(type default)
		)
		(layer "In5.Cu")
	)
	(gr_line
		(start 217.748612 -415.600134)
		(end 217.748612 -414.20034)
		(stroke
			(width 0.2)
			(type default)
		)
		(layer "In5.Cu")
	)
	(gr_arc
		(start 217.748612 -414.20034)
		(mid 217.200099 -413.651446)
		(end 216.651332 -414.200086)
		(stroke
			(width 0.2)
			(type default)
		)
		(layer "In5.Cu")
	)
	(gr_line
		(start 217.748612 -408.399996)
		(end 217.748612 -407.000456)
		(stroke
			(width 0.2)
			(type default)
		)
		(layer "In5.Cu")
	)
	(gr_arc
		(start 217.748612 -407.000456)
		(mid 217.200099 -406.451562)
		(end 216.651332 -407.000202)
		(stroke
			(width 0.2)
			(type default)
		)
		(layer "In5.Cu")
	)
	(gr_arc
		(start 218.45143 -418.200078)
		(mid 219.00007 -418.748718)
		(end 219.54871 -418.200078)
		(stroke
			(width 0.2)
			(type default)
		)
		(layer "In5.Cu")
	)
	(gr_line
		(start 218.45143 -416.80003)
		(end 218.45143 -418.200078)
		(stroke
			(width 0.2)
			(type default)
		)
		(layer "In5.Cu")
	)
	(gr_arc
		(start 218.45143 -407.399998)
		(mid 219.00007 -407.948638)
		(end 219.54871 -407.399998)
		(stroke
			(width 0.2)
			(type default)
		)
		(layer "In5.Cu")
	)
	(gr_line
		(start 218.45143 -405.99995)
		(end 218.45143 -407.399998)
		(stroke
			(width 0.2)
			(type default)
		)
		(layer "In5.Cu")
	)
	(gr_arc
		(start 219.00007 1.999996)
		(mid 219.707175 2.292889)
		(end 220.000068 2.999994)
		(stroke
			(width 2.54)
			(type default)
		)
		(layer "In5.Cu")
	)
	(gr_line
		(start 219.4306 -197.8406)
		(end 240.284 -197.8406)
		(stroke
			(width 0.381)
			(type default)
		)
		(layer "In5.Cu")
	)
	(gr_line
		(start 219.54871 -418.200078)
		(end 219.54871 -416.800284)
		(stroke
			(width 0.2)
			(type default)
		)
		(layer "In5.Cu")
	)
	(gr_arc
		(start 219.54871 -416.800284)
		(mid 219.000197 -416.25139)
		(end 218.45143 -416.80003)
		(stroke
			(width 0.2)
			(type default)
		)
		(layer "In5.Cu")
	)
	(gr_line
		(start 219.54871 -407.399998)
		(end 219.54871 -406.000204)
		(stroke
			(width 0.2)
			(type default)
		)
		(layer "In5.Cu")
	)
	(gr_arc
		(start 219.54871 -406.000204)
		(mid 219.000197 -405.45131)
		(end 218.45143 -405.99995)
		(stroke
			(width 0.2)
			(type default)
		)
		(layer "In5.Cu")
	)
	(gr_line
		(start 220.000068 2.999994)
		(end 220.000068 37.800026)
		(stroke
			(width 2.54)
			(type default)
		)
		(layer "In5.Cu")
	)
	(gr_arc
		(start 220.251528 -415.600134)
		(mid 220.800168 -416.148774)
		(end 221.348808 -415.600134)
		(stroke
			(width 0.2)
			(type default)
		)
		(layer "In5.Cu")
	)
	(gr_line
		(start 220.251528 -414.200086)
		(end 220.251528 -415.600134)
		(stroke
			(width 0.2)
			(type default)
		)
		(layer "In5.Cu")
	)
	(gr_arc
		(start 220.251528 -408.399996)
		(mid 220.800168 -408.948636)
		(end 221.348808 -408.399996)
		(stroke
			(width 0.2)
			(type default)
		)
		(layer "In5.Cu")
	)
	(gr_line
		(start 220.251528 -407.000202)
		(end 220.251528 -408.399996)
		(stroke
			(width 0.2)
			(type default)
		)
		(layer "In5.Cu")
	)
	(gr_arc
		(start 221.000066 38.800024)
		(mid 220.292973 38.507121)
		(end 220.000068 37.800026)
		(stroke
			(width 2.54)
			(type default)
		)
		(layer "In5.Cu")
	)
	(gr_line
		(start 221.000066 38.800024)
		(end 298.99991 38.800024)
		(stroke
			(width 2.54)
			(type default)
		)
		(layer "In5.Cu")
	)
	(gr_line
		(start 221.348808 -415.600134)
		(end 221.348808 -414.20034)
		(stroke
			(width 0.2)
			(type default)
		)
		(layer "In5.Cu")
	)
	(gr_arc
		(start 221.348808 -414.20034)
		(mid 220.800295 -413.651446)
		(end 220.251528 -414.200086)
		(stroke
			(width 0.2)
			(type default)
		)
		(layer "In5.Cu")
	)
	(gr_line
		(start 221.348808 -408.399996)
		(end 221.348808 -407.000456)
		(stroke
			(width 0.2)
			(type default)
		)
		(layer "In5.Cu")
	)
	(gr_arc
		(start 221.348808 -407.000456)
		(mid 220.800295 -406.451562)
		(end 220.251528 -407.000202)
		(stroke
			(width 0.2)
			(type default)
		)
		(layer "In5.Cu")
	)
	(gr_arc
		(start 222.051372 -418.200078)
		(mid 222.600012 -418.748718)
		(end 223.148652 -418.200078)
		(stroke
			(width 0.2)
			(type default)
		)
		(layer "In5.Cu")
	)
	(gr_line
		(start 222.051372 -416.80003)
		(end 222.051372 -418.200078)
		(stroke
			(width 0.2)
			(type default)
		)
		(layer "In5.Cu")
	)
	(gr_arc
		(start 222.051372 -407.399998)
		(mid 222.600012 -407.948638)
		(end 223.148652 -407.399998)
		(stroke
			(width 0.2)
			(type default)
		)
		(layer "In5.Cu")
	)
	(gr_line
		(start 222.051372 -405.99995)
		(end 222.051372 -407.399998)
		(stroke
			(width 0.2)
			(type default)
		)
		(layer "In5.Cu")
	)
	(gr_line
		(start 223.148652 -418.200078)
		(end 223.148652 -416.800284)
		(stroke
			(width 0.2)
			(type default)
		)
		(layer "In5.Cu")
	)
	(gr_arc
		(start 223.148652 -416.800284)
		(mid 222.600139 -416.25139)
		(end 222.051372 -416.80003)
		(stroke
			(width 0.2)
			(type default)
		)
		(layer "In5.Cu")
	)
	(gr_line
		(start 223.148652 -407.399998)
		(end 223.148652 -406.000204)
		(stroke
			(width 0.2)
			(type default)
		)
		(layer "In5.Cu")
	)
	(gr_arc
		(start 223.148652 -406.000204)
		(mid 222.600139 -405.45131)
		(end 222.051372 -405.99995)
		(stroke
			(width 0.2)
			(type default)
		)
		(layer "In5.Cu")
	)
	(gr_line
		(start 226.625404 0.814832)
		(end 213.9442 -11.866372)
		(stroke
			(width 0.381)
			(type default)
		)
		(layer "In5.Cu")
	)
	(gr_line
		(start 234.547918 -180.977286)
		(end 235.065824 -181.495192)
		(stroke
			(width 0.381)
			(type default)
		)
		(layer "In5.Cu")
	)
	(gr_line
		(start 234.547918 -102.46868)
		(end 234.547918 -180.977286)
		(stroke
			(width 0.381)
			(type default)
		)
		(layer "In5.Cu")
	)
	(gr_line
		(start 234.547918 -84.677504)
		(end 235.065824 -85.19541)
		(stroke
			(width 0.381)
			(type default)
		)
		(layer "In5.Cu")
	)
	(gr_line
		(start 234.547918 -6.168898)
		(end 234.547918 -84.677504)
		(stroke
			(width 0.381)
			(type default)
		)
		(layer "In5.Cu")
	)
	(gr_line
		(start 235.065824 -181.495192)
		(end 235.933742 -181.495192)
		(stroke
			(width 0.381)
			(type default)
		)
		(layer "In5.Cu")
	)
	(gr_line
		(start 235.065824 -85.19541)
		(end 235.933742 -85.19541)
		(stroke
			(width 0.381)
			(type default)
		)
		(layer "In5.Cu")
	)
	(gr_line
		(start 235.474002 -101.542596)
		(end 234.547918 -102.46868)
		(stroke
			(width 0.381)
			(type default)
		)
		(layer "In5.Cu")
	)
	(gr_line
		(start 235.474002 -5.242814)
		(end 234.547918 -6.168898)
		(stroke
			(width 0.381)
			(type default)
		)
		(layer "In5.Cu")
	)
	(gr_arc
		(start 235.722922 -121.845578)
		(mid 235.39577 -122.827034)
		(end 236.377226 -123.154186)
		(stroke
			(width 0.2)
			(type default)
		)
		(layer "In5.Cu")
	)
	(gr_line
		(start 235.723938 -65.548002)
		(end 235.725208 -65.550288)
		(stroke
			(width 0.2)
			(type default)
		)
		(layer "In5.Cu")
	)
	(gr_line
		(start 235.724192 -177.848006)
		(end 235.725208 -177.850038)
		(stroke
			(width 0.2)
			(type default)
		)
		(layer "In5.Cu")
	)
	(gr_line
		(start 235.724192 -177.847752)
		(end 235.724192 -177.848006)
		(stroke
			(width 0.2)
			(type default)
		)
		(layer "In5.Cu")
	)
	(gr_line
		(start 235.724192 -173.848014)
		(end 235.725208 -173.850046)
		(stroke
			(width 0.2)
			(type default)
		)
		(layer "In5.Cu")
	)
	(gr_line
		(start 235.724192 -173.84776)
		(end 235.724192 -173.848014)
		(stroke
			(width 0.2)
			(type default)
		)
		(layer "In5.Cu")
	)
	(gr_line
		(start 235.724192 -169.848022)
		(end 235.725208 -169.850054)
		(stroke
			(width 0.2)
			(type default)
		)
		(layer "In5.Cu")
	)
	(gr_line
		(start 235.724192 -169.847768)
		(end 235.724192 -169.848022)
		(stroke
			(width 0.2)
			(type default)
		)
		(layer "In5.Cu")
	)
	(gr_line
		(start 235.724192 -165.84803)
		(end 235.725208 -165.850062)
		(stroke
			(width 0.2)
			(type default)
		)
		(layer "In5.Cu")
	)
	(gr_line
		(start 235.724192 -165.847776)
		(end 235.724192 -165.84803)
		(stroke
			(width 0.2)
			(type default)
		)
		(layer "In5.Cu")
	)
	(gr_line
		(start 235.724192 -137.848086)
		(end 235.725208 -137.850118)
		(stroke
			(width 0.2)
			(type default)
		)
		(layer "In5.Cu")
	)
	(gr_line
		(start 235.724192 -137.847832)
		(end 235.724192 -137.848086)
		(stroke
			(width 0.2)
			(type default)
		)
		(layer "In5.Cu")
	)
	(gr_line
		(start 235.724192 -81.548224)
		(end 235.725208 -81.550256)
		(stroke
			(width 0.2)
			(type default)
		)
		(layer "In5.Cu")
	)
	(gr_line
		(start 235.724192 -81.54797)
		(end 235.724192 -81.548224)
		(stroke
			(width 0.2)
			(type default)
		)
		(layer "In5.Cu")
	)
	(gr_line
		(start 235.724192 -77.548232)
		(end 235.725208 -77.550264)
		(stroke
			(width 0.2)
			(type default)
		)
		(layer "In5.Cu")
	)
	(gr_line
		(start 235.724192 -77.547978)
		(end 235.724192 -77.548232)
		(stroke
			(width 0.2)
			(type default)
		)
		(layer "In5.Cu")
	)
	(gr_line
		(start 235.724192 -73.54824)
		(end 235.725208 -73.550272)
		(stroke
			(width 0.2)
			(type default)
		)
		(layer "In5.Cu")
	)
	(gr_line
		(start 235.724192 -73.547986)
		(end 235.724192 -73.54824)
		(stroke
			(width 0.2)
			(type default)
		)
		(layer "In5.Cu")
	)
	(gr_line
		(start 235.724192 -69.548248)
		(end 235.725208 -69.55028)
		(stroke
			(width 0.2)
			(type default)
		)
		(layer "In5.Cu")
	)
	(gr_line
		(start 235.724192 -69.547994)
		(end 235.724192 -69.548248)
		(stroke
			(width 0.2)
			(type default)
		)
		(layer "In5.Cu")
	)
	(gr_line
		(start 235.724192 -61.548264)
		(end 235.725208 -61.550296)
		(stroke
			(width 0.2)
			(type default)
		)
		(layer "In5.Cu")
	)
	(gr_line
		(start 235.724192 -61.54801)
		(end 235.724192 -61.548264)
		(stroke
			(width 0.2)
			(type default)
		)
		(layer "In5.Cu")
	)
	(gr_line
		(start 235.724192 -57.548272)
		(end 235.725208 -57.550304)
		(stroke
			(width 0.2)
			(type default)
		)
		(layer "In5.Cu")
	)
	(gr_line
		(start 235.724192 -57.548018)
		(end 235.724192 -57.548272)
		(stroke
			(width 0.2)
			(type default)
		)
		(layer "In5.Cu")
	)
	(gr_line
		(start 235.724192 -53.54828)
		(end 235.725208 -53.550312)
		(stroke
			(width 0.2)
			(type default)
		)
		(layer "In5.Cu")
	)
	(gr_line
		(start 235.724192 -53.548026)
		(end 235.724192 -53.54828)
		(stroke
			(width 0.2)
			(type default)
		)
		(layer "In5.Cu")
	)
	(gr_line
		(start 235.724192 -49.548288)
		(end 235.725208 -49.55032)
		(stroke
			(width 0.2)
			(type default)
		)
		(layer "In5.Cu")
	)
	(gr_line
		(start 235.724192 -49.548034)
		(end 235.724192 -49.548288)
		(stroke
			(width 0.2)
			(type default)
		)
		(layer "In5.Cu")
	)
	(gr_line
		(start 235.724192 -45.548296)
		(end 235.725208 -45.550328)
		(stroke
			(width 0.2)
			(type default)
		)
		(layer "In5.Cu")
	)
	(gr_line
		(start 235.724192 -45.548042)
		(end 235.724192 -45.548296)
		(stroke
			(width 0.2)
			(type default)
		)
		(layer "In5.Cu")
	)
	(gr_line
		(start 235.724192 -41.548304)
		(end 235.725208 -41.550336)
		(stroke
			(width 0.2)
			(type default)
		)
		(layer "In5.Cu")
	)
	(gr_line
		(start 235.724192 -41.54805)
		(end 235.724192 -41.548304)
		(stroke
			(width 0.2)
			(type default)
		)
		(layer "In5.Cu")
	)
	(gr_line
		(start 235.724192 -37.548312)
		(end 235.725208 -37.550344)
		(stroke
			(width 0.2)
			(type default)
		)
		(layer "In5.Cu")
	)
	(gr_line
		(start 235.724192 -37.548058)
		(end 235.724192 -37.548312)
		(stroke
			(width 0.2)
			(type default)
		)
		(layer "In5.Cu")
	)
	(gr_line
		(start 235.724192 -17.548352)
		(end 235.725208 -17.550384)
		(stroke
			(width 0.2)
			(type default)
		)
		(layer "In5.Cu")
	)
	(gr_line
		(start 235.724192 -17.548098)
		(end 235.724192 -17.548352)
		(stroke
			(width 0.2)
			(type default)
		)
		(layer "In5.Cu")
	)
	(gr_arc
		(start 235.725208 -177.850038)
		(mid 235.400342 -178.824636)
		(end 236.37494 -179.149502)
		(stroke
			(width 0.2)
			(type default)
		)
		(layer "In5.Cu")
	)
	(gr_arc
		(start 235.725208 -173.850046)
		(mid 235.400342 -174.824644)
		(end 236.37494 -175.14951)
		(stroke
			(width 0.2)
			(type default)
		)
		(layer "In5.Cu")
	)
	(gr_arc
		(start 235.725208 -169.850054)
		(mid 235.400342 -170.824652)
		(end 236.37494 -171.149518)
		(stroke
			(width 0.2)
			(type default)
		)
		(layer "In5.Cu")
	)
	(gr_arc
		(start 235.725208 -165.850062)
		(mid 235.400342 -166.82466)
		(end 236.37494 -167.149526)
		(stroke
			(width 0.2)
			(type default)
		)
		(layer "In5.Cu")
	)
	(gr_arc
		(start 235.725208 -137.850118)
		(mid 235.400342 -138.824716)
		(end 236.37494 -139.149582)
		(stroke
			(width 0.2)
			(type default)
		)
		(layer "In5.Cu")
	)
	(gr_arc
		(start 235.725208 -81.550256)
		(mid 235.400342 -82.524854)
		(end 236.37494 -82.84972)
		(stroke
			(width 0.2)
			(type default)
		)
		(layer "In5.Cu")
	)
	(gr_arc
		(start 235.725208 -77.550264)
		(mid 235.400342 -78.524862)
		(end 236.37494 -78.849728)
		(stroke
			(width 0.2)
			(type default)
		)
		(layer "In5.Cu")
	)
	(gr_arc
		(start 235.725208 -73.550272)
		(mid 235.400342 -74.52487)
		(end 236.37494 -74.849736)
		(stroke
			(width 0.2)
			(type default)
		)
		(layer "In5.Cu")
	)
	(gr_arc
		(start 235.725208 -69.55028)
		(mid 235.400342 -70.524878)
		(end 236.37494 -70.849744)
		(stroke
			(width 0.2)
			(type default)
		)
		(layer "In5.Cu")
	)
	(gr_arc
		(start 235.725208 -65.550288)
		(mid 235.400342 -66.524886)
		(end 236.37494 -66.849752)
		(stroke
			(width 0.2)
			(type default)
		)
		(layer "In5.Cu")
	)
	(gr_arc
		(start 235.725208 -61.550296)
		(mid 235.400342 -62.524894)
		(end 236.37494 -62.84976)
		(stroke
			(width 0.2)
			(type default)
		)
		(layer "In5.Cu")
	)
	(gr_arc
		(start 235.725208 -57.550304)
		(mid 235.400342 -58.524902)
		(end 236.37494 -58.849768)
		(stroke
			(width 0.2)
			(type default)
		)
		(layer "In5.Cu")
	)
	(gr_arc
		(start 235.725208 -53.550312)
		(mid 235.400342 -54.52491)
		(end 236.37494 -54.849776)
		(stroke
			(width 0.2)
			(type default)
		)
		(layer "In5.Cu")
	)
	(gr_arc
		(start 235.725208 -49.55032)
		(mid 235.400342 -50.524918)
		(end 236.37494 -50.849784)
		(stroke
			(width 0.2)
			(type default)
		)
		(layer "In5.Cu")
	)
	(gr_arc
		(start 235.725208 -45.550328)
		(mid 235.400342 -46.524926)
		(end 236.37494 -46.849792)
		(stroke
			(width 0.2)
			(type default)
		)
		(layer "In5.Cu")
	)
	(gr_arc
		(start 235.725208 -41.550336)
		(mid 235.400342 -42.524934)
		(end 236.37494 -42.8498)
		(stroke
			(width 0.2)
			(type default)
		)
		(layer "In5.Cu")
	)
	(gr_arc
		(start 235.725208 -37.550344)
		(mid 235.400342 -38.524942)
		(end 236.37494 -38.849808)
		(stroke
			(width 0.2)
			(type default)
		)
		(layer "In5.Cu")
	)
	(gr_arc
		(start 235.725208 -17.550384)
		(mid 235.400342 -18.524982)
		(end 236.37494 -18.849848)
		(stroke
			(width 0.2)
			(type default)
		)
		(layer "In5.Cu")
	)
	(gr_arc
		(start 235.733844 -161.840164)
		(mid 235.393447 -162.821194)
		(end 236.377226 -163.154106)
		(stroke
			(width 0.2)
			(type default)
		)
		(layer "In5.Cu")
	)
	(gr_arc
		(start 235.733844 -157.840172)
		(mid 235.393447 -158.821202)
		(end 236.377226 -159.154114)
		(stroke
			(width 0.2)
			(type default)
		)
		(layer "In5.Cu")
	)
	(gr_arc
		(start 235.733844 -153.84018)
		(mid 235.393447 -154.82121)
		(end 236.377226 -155.154122)
		(stroke
			(width 0.2)
			(type default)
		)
		(layer "In5.Cu")
	)
	(gr_arc
		(start 235.733844 -149.840188)
		(mid 235.393447 -150.821218)
		(end 236.377226 -151.15413)
		(stroke
			(width 0.2)
			(type default)
		)
		(layer "In5.Cu")
	)
	(gr_arc
		(start 235.733844 -129.840228)
		(mid 235.393447 -130.821258)
		(end 236.377226 -131.15417)
		(stroke
			(width 0.2)
			(type default)
		)
		(layer "In5.Cu")
	)
	(gr_arc
		(start 235.733844 -125.840236)
		(mid 235.393447 -126.821266)
		(end 236.377226 -127.154178)
		(stroke
			(width 0.2)
			(type default)
		)
		(layer "In5.Cu")
	)
	(gr_arc
		(start 235.733844 -117.840252)
		(mid 235.393447 -118.821282)
		(end 236.377226 -119.154194)
		(stroke
			(width 0.2)
			(type default)
		)
		(layer "In5.Cu")
	)
	(gr_arc
		(start 235.733844 -113.84026)
		(mid 235.393447 -114.82129)
		(end 236.377226 -115.154202)
		(stroke
			(width 0.2)
			(type default)
		)
		(layer "In5.Cu")
	)
	(gr_arc
		(start 235.733844 -11.54049)
		(mid 235.393447 -12.52152)
		(end 236.377226 -12.854432)
		(stroke
			(width 0.2)
			(type default)
		)
		(layer "In5.Cu")
	)
	(gr_line
		(start 235.933742 -181.495192)
		(end 237.300008 -180.128926)
		(stroke
			(width 0.381)
			(type default)
		)
		(layer "In5.Cu")
	)
	(gr_line
		(start 235.933742 -85.19541)
		(end 237.300008 -83.829144)
		(stroke
			(width 0.381)
			(type default)
		)
		(layer "In5.Cu")
	)
	(gr_line
		(start 236.37494 -179.149502)
		(end 236.37621 -179.151788)
		(stroke
			(width 0.2)
			(type default)
		)
		(layer "In5.Cu")
	)
	(gr_line
		(start 236.37494 -175.14951)
		(end 236.37621 -175.151796)
		(stroke
			(width 0.2)
			(type default)
		)
		(layer "In5.Cu")
	)
	(gr_line
		(start 236.37494 -171.149518)
		(end 236.37621 -171.151804)
		(stroke
			(width 0.2)
			(type default)
		)
		(layer "In5.Cu")
	)
	(gr_line
		(start 236.37494 -167.149526)
		(end 236.37621 -167.151812)
		(stroke
			(width 0.2)
			(type default)
		)
		(layer "In5.Cu")
	)
	(gr_line
		(start 236.37494 -139.149582)
		(end 236.37621 -139.151868)
		(stroke
			(width 0.2)
			(type default)
		)
		(layer "In5.Cu")
	)
	(gr_line
		(start 236.37494 -82.84972)
		(end 236.37621 -82.852006)
		(stroke
			(width 0.2)
			(type default)
		)
		(layer "In5.Cu")
	)
	(gr_line
		(start 236.37494 -78.849728)
		(end 236.37621 -78.852014)
		(stroke
			(width 0.2)
			(type default)
		)
		(layer "In5.Cu")
	)
	(gr_line
		(start 236.37494 -74.849736)
		(end 236.37621 -74.852022)
		(stroke
			(width 0.2)
			(type default)
		)
		(layer "In5.Cu")
	)
	(gr_line
		(start 236.37494 -70.849744)
		(end 236.37621 -70.85203)
		(stroke
			(width 0.2)
			(type default)
		)
		(layer "In5.Cu")
	)
	(gr_line
		(start 236.37494 -66.849752)
		(end 236.37621 -66.852038)
		(stroke
			(width 0.2)
			(type default)
		)
		(layer "In5.Cu")
	)
	(gr_line
		(start 236.37494 -62.84976)
		(end 236.37621 -62.852046)
		(stroke
			(width 0.2)
			(type default)
		)
		(layer "In5.Cu")
	)
	(gr_line
		(start 236.37494 -58.849768)
		(end 236.37621 -58.852054)
		(stroke
			(width 0.2)
			(type default)
		)
		(layer "In5.Cu")
	)
	(gr_line
		(start 236.37494 -54.849776)
		(end 236.37621 -54.852062)
		(stroke
			(width 0.2)
			(type default)
		)
		(layer "In5.Cu")
	)
	(gr_line
		(start 236.37494 -50.849784)
		(end 236.37621 -50.85207)
		(stroke
			(width 0.2)
			(type default)
		)
		(layer "In5.Cu")
	)
	(gr_line
		(start 236.37494 -46.849792)
		(end 236.37621 -46.852078)
		(stroke
			(width 0.2)
			(type default)
		)
		(layer "In5.Cu")
	)
	(gr_line
		(start 236.37494 -42.8498)
		(end 236.37621 -42.852086)
		(stroke
			(width 0.2)
			(type default)
		)
		(layer "In5.Cu")
	)
	(gr_line
		(start 236.37494 -38.849808)
		(end 236.37621 -38.852094)
		(stroke
			(width 0.2)
			(type default)
		)
		(layer "In5.Cu")
	)
	(gr_line
		(start 236.37494 -18.849848)
		(end 236.37621 -18.852134)
		(stroke
			(width 0.2)
			(type default)
		)
		(layer "In5.Cu")
	)
	(gr_line
		(start 236.37621 -179.151788)
		(end 238.376206 -178.15179)
		(stroke
			(width 0.2)
			(type default)
		)
		(layer "In5.Cu")
	)
	(gr_line
		(start 236.37621 -175.151796)
		(end 238.376206 -174.151798)
		(stroke
			(width 0.2)
			(type default)
		)
		(layer "In5.Cu")
	)
	(gr_line
		(start 236.37621 -171.151804)
		(end 238.376206 -170.151806)
		(stroke
			(width 0.2)
			(type default)
		)
		(layer "In5.Cu")
	)
	(gr_line
		(start 236.37621 -167.151812)
		(end 238.376206 -166.151814)
		(stroke
			(width 0.2)
			(type default)
		)
		(layer "In5.Cu")
	)
	(gr_line
		(start 236.37621 -139.151868)
		(end 238.376206 -138.15187)
		(stroke
			(width 0.2)
			(type default)
		)
		(layer "In5.Cu")
	)
	(gr_line
		(start 236.37621 -82.852006)
		(end 238.376206 -81.852008)
		(stroke
			(width 0.2)
			(type default)
		)
		(layer "In5.Cu")
	)
	(gr_line
		(start 236.37621 -78.852014)
		(end 238.376206 -77.852016)
		(stroke
			(width 0.2)
			(type default)
		)
		(layer "In5.Cu")
	)
	(gr_line
		(start 236.37621 -74.852022)
		(end 238.376206 -73.852024)
		(stroke
			(width 0.2)
			(type default)
		)
		(layer "In5.Cu")
	)
	(gr_line
		(start 236.37621 -70.85203)
		(end 238.376206 -69.852032)
		(stroke
			(width 0.2)
			(type default)
		)
		(layer "In5.Cu")
	)
	(gr_line
		(start 236.37621 -66.852038)
		(end 238.375952 -65.85204)
		(stroke
			(width 0.2)
			(type default)
		)
		(layer "In5.Cu")
	)
	(gr_line
		(start 236.37621 -62.852046)
		(end 238.376206 -61.852048)
		(stroke
			(width 0.2)
			(type default)
		)
		(layer "In5.Cu")
	)
	(gr_line
		(start 236.37621 -58.852054)
		(end 238.376206 -57.852056)
		(stroke
			(width 0.2)
			(type default)
		)
		(layer "In5.Cu")
	)
	(gr_line
		(start 236.37621 -54.852062)
		(end 238.376206 -53.852064)
		(stroke
			(width 0.2)
			(type default)
		)
		(layer "In5.Cu")
	)
	(gr_line
		(start 236.37621 -50.85207)
		(end 238.376206 -49.852072)
		(stroke
			(width 0.2)
			(type default)
		)
		(layer "In5.Cu")
	)
	(gr_line
		(start 236.37621 -46.852078)
		(end 238.376206 -45.85208)
		(stroke
			(width 0.2)
			(type default)
		)
		(layer "In5.Cu")
	)
	(gr_line
		(start 236.37621 -42.852086)
		(end 238.376206 -41.852088)
		(stroke
			(width 0.2)
			(type default)
		)
		(layer "In5.Cu")
	)
	(gr_line
		(start 236.37621 -38.852094)
		(end 238.376206 -37.852096)
		(stroke
			(width 0.2)
			(type default)
		)
		(layer "In5.Cu")
	)
	(gr_line
		(start 236.37621 -18.852134)
		(end 238.376206 -17.852136)
		(stroke
			(width 0.2)
			(type default)
		)
		(layer "In5.Cu")
	)
	(gr_line
		(start 236.377226 -163.154106)
		(end 238.377222 -162.154108)
		(stroke
			(width 0.2)
			(type default)
		)
		(layer "In5.Cu")
	)
	(gr_line
		(start 236.377226 -159.154114)
		(end 238.377222 -158.154116)
		(stroke
			(width 0.2)
			(type default)
		)
		(layer "In5.Cu")
	)
	(gr_line
		(start 236.377226 -155.154122)
		(end 238.377222 -154.154124)
		(stroke
			(width 0.2)
			(type default)
		)
		(layer "In5.Cu")
	)
	(gr_line
		(start 236.377226 -151.15413)
		(end 238.377222 -150.154132)
		(stroke
			(width 0.2)
			(type default)
		)
		(layer "In5.Cu")
	)
	(gr_line
		(start 236.377226 -131.15417)
		(end 238.377222 -130.154172)
		(stroke
			(width 0.2)
			(type default)
		)
		(layer "In5.Cu")
	)
	(gr_line
		(start 236.377226 -127.154178)
		(end 238.377222 -126.15418)
		(stroke
			(width 0.2)
			(type default)
		)
		(layer "In5.Cu")
	)
	(gr_line
		(start 236.377226 -123.154186)
		(end 238.3663 -122.159522)
		(stroke
			(width 0.2)
			(type default)
		)
		(layer "In5.Cu")
	)
	(gr_line
		(start 236.377226 -119.154194)
		(end 238.377222 -118.154196)
		(stroke
			(width 0.2)
			(type default)
		)
		(layer "In5.Cu")
	)
	(gr_line
		(start 236.377226 -115.154202)
		(end 238.377222 -114.154204)
		(stroke
			(width 0.2)
			(type default)
		)
		(layer "In5.Cu")
	)
	(gr_line
		(start 236.377226 -12.854432)
		(end 238.377222 -11.854434)
		(stroke
			(width 0.2)
			(type default)
		)
		(layer "In5.Cu")
	)
	(gr_line
		(start 236.482128 -101.542596)
		(end 235.474002 -101.542596)
		(stroke
			(width 0.381)
			(type default)
		)
		(layer "In5.Cu")
	)
	(gr_line
		(start 236.482128 -5.242814)
		(end 235.474002 -5.242814)
		(stroke
			(width 0.381)
			(type default)
		)
		(layer "In5.Cu")
	)
	(gr_line
		(start 237.300008 -180.128926)
		(end 238.317024 -180.128926)
		(stroke
			(width 0.381)
			(type default)
		)
		(layer "In5.Cu")
	)
	(gr_line
		(start 237.300008 -83.829144)
		(end 238.317024 -83.829144)
		(stroke
			(width 0.381)
			(type default)
		)
		(layer "In5.Cu")
	)
	(gr_line
		(start 237.47857 -102.539038)
		(end 236.482128 -101.542596)
		(stroke
			(width 0.381)
			(type default)
		)
		(layer "In5.Cu")
	)
	(gr_line
		(start 237.47857 -6.239256)
		(end 236.482128 -5.242814)
		(stroke
			(width 0.381)
			(type default)
		)
		(layer "In5.Cu")
	)
	(gr_line
		(start 237.722918 -160.8455)
		(end 235.733844 -161.840164)
		(stroke
			(width 0.2)
			(type default)
		)
		(layer "In5.Cu")
	)
	(gr_line
		(start 237.722918 -156.845508)
		(end 235.733844 -157.840172)
		(stroke
			(width 0.2)
			(type default)
		)
		(layer "In5.Cu")
	)
	(gr_line
		(start 237.722918 -152.845516)
		(end 235.733844 -153.84018)
		(stroke
			(width 0.2)
			(type default)
		)
		(layer "In5.Cu")
	)
	(gr_line
		(start 237.722918 -148.845524)
		(end 235.733844 -149.840188)
		(stroke
			(width 0.2)
			(type default)
		)
		(layer "In5.Cu")
	)
	(gr_line
		(start 237.722918 -128.845564)
		(end 235.733844 -129.840228)
		(stroke
			(width 0.2)
			(type default)
		)
		(layer "In5.Cu")
	)
	(gr_line
		(start 237.722918 -124.845572)
		(end 235.733844 -125.840236)
		(stroke
			(width 0.2)
			(type default)
		)
		(layer "In5.Cu")
	)
	(gr_line
		(start 237.722918 -120.84558)
		(end 235.722922 -121.845578)
		(stroke
			(width 0.2)
			(type default)
		)
		(layer "In5.Cu")
	)
	(gr_line
		(start 237.722918 -116.845588)
		(end 235.733844 -117.840252)
		(stroke
			(width 0.2)
			(type default)
		)
		(layer "In5.Cu")
	)
	(gr_line
		(start 237.722918 -112.845596)
		(end 235.733844 -113.84026)
		(stroke
			(width 0.2)
			(type default)
		)
		(layer "In5.Cu")
	)
	(gr_line
		(start 237.722918 -10.545826)
		(end 235.733844 -11.54049)
		(stroke
			(width 0.2)
			(type default)
		)
		(layer "In5.Cu")
	)
	(gr_line
		(start 237.723934 -176.847754)
		(end 235.724192 -177.847752)
		(stroke
			(width 0.2)
			(type default)
		)
		(layer "In5.Cu")
	)
	(gr_line
		(start 237.723934 -172.847762)
		(end 235.724192 -173.84776)
		(stroke
			(width 0.2)
			(type default)
		)
		(layer "In5.Cu")
	)
	(gr_line
		(start 237.723934 -168.84777)
		(end 235.724192 -169.847768)
		(stroke
			(width 0.2)
			(type default)
		)
		(layer "In5.Cu")
	)
	(gr_line
		(start 237.723934 -164.847778)
		(end 235.724192 -165.847776)
		(stroke
			(width 0.2)
			(type default)
		)
		(layer "In5.Cu")
	)
	(gr_line
		(start 237.723934 -136.847834)
		(end 235.724192 -137.847832)
		(stroke
			(width 0.2)
			(type default)
		)
		(layer "In5.Cu")
	)
	(gr_line
		(start 237.723934 -80.547972)
		(end 235.724192 -81.54797)
		(stroke
			(width 0.2)
			(type default)
		)
		(layer "In5.Cu")
	)
	(gr_line
		(start 237.723934 -76.54798)
		(end 235.724192 -77.547978)
		(stroke
			(width 0.2)
			(type default)
		)
		(layer "In5.Cu")
	)
	(gr_line
		(start 237.723934 -72.547988)
		(end 235.724192 -73.547986)
		(stroke
			(width 0.2)
			(type default)
		)
		(layer "In5.Cu")
	)
	(gr_line
		(start 237.723934 -68.547996)
		(end 235.724192 -69.547994)
		(stroke
			(width 0.2)
			(type default)
		)
		(layer "In5.Cu")
	)
	(gr_line
		(start 237.723934 -64.548004)
		(end 235.723938 -65.548002)
		(stroke
			(width 0.2)
			(type default)
		)
		(layer "In5.Cu")
	)
	(gr_line
		(start 237.723934 -60.548012)
		(end 235.724192 -61.54801)
		(stroke
			(width 0.2)
			(type default)
		)
		(layer "In5.Cu")
	)
	(gr_line
		(start 237.723934 -56.54802)
		(end 235.724192 -57.548018)
		(stroke
			(width 0.2)
			(type default)
		)
		(layer "In5.Cu")
	)
	(gr_line
		(start 237.723934 -52.548028)
		(end 235.724192 -53.548026)
		(stroke
			(width 0.2)
			(type default)
		)
		(layer "In5.Cu")
	)
	(gr_line
		(start 237.723934 -48.548036)
		(end 235.724192 -49.548034)
		(stroke
			(width 0.2)
			(type default)
		)
		(layer "In5.Cu")
	)
	(gr_line
		(start 237.723934 -44.548044)
		(end 235.724192 -45.548042)
		(stroke
			(width 0.2)
			(type default)
		)
		(layer "In5.Cu")
	)
	(gr_line
		(start 237.723934 -40.548052)
		(end 235.724192 -41.54805)
		(stroke
			(width 0.2)
			(type default)
		)
		(layer "In5.Cu")
	)
	(gr_line
		(start 237.723934 -36.54806)
		(end 235.724192 -37.548058)
		(stroke
			(width 0.2)
			(type default)
		)
		(layer "In5.Cu")
	)
	(gr_line
		(start 237.723934 -16.5481)
		(end 235.724192 -17.548098)
		(stroke
			(width 0.2)
			(type default)
		)
		(layer "In5.Cu")
	)
	(gr_line
		(start 237.725204 -176.85004)
		(end 237.723934 -176.847754)
		(stroke
			(width 0.2)
			(type default)
		)
		(layer "In5.Cu")
	)
	(gr_line
		(start 237.725204 -172.850048)
		(end 237.723934 -172.847762)
		(stroke
			(width 0.2)
			(type default)
		)
		(layer "In5.Cu")
	)
	(gr_line
		(start 237.725204 -168.850056)
		(end 237.723934 -168.84777)
		(stroke
			(width 0.2)
			(type default)
		)
		(layer "In5.Cu")
	)
	(gr_line
		(start 237.725204 -164.850064)
		(end 237.723934 -164.847778)
		(stroke
			(width 0.2)
			(type default)
		)
		(layer "In5.Cu")
	)
	(gr_line
		(start 237.725204 -136.85012)
		(end 237.723934 -136.847834)
		(stroke
			(width 0.2)
			(type default)
		)
		(layer "In5.Cu")
	)
	(gr_line
		(start 237.725204 -80.550258)
		(end 237.723934 -80.547972)
		(stroke
			(width 0.2)
			(type default)
		)
		(layer "In5.Cu")
	)
	(gr_line
		(start 237.725204 -76.550266)
		(end 237.723934 -76.54798)
		(stroke
			(width 0.2)
			(type default)
		)
		(layer "In5.Cu")
	)
	(gr_line
		(start 237.725204 -72.550274)
		(end 237.723934 -72.547988)
		(stroke
			(width 0.2)
			(type default)
		)
		(layer "In5.Cu")
	)
	(gr_line
		(start 237.725204 -68.550282)
		(end 237.723934 -68.547996)
		(stroke
			(width 0.2)
			(type default)
		)
		(layer "In5.Cu")
	)
	(gr_line
		(start 237.725204 -64.55029)
		(end 237.723934 -64.548004)
		(stroke
			(width 0.2)
			(type default)
		)
		(layer "In5.Cu")
	)
	(gr_line
		(start 237.725204 -60.550298)
		(end 237.723934 -60.548012)
		(stroke
			(width 0.2)
			(type default)
		)
		(layer "In5.Cu")
	)
	(gr_line
		(start 237.725204 -56.550306)
		(end 237.723934 -56.54802)
		(stroke
			(width 0.2)
			(type default)
		)
		(layer "In5.Cu")
	)
	(gr_line
		(start 237.725204 -52.550314)
		(end 237.723934 -52.548028)
		(stroke
			(width 0.2)
			(type default)
		)
		(layer "In5.Cu")
	)
	(gr_line
		(start 237.725204 -48.550322)
		(end 237.723934 -48.548036)
		(stroke
			(width 0.2)
			(type default)
		)
		(layer "In5.Cu")
	)
	(gr_line
		(start 237.725204 -44.55033)
		(end 237.723934 -44.548044)
		(stroke
			(width 0.2)
			(type default)
		)
		(layer "In5.Cu")
	)
	(gr_line
		(start 237.725204 -40.550338)
		(end 237.723934 -40.548052)
		(stroke
			(width 0.2)
			(type default)
		)
		(layer "In5.Cu")
	)
	(gr_line
		(start 237.725204 -36.550346)
		(end 237.723934 -36.54806)
		(stroke
			(width 0.2)
			(type default)
		)
		(layer "In5.Cu")
	)
	(gr_line
		(start 237.725204 -16.550386)
		(end 237.723934 -16.5481)
		(stroke
			(width 0.2)
			(type default)
		)
		(layer "In5.Cu")
	)
	(gr_circle
		(center 238.317024 -180.12918)
		(end 238.317278 -180.12918)
		(stroke
			(width 0.381)
			(type default)
		)
		(fill no)
		(layer "In5.Cu")
	)
	(gr_line
		(start 238.317024 -180.128926)
		(end 241.821462 -183.633364)
		(stroke
			(width 0.381)
			(type default)
		)
		(layer "In5.Cu")
	)
	(gr_line
		(start 238.317024 -83.829144)
		(end 241.821462 -87.333582)
		(stroke
			(width 0.381)
			(type default)
		)
		(layer "In5.Cu")
	)
	(gr_arc
		(start 238.3663 -122.159522)
		(mid 238.706697 -121.178492)
		(end 237.722918 -120.84558)
		(stroke
			(width 0.2)
			(type default)
		)
		(layer "In5.Cu")
	)
	(gr_arc
		(start 238.374936 -178.149504)
		(mid 238.699802 -177.174906)
		(end 237.725204 -176.85004)
		(stroke
			(width 0.2)
			(type default)
		)
		(layer "In5.Cu")
	)
	(gr_arc
		(start 238.374936 -174.149512)
		(mid 238.699802 -173.174914)
		(end 237.725204 -172.850048)
		(stroke
			(width 0.2)
			(type default)
		)
		(layer "In5.Cu")
	)
	(gr_arc
		(start 238.374936 -170.14952)
		(mid 238.699802 -169.174922)
		(end 237.725204 -168.850056)
		(stroke
			(width 0.2)
			(type default)
		)
		(layer "In5.Cu")
	)
	(gr_arc
		(start 238.374936 -166.149528)
		(mid 238.699802 -165.17493)
		(end 237.725204 -164.850064)
		(stroke
			(width 0.2)
			(type default)
		)
		(layer "In5.Cu")
	)
	(gr_arc
		(start 238.374936 -138.149584)
		(mid 238.699802 -137.174986)
		(end 237.725204 -136.85012)
		(stroke
			(width 0.2)
			(type default)
		)
		(layer "In5.Cu")
	)
	(gr_arc
		(start 238.374936 -81.849722)
		(mid 238.699802 -80.875124)
		(end 237.725204 -80.550258)
		(stroke
			(width 0.2)
			(type default)
		)
		(layer "In5.Cu")
	)
	(gr_arc
		(start 238.374936 -77.84973)
		(mid 238.699802 -76.875132)
		(end 237.725204 -76.550266)
		(stroke
			(width 0.2)
			(type default)
		)
		(layer "In5.Cu")
	)
	(gr_arc
		(start 238.374936 -73.849738)
		(mid 238.699802 -72.87514)
		(end 237.725204 -72.550274)
		(stroke
			(width 0.2)
			(type default)
		)
		(layer "In5.Cu")
	)
	(gr_arc
		(start 238.374936 -69.849746)
		(mid 238.699802 -68.875148)
		(end 237.725204 -68.550282)
		(stroke
			(width 0.2)
			(type default)
		)
		(layer "In5.Cu")
	)
	(gr_arc
		(start 238.374936 -65.849754)
		(mid 238.699802 -64.875156)
		(end 237.725204 -64.55029)
		(stroke
			(width 0.2)
			(type default)
		)
		(layer "In5.Cu")
	)
	(gr_arc
		(start 238.374936 -61.849762)
		(mid 238.699802 -60.875164)
		(end 237.725204 -60.550298)
		(stroke
			(width 0.2)
			(type default)
		)
		(layer "In5.Cu")
	)
	(gr_arc
		(start 238.374936 -57.84977)
		(mid 238.699802 -56.875172)
		(end 237.725204 -56.550306)
		(stroke
			(width 0.2)
			(type default)
		)
		(layer "In5.Cu")
	)
	(gr_arc
		(start 238.374936 -53.849778)
		(mid 238.699802 -52.87518)
		(end 237.725204 -52.550314)
		(stroke
			(width 0.2)
			(type default)
		)
		(layer "In5.Cu")
	)
	(gr_arc
		(start 238.374936 -49.849786)
		(mid 238.699802 -48.875188)
		(end 237.725204 -48.550322)
		(stroke
			(width 0.2)
			(type default)
		)
		(layer "In5.Cu")
	)
	(gr_arc
		(start 238.374936 -45.849794)
		(mid 238.699802 -44.875196)
		(end 237.725204 -44.55033)
		(stroke
			(width 0.2)
			(type default)
		)
		(layer "In5.Cu")
	)
	(gr_arc
		(start 238.374936 -41.849802)
		(mid 238.699802 -40.875204)
		(end 237.725204 -40.550338)
		(stroke
			(width 0.2)
			(type default)
		)
		(layer "In5.Cu")
	)
	(gr_arc
		(start 238.374936 -37.84981)
		(mid 238.699802 -36.875212)
		(end 237.725204 -36.550346)
		(stroke
			(width 0.2)
			(type default)
		)
		(layer "In5.Cu")
	)
	(gr_arc
		(start 238.374936 -17.84985)
		(mid 238.699802 -16.875252)
		(end 237.725204 -16.550386)
		(stroke
			(width 0.2)
			(type default)
		)
		(layer "In5.Cu")
	)
	(gr_line
		(start 238.375952 -65.85204)
		(end 238.375952 -65.851786)
		(stroke
			(width 0.2)
			(type default)
		)
		(layer "In5.Cu")
	)
	(gr_line
		(start 238.375952 -65.851786)
		(end 238.374936 -65.849754)
		(stroke
			(width 0.2)
			(type default)
		)
		(layer "In5.Cu")
	)
	(gr_line
		(start 238.376206 -178.15179)
		(end 238.374936 -178.149504)
		(stroke
			(width 0.2)
			(type default)
		)
		(layer "In5.Cu")
	)
	(gr_line
		(start 238.376206 -174.151798)
		(end 238.374936 -174.149512)
		(stroke
			(width 0.2)
			(type default)
		)
		(layer "In5.Cu")
	)
	(gr_line
		(start 238.376206 -170.151806)
		(end 238.374936 -170.14952)
		(stroke
			(width 0.2)
			(type default)
		)
		(layer "In5.Cu")
	)
	(gr_line
		(start 238.376206 -166.151814)
		(end 238.374936 -166.149528)
		(stroke
			(width 0.2)
			(type default)
		)
		(layer "In5.Cu")
	)
	(gr_line
		(start 238.376206 -138.15187)
		(end 238.374936 -138.149584)
		(stroke
			(width 0.2)
			(type default)
		)
		(layer "In5.Cu")
	)
	(gr_line
		(start 238.376206 -81.852008)
		(end 238.374936 -81.849722)
		(stroke
			(width 0.2)
			(type default)
		)
		(layer "In5.Cu")
	)
	(gr_line
		(start 238.376206 -77.852016)
		(end 238.374936 -77.84973)
		(stroke
			(width 0.2)
			(type default)
		)
		(layer "In5.Cu")
	)
	(gr_line
		(start 238.376206 -73.852024)
		(end 238.374936 -73.849738)
		(stroke
			(width 0.2)
			(type default)
		)
		(layer "In5.Cu")
	)
	(gr_line
		(start 238.376206 -69.852032)
		(end 238.374936 -69.849746)
		(stroke
			(width 0.2)
			(type default)
		)
		(layer "In5.Cu")
	)
	(gr_line
		(start 238.376206 -61.852048)
		(end 238.374936 -61.849762)
		(stroke
			(width 0.2)
			(type default)
		)
		(layer "In5.Cu")
	)
	(gr_line
		(start 238.376206 -57.852056)
		(end 238.374936 -57.84977)
		(stroke
			(width 0.2)
			(type default)
		)
		(layer "In5.Cu")
	)
	(gr_line
		(start 238.376206 -53.852064)
		(end 238.374936 -53.849778)
		(stroke
			(width 0.2)
			(type default)
		)
		(layer "In5.Cu")
	)
	(gr_line
		(start 238.376206 -49.852072)
		(end 238.374936 -49.849786)
		(stroke
			(width 0.2)
			(type default)
		)
		(layer "In5.Cu")
	)
	(gr_line
		(start 238.376206 -45.85208)
		(end 238.374936 -45.849794)
		(stroke
			(width 0.2)
			(type default)
		)
		(layer "In5.Cu")
	)
	(gr_line
		(start 238.376206 -41.852088)
		(end 238.374936 -41.849802)
		(stroke
			(width 0.2)
			(type default)
		)
		(layer "In5.Cu")
	)
	(gr_line
		(start 238.376206 -37.852096)
		(end 238.374936 -37.84981)
		(stroke
			(width 0.2)
			(type default)
		)
		(layer "In5.Cu")
	)
	(gr_line
		(start 238.376206 -17.852136)
		(end 238.374936 -17.84985)
		(stroke
			(width 0.2)
			(type default)
		)
		(layer "In5.Cu")
	)
	(gr_arc
		(start 238.377222 -162.154108)
		(mid 238.704374 -161.172652)
		(end 237.722918 -160.8455)
		(stroke
			(width 0.2)
			(type default)
		)
		(layer "In5.Cu")
	)
	(gr_arc
		(start 238.377222 -158.154116)
		(mid 238.704374 -157.17266)
		(end 237.722918 -156.845508)
		(stroke
			(width 0.2)
			(type default)
		)
		(layer "In5.Cu")
	)
	(gr_arc
		(start 238.377222 -154.154124)
		(mid 238.704374 -153.172668)
		(end 237.722918 -152.845516)
		(stroke
			(width 0.2)
			(type default)
		)
		(layer "In5.Cu")
	)
	(gr_arc
		(start 238.377222 -150.154132)
		(mid 238.704374 -149.172676)
		(end 237.722918 -148.845524)
		(stroke
			(width 0.2)
			(type default)
		)
		(layer "In5.Cu")
	)
	(gr_arc
		(start 238.377222 -130.154172)
		(mid 238.704374 -129.172716)
		(end 237.722918 -128.845564)
		(stroke
			(width 0.2)
			(type default)
		)
		(layer "In5.Cu")
	)
	(gr_arc
		(start 238.377222 -126.15418)
		(mid 238.704374 -125.172724)
		(end 237.722918 -124.845572)
		(stroke
			(width 0.2)
			(type default)
		)
		(layer "In5.Cu")
	)
	(gr_arc
		(start 238.377222 -118.154196)
		(mid 238.704374 -117.17274)
		(end 237.722918 -116.845588)
		(stroke
			(width 0.2)
			(type default)
		)
		(layer "In5.Cu")
	)
	(gr_arc
		(start 238.377222 -114.154204)
		(mid 238.704374 -113.172748)
		(end 237.722918 -112.845596)
		(stroke
			(width 0.2)
			(type default)
		)
		(layer "In5.Cu")
	)
	(gr_arc
		(start 238.377222 -11.854434)
		(mid 238.704374 -10.872978)
		(end 237.722918 -10.545826)
		(stroke
			(width 0.2)
			(type default)
		)
		(layer "In5.Cu")
	)
	(gr_line
		(start 240.219484 -128.161034)
		(end 242.21948 -129.161032)
		(stroke
			(width 0.2)
			(type default)
		)
		(layer "In5.Cu")
	)
	(gr_line
		(start 240.219484 -124.161042)
		(end 242.20805 -125.155198)
		(stroke
			(width 0.2)
			(type default)
		)
		(layer "In5.Cu")
	)
	(gr_line
		(start 240.222786 -164.154104)
		(end 242.222782 -165.154102)
		(stroke
			(width 0.2)
			(type default)
		)
		(layer "In5.Cu")
	)
	(gr_line
		(start 240.222786 -160.154112)
		(end 242.222528 -161.15411)
		(stroke
			(width 0.2)
			(type default)
		)
		(layer "In5.Cu")
	)
	(gr_line
		(start 240.222786 -156.15412)
		(end 242.222528 -157.154118)
		(stroke
			(width 0.2)
			(type default)
		)
		(layer "In5.Cu")
	)
	(gr_line
		(start 240.222786 -152.154128)
		(end 242.222782 -153.154126)
		(stroke
			(width 0.2)
			(type default)
		)
		(layer "In5.Cu")
	)
	(gr_line
		(start 240.222786 -120.154192)
		(end 242.222528 -121.15419)
		(stroke
			(width 0.2)
			(type default)
		)
		(layer "In5.Cu")
	)
	(gr_line
		(start 240.222786 -116.1542)
		(end 242.222782 -117.154198)
		(stroke
			(width 0.2)
			(type default)
		)
		(layer "In5.Cu")
	)
	(gr_line
		(start 240.223802 -136.151874)
		(end 242.223798 -137.151872)
		(stroke
			(width 0.2)
			(type default)
		)
		(layer "In5.Cu")
	)
	(gr_line
		(start 240.223802 -108.15193)
		(end 242.223798 -109.151928)
		(stroke
			(width 0.2)
			(type default)
		)
		(layer "In5.Cu")
	)
	(gr_line
		(start 240.223802 -35.8521)
		(end 242.223798 -36.852098)
		(stroke
			(width 0.2)
			(type default)
		)
		(layer "In5.Cu")
	)
	(gr_line
		(start 240.225072 -136.149588)
		(end 240.223802 -136.151874)
		(stroke
			(width 0.2)
			(type default)
		)
		(layer "In5.Cu")
	)
	(gr_line
		(start 240.225072 -108.149644)
		(end 240.223802 -108.15193)
		(stroke
			(width 0.2)
			(type default)
		)
		(layer "In5.Cu")
	)
	(gr_line
		(start 240.236502 -180.126894)
		(end 242.236498 -181.126892)
		(stroke
			(width 0.2)
			(type default)
		)
		(layer "In5.Cu")
	)
	(gr_line
		(start 240.236502 -176.126902)
		(end 242.236498 -177.1269)
		(stroke
			(width 0.2)
			(type default)
		)
		(layer "In5.Cu")
	)
	(gr_line
		(start 240.236502 -172.12691)
		(end 242.236498 -173.126908)
		(stroke
			(width 0.2)
			(type default)
		)
		(layer "In5.Cu")
	)
	(gr_line
		(start 240.236502 -168.126918)
		(end 242.236498 -169.126916)
		(stroke
			(width 0.2)
			(type default)
		)
		(layer "In5.Cu")
	)
	(gr_line
		(start 240.236502 -83.827112)
		(end 242.236498 -84.82711)
		(stroke
			(width 0.2)
			(type default)
		)
		(layer "In5.Cu")
	)
	(gr_line
		(start 240.236502 -79.82712)
		(end 242.228116 -80.8228)
		(stroke
			(width 0.2)
			(type default)
		)
		(layer "In5.Cu")
	)
	(gr_line
		(start 240.236502 -75.827128)
		(end 242.228116 -76.822808)
		(stroke
			(width 0.2)
			(type default)
		)
		(layer "In5.Cu")
	)
	(gr_line
		(start 240.236502 -71.827136)
		(end 242.228116 -72.822816)
		(stroke
			(width 0.2)
			(type default)
		)
		(layer "In5.Cu")
	)
	(gr_line
		(start 240.236502 -67.827144)
		(end 242.236498 -68.827142)
		(stroke
			(width 0.2)
			(type default)
		)
		(layer "In5.Cu")
	)
	(gr_line
		(start 240.236502 -63.827152)
		(end 242.236498 -64.82715)
		(stroke
			(width 0.2)
			(type default)
		)
		(layer "In5.Cu")
	)
	(gr_line
		(start 240.236502 -59.82716)
		(end 242.236498 -60.827158)
		(stroke
			(width 0.2)
			(type default)
		)
		(layer "In5.Cu")
	)
	(gr_line
		(start 240.236502 -55.827168)
		(end 242.236498 -56.827166)
		(stroke
			(width 0.2)
			(type default)
		)
		(layer "In5.Cu")
	)
	(gr_line
		(start 240.236502 -51.827176)
		(end 242.228116 -52.822856)
		(stroke
			(width 0.2)
			(type default)
		)
		(layer "In5.Cu")
	)
	(gr_line
		(start 240.236502 -47.827184)
		(end 242.236498 -48.827182)
		(stroke
			(width 0.2)
			(type default)
		)
		(layer "In5.Cu")
	)
	(gr_line
		(start 240.236502 -43.827192)
		(end 242.236498 -44.82719)
		(stroke
			(width 0.2)
			(type default)
		)
		(layer "In5.Cu")
	)
	(gr_line
		(start 240.236502 -39.8272)
		(end 242.236498 -40.827198)
		(stroke
			(width 0.2)
			(type default)
		)
		(layer "In5.Cu")
	)
	(gr_line
		(start 240.284 -197.8406)
		(end 245.999 -197.8406)
		(stroke
			(width 0.381)
			(type default)
		)
		(layer "In5.Cu")
	)
	(gr_arc
		(start 240.863374 -78.572868)
		(mid 239.922812 -78.886558)
		(end 240.236502 -79.82712)
		(stroke
			(width 0.2)
			(type default)
		)
		(layer "In5.Cu")
	)
	(gr_arc
		(start 240.863374 -74.572876)
		(mid 239.922812 -74.886566)
		(end 240.236502 -75.827128)
		(stroke
			(width 0.2)
			(type default)
		)
		(layer "In5.Cu")
	)
	(gr_arc
		(start 240.863374 -70.572884)
		(mid 239.922812 -70.886574)
		(end 240.236502 -71.827136)
		(stroke
			(width 0.2)
			(type default)
		)
		(layer "In5.Cu")
	)
	(gr_arc
		(start 240.863374 -50.572924)
		(mid 239.922812 -50.886614)
		(end 240.236502 -51.827176)
		(stroke
			(width 0.2)
			(type default)
		)
		(layer "In5.Cu")
	)
	(gr_arc
		(start 240.871756 -178.87696)
		(mid 239.92498 -179.182145)
		(end 240.236502 -180.126894)
		(stroke
			(width 0.2)
			(type default)
		)
		(layer "In5.Cu")
	)
	(gr_arc
		(start 240.871756 -174.876968)
		(mid 239.92498 -175.182153)
		(end 240.236502 -176.126902)
		(stroke
			(width 0.2)
			(type default)
		)
		(layer "In5.Cu")
	)
	(gr_arc
		(start 240.871756 -170.876976)
		(mid 239.92498 -171.182161)
		(end 240.236502 -172.12691)
		(stroke
			(width 0.2)
			(type default)
		)
		(layer "In5.Cu")
	)
	(gr_arc
		(start 240.871756 -166.876984)
		(mid 239.92498 -167.182169)
		(end 240.236502 -168.126918)
		(stroke
			(width 0.2)
			(type default)
		)
		(layer "In5.Cu")
	)
	(gr_arc
		(start 240.871756 -82.577178)
		(mid 239.92498 -82.882363)
		(end 240.236502 -83.827112)
		(stroke
			(width 0.2)
			(type default)
		)
		(layer "In5.Cu")
	)
	(gr_arc
		(start 240.871756 -66.57721)
		(mid 239.92498 -66.882395)
		(end 240.236502 -67.827144)
		(stroke
			(width 0.2)
			(type default)
		)
		(layer "In5.Cu")
	)
	(gr_arc
		(start 240.871756 -62.577218)
		(mid 239.92498 -62.882403)
		(end 240.236502 -63.827152)
		(stroke
			(width 0.2)
			(type default)
		)
		(layer "In5.Cu")
	)
	(gr_arc
		(start 240.871756 -58.577226)
		(mid 239.92498 -58.882411)
		(end 240.236502 -59.82716)
		(stroke
			(width 0.2)
			(type default)
		)
		(layer "In5.Cu")
	)
	(gr_arc
		(start 240.871756 -54.577234)
		(mid 239.92498 -54.882419)
		(end 240.236502 -55.827168)
		(stroke
			(width 0.2)
			(type default)
		)
		(layer "In5.Cu")
	)
	(gr_arc
		(start 240.871756 -46.57725)
		(mid 239.92498 -46.882435)
		(end 240.236502 -47.827184)
		(stroke
			(width 0.2)
			(type default)
		)
		(layer "In5.Cu")
	)
	(gr_arc
		(start 240.871756 -42.577258)
		(mid 239.92498 -42.882443)
		(end 240.236502 -43.827192)
		(stroke
			(width 0.2)
			(type default)
		)
		(layer "In5.Cu")
	)
	(gr_arc
		(start 240.871756 -38.577266)
		(mid 239.92498 -38.882451)
		(end 240.236502 -39.8272)
		(stroke
			(width 0.2)
			(type default)
		)
		(layer "In5.Cu")
	)
	(gr_arc
		(start 240.874804 -134.850124)
		(mid 239.900206 -135.17499)
		(end 240.225072 -136.149588)
		(stroke
			(width 0.2)
			(type default)
		)
		(layer "In5.Cu")
	)
	(gr_arc
		(start 240.874804 -106.85018)
		(mid 239.900206 -107.175046)
		(end 240.225072 -108.149644)
		(stroke
			(width 0.2)
			(type default)
		)
		(layer "In5.Cu")
	)
	(gr_line
		(start 240.876074 -134.847838)
		(end 240.874804 -134.850124)
		(stroke
			(width 0.2)
			(type default)
		)
		(layer "In5.Cu")
	)
	(gr_line
		(start 240.876074 -106.847894)
		(end 240.874804 -106.85018)
		(stroke
			(width 0.2)
			(type default)
		)
		(layer "In5.Cu")
	)
	(gr_arc
		(start 240.876074 -34.548064)
		(mid 239.89792 -34.873946)
		(end 240.223802 -35.8521)
		(stroke
			(width 0.2)
			(type default)
		)
		(layer "In5.Cu")
	)
	(gr_arc
		(start 240.87709 -158.845504)
		(mid 239.895634 -159.172656)
		(end 240.222786 -160.154112)
		(stroke
			(width 0.2)
			(type default)
		)
		(layer "In5.Cu")
	)
	(gr_arc
		(start 240.87709 -154.845512)
		(mid 239.895634 -155.172664)
		(end 240.222786 -156.15412)
		(stroke
			(width 0.2)
			(type default)
		)
		(layer "In5.Cu")
	)
	(gr_arc
		(start 240.87709 -118.845584)
		(mid 239.895634 -119.172736)
		(end 240.222786 -120.154192)
		(stroke
			(width 0.2)
			(type default)
		)
		(layer "In5.Cu")
	)
	(gr_arc
		(start 240.877344 -162.845496)
		(mid 239.895939 -163.172546)
		(end 240.222786 -164.154104)
		(stroke
			(width 0.2)
			(type default)
		)
		(layer "In5.Cu")
	)
	(gr_arc
		(start 240.877344 -150.84552)
		(mid 239.895939 -151.17257)
		(end 240.222786 -152.154128)
		(stroke
			(width 0.2)
			(type default)
		)
		(layer "In5.Cu")
	)
	(gr_arc
		(start 240.877344 -114.845592)
		(mid 239.895939 -115.172642)
		(end 240.222786 -116.1542)
		(stroke
			(width 0.2)
			(type default)
		)
		(layer "In5.Cu")
	)
	(gr_arc
		(start 240.880392 -122.838718)
		(mid 239.888776 -123.169426)
		(end 240.219484 -124.161042)
		(stroke
			(width 0.2)
			(type default)
		)
		(layer "In5.Cu")
	)
	(gr_arc
		(start 240.891822 -126.844552)
		(mid 239.891674 -127.163691)
		(end 240.219484 -128.161034)
		(stroke
			(width 0.2)
			(type default)
		)
		(layer "In5.Cu")
	)
	(gr_line
		(start 241.114834 -102.539038)
		(end 237.47857 -102.539038)
		(stroke
			(width 0.381)
			(type default)
		)
		(layer "In5.Cu")
	)
	(gr_line
		(start 241.114834 -6.239256)
		(end 237.47857 -6.239256)
		(stroke
			(width 0.381)
			(type default)
		)
		(layer "In5.Cu")
	)
	(gr_line
		(start 241.821462 -183.633364)
		(end 244.323108 -183.633364)
		(stroke
			(width 0.381)
			(type default)
		)
		(layer "In5.Cu")
	)
	(gr_line
		(start 241.821462 -87.333582)
		(end 244.323108 -87.333582)
		(stroke
			(width 0.381)
			(type default)
		)
		(layer "In5.Cu")
	)
	(gr_line
		(start 242.163092 -101.49078)
		(end 241.114834 -102.539038)
		(stroke
			(width 0.381)
			(type default)
		)
		(layer "In5.Cu")
	)
	(gr_line
		(start 242.163092 -5.190998)
		(end 241.114834 -6.239256)
		(stroke
			(width 0.381)
			(type default)
		)
		(layer "In5.Cu")
	)
	(gr_arc
		(start 242.20805 -125.155198)
		(mid 243.208198 -124.836059)
		(end 242.880388 -123.838716)
		(stroke
			(width 0.2)
			(type default)
		)
		(layer "In5.Cu")
	)
	(gr_arc
		(start 242.21948 -129.161032)
		(mid 243.211096 -128.830324)
		(end 242.880388 -127.838708)
		(stroke
			(width 0.2)
			(type default)
		)
		(layer "In5.Cu")
	)
	(gr_arc
		(start 242.222528 -161.15411)
		(mid 243.204289 -160.82711)
		(end 242.877086 -159.845502)
		(stroke
			(width 0.2)
			(type default)
		)
		(layer "In5.Cu")
	)
	(gr_arc
		(start 242.222528 -157.154118)
		(mid 243.204289 -156.827118)
		(end 242.877086 -155.84551)
		(stroke
			(width 0.2)
			(type default)
		)
		(layer "In5.Cu")
	)
	(gr_arc
		(start 242.222528 -121.15419)
		(mid 243.204289 -120.82719)
		(end 242.877086 -119.845582)
		(stroke
			(width 0.2)
			(type default)
		)
		(layer "In5.Cu")
	)
	(gr_arc
		(start 242.222782 -165.154102)
		(mid 243.204238 -164.82695)
		(end 242.877086 -163.845494)
		(stroke
			(width 0.2)
			(type default)
		)
		(layer "In5.Cu")
	)
	(gr_arc
		(start 242.222782 -153.154126)
		(mid 243.204238 -152.826974)
		(end 242.877086 -151.845518)
		(stroke
			(width 0.2)
			(type default)
		)
		(layer "In5.Cu")
	)
	(gr_arc
		(start 242.222782 -117.154198)
		(mid 243.204238 -116.827046)
		(end 242.877086 -115.84559)
		(stroke
			(width 0.2)
			(type default)
		)
		(layer "In5.Cu")
	)
	(gr_line
		(start 242.223798 -137.151872)
		(end 242.224052 -137.151618)
		(stroke
			(width 0.2)
			(type default)
		)
		(layer "In5.Cu")
	)
	(gr_line
		(start 242.223798 -109.151928)
		(end 242.224052 -109.151674)
		(stroke
			(width 0.2)
			(type default)
		)
		(layer "In5.Cu")
	)
	(gr_arc
		(start 242.223798 -36.852098)
		(mid 243.201952 -36.526216)
		(end 242.87607 -35.548062)
		(stroke
			(width 0.2)
			(type default)
		)
		(layer "In5.Cu")
	)
	(gr_line
		(start 242.224052 -137.151618)
		(end 242.225068 -137.149586)
		(stroke
			(width 0.2)
			(type default)
		)
		(layer "In5.Cu")
	)
	(gr_line
		(start 242.224052 -109.151674)
		(end 242.225068 -109.149642)
		(stroke
			(width 0.2)
			(type default)
		)
		(layer "In5.Cu")
	)
	(gr_arc
		(start 242.225068 -137.149586)
		(mid 243.199666 -136.82472)
		(end 242.8748 -135.850122)
		(stroke
			(width 0.2)
			(type default)
		)
		(layer "In5.Cu")
	)
	(gr_arc
		(start 242.225068 -109.149642)
		(mid 243.199666 -108.824776)
		(end 242.8748 -107.850178)
		(stroke
			(width 0.2)
			(type default)
		)
		(layer "In5.Cu")
	)
	(gr_arc
		(start 242.228116 -80.8228)
		(mid 243.174892 -80.517615)
		(end 242.86337 -79.572866)
		(stroke
			(width 0.2)
			(type default)
		)
		(layer "In5.Cu")
	)
	(gr_arc
		(start 242.228116 -76.822808)
		(mid 243.174892 -76.517623)
		(end 242.86337 -75.572874)
		(stroke
			(width 0.2)
			(type default)
		)
		(layer "In5.Cu")
	)
	(gr_arc
		(start 242.228116 -72.822816)
		(mid 243.174892 -72.517631)
		(end 242.86337 -71.572882)
		(stroke
			(width 0.2)
			(type default)
		)
		(layer "In5.Cu")
	)
	(gr_arc
		(start 242.228116 -52.822856)
		(mid 243.174892 -52.517671)
		(end 242.86337 -51.572922)
		(stroke
			(width 0.2)
			(type default)
		)
		(layer "In5.Cu")
	)
	(gr_arc
		(start 242.236498 -181.126892)
		(mid 243.17706 -180.813202)
		(end 242.86337 -179.87264)
		(stroke
			(width 0.2)
			(type default)
		)
		(layer "In5.Cu")
	)
	(gr_arc
		(start 242.236498 -177.1269)
		(mid 243.17706 -176.81321)
		(end 242.86337 -175.872648)
		(stroke
			(width 0.2)
			(type default)
		)
		(layer "In5.Cu")
	)
	(gr_arc
		(start 242.236498 -173.126908)
		(mid 243.17706 -172.813218)
		(end 242.86337 -171.872656)
		(stroke
			(width 0.2)
			(type default)
		)
		(layer "In5.Cu")
	)
	(gr_arc
		(start 242.236498 -169.126916)
		(mid 243.17706 -168.813226)
		(end 242.86337 -167.872664)
		(stroke
			(width 0.2)
			(type default)
		)
		(layer "In5.Cu")
	)
	(gr_arc
		(start 242.236498 -84.82711)
		(mid 243.17706 -84.51342)
		(end 242.86337 -83.572858)
		(stroke
			(width 0.2)
			(type default)
		)
		(layer "In5.Cu")
	)
	(gr_arc
		(start 242.236498 -68.827142)
		(mid 243.17706 -68.513452)
		(end 242.86337 -67.57289)
		(stroke
			(width 0.2)
			(type default)
		)
		(layer "In5.Cu")
	)
	(gr_arc
		(start 242.236498 -64.82715)
		(mid 243.17706 -64.51346)
		(end 242.86337 -63.572898)
		(stroke
			(width 0.2)
			(type default)
		)
		(layer "In5.Cu")
	)
	(gr_arc
		(start 242.236498 -60.827158)
		(mid 243.17706 -60.513468)
		(end 242.86337 -59.572906)
		(stroke
			(width 0.2)
			(type default)
		)
		(layer "In5.Cu")
	)
	(gr_arc
		(start 242.236498 -56.827166)
		(mid 243.17706 -56.513476)
		(end 242.86337 -55.572914)
		(stroke
			(width 0.2)
			(type default)
		)
		(layer "In5.Cu")
	)
	(gr_arc
		(start 242.236498 -48.827182)
		(mid 243.17706 -48.513492)
		(end 242.86337 -47.57293)
		(stroke
			(width 0.2)
			(type default)
		)
		(layer "In5.Cu")
	)
	(gr_arc
		(start 242.236498 -44.82719)
		(mid 243.17706 -44.5135)
		(end 242.86337 -43.572938)
		(stroke
			(width 0.2)
			(type default)
		)
		(layer "In5.Cu")
	)
	(gr_arc
		(start 242.236498 -40.827198)
		(mid 243.17706 -40.513508)
		(end 242.86337 -39.572946)
		(stroke
			(width 0.2)
			(type default)
		)
		(layer "In5.Cu")
	)
	(gr_line
		(start 242.86337 -179.87264)
		(end 240.871756 -178.87696)
		(stroke
			(width 0.2)
			(type default)
		)
		(layer "In5.Cu")
	)
	(gr_line
		(start 242.86337 -175.872648)
		(end 240.871756 -174.876968)
		(stroke
			(width 0.2)
			(type default)
		)
		(layer "In5.Cu")
	)
	(gr_line
		(start 242.86337 -171.872656)
		(end 240.871756 -170.876976)
		(stroke
			(width 0.2)
			(type default)
		)
		(layer "In5.Cu")
	)
	(gr_line
		(start 242.86337 -167.872664)
		(end 240.871756 -166.876984)
		(stroke
			(width 0.2)
			(type default)
		)
		(layer "In5.Cu")
	)
	(gr_line
		(start 242.86337 -83.572858)
		(end 240.871756 -82.577178)
		(stroke
			(width 0.2)
			(type default)
		)
		(layer "In5.Cu")
	)
	(gr_line
		(start 242.86337 -79.572866)
		(end 240.863374 -78.572868)
		(stroke
			(width 0.2)
			(type default)
		)
		(layer "In5.Cu")
	)
	(gr_line
		(start 242.86337 -75.572874)
		(end 240.863374 -74.572876)
		(stroke
			(width 0.2)
			(type default)
		)
		(layer "In5.Cu")
	)
	(gr_line
		(start 242.86337 -71.572882)
		(end 240.863374 -70.572884)
		(stroke
			(width 0.2)
			(type default)
		)
		(layer "In5.Cu")
	)
	(gr_line
		(start 242.86337 -67.57289)
		(end 240.871756 -66.57721)
		(stroke
			(width 0.2)
			(type default)
		)
		(layer "In5.Cu")
	)
	(gr_line
		(start 242.86337 -63.572898)
		(end 240.871756 -62.577218)
		(stroke
			(width 0.2)
			(type default)
		)
		(layer "In5.Cu")
	)
	(gr_line
		(start 242.86337 -59.572906)
		(end 240.871756 -58.577226)
		(stroke
			(width 0.2)
			(type default)
		)
		(layer "In5.Cu")
	)
	(gr_line
		(start 242.86337 -55.572914)
		(end 240.871756 -54.577234)
		(stroke
			(width 0.2)
			(type default)
		)
		(layer "In5.Cu")
	)
	(gr_line
		(start 242.86337 -51.572922)
		(end 240.863374 -50.572924)
		(stroke
			(width 0.2)
			(type default)
		)
		(layer "In5.Cu")
	)
	(gr_line
		(start 242.86337 -47.57293)
		(end 240.871756 -46.57725)
		(stroke
			(width 0.2)
			(type default)
		)
		(layer "In5.Cu")
	)
	(gr_line
		(start 242.86337 -43.572938)
		(end 240.871756 -42.577258)
		(stroke
			(width 0.2)
			(type default)
		)
		(layer "In5.Cu")
	)
	(gr_line
		(start 242.86337 -39.572946)
		(end 240.871756 -38.577266)
		(stroke
			(width 0.2)
			(type default)
		)
		(layer "In5.Cu")
	)
	(gr_line
		(start 242.8748 -135.850122)
		(end 242.87607 -135.847836)
		(stroke
			(width 0.2)
			(type default)
		)
		(layer "In5.Cu")
	)
	(gr_line
		(start 242.8748 -107.850178)
		(end 242.87607 -107.847892)
		(stroke
			(width 0.2)
			(type default)
		)
		(layer "In5.Cu")
	)
	(gr_line
		(start 242.87607 -135.847836)
		(end 240.876074 -134.847838)
		(stroke
			(width 0.2)
			(type default)
		)
		(layer "In5.Cu")
	)
	(gr_line
		(start 242.87607 -107.847892)
		(end 240.876074 -106.847894)
		(stroke
			(width 0.2)
			(type default)
		)
		(layer "In5.Cu")
	)
	(gr_line
		(start 242.87607 -35.548062)
		(end 240.876074 -34.548064)
		(stroke
			(width 0.2)
			(type default)
		)
		(layer "In5.Cu")
	)
	(gr_line
		(start 242.877086 -163.845494)
		(end 240.877344 -162.845496)
		(stroke
			(width 0.2)
			(type default)
		)
		(layer "In5.Cu")
	)
	(gr_line
		(start 242.877086 -159.845502)
		(end 240.87709 -158.845504)
		(stroke
			(width 0.2)
			(type default)
		)
		(layer "In5.Cu")
	)
	(gr_line
		(start 242.877086 -155.84551)
		(end 240.87709 -154.845512)
		(stroke
			(width 0.2)
			(type default)
		)
		(layer "In5.Cu")
	)
	(gr_line
		(start 242.877086 -151.845518)
		(end 240.877344 -150.84552)
		(stroke
			(width 0.2)
			(type default)
		)
		(layer "In5.Cu")
	)
	(gr_line
		(start 242.877086 -119.845582)
		(end 240.87709 -118.845584)
		(stroke
			(width 0.2)
			(type default)
		)
		(layer "In5.Cu")
	)
	(gr_line
		(start 242.877086 -115.84559)
		(end 240.877344 -114.845592)
		(stroke
			(width 0.2)
			(type default)
		)
		(layer "In5.Cu")
	)
	(gr_line
		(start 242.880388 -127.838708)
		(end 240.891822 -126.844552)
		(stroke
			(width 0.2)
			(type default)
		)
		(layer "In5.Cu")
	)
	(gr_line
		(start 242.880388 -123.838716)
		(end 240.880392 -122.838718)
		(stroke
			(width 0.2)
			(type default)
		)
		(layer "In5.Cu")
	)
	(gr_line
		(start 243.02212 -399.484088)
		(end 243.02212 -420.589202)
		(stroke
			(width 0.381)
			(type default)
		)
		(layer "In5.Cu")
	)
	(gr_line
		(start 243.534438 -101.49078)
		(end 242.163092 -101.49078)
		(stroke
			(width 0.381)
			(type default)
		)
		(layer "In5.Cu")
	)
	(gr_line
		(start 243.534438 -5.190998)
		(end 242.163092 -5.190998)
		(stroke
			(width 0.381)
			(type default)
		)
		(layer "In5.Cu")
	)
	(gr_line
		(start 244.261894 -398.244314)
		(end 243.02212 -399.484088)
		(stroke
			(width 0.381)
			(type default)
		)
		(layer "In5.Cu")
	)
	(gr_line
		(start 244.323108 -183.633364)
		(end 244.9703 -182.986172)
		(stroke
			(width 0.381)
			(type default)
		)
		(layer "In5.Cu")
	)
	(gr_line
		(start 244.323108 -87.333582)
		(end 244.9703 -86.68639)
		(stroke
			(width 0.381)
			(type default)
		)
		(layer "In5.Cu")
	)
	(gr_line
		(start 244.9703 -182.986172)
		(end 244.9703 -102.926642)
		(stroke
			(width 0.381)
			(type default)
		)
		(layer "In5.Cu")
	)
	(gr_line
		(start 244.9703 -102.926642)
		(end 243.534438 -101.49078)
		(stroke
			(width 0.381)
			(type default)
		)
		(layer "In5.Cu")
	)
	(gr_line
		(start 244.9703 -86.68639)
		(end 244.9703 -6.62686)
		(stroke
			(width 0.381)
			(type default)
		)
		(layer "In5.Cu")
	)
	(gr_line
		(start 244.9703 -6.62686)
		(end 243.534438 -5.190998)
		(stroke
			(width 0.381)
			(type default)
		)
		(layer "In5.Cu")
	)
	(gr_line
		(start 245.999 -197.8406)
		(end 249.3772 -194.4624)
		(stroke
			(width 0.381)
			(type default)
		)
		(layer "In5.Cu")
	)
	(gr_line
		(start 247.654318 0.814832)
		(end 226.625404 0.814832)
		(stroke
			(width 0.381)
			(type default)
		)
		(layer "In5.Cu")
	)
	(gr_line
		(start 249.3772 -194.4624)
		(end 249.3772 -0.90805)
		(stroke
			(width 0.381)
			(type default)
		)
		(layer "In5.Cu")
	)
	(gr_line
		(start 249.3772 -0.90805)
		(end 247.654318 0.814832)
		(stroke
			(width 0.381)
			(type default)
		)
		(layer "In5.Cu")
	)
	(gr_line
		(start 251.005086 -398.244314)
		(end 244.261894 -398.244314)
		(stroke
			(width 0.381)
			(type default)
		)
		(layer "In5.Cu")
	)
	(gr_line
		(start 252.2982 -396.9512)
		(end 251.005086 -398.244314)
		(stroke
			(width 0.381)
			(type default)
		)
		(layer "In5.Cu")
	)
	(gr_line
		(start 252.2982 -390.398)
		(end 252.2982 -396.9512)
		(stroke
			(width 0.381)
			(type default)
		)
		(layer "In5.Cu")
	)
	(gr_line
		(start 252.2982 -378.2314)
		(end 252.2982 -390.398)
		(stroke
			(width 0.381)
			(type default)
		)
		(layer "In5.Cu")
	)
	(gr_line
		(start 252.909324 -390.411208)
		(end 252.2982 -389.800084)
		(stroke
			(width 0.381)
			(type default)
		)
		(layer "In5.Cu")
	)
	(gr_line
		(start 252.946408 -390.399016)
		(end 252.335284 -391.01014)
		(stroke
			(width 0.381)
			(type default)
		)
		(layer "In5.Cu")
	)
	(gr_line
		(start 252.946408 -390.399016)
		(end 252.808232 -390.399016)
		(stroke
			(width 0.381)
			(type default)
		)
		(layer "In5.Cu")
	)
	(gr_line
		(start 252.9586 -377.571)
		(end 252.2982 -378.2314)
		(stroke
			(width 0.381)
			(type default)
		)
		(layer "In5.Cu")
	)
	(gr_line
		(start 252.979936 -390.399016)
		(end 252.946408 -390.399016)
		(stroke
			(width 0.381)
			(type default)
		)
		(layer "In5.Cu")
	)
	(gr_line
		(start 252.980444 -390.398)
		(end 252.980952 -390.398)
		(stroke
			(width 0.381)
			(type default)
		)
		(layer "In5.Cu")
	)
	(gr_line
		(start 262.8392 -193.1416)
		(end 267.716 -198.0184)
		(stroke
			(width 0.381)
			(type default)
		)
		(layer "In5.Cu")
	)
	(gr_line
		(start 262.8392 2.4892)
		(end 262.8392 -193.1416)
		(stroke
			(width 0.381)
			(type default)
		)
		(layer "In5.Cu")
	)
	(gr_line
		(start 266.6492 6.2992)
		(end 262.8392 2.4892)
		(stroke
			(width 0.381)
			(type default)
		)
		(layer "In5.Cu")
	)
	(gr_line
		(start 267.716 -198.0184)
		(end 284.6324 -198.0184)
		(stroke
			(width 0.381)
			(type default)
		)
		(layer "In5.Cu")
	)
	(gr_line
		(start 271.9705 -359.885996)
		(end 273.1135 -359.885996)
		(stroke
			(width 0.2)
			(type default)
		)
		(layer "In5.Cu")
	)
	(gr_line
		(start 271.9705 -358.085898)
		(end 273.1135 -358.085898)
		(stroke
			(width 0.2)
			(type default)
		)
		(layer "In5.Cu")
	)
	(gr_line
		(start 271.9705 -356.286054)
		(end 273.1135 -356.286054)
		(stroke
			(width 0.2)
			(type default)
		)
		(layer "In5.Cu")
	)
	(gr_line
		(start 271.9705 -354.485956)
		(end 273.1135 -354.485956)
		(stroke
			(width 0.2)
			(type default)
		)
		(layer "In5.Cu")
	)
	(gr_line
		(start 271.9705 -352.686112)
		(end 273.1135 -352.686112)
		(stroke
			(width 0.2)
			(type default)
		)
		(layer "In5.Cu")
	)
	(gr_line
		(start 271.9705 -350.886014)
		(end 273.1135 -350.886014)
		(stroke
			(width 0.2)
			(type default)
		)
		(layer "In5.Cu")
	)
	(gr_line
		(start 271.9705 -338.28863)
		(end 273.1135 -338.28863)
		(stroke
			(width 0.2)
			(type default)
		)
		(layer "In5.Cu")
	)
	(gr_line
		(start 271.9705 -336.488532)
		(end 273.1135 -336.488532)
		(stroke
			(width 0.2)
			(type default)
		)
		(layer "In5.Cu")
	)
	(gr_line
		(start 271.9705 -334.688434)
		(end 273.1135 -334.688434)
		(stroke
			(width 0.2)
			(type default)
		)
		(layer "In5.Cu")
	)
	(gr_line
		(start 271.9705 -332.88859)
		(end 273.1135 -332.88859)
		(stroke
			(width 0.2)
			(type default)
		)
		(layer "In5.Cu")
	)
	(gr_line
		(start 271.9705 -331.088492)
		(end 273.1135 -331.088492)
		(stroke
			(width 0.2)
			(type default)
		)
		(layer "In5.Cu")
	)
	(gr_line
		(start 271.9705 -329.288648)
		(end 273.1135 -329.288648)
		(stroke
			(width 0.2)
			(type default)
		)
		(layer "In5.Cu")
	)
	(gr_line
		(start 271.9705 -316.68847)
		(end 273.1135 -316.68847)
		(stroke
			(width 0.2)
			(type default)
		)
		(layer "In5.Cu")
	)
	(gr_line
		(start 271.9705 -314.888626)
		(end 273.1135 -314.888626)
		(stroke
			(width 0.2)
			(type default)
		)
		(layer "In5.Cu")
	)
	(gr_line
		(start 271.9705 -313.088528)
		(end 273.1135 -313.088528)
		(stroke
			(width 0.2)
			(type default)
		)
		(layer "In5.Cu")
	)
	(gr_line
		(start 271.9705 -311.28843)
		(end 273.1135 -311.28843)
		(stroke
			(width 0.2)
			(type default)
		)
		(layer "In5.Cu")
	)
	(gr_line
		(start 271.9705 -309.488586)
		(end 273.1135 -309.488586)
		(stroke
			(width 0.2)
			(type default)
		)
		(layer "In5.Cu")
	)
	(gr_line
		(start 271.9705 -307.688488)
		(end 273.1135 -307.688488)
		(stroke
			(width 0.2)
			(type default)
		)
		(layer "In5.Cu")
	)
	(gr_arc
		(start 271.970754 -359.123996)
		(mid 271.5895 -359.504869)
		(end 271.9705 -359.885996)
		(stroke
			(width 0.2)
			(type default)
		)
		(layer "In5.Cu")
	)
	(gr_arc
		(start 271.970754 -357.323898)
		(mid 271.5895 -357.704771)
		(end 271.9705 -358.085898)
		(stroke
			(width 0.2)
			(type default)
		)
		(layer "In5.Cu")
	)
	(gr_arc
		(start 271.970754 -355.524054)
		(mid 271.5895 -355.904927)
		(end 271.9705 -356.286054)
		(stroke
			(width 0.2)
			(type default)
		)
		(layer "In5.Cu")
	)
	(gr_arc
		(start 271.970754 -353.723956)
		(mid 271.5895 -354.104829)
		(end 271.9705 -354.485956)
		(stroke
			(width 0.2)
			(type default)
		)
		(layer "In5.Cu")
	)
	(gr_arc
		(start 271.970754 -351.924112)
		(mid 271.5895 -352.304985)
		(end 271.9705 -352.686112)
		(stroke
			(width 0.2)
			(type default)
		)
		(layer "In5.Cu")
	)
	(gr_arc
		(start 271.970754 -350.124014)
		(mid 271.5895 -350.504887)
		(end 271.9705 -350.886014)
		(stroke
			(width 0.2)
			(type default)
		)
		(layer "In5.Cu")
	)
	(gr_arc
		(start 271.970754 -337.52155)
		(mid 271.58696 -337.904963)
		(end 271.9705 -338.28863)
		(stroke
			(width 0.2)
			(type default)
		)
		(layer "In5.Cu")
	)
	(gr_arc
		(start 271.970754 -335.721452)
		(mid 271.58696 -336.104865)
		(end 271.9705 -336.488532)
		(stroke
			(width 0.2)
			(type default)
		)
		(layer "In5.Cu")
	)
	(gr_arc
		(start 271.970754 -333.921354)
		(mid 271.58696 -334.304767)
		(end 271.9705 -334.688434)
		(stroke
			(width 0.2)
			(type default)
		)
		(layer "In5.Cu")
	)
	(gr_arc
		(start 271.970754 -332.12151)
		(mid 271.58696 -332.504923)
		(end 271.9705 -332.88859)
		(stroke
			(width 0.2)
			(type default)
		)
		(layer "In5.Cu")
	)
	(gr_arc
		(start 271.970754 -330.321412)
		(mid 271.58696 -330.704825)
		(end 271.9705 -331.088492)
		(stroke
			(width 0.2)
			(type default)
		)
		(layer "In5.Cu")
	)
	(gr_arc
		(start 271.970754 -328.521568)
		(mid 271.58696 -328.904981)
		(end 271.9705 -329.288648)
		(stroke
			(width 0.2)
			(type default)
		)
		(layer "In5.Cu")
	)
	(gr_arc
		(start 271.970754 -315.92139)
		(mid 271.58696 -316.304803)
		(end 271.9705 -316.68847)
		(stroke
			(width 0.2)
			(type default)
		)
		(layer "In5.Cu")
	)
	(gr_arc
		(start 271.970754 -314.121546)
		(mid 271.58696 -314.504959)
		(end 271.9705 -314.888626)
		(stroke
			(width 0.2)
			(type default)
		)
		(layer "In5.Cu")
	)
	(gr_arc
		(start 271.970754 -312.321448)
		(mid 271.58696 -312.704861)
		(end 271.9705 -313.088528)
		(stroke
			(width 0.2)
			(type default)
		)
		(layer "In5.Cu")
	)
	(gr_arc
		(start 271.970754 -310.52135)
		(mid 271.58696 -310.904763)
		(end 271.9705 -311.28843)
		(stroke
			(width 0.2)
			(type default)
		)
		(layer "In5.Cu")
	)
	(gr_arc
		(start 271.970754 -308.721506)
		(mid 271.58696 -309.104919)
		(end 271.9705 -309.488586)
		(stroke
			(width 0.2)
			(type default)
		)
		(layer "In5.Cu")
	)
	(gr_arc
		(start 271.970754 -306.921408)
		(mid 271.58696 -307.304821)
		(end 271.9705 -307.688488)
		(stroke
			(width 0.2)
			(type default)
		)
		(layer "In5.Cu")
	)
	(gr_arc
		(start 273.1135 -359.885996)
		(mid 273.4945 -359.504996)
		(end 273.1135 -359.123996)
		(stroke
			(width 0.2)
			(type default)
		)
		(layer "In5.Cu")
	)
	(gr_line
		(start 273.1135 -359.123996)
		(end 271.970754 -359.123996)
		(stroke
			(width 0.2)
			(type default)
		)
		(layer "In5.Cu")
	)
	(gr_arc
		(start 273.1135 -358.085898)
		(mid 273.4945 -357.704898)
		(end 273.1135 -357.323898)
		(stroke
			(width 0.2)
			(type default)
		)
		(layer "In5.Cu")
	)
	(gr_line
		(start 273.1135 -357.323898)
		(end 271.970754 -357.323898)
		(stroke
			(width 0.2)
			(type default)
		)
		(layer "In5.Cu")
	)
	(gr_arc
		(start 273.1135 -356.286054)
		(mid 273.4945 -355.905054)
		(end 273.1135 -355.524054)
		(stroke
			(width 0.2)
			(type default)
		)
		(layer "In5.Cu")
	)
	(gr_line
		(start 273.1135 -355.524054)
		(end 271.970754 -355.524054)
		(stroke
			(width 0.2)
			(type default)
		)
		(layer "In5.Cu")
	)
	(gr_arc
		(start 273.1135 -354.485956)
		(mid 273.4945 -354.104956)
		(end 273.1135 -353.723956)
		(stroke
			(width 0.2)
			(type default)
		)
		(layer "In5.Cu")
	)
	(gr_line
		(start 273.1135 -353.723956)
		(end 271.970754 -353.723956)
		(stroke
			(width 0.2)
			(type default)
		)
		(layer "In5.Cu")
	)
	(gr_arc
		(start 273.1135 -352.686112)
		(mid 273.4945 -352.305112)
		(end 273.1135 -351.924112)
		(stroke
			(width 0.2)
			(type default)
		)
		(layer "In5.Cu")
	)
	(gr_line
		(start 273.1135 -351.924112)
		(end 271.970754 -351.924112)
		(stroke
			(width 0.2)
			(type default)
		)
		(layer "In5.Cu")
	)
	(gr_arc
		(start 273.1135 -350.886014)
		(mid 273.4945 -350.505014)
		(end 273.1135 -350.124014)
		(stroke
			(width 0.2)
			(type default)
		)
		(layer "In5.Cu")
	)
	(gr_line
		(start 273.1135 -350.124014)
		(end 271.970754 -350.124014)
		(stroke
			(width 0.2)
			(type default)
		)
		(layer "In5.Cu")
	)
	(gr_arc
		(start 273.1135 -338.28863)
		(mid 273.49704 -337.90509)
		(end 273.1135 -337.52155)
		(stroke
			(width 0.2)
			(type default)
		)
		(layer "In5.Cu")
	)
	(gr_line
		(start 273.1135 -337.52155)
		(end 271.970754 -337.52155)
		(stroke
			(width 0.2)
			(type default)
		)
		(layer "In5.Cu")
	)
	(gr_arc
		(start 273.1135 -336.488532)
		(mid 273.49704 -336.104992)
		(end 273.1135 -335.721452)
		(stroke
			(width 0.2)
			(type default)
		)
		(layer "In5.Cu")
	)
	(gr_line
		(start 273.1135 -335.721452)
		(end 271.970754 -335.721452)
		(stroke
			(width 0.2)
			(type default)
		)
		(layer "In5.Cu")
	)
	(gr_arc
		(start 273.1135 -334.688434)
		(mid 273.49704 -334.304894)
		(end 273.1135 -333.921354)
		(stroke
			(width 0.2)
			(type default)
		)
		(layer "In5.Cu")
	)
	(gr_line
		(start 273.1135 -333.921354)
		(end 271.970754 -333.921354)
		(stroke
			(width 0.2)
			(type default)
		)
		(layer "In5.Cu")
	)
	(gr_arc
		(start 273.1135 -332.88859)
		(mid 273.49704 -332.50505)
		(end 273.1135 -332.12151)
		(stroke
			(width 0.2)
			(type default)
		)
		(layer "In5.Cu")
	)
	(gr_line
		(start 273.1135 -332.12151)
		(end 271.970754 -332.12151)
		(stroke
			(width 0.2)
			(type default)
		)
		(layer "In5.Cu")
	)
	(gr_arc
		(start 273.1135 -331.088492)
		(mid 273.49704 -330.704952)
		(end 273.1135 -330.321412)
		(stroke
			(width 0.2)
			(type default)
		)
		(layer "In5.Cu")
	)
	(gr_line
		(start 273.1135 -330.321412)
		(end 271.970754 -330.321412)
		(stroke
			(width 0.2)
			(type default)
		)
		(layer "In5.Cu")
	)
	(gr_arc
		(start 273.1135 -329.288648)
		(mid 273.49704 -328.905108)
		(end 273.1135 -328.521568)
		(stroke
			(width 0.2)
			(type default)
		)
		(layer "In5.Cu")
	)
	(gr_line
		(start 273.1135 -328.521568)
		(end 271.970754 -328.521568)
		(stroke
			(width 0.2)
			(type default)
		)
		(layer "In5.Cu")
	)
	(gr_arc
		(start 273.1135 -316.68847)
		(mid 273.49704 -316.30493)
		(end 273.1135 -315.92139)
		(stroke
			(width 0.2)
			(type default)
		)
		(layer "In5.Cu")
	)
	(gr_line
		(start 273.1135 -315.92139)
		(end 271.970754 -315.92139)
		(stroke
			(width 0.2)
			(type default)
		)
		(layer "In5.Cu")
	)
	(gr_arc
		(start 273.1135 -314.888626)
		(mid 273.49704 -314.505086)
		(end 273.1135 -314.121546)
		(stroke
			(width 0.2)
			(type default)
		)
		(layer "In5.Cu")
	)
	(gr_line
		(start 273.1135 -314.121546)
		(end 271.970754 -314.121546)
		(stroke
			(width 0.2)
			(type default)
		)
		(layer "In5.Cu")
	)
	(gr_arc
		(start 273.1135 -313.088528)
		(mid 273.49704 -312.704988)
		(end 273.1135 -312.321448)
		(stroke
			(width 0.2)
			(type default)
		)
		(layer "In5.Cu")
	)
	(gr_line
		(start 273.1135 -312.321448)
		(end 271.970754 -312.321448)
		(stroke
			(width 0.2)
			(type default)
		)
		(layer "In5.Cu")
	)
	(gr_arc
		(start 273.1135 -311.28843)
		(mid 273.49704 -310.90489)
		(end 273.1135 -310.52135)
		(stroke
			(width 0.2)
			(type default)
		)
		(layer "In5.Cu")
	)
	(gr_line
		(start 273.1135 -310.52135)
		(end 271.970754 -310.52135)
		(stroke
			(width 0.2)
			(type default)
		)
		(layer "In5.Cu")
	)
	(gr_arc
		(start 273.1135 -309.488586)
		(mid 273.49704 -309.105046)
		(end 273.1135 -308.721506)
		(stroke
			(width 0.2)
			(type default)
		)
		(layer "In5.Cu")
	)
	(gr_line
		(start 273.1135 -308.721506)
		(end 271.970754 -308.721506)
		(stroke
			(width 0.2)
			(type default)
		)
		(layer "In5.Cu")
	)
	(gr_arc
		(start 273.1135 -307.688488)
		(mid 273.49704 -307.304948)
		(end 273.1135 -306.921408)
		(stroke
			(width 0.2)
			(type default)
		)
		(layer "In5.Cu")
	)
	(gr_line
		(start 273.1135 -306.921408)
		(end 271.970754 -306.921408)
		(stroke
			(width 0.2)
			(type default)
		)
		(layer "In5.Cu")
	)
	(gr_line
		(start 273.51736 -390.440926)
		(end 273.996658 -390.920224)
		(stroke
			(width 0.381)
			(type default)
		)
		(layer "In5.Cu")
	)
	(gr_line
		(start 273.924522 -263.586722)
		(end 273.924522 -249.373136)
		(stroke
			(width 0.381)
			(type default)
		)
		(layer "In5.Cu")
	)
	(gr_line
		(start 273.924522 -249.373136)
		(end 274.508468 -248.78919)
		(stroke
			(width 0.381)
			(type default)
		)
		(layer "In5.Cu")
	)
	(gr_line
		(start 274.005548 -420.7891)
		(end 274.005548 -401.761452)
		(stroke
			(width 0.381)
			(type default)
		)
		(layer "In5.Cu")
	)
	(gr_line
		(start 274.005548 -401.761452)
		(end 275.209 -400.558)
		(stroke
			(width 0.381)
			(type default)
		)
		(layer "In5.Cu")
	)
	(gr_line
		(start 274.005548 -395.097)
		(end 274.005548 -390.398)
		(stroke
			(width 0.381)
			(type default)
		)
		(layer "In5.Cu")
	)
	(gr_line
		(start 274.005548 -390.398)
		(end 252.2982 -390.398)
		(stroke
			(width 0.381)
			(type default)
		)
		(layer "In5.Cu")
	)
	(gr_line
		(start 274.005548 -390.398)
		(end 274.005548 -390.356852)
		(stroke
			(width 0.381)
			(type default)
		)
		(layer "In5.Cu")
	)
	(gr_line
		(start 274.005548 -390.356852)
		(end 274.6502 -389.7122)
		(stroke
			(width 0.381)
			(type default)
		)
		(layer "In5.Cu")
	)
	(gr_line
		(start 274.2438 -377.571)
		(end 252.9586 -377.571)
		(stroke
			(width 0.381)
			(type default)
		)
		(layer "In5.Cu")
	)
	(gr_line
		(start 274.508468 -248.78919)
		(end 290.403788 -248.78919)
		(stroke
			(width 0.381)
			(type default)
		)
		(layer "In5.Cu")
	)
	(gr_circle
		(center 274.649946 -378.9934)
		(end 274.6502 -378.9934)
		(stroke
			(width 0.381)
			(type default)
		)
		(fill no)
		(layer "In5.Cu")
	)
	(gr_line
		(start 274.6502 -389.7122)
		(end 274.6502 -378.9934)
		(stroke
			(width 0.381)
			(type default)
		)
		(layer "In5.Cu")
	)
	(gr_line
		(start 274.6502 -378.9934)
		(end 274.6502 -377.9774)
		(stroke
			(width 0.381)
			(type default)
		)
		(layer "In5.Cu")
	)
	(gr_line
		(start 274.6502 -377.9774)
		(end 274.2438 -377.571)
		(stroke
			(width 0.381)
			(type default)
		)
		(layer "In5.Cu")
	)
	(gr_line
		(start 275.209 -400.558)
		(end 275.209 -396.300452)
		(stroke
			(width 0.381)
			(type default)
		)
		(layer "In5.Cu")
	)
	(gr_line
		(start 275.209 -396.300452)
		(end 274.005548 -395.097)
		(stroke
			(width 0.381)
			(type default)
		)
		(layer "In5.Cu")
	)
	(gr_line
		(start 275.387562 -359.925112)
		(end 275.775674 -360.313224)
		(stroke
			(width 0.381)
			(type default)
		)
		(layer "In5.Cu")
	)
	(gr_line
		(start 275.387562 -292.157912)
		(end 275.387562 -359.925112)
		(stroke
			(width 0.381)
			(type default)
		)
		(layer "In5.Cu")
	)
	(gr_line
		(start 275.775674 -360.313224)
		(end 295.540938 -360.313224)
		(stroke
			(width 0.381)
			(type default)
		)
		(layer "In5.Cu")
	)
	(gr_line
		(start 275.972016 -291.573458)
		(end 275.387562 -292.157912)
		(stroke
			(width 0.381)
			(type default)
		)
		(layer "In5.Cu")
	)
	(gr_line
		(start 276.9362 -266.5984)
		(end 273.924522 -263.586722)
		(stroke
			(width 0.381)
			(type default)
		)
		(layer "In5.Cu")
	)
	(gr_line
		(start 277.247858 -180.977286)
		(end 277.765764 -181.495192)
		(stroke
			(width 0.381)
			(type default)
		)
		(layer "In5.Cu")
	)
	(gr_line
		(start 277.247858 -102.46868)
		(end 277.247858 -180.977286)
		(stroke
			(width 0.381)
			(type default)
		)
		(layer "In5.Cu")
	)
	(gr_line
		(start 277.247858 -84.677504)
		(end 277.765764 -85.19541)
		(stroke
			(width 0.381)
			(type default)
		)
		(layer "In5.Cu")
	)
	(gr_line
		(start 277.247858 -6.168898)
		(end 277.247858 -84.677504)
		(stroke
			(width 0.381)
			(type default)
		)
		(layer "In5.Cu")
	)
	(gr_line
		(start 277.765764 -181.495192)
		(end 278.633682 -181.495192)
		(stroke
			(width 0.381)
			(type default)
		)
		(layer "In5.Cu")
	)
	(gr_line
		(start 277.765764 -85.19541)
		(end 278.633682 -85.19541)
		(stroke
			(width 0.381)
			(type default)
		)
		(layer "In5.Cu")
	)
	(gr_line
		(start 278.173942 -101.542596)
		(end 277.247858 -102.46868)
		(stroke
			(width 0.381)
			(type default)
		)
		(layer "In5.Cu")
	)
	(gr_line
		(start 278.173942 -5.242814)
		(end 277.247858 -6.168898)
		(stroke
			(width 0.381)
			(type default)
		)
		(layer "In5.Cu")
	)
	(gr_line
		(start 278.23668 -356.453694)
		(end 279.636728 -356.453694)
		(stroke
			(width 0.2)
			(type default)
		)
		(layer "In5.Cu")
	)
	(gr_arc
		(start 278.23668 -355.356414)
		(mid 277.68804 -355.905054)
		(end 278.23668 -356.453694)
		(stroke
			(width 0.2)
			(type default)
		)
		(layer "In5.Cu")
	)
	(gr_line
		(start 278.23668 -352.853752)
		(end 279.636728 -352.853752)
		(stroke
			(width 0.2)
			(type default)
		)
		(layer "In5.Cu")
	)
	(gr_arc
		(start 278.23668 -351.756472)
		(mid 277.68804 -352.305112)
		(end 278.23668 -352.853752)
		(stroke
			(width 0.2)
			(type default)
		)
		(layer "In5.Cu")
	)
	(gr_line
		(start 278.23668 -349.25381)
		(end 279.636728 -349.25381)
		(stroke
			(width 0.2)
			(type default)
		)
		(layer "In5.Cu")
	)
	(gr_arc
		(start 278.23668 -348.15653)
		(mid 277.68804 -348.70517)
		(end 278.23668 -349.25381)
		(stroke
			(width 0.2)
			(type default)
		)
		(layer "In5.Cu")
	)
	(gr_line
		(start 278.23668 -345.653868)
		(end 279.636728 -345.653868)
		(stroke
			(width 0.2)
			(type default)
		)
		(layer "In5.Cu")
	)
	(gr_arc
		(start 278.23668 -344.556588)
		(mid 277.68804 -345.105228)
		(end 278.23668 -345.653868)
		(stroke
			(width 0.2)
			(type default)
		)
		(layer "In5.Cu")
	)
	(gr_line
		(start 278.23668 -342.053672)
		(end 279.636728 -342.053672)
		(stroke
			(width 0.2)
			(type default)
		)
		(layer "In5.Cu")
	)
	(gr_arc
		(start 278.23668 -340.956392)
		(mid 277.68804 -341.505032)
		(end 278.23668 -342.053672)
		(stroke
			(width 0.2)
			(type default)
		)
		(layer "In5.Cu")
	)
	(gr_line
		(start 278.23668 -338.45373)
		(end 279.636728 -338.45373)
		(stroke
			(width 0.2)
			(type default)
		)
		(layer "In5.Cu")
	)
	(gr_arc
		(start 278.23668 -337.35645)
		(mid 277.68804 -337.90509)
		(end 278.23668 -338.45373)
		(stroke
			(width 0.2)
			(type default)
		)
		(layer "In5.Cu")
	)
	(gr_line
		(start 278.23668 -334.853788)
		(end 279.636728 -334.853788)
		(stroke
			(width 0.2)
			(type default)
		)
		(layer "In5.Cu")
	)
	(gr_arc
		(start 278.23668 -333.756508)
		(mid 277.68804 -334.305148)
		(end 278.23668 -334.853788)
		(stroke
			(width 0.2)
			(type default)
		)
		(layer "In5.Cu")
	)
	(gr_line
		(start 278.23668 -331.253846)
		(end 279.636728 -331.253846)
		(stroke
			(width 0.2)
			(type default)
		)
		(layer "In5.Cu")
	)
	(gr_arc
		(start 278.23668 -330.156566)
		(mid 277.68804 -330.705206)
		(end 278.23668 -331.253846)
		(stroke
			(width 0.2)
			(type default)
		)
		(layer "In5.Cu")
	)
	(gr_line
		(start 278.23668 -327.653904)
		(end 279.636728 -327.653904)
		(stroke
			(width 0.2)
			(type default)
		)
		(layer "In5.Cu")
	)
	(gr_arc
		(start 278.23668 -326.556624)
		(mid 277.68804 -327.105264)
		(end 278.23668 -327.653904)
		(stroke
			(width 0.2)
			(type default)
		)
		(layer "In5.Cu")
	)
	(gr_line
		(start 278.23668 -324.053708)
		(end 279.636728 -324.053708)
		(stroke
			(width 0.2)
			(type default)
		)
		(layer "In5.Cu")
	)
	(gr_arc
		(start 278.23668 -322.956428)
		(mid 277.68804 -323.505068)
		(end 278.23668 -324.053708)
		(stroke
			(width 0.2)
			(type default)
		)
		(layer "In5.Cu")
	)
	(gr_line
		(start 278.23668 -320.453766)
		(end 279.636728 -320.453766)
		(stroke
			(width 0.2)
			(type default)
		)
		(layer "In5.Cu")
	)
	(gr_arc
		(start 278.23668 -319.356486)
		(mid 277.68804 -319.905126)
		(end 278.23668 -320.453766)
		(stroke
			(width 0.2)
			(type default)
		)
		(layer "In5.Cu")
	)
	(gr_line
		(start 278.23668 -316.853824)
		(end 279.636728 -316.853824)
		(stroke
			(width 0.2)
			(type default)
		)
		(layer "In5.Cu")
	)
	(gr_arc
		(start 278.23668 -315.756544)
		(mid 277.68804 -316.305184)
		(end 278.23668 -316.853824)
		(stroke
			(width 0.2)
			(type default)
		)
		(layer "In5.Cu")
	)
	(gr_line
		(start 278.23668 -313.253882)
		(end 279.636728 -313.253882)
		(stroke
			(width 0.2)
			(type default)
		)
		(layer "In5.Cu")
	)
	(gr_arc
		(start 278.23668 -312.156602)
		(mid 277.68804 -312.705242)
		(end 278.23668 -313.253882)
		(stroke
			(width 0.2)
			(type default)
		)
		(layer "In5.Cu")
	)
	(gr_line
		(start 278.23668 -309.653686)
		(end 279.636728 -309.653686)
		(stroke
			(width 0.2)
			(type default)
		)
		(layer "In5.Cu")
	)
	(gr_arc
		(start 278.23668 -308.556406)
		(mid 277.68804 -309.105046)
		(end 278.23668 -309.653686)
		(stroke
			(width 0.2)
			(type default)
		)
		(layer "In5.Cu")
	)
	(gr_line
		(start 278.23668 -306.053744)
		(end 279.636728 -306.053744)
		(stroke
			(width 0.2)
			(type default)
		)
		(layer "In5.Cu")
	)
	(gr_arc
		(start 278.23668 -304.956464)
		(mid 277.68804 -305.505104)
		(end 278.23668 -306.053744)
		(stroke
			(width 0.2)
			(type default)
		)
		(layer "In5.Cu")
	)
	(gr_line
		(start 278.23668 -302.453802)
		(end 279.636728 -302.453802)
		(stroke
			(width 0.2)
			(type default)
		)
		(layer "In5.Cu")
	)
	(gr_arc
		(start 278.23668 -301.356522)
		(mid 277.68804 -301.905162)
		(end 278.23668 -302.453802)
		(stroke
			(width 0.2)
			(type default)
		)
		(layer "In5.Cu")
	)
	(gr_line
		(start 278.23668 -298.85386)
		(end 279.636728 -298.85386)
		(stroke
			(width 0.2)
			(type default)
		)
		(layer "In5.Cu")
	)
	(gr_arc
		(start 278.23668 -297.75658)
		(mid 277.68804 -298.30522)
		(end 278.23668 -298.85386)
		(stroke
			(width 0.2)
			(type default)
		)
		(layer "In5.Cu")
	)
	(gr_line
		(start 278.23668 -295.253918)
		(end 279.636728 -295.253918)
		(stroke
			(width 0.2)
			(type default)
		)
		(layer "In5.Cu")
	)
	(gr_arc
		(start 278.23668 -294.156638)
		(mid 277.68804 -294.705278)
		(end 278.23668 -295.253918)
		(stroke
			(width 0.2)
			(type default)
		)
		(layer "In5.Cu")
	)
	(gr_line
		(start 278.23668 -262.453374)
		(end 279.636728 -262.453374)
		(stroke
			(width 0.2)
			(type default)
		)
		(layer "In5.Cu")
	)
	(gr_arc
		(start 278.23668 -261.351014)
		(mid 277.6855 -261.902194)
		(end 278.23668 -262.453374)
		(stroke
			(width 0.2)
			(type default)
		)
		(layer "In5.Cu")
	)
	(gr_line
		(start 278.23668 -258.853432)
		(end 279.636728 -258.853432)
		(stroke
			(width 0.2)
			(type default)
		)
		(layer "In5.Cu")
	)
	(gr_arc
		(start 278.23668 -257.751072)
		(mid 277.6855 -258.302252)
		(end 278.23668 -258.853432)
		(stroke
			(width 0.2)
			(type default)
		)
		(layer "In5.Cu")
	)
	(gr_line
		(start 278.23668 -255.25349)
		(end 279.636728 -255.25349)
		(stroke
			(width 0.2)
			(type default)
		)
		(layer "In5.Cu")
	)
	(gr_arc
		(start 278.23668 -254.15113)
		(mid 277.6855 -254.70231)
		(end 278.23668 -255.25349)
		(stroke
			(width 0.2)
			(type default)
		)
		(layer "In5.Cu")
	)
	(gr_line
		(start 278.23668 -251.653548)
		(end 279.636728 -251.653548)
		(stroke
			(width 0.2)
			(type default)
		)
		(layer "In5.Cu")
	)
	(gr_arc
		(start 278.23668 -250.551188)
		(mid 277.6855 -251.102368)
		(end 278.23668 -251.653548)
		(stroke
			(width 0.2)
			(type default)
		)
		(layer "In5.Cu")
	)
	(gr_line
		(start 278.236934 -355.356414)
		(end 278.23668 -355.356414)
		(stroke
			(width 0.2)
			(type default)
		)
		(layer "In5.Cu")
	)
	(gr_line
		(start 278.236934 -351.756472)
		(end 278.23668 -351.756472)
		(stroke
			(width 0.2)
			(type default)
		)
		(layer "In5.Cu")
	)
	(gr_line
		(start 278.236934 -348.15653)
		(end 278.23668 -348.15653)
		(stroke
			(width 0.2)
			(type default)
		)
		(layer "In5.Cu")
	)
	(gr_line
		(start 278.236934 -344.556588)
		(end 278.23668 -344.556588)
		(stroke
			(width 0.2)
			(type default)
		)
		(layer "In5.Cu")
	)
	(gr_line
		(start 278.236934 -340.956392)
		(end 278.23668 -340.956392)
		(stroke
			(width 0.2)
			(type default)
		)
		(layer "In5.Cu")
	)
	(gr_line
		(start 278.236934 -337.35645)
		(end 278.23668 -337.35645)
		(stroke
			(width 0.2)
			(type default)
		)
		(layer "In5.Cu")
	)
	(gr_line
		(start 278.236934 -333.756508)
		(end 278.23668 -333.756508)
		(stroke
			(width 0.2)
			(type default)
		)
		(layer "In5.Cu")
	)
	(gr_line
		(start 278.236934 -330.156566)
		(end 278.23668 -330.156566)
		(stroke
			(width 0.2)
			(type default)
		)
		(layer "In5.Cu")
	)
	(gr_line
		(start 278.236934 -326.556624)
		(end 278.23668 -326.556624)
		(stroke
			(width 0.2)
			(type default)
		)
		(layer "In5.Cu")
	)
	(gr_line
		(start 278.236934 -322.956428)
		(end 278.23668 -322.956428)
		(stroke
			(width 0.2)
			(type default)
		)
		(layer "In5.Cu")
	)
	(gr_line
		(start 278.236934 -319.356486)
		(end 278.23668 -319.356486)
		(stroke
			(width 0.2)
			(type default)
		)
		(layer "In5.Cu")
	)
	(gr_line
		(start 278.236934 -315.756544)
		(end 278.23668 -315.756544)
		(stroke
			(width 0.2)
			(type default)
		)
		(layer "In5.Cu")
	)
	(gr_line
		(start 278.236934 -312.156602)
		(end 278.23668 -312.156602)
		(stroke
			(width 0.2)
			(type default)
		)
		(layer "In5.Cu")
	)
	(gr_line
		(start 278.236934 -308.556406)
		(end 278.23668 -308.556406)
		(stroke
			(width 0.2)
			(type default)
		)
		(layer "In5.Cu")
	)
	(gr_line
		(start 278.236934 -304.956464)
		(end 278.23668 -304.956464)
		(stroke
			(width 0.2)
			(type default)
		)
		(layer "In5.Cu")
	)
	(gr_line
		(start 278.236934 -301.356522)
		(end 278.23668 -301.356522)
		(stroke
			(width 0.2)
			(type default)
		)
		(layer "In5.Cu")
	)
	(gr_line
		(start 278.236934 -297.75658)
		(end 278.23668 -297.75658)
		(stroke
			(width 0.2)
			(type default)
		)
		(layer "In5.Cu")
	)
	(gr_line
		(start 278.236934 -294.156638)
		(end 278.23668 -294.156638)
		(stroke
			(width 0.2)
			(type default)
		)
		(layer "In5.Cu")
	)
	(gr_line
		(start 278.236934 -261.351014)
		(end 278.23668 -261.351014)
		(stroke
			(width 0.2)
			(type default)
		)
		(layer "In5.Cu")
	)
	(gr_line
		(start 278.236934 -257.751072)
		(end 278.23668 -257.751072)
		(stroke
			(width 0.2)
			(type default)
		)
		(layer "In5.Cu")
	)
	(gr_line
		(start 278.236934 -254.15113)
		(end 278.23668 -254.15113)
		(stroke
			(width 0.2)
			(type default)
		)
		(layer "In5.Cu")
	)
	(gr_line
		(start 278.236934 -250.551188)
		(end 278.23668 -250.551188)
		(stroke
			(width 0.2)
			(type default)
		)
		(layer "In5.Cu")
	)
	(gr_line
		(start 278.424132 -177.848006)
		(end 278.425148 -177.850038)
		(stroke
			(width 0.2)
			(type default)
		)
		(layer "In5.Cu")
	)
	(gr_line
		(start 278.424132 -177.847752)
		(end 278.424132 -177.848006)
		(stroke
			(width 0.2)
			(type default)
		)
		(layer "In5.Cu")
	)
	(gr_line
		(start 278.424132 -173.848014)
		(end 278.425148 -173.850046)
		(stroke
			(width 0.2)
			(type default)
		)
		(layer "In5.Cu")
	)
	(gr_line
		(start 278.424132 -173.84776)
		(end 278.424132 -173.848014)
		(stroke
			(width 0.2)
			(type default)
		)
		(layer "In5.Cu")
	)
	(gr_line
		(start 278.424132 -169.848022)
		(end 278.425148 -169.850054)
		(stroke
			(width 0.2)
			(type default)
		)
		(layer "In5.Cu")
	)
	(gr_line
		(start 278.424132 -169.847768)
		(end 278.424132 -169.848022)
		(stroke
			(width 0.2)
			(type default)
		)
		(layer "In5.Cu")
	)
	(gr_line
		(start 278.424132 -165.84803)
		(end 278.425148 -165.850062)
		(stroke
			(width 0.2)
			(type default)
		)
		(layer "In5.Cu")
	)
	(gr_line
		(start 278.424132 -165.847776)
		(end 278.424132 -165.84803)
		(stroke
			(width 0.2)
			(type default)
		)
		(layer "In5.Cu")
	)
	(gr_line
		(start 278.424132 -137.848086)
		(end 278.425148 -137.850118)
		(stroke
			(width 0.2)
			(type default)
		)
		(layer "In5.Cu")
	)
	(gr_line
		(start 278.424132 -137.847832)
		(end 278.424132 -137.848086)
		(stroke
			(width 0.2)
			(type default)
		)
		(layer "In5.Cu")
	)
	(gr_line
		(start 278.424132 -81.548224)
		(end 278.425148 -81.550256)
		(stroke
			(width 0.2)
			(type default)
		)
		(layer "In5.Cu")
	)
	(gr_line
		(start 278.424132 -81.54797)
		(end 278.424132 -81.548224)
		(stroke
			(width 0.2)
			(type default)
		)
		(layer "In5.Cu")
	)
	(gr_line
		(start 278.424132 -77.548232)
		(end 278.425148 -77.550264)
		(stroke
			(width 0.2)
			(type default)
		)
		(layer "In5.Cu")
	)
	(gr_line
		(start 278.424132 -77.547978)
		(end 278.424132 -77.548232)
		(stroke
			(width 0.2)
			(type default)
		)
		(layer "In5.Cu")
	)
	(gr_line
		(start 278.424132 -73.54824)
		(end 278.425148 -73.550272)
		(stroke
			(width 0.2)
			(type default)
		)
		(layer "In5.Cu")
	)
	(gr_line
		(start 278.424132 -73.547986)
		(end 278.424132 -73.54824)
		(stroke
			(width 0.2)
			(type default)
		)
		(layer "In5.Cu")
	)
	(gr_line
		(start 278.424132 -69.548248)
		(end 278.425148 -69.55028)
		(stroke
			(width 0.2)
			(type default)
		)
		(layer "In5.Cu")
	)
	(gr_line
		(start 278.424132 -69.547994)
		(end 278.424132 -69.548248)
		(stroke
			(width 0.2)
			(type default)
		)
		(layer "In5.Cu")
	)
	(gr_line
		(start 278.424132 -65.548256)
		(end 278.425148 -65.550288)
		(stroke
			(width 0.2)
			(type default)
		)
		(layer "In5.Cu")
	)
	(gr_line
		(start 278.424132 -65.548002)
		(end 278.424132 -65.548256)
		(stroke
			(width 0.2)
			(type default)
		)
		(layer "In5.Cu")
	)
	(gr_line
		(start 278.424132 -61.548264)
		(end 278.425148 -61.550296)
		(stroke
			(width 0.2)
			(type default)
		)
		(layer "In5.Cu")
	)
	(gr_line
		(start 278.424132 -61.54801)
		(end 278.424132 -61.548264)
		(stroke
			(width 0.2)
			(type default)
		)
		(layer "In5.Cu")
	)
	(gr_line
		(start 278.424132 -57.548272)
		(end 278.425148 -57.550304)
		(stroke
			(width 0.2)
			(type default)
		)
		(layer "In5.Cu")
	)
	(gr_line
		(start 278.424132 -57.548018)
		(end 278.424132 -57.548272)
		(stroke
			(width 0.2)
			(type default)
		)
		(layer "In5.Cu")
	)
	(gr_line
		(start 278.424132 -53.54828)
		(end 278.425148 -53.550312)
		(stroke
			(width 0.2)
			(type default)
		)
		(layer "In5.Cu")
	)
	(gr_line
		(start 278.424132 -53.548026)
		(end 278.424132 -53.54828)
		(stroke
			(width 0.2)
			(type default)
		)
		(layer "In5.Cu")
	)
	(gr_line
		(start 278.424132 -49.548288)
		(end 278.425148 -49.55032)
		(stroke
			(width 0.2)
			(type default)
		)
		(layer "In5.Cu")
	)
	(gr_line
		(start 278.424132 -49.548034)
		(end 278.424132 -49.548288)
		(stroke
			(width 0.2)
			(type default)
		)
		(layer "In5.Cu")
	)
	(gr_line
		(start 278.424132 -45.548296)
		(end 278.425148 -45.550328)
		(stroke
			(width 0.2)
			(type default)
		)
		(layer "In5.Cu")
	)
	(gr_line
		(start 278.424132 -45.548042)
		(end 278.424132 -45.548296)
		(stroke
			(width 0.2)
			(type default)
		)
		(layer "In5.Cu")
	)
	(gr_line
		(start 278.424132 -41.548304)
		(end 278.425148 -41.550336)
		(stroke
			(width 0.2)
			(type default)
		)
		(layer "In5.Cu")
	)
	(gr_line
		(start 278.424132 -41.54805)
		(end 278.424132 -41.548304)
		(stroke
			(width 0.2)
			(type default)
		)
		(layer "In5.Cu")
	)
	(gr_line
		(start 278.424132 -37.548312)
		(end 278.425148 -37.550344)
		(stroke
			(width 0.2)
			(type default)
		)
		(layer "In5.Cu")
	)
	(gr_line
		(start 278.424132 -37.548058)
		(end 278.424132 -37.548312)
		(stroke
			(width 0.2)
			(type default)
		)
		(layer "In5.Cu")
	)
	(gr_line
		(start 278.424132 -17.548352)
		(end 278.425148 -17.550384)
		(stroke
			(width 0.2)
			(type default)
		)
		(layer "In5.Cu")
	)
	(gr_line
		(start 278.424132 -17.548098)
		(end 278.424132 -17.548352)
		(stroke
			(width 0.2)
			(type default)
		)
		(layer "In5.Cu")
	)
	(gr_arc
		(start 278.425148 -177.850038)
		(mid 278.100282 -178.824636)
		(end 279.07488 -179.149502)
		(stroke
			(width 0.2)
			(type default)
		)
		(layer "In5.Cu")
	)
	(gr_arc
		(start 278.425148 -173.850046)
		(mid 278.100282 -174.824644)
		(end 279.07488 -175.14951)
		(stroke
			(width 0.2)
			(type default)
		)
		(layer "In5.Cu")
	)
	(gr_arc
		(start 278.425148 -169.850054)
		(mid 278.100282 -170.824652)
		(end 279.07488 -171.149518)
		(stroke
			(width 0.2)
			(type default)
		)
		(layer "In5.Cu")
	)
	(gr_arc
		(start 278.425148 -165.850062)
		(mid 278.100282 -166.82466)
		(end 279.07488 -167.149526)
		(stroke
			(width 0.2)
			(type default)
		)
		(layer "In5.Cu")
	)
	(gr_arc
		(start 278.425148 -137.850118)
		(mid 278.100282 -138.824716)
		(end 279.07488 -139.149582)
		(stroke
			(width 0.2)
			(type default)
		)
		(layer "In5.Cu")
	)
	(gr_arc
		(start 278.425148 -81.550256)
		(mid 278.100282 -82.524854)
		(end 279.07488 -82.84972)
		(stroke
			(width 0.2)
			(type default)
		)
		(layer "In5.Cu")
	)
	(gr_arc
		(start 278.425148 -77.550264)
		(mid 278.100282 -78.524862)
		(end 279.07488 -78.849728)
		(stroke
			(width 0.2)
			(type default)
		)
		(layer "In5.Cu")
	)
	(gr_arc
		(start 278.425148 -73.550272)
		(mid 278.100282 -74.52487)
		(end 279.07488 -74.849736)
		(stroke
			(width 0.2)
			(type default)
		)
		(layer "In5.Cu")
	)
	(gr_arc
		(start 278.425148 -69.55028)
		(mid 278.100282 -70.524878)
		(end 279.07488 -70.849744)
		(stroke
			(width 0.2)
			(type default)
		)
		(layer "In5.Cu")
	)
	(gr_arc
		(start 278.425148 -65.550288)
		(mid 278.100282 -66.524886)
		(end 279.07488 -66.849752)
		(stroke
			(width 0.2)
			(type default)
		)
		(layer "In5.Cu")
	)
	(gr_arc
		(start 278.425148 -61.550296)
		(mid 278.100282 -62.524894)
		(end 279.07488 -62.84976)
		(stroke
			(width 0.2)
			(type default)
		)
		(layer "In5.Cu")
	)
	(gr_arc
		(start 278.425148 -57.550304)
		(mid 278.100282 -58.524902)
		(end 279.07488 -58.849768)
		(stroke
			(width 0.2)
			(type default)
		)
		(layer "In5.Cu")
	)
	(gr_arc
		(start 278.425148 -53.550312)
		(mid 278.100282 -54.52491)
		(end 279.07488 -54.849776)
		(stroke
			(width 0.2)
			(type default)
		)
		(layer "In5.Cu")
	)
	(gr_arc
		(start 278.425148 -49.55032)
		(mid 278.100282 -50.524918)
		(end 279.07488 -50.849784)
		(stroke
			(width 0.2)
			(type default)
		)
		(layer "In5.Cu")
	)
	(gr_arc
		(start 278.425148 -45.550328)
		(mid 278.100282 -46.524926)
		(end 279.07488 -46.849792)
		(stroke
			(width 0.2)
			(type default)
		)
		(layer "In5.Cu")
	)
	(gr_arc
		(start 278.425148 -41.550336)
		(mid 278.100282 -42.524934)
		(end 279.07488 -42.8498)
		(stroke
			(width 0.2)
			(type default)
		)
		(layer "In5.Cu")
	)
	(gr_arc
		(start 278.425148 -37.550344)
		(mid 278.100282 -38.524942)
		(end 279.07488 -38.849808)
		(stroke
			(width 0.2)
			(type default)
		)
		(layer "In5.Cu")
	)
	(gr_arc
		(start 278.425148 -17.550384)
		(mid 278.100282 -18.524982)
		(end 279.07488 -18.849848)
		(stroke
			(width 0.2)
			(type default)
		)
		(layer "In5.Cu")
	)
	(gr_arc
		(start 278.426418 -161.852356)
		(mid 278.102619 -162.8235)
		(end 279.073864 -163.147248)
		(stroke
			(width 0.2)
			(type default)
		)
		(layer "In5.Cu")
	)
	(gr_line
		(start 278.426418 -161.852102)
		(end 278.426418 -161.852356)
		(stroke
			(width 0.2)
			(type default)
		)
		(layer "In5.Cu")
	)
	(gr_arc
		(start 278.426418 -157.852364)
		(mid 278.102619 -158.823508)
		(end 279.073864 -159.147256)
		(stroke
			(width 0.2)
			(type default)
		)
		(layer "In5.Cu")
	)
	(gr_line
		(start 278.426418 -157.85211)
		(end 278.426418 -157.852364)
		(stroke
			(width 0.2)
			(type default)
		)
		(layer "In5.Cu")
	)
	(gr_arc
		(start 278.426418 -153.852372)
		(mid 278.102619 -154.823516)
		(end 279.073864 -155.147264)
		(stroke
			(width 0.2)
			(type default)
		)
		(layer "In5.Cu")
	)
	(gr_line
		(start 278.426418 -153.852118)
		(end 278.426418 -153.852372)
		(stroke
			(width 0.2)
			(type default)
		)
		(layer "In5.Cu")
	)
	(gr_arc
		(start 278.426418 -149.85238)
		(mid 278.102619 -150.823524)
		(end 279.073864 -151.147272)
		(stroke
			(width 0.2)
			(type default)
		)
		(layer "In5.Cu")
	)
	(gr_line
		(start 278.426418 -149.852126)
		(end 278.426418 -149.85238)
		(stroke
			(width 0.2)
			(type default)
		)
		(layer "In5.Cu")
	)
	(gr_arc
		(start 278.426418 -129.85242)
		(mid 278.102619 -130.823564)
		(end 279.073864 -131.147312)
		(stroke
			(width 0.2)
			(type default)
		)
		(layer "In5.Cu")
	)
	(gr_line
		(start 278.426418 -129.852166)
		(end 278.426418 -129.85242)
		(stroke
			(width 0.2)
			(type default)
		)
		(layer "In5.Cu")
	)
	(gr_arc
		(start 278.426418 -125.852428)
		(mid 278.102619 -126.823572)
		(end 279.073864 -127.14732)
		(stroke
			(width 0.2)
			(type default)
		)
		(layer "In5.Cu")
	)
	(gr_line
		(start 278.426418 -125.852174)
		(end 278.426418 -125.852428)
		(stroke
			(width 0.2)
			(type default)
		)
		(layer "In5.Cu")
	)
	(gr_arc
		(start 278.426418 -121.852436)
		(mid 278.102619 -122.82358)
		(end 279.073864 -123.147328)
		(stroke
			(width 0.2)
			(type default)
		)
		(layer "In5.Cu")
	)
	(gr_line
		(start 278.426418 -121.852182)
		(end 278.426418 -121.852436)
		(stroke
			(width 0.2)
			(type default)
		)
		(layer "In5.Cu")
	)
	(gr_arc
		(start 278.426418 -117.852444)
		(mid 278.102619 -118.823588)
		(end 279.073864 -119.147336)
		(stroke
			(width 0.2)
			(type default)
		)
		(layer "In5.Cu")
	)
	(gr_line
		(start 278.426418 -117.85219)
		(end 278.426418 -117.852444)
		(stroke
			(width 0.2)
			(type default)
		)
		(layer "In5.Cu")
	)
	(gr_arc
		(start 278.433784 -11.54049)
		(mid 278.093387 -12.52152)
		(end 279.077166 -12.854432)
		(stroke
			(width 0.2)
			(type default)
		)
		(layer "In5.Cu")
	)
	(gr_arc
		(start 278.44496 -113.868708)
		(mid 278.120865 -114.809139)
		(end 279.06345 -115.127024)
		(stroke
			(width 0.2)
			(type default)
		)
		(layer "In5.Cu")
	)
	(gr_line
		(start 278.633682 -181.495192)
		(end 279.999948 -180.128926)
		(stroke
			(width 0.381)
			(type default)
		)
		(layer "In5.Cu")
	)
	(gr_line
		(start 278.633682 -85.19541)
		(end 279.999948 -83.829144)
		(stroke
			(width 0.381)
			(type default)
		)
		(layer "In5.Cu")
	)
	(gr_line
		(start 279.06345 -115.127024)
		(end 281.063446 -114.127026)
		(stroke
			(width 0.2)
			(type default)
		)
		(layer "In5.Cu")
	)
	(gr_line
		(start 279.073864 -163.147248)
		(end 281.07386 -162.14725)
		(stroke
			(width 0.2)
			(type default)
		)
		(layer "In5.Cu")
	)
	(gr_line
		(start 279.073864 -159.147256)
		(end 281.07386 -158.147258)
		(stroke
			(width 0.2)
			(type default)
		)
		(layer "In5.Cu")
	)
	(gr_line
		(start 279.073864 -155.147264)
		(end 281.07386 -154.147266)
		(stroke
			(width 0.2)
			(type default)
		)
		(layer "In5.Cu")
	)
	(gr_line
		(start 279.073864 -151.147272)
		(end 281.07386 -150.147274)
		(stroke
			(width 0.2)
			(type default)
		)
		(layer "In5.Cu")
	)
	(gr_line
		(start 279.073864 -131.147312)
		(end 281.07386 -130.147314)
		(stroke
			(width 0.2)
			(type default)
		)
		(layer "In5.Cu")
	)
	(gr_line
		(start 279.073864 -127.14732)
		(end 281.07386 -126.147322)
		(stroke
			(width 0.2)
			(type default)
		)
		(layer "In5.Cu")
	)
	(gr_line
		(start 279.073864 -123.147328)
		(end 281.07386 -122.14733)
		(stroke
			(width 0.2)
			(type default)
		)
		(layer "In5.Cu")
	)
	(gr_line
		(start 279.073864 -119.147336)
		(end 281.07386 -118.147338)
		(stroke
			(width 0.2)
			(type default)
		)
		(layer "In5.Cu")
	)
	(gr_line
		(start 279.07488 -179.149502)
		(end 279.07615 -179.151788)
		(stroke
			(width 0.2)
			(type default)
		)
		(layer "In5.Cu")
	)
	(gr_line
		(start 279.07488 -175.14951)
		(end 279.07615 -175.151796)
		(stroke
			(width 0.2)
			(type default)
		)
		(layer "In5.Cu")
	)
	(gr_line
		(start 279.07488 -171.149518)
		(end 279.07615 -171.151804)
		(stroke
			(width 0.2)
			(type default)
		)
		(layer "In5.Cu")
	)
	(gr_line
		(start 279.07488 -167.149526)
		(end 279.07615 -167.151812)
		(stroke
			(width 0.2)
			(type default)
		)
		(layer "In5.Cu")
	)
	(gr_line
		(start 279.07488 -139.149582)
		(end 279.07615 -139.151868)
		(stroke
			(width 0.2)
			(type default)
		)
		(layer "In5.Cu")
	)
	(gr_line
		(start 279.07488 -82.84972)
		(end 279.07615 -82.852006)
		(stroke
			(width 0.2)
			(type default)
		)
		(layer "In5.Cu")
	)
	(gr_line
		(start 279.07488 -78.849728)
		(end 279.07615 -78.852014)
		(stroke
			(width 0.2)
			(type default)
		)
		(layer "In5.Cu")
	)
	(gr_line
		(start 279.07488 -74.849736)
		(end 279.07615 -74.852022)
		(stroke
			(width 0.2)
			(type default)
		)
		(layer "In5.Cu")
	)
	(gr_line
		(start 279.07488 -70.849744)
		(end 279.07615 -70.85203)
		(stroke
			(width 0.2)
			(type default)
		)
		(layer "In5.Cu")
	)
	(gr_line
		(start 279.07488 -66.849752)
		(end 279.07615 -66.852038)
		(stroke
			(width 0.2)
			(type default)
		)
		(layer "In5.Cu")
	)
	(gr_line
		(start 279.07488 -62.84976)
		(end 279.07615 -62.852046)
		(stroke
			(width 0.2)
			(type default)
		)
		(layer "In5.Cu")
	)
	(gr_line
		(start 279.07488 -58.849768)
		(end 279.07615 -58.852054)
		(stroke
			(width 0.2)
			(type default)
		)
		(layer "In5.Cu")
	)
	(gr_line
		(start 279.07488 -54.849776)
		(end 279.07615 -54.852062)
		(stroke
			(width 0.2)
			(type default)
		)
		(layer "In5.Cu")
	)
	(gr_line
		(start 279.07488 -50.849784)
		(end 279.07615 -50.85207)
		(stroke
			(width 0.2)
			(type default)
		)
		(layer "In5.Cu")
	)
	(gr_line
		(start 279.07488 -46.849792)
		(end 279.07615 -46.852078)
		(stroke
			(width 0.2)
			(type default)
		)
		(layer "In5.Cu")
	)
	(gr_line
		(start 279.07488 -42.8498)
		(end 279.07615 -42.852086)
		(stroke
			(width 0.2)
			(type default)
		)
		(layer "In5.Cu")
	)
	(gr_line
		(start 279.07488 -38.849808)
		(end 279.07615 -38.852094)
		(stroke
			(width 0.2)
			(type default)
		)
		(layer "In5.Cu")
	)
	(gr_line
		(start 279.07488 -18.849848)
		(end 279.07615 -18.852134)
		(stroke
			(width 0.2)
			(type default)
		)
		(layer "In5.Cu")
	)
	(gr_line
		(start 279.07615 -179.151788)
		(end 281.076146 -178.15179)
		(stroke
			(width 0.2)
			(type default)
		)
		(layer "In5.Cu")
	)
	(gr_line
		(start 279.07615 -175.151796)
		(end 281.076146 -174.151798)
		(stroke
			(width 0.2)
			(type default)
		)
		(layer "In5.Cu")
	)
	(gr_line
		(start 279.07615 -171.151804)
		(end 281.076146 -170.151806)
		(stroke
			(width 0.2)
			(type default)
		)
		(layer "In5.Cu")
	)
	(gr_line
		(start 279.07615 -167.151812)
		(end 281.076146 -166.151814)
		(stroke
			(width 0.2)
			(type default)
		)
		(layer "In5.Cu")
	)
	(gr_line
		(start 279.07615 -139.151868)
		(end 281.076146 -138.15187)
		(stroke
			(width 0.2)
			(type default)
		)
		(layer "In5.Cu")
	)
	(gr_line
		(start 279.07615 -82.852006)
		(end 281.076146 -81.852008)
		(stroke
			(width 0.2)
			(type default)
		)
		(layer "In5.Cu")
	)
	(gr_line
		(start 279.07615 -78.852014)
		(end 281.076146 -77.852016)
		(stroke
			(width 0.2)
			(type default)
		)
		(layer "In5.Cu")
	)
	(gr_line
		(start 279.07615 -74.852022)
		(end 281.076146 -73.852024)
		(stroke
			(width 0.2)
			(type default)
		)
		(layer "In5.Cu")
	)
	(gr_line
		(start 279.07615 -70.85203)
		(end 281.076146 -69.852032)
		(stroke
			(width 0.2)
			(type default)
		)
		(layer "In5.Cu")
	)
	(gr_line
		(start 279.07615 -66.852038)
		(end 281.076146 -65.85204)
		(stroke
			(width 0.2)
			(type default)
		)
		(layer "In5.Cu")
	)
	(gr_line
		(start 279.07615 -62.852046)
		(end 281.076146 -61.852048)
		(stroke
			(width 0.2)
			(type default)
		)
		(layer "In5.Cu")
	)
	(gr_line
		(start 279.07615 -58.852054)
		(end 281.076146 -57.852056)
		(stroke
			(width 0.2)
			(type default)
		)
		(layer "In5.Cu")
	)
	(gr_line
		(start 279.07615 -54.852062)
		(end 281.076146 -53.852064)
		(stroke
			(width 0.2)
			(type default)
		)
		(layer "In5.Cu")
	)
	(gr_line
		(start 279.07615 -50.85207)
		(end 281.076146 -49.852072)
		(stroke
			(width 0.2)
			(type default)
		)
		(layer "In5.Cu")
	)
	(gr_line
		(start 279.07615 -46.852078)
		(end 281.076146 -45.85208)
		(stroke
			(width 0.2)
			(type default)
		)
		(layer "In5.Cu")
	)
	(gr_line
		(start 279.07615 -42.852086)
		(end 281.076146 -41.852088)
		(stroke
			(width 0.2)
			(type default)
		)
		(layer "In5.Cu")
	)
	(gr_line
		(start 279.07615 -38.852094)
		(end 281.076146 -37.852096)
		(stroke
			(width 0.2)
			(type default)
		)
		(layer "In5.Cu")
	)
	(gr_line
		(start 279.07615 -18.852134)
		(end 281.076146 -17.852136)
		(stroke
			(width 0.2)
			(type default)
		)
		(layer "In5.Cu")
	)
	(gr_line
		(start 279.077166 -12.854432)
		(end 281.077162 -11.854434)
		(stroke
			(width 0.2)
			(type default)
		)
		(layer "In5.Cu")
	)
	(gr_line
		(start 279.182068 -101.542596)
		(end 278.173942 -101.542596)
		(stroke
			(width 0.381)
			(type default)
		)
		(layer "In5.Cu")
	)
	(gr_line
		(start 279.182068 -5.242814)
		(end 278.173942 -5.242814)
		(stroke
			(width 0.381)
			(type default)
		)
		(layer "In5.Cu")
	)
	(gr_line
		(start 279.236678 -358.253792)
		(end 280.636726 -358.253792)
		(stroke
			(width 0.2)
			(type default)
		)
		(layer "In5.Cu")
	)
	(gr_arc
		(start 279.236678 -357.156512)
		(mid 278.688038 -357.705152)
		(end 279.236678 -358.253792)
		(stroke
			(width 0.2)
			(type default)
		)
		(layer "In5.Cu")
	)
	(gr_line
		(start 279.236678 -354.65385)
		(end 280.636726 -354.65385)
		(stroke
			(width 0.2)
			(type default)
		)
		(layer "In5.Cu")
	)
	(gr_arc
		(start 279.236678 -353.55657)
		(mid 278.688038 -354.10521)
		(end 279.236678 -354.65385)
		(stroke
			(width 0.2)
			(type default)
		)
		(layer "In5.Cu")
	)
	(gr_line
		(start 279.236678 -351.053908)
		(end 280.636726 -351.053908)
		(stroke
			(width 0.2)
			(type default)
		)
		(layer "In5.Cu")
	)
	(gr_arc
		(start 279.236678 -349.956628)
		(mid 278.688038 -350.505268)
		(end 279.236678 -351.053908)
		(stroke
			(width 0.2)
			(type default)
		)
		(layer "In5.Cu")
	)
	(gr_line
		(start 279.236678 -347.453712)
		(end 280.636726 -347.453712)
		(stroke
			(width 0.2)
			(type default)
		)
		(layer "In5.Cu")
	)
	(gr_arc
		(start 279.236678 -346.356432)
		(mid 278.688038 -346.905072)
		(end 279.236678 -347.453712)
		(stroke
			(width 0.2)
			(type default)
		)
		(layer "In5.Cu")
	)
	(gr_line
		(start 279.236678 -343.85377)
		(end 280.636726 -343.85377)
		(stroke
			(width 0.2)
			(type default)
		)
		(layer "In5.Cu")
	)
	(gr_arc
		(start 279.236678 -342.75649)
		(mid 278.688038 -343.30513)
		(end 279.236678 -343.85377)
		(stroke
			(width 0.2)
			(type default)
		)
		(layer "In5.Cu")
	)
	(gr_line
		(start 279.236678 -340.253828)
		(end 280.636726 -340.253828)
		(stroke
			(width 0.2)
			(type default)
		)
		(layer "In5.Cu")
	)
	(gr_arc
		(start 279.236678 -339.156548)
		(mid 278.688038 -339.705188)
		(end 279.236678 -340.253828)
		(stroke
			(width 0.2)
			(type default)
		)
		(layer "In5.Cu")
	)
	(gr_line
		(start 279.236678 -336.653886)
		(end 280.636726 -336.653886)
		(stroke
			(width 0.2)
			(type default)
		)
		(layer "In5.Cu")
	)
	(gr_arc
		(start 279.236678 -335.556606)
		(mid 278.688038 -336.105246)
		(end 279.236678 -336.653886)
		(stroke
			(width 0.2)
			(type default)
		)
		(layer "In5.Cu")
	)
	(gr_line
		(start 279.236678 -333.05369)
		(end 280.636726 -333.05369)
		(stroke
			(width 0.2)
			(type default)
		)
		(layer "In5.Cu")
	)
	(gr_arc
		(start 279.236678 -331.95641)
		(mid 278.688038 -332.50505)
		(end 279.236678 -333.05369)
		(stroke
			(width 0.2)
			(type default)
		)
		(layer "In5.Cu")
	)
	(gr_line
		(start 279.236678 -329.453748)
		(end 280.636726 -329.453748)
		(stroke
			(width 0.2)
			(type default)
		)
		(layer "In5.Cu")
	)
	(gr_arc
		(start 279.236678 -328.356468)
		(mid 278.688038 -328.905108)
		(end 279.236678 -329.453748)
		(stroke
			(width 0.2)
			(type default)
		)
		(layer "In5.Cu")
	)
	(gr_line
		(start 279.236678 -325.853806)
		(end 280.636726 -325.853806)
		(stroke
			(width 0.2)
			(type default)
		)
		(layer "In5.Cu")
	)
	(gr_arc
		(start 279.236678 -324.756526)
		(mid 278.688038 -325.305166)
		(end 279.236678 -325.853806)
		(stroke
			(width 0.2)
			(type default)
		)
		(layer "In5.Cu")
	)
	(gr_line
		(start 279.236678 -322.253864)
		(end 280.636726 -322.253864)
		(stroke
			(width 0.2)
			(type default)
		)
		(layer "In5.Cu")
	)
	(gr_arc
		(start 279.236678 -321.156584)
		(mid 278.688038 -321.705224)
		(end 279.236678 -322.253864)
		(stroke
			(width 0.2)
			(type default)
		)
		(layer "In5.Cu")
	)
	(gr_line
		(start 279.236678 -318.653668)
		(end 280.636726 -318.653668)
		(stroke
			(width 0.2)
			(type default)
		)
		(layer "In5.Cu")
	)
	(gr_arc
		(start 279.236678 -317.556388)
		(mid 278.688038 -318.105028)
		(end 279.236678 -318.653668)
		(stroke
			(width 0.2)
			(type default)
		)
		(layer "In5.Cu")
	)
	(gr_line
		(start 279.236678 -315.053726)
		(end 280.636726 -315.053726)
		(stroke
			(width 0.2)
			(type default)
		)
		(layer "In5.Cu")
	)
	(gr_arc
		(start 279.236678 -313.956446)
		(mid 278.688038 -314.505086)
		(end 279.236678 -315.053726)
		(stroke
			(width 0.2)
			(type default)
		)
		(layer "In5.Cu")
	)
	(gr_line
		(start 279.236678 -311.453784)
		(end 280.636726 -311.453784)
		(stroke
			(width 0.2)
			(type default)
		)
		(layer "In5.Cu")
	)
	(gr_arc
		(start 279.236678 -310.356504)
		(mid 278.688038 -310.905144)
		(end 279.236678 -311.453784)
		(stroke
			(width 0.2)
			(type default)
		)
		(layer "In5.Cu")
	)
	(gr_line
		(start 279.236678 -307.853842)
		(end 280.636726 -307.853842)
		(stroke
			(width 0.2)
			(type default)
		)
		(layer "In5.Cu")
	)
	(gr_arc
		(start 279.236678 -306.756562)
		(mid 278.688038 -307.305202)
		(end 279.236678 -307.853842)
		(stroke
			(width 0.2)
			(type default)
		)
		(layer "In5.Cu")
	)
	(gr_line
		(start 279.236678 -304.2539)
		(end 280.636726 -304.2539)
		(stroke
			(width 0.2)
			(type default)
		)
		(layer "In5.Cu")
	)
	(gr_arc
		(start 279.236678 -303.15662)
		(mid 278.688038 -303.70526)
		(end 279.236678 -304.2539)
		(stroke
			(width 0.2)
			(type default)
		)
		(layer "In5.Cu")
	)
	(gr_line
		(start 279.236678 -300.653704)
		(end 280.636726 -300.653704)
		(stroke
			(width 0.2)
			(type default)
		)
		(layer "In5.Cu")
	)
	(gr_arc
		(start 279.236678 -299.556424)
		(mid 278.688038 -300.105064)
		(end 279.236678 -300.653704)
		(stroke
			(width 0.2)
			(type default)
		)
		(layer "In5.Cu")
	)
	(gr_line
		(start 279.236678 -297.053762)
		(end 280.636726 -297.053762)
		(stroke
			(width 0.2)
			(type default)
		)
		(layer "In5.Cu")
	)
	(gr_arc
		(start 279.236678 -295.956482)
		(mid 278.688038 -296.505122)
		(end 279.236678 -297.053762)
		(stroke
			(width 0.2)
			(type default)
		)
		(layer "In5.Cu")
	)
	(gr_line
		(start 279.236678 -264.253472)
		(end 280.636726 -264.253472)
		(stroke
			(width 0.2)
			(type default)
		)
		(layer "In5.Cu")
	)
	(gr_arc
		(start 279.236678 -263.151112)
		(mid 278.685498 -263.702292)
		(end 279.236678 -264.253472)
		(stroke
			(width 0.2)
			(type default)
		)
		(layer "In5.Cu")
	)
	(gr_line
		(start 279.236678 -260.65353)
		(end 280.636726 -260.65353)
		(stroke
			(width 0.2)
			(type default)
		)
		(layer "In5.Cu")
	)
	(gr_arc
		(start 279.236678 -259.55117)
		(mid 278.685498 -260.10235)
		(end 279.236678 -260.65353)
		(stroke
			(width 0.2)
			(type default)
		)
		(layer "In5.Cu")
	)
	(gr_line
		(start 279.236678 -257.053588)
		(end 280.636726 -257.053588)
		(stroke
			(width 0.2)
			(type default)
		)
		(layer "In5.Cu")
	)
	(gr_arc
		(start 279.236678 -255.951228)
		(mid 278.685498 -256.502408)
		(end 279.236678 -257.053588)
		(stroke
			(width 0.2)
			(type default)
		)
		(layer "In5.Cu")
	)
	(gr_line
		(start 279.236678 -253.453392)
		(end 280.636726 -253.453392)
		(stroke
			(width 0.2)
			(type default)
		)
		(layer "In5.Cu")
	)
	(gr_arc
		(start 279.236678 -252.351032)
		(mid 278.685498 -252.902212)
		(end 279.236678 -253.453392)
		(stroke
			(width 0.2)
			(type default)
		)
		(layer "In5.Cu")
	)
	(gr_line
		(start 279.236932 -357.156512)
		(end 279.236678 -357.156512)
		(stroke
			(width 0.2)
			(type default)
		)
		(layer "In5.Cu")
	)
	(gr_line
		(start 279.236932 -353.55657)
		(end 279.236678 -353.55657)
		(stroke
			(width 0.2)
			(type default)
		)
		(layer "In5.Cu")
	)
	(gr_line
		(start 279.236932 -349.956628)
		(end 279.236678 -349.956628)
		(stroke
			(width 0.2)
			(type default)
		)
		(layer "In5.Cu")
	)
	(gr_line
		(start 279.236932 -346.356432)
		(end 279.236678 -346.356432)
		(stroke
			(width 0.2)
			(type default)
		)
		(layer "In5.Cu")
	)
	(gr_line
		(start 279.236932 -342.75649)
		(end 279.236678 -342.75649)
		(stroke
			(width 0.2)
			(type default)
		)
		(layer "In5.Cu")
	)
	(gr_line
		(start 279.236932 -339.156548)
		(end 279.236678 -339.156548)
		(stroke
			(width 0.2)
			(type default)
		)
		(layer "In5.Cu")
	)
	(gr_line
		(start 279.236932 -335.556606)
		(end 279.236678 -335.556606)
		(stroke
			(width 0.2)
			(type default)
		)
		(layer "In5.Cu")
	)
	(gr_line
		(start 279.236932 -331.95641)
		(end 279.236678 -331.95641)
		(stroke
			(width 0.2)
			(type default)
		)
		(layer "In5.Cu")
	)
	(gr_line
		(start 279.236932 -328.356468)
		(end 279.236678 -328.356468)
		(stroke
			(width 0.2)
			(type default)
		)
		(layer "In5.Cu")
	)
	(gr_line
		(start 279.236932 -324.756526)
		(end 279.236678 -324.756526)
		(stroke
			(width 0.2)
			(type default)
		)
		(layer "In5.Cu")
	)
	(gr_line
		(start 279.236932 -321.156584)
		(end 279.236678 -321.156584)
		(stroke
			(width 0.2)
			(type default)
		)
		(layer "In5.Cu")
	)
	(gr_line
		(start 279.236932 -317.556388)
		(end 279.236678 -317.556388)
		(stroke
			(width 0.2)
			(type default)
		)
		(layer "In5.Cu")
	)
	(gr_line
		(start 279.236932 -313.956446)
		(end 279.236678 -313.956446)
		(stroke
			(width 0.2)
			(type default)
		)
		(layer "In5.Cu")
	)
	(gr_line
		(start 279.236932 -310.356504)
		(end 279.236678 -310.356504)
		(stroke
			(width 0.2)
			(type default)
		)
		(layer "In5.Cu")
	)
	(gr_line
		(start 279.236932 -306.756562)
		(end 279.236678 -306.756562)
		(stroke
			(width 0.2)
			(type default)
		)
		(layer "In5.Cu")
	)
	(gr_line
		(start 279.236932 -303.15662)
		(end 279.236678 -303.15662)
		(stroke
			(width 0.2)
			(type default)
		)
		(layer "In5.Cu")
	)
	(gr_line
		(start 279.236932 -299.556424)
		(end 279.236678 -299.556424)
		(stroke
			(width 0.2)
			(type default)
		)
		(layer "In5.Cu")
	)
	(gr_line
		(start 279.236932 -295.956482)
		(end 279.236678 -295.956482)
		(stroke
			(width 0.2)
			(type default)
		)
		(layer "In5.Cu")
	)
	(gr_line
		(start 279.236932 -263.151112)
		(end 279.236678 -263.151112)
		(stroke
			(width 0.2)
			(type default)
		)
		(layer "In5.Cu")
	)
	(gr_line
		(start 279.236932 -259.55117)
		(end 279.236678 -259.55117)
		(stroke
			(width 0.2)
			(type default)
		)
		(layer "In5.Cu")
	)
	(gr_line
		(start 279.236932 -255.951228)
		(end 279.236678 -255.951228)
		(stroke
			(width 0.2)
			(type default)
		)
		(layer "In5.Cu")
	)
	(gr_line
		(start 279.236932 -252.351032)
		(end 279.236678 -252.351032)
		(stroke
			(width 0.2)
			(type default)
		)
		(layer "In5.Cu")
	)
	(gr_arc
		(start 279.636728 -356.453694)
		(mid 280.185368 -355.905054)
		(end 279.636728 -355.356414)
		(stroke
			(width 0.2)
			(type default)
		)
		(layer "In5.Cu")
	)
	(gr_line
		(start 279.636728 -355.356414)
		(end 278.236934 -355.356414)
		(stroke
			(width 0.2)
			(type default)
		)
		(layer "In5.Cu")
	)
	(gr_arc
		(start 279.636728 -352.853752)
		(mid 280.185368 -352.305112)
		(end 279.636728 -351.756472)
		(stroke
			(width 0.2)
			(type default)
		)
		(layer "In5.Cu")
	)
	(gr_line
		(start 279.636728 -351.756472)
		(end 278.236934 -351.756472)
		(stroke
			(width 0.2)
			(type default)
		)
		(layer "In5.Cu")
	)
	(gr_arc
		(start 279.636728 -349.25381)
		(mid 280.185368 -348.70517)
		(end 279.636728 -348.15653)
		(stroke
			(width 0.2)
			(type default)
		)
		(layer "In5.Cu")
	)
	(gr_line
		(start 279.636728 -348.15653)
		(end 278.236934 -348.15653)
		(stroke
			(width 0.2)
			(type default)
		)
		(layer "In5.Cu")
	)
	(gr_arc
		(start 279.636728 -345.653868)
		(mid 280.185368 -345.105228)
		(end 279.636728 -344.556588)
		(stroke
			(width 0.2)
			(type default)
		)
		(layer "In5.Cu")
	)
	(gr_line
		(start 279.636728 -344.556588)
		(end 278.236934 -344.556588)
		(stroke
			(width 0.2)
			(type default)
		)
		(layer "In5.Cu")
	)
	(gr_arc
		(start 279.636728 -342.053672)
		(mid 280.185368 -341.505032)
		(end 279.636728 -340.956392)
		(stroke
			(width 0.2)
			(type default)
		)
		(layer "In5.Cu")
	)
	(gr_line
		(start 279.636728 -340.956392)
		(end 278.236934 -340.956392)
		(stroke
			(width 0.2)
			(type default)
		)
		(layer "In5.Cu")
	)
	(gr_arc
		(start 279.636728 -338.45373)
		(mid 280.185368 -337.90509)
		(end 279.636728 -337.35645)
		(stroke
			(width 0.2)
			(type default)
		)
		(layer "In5.Cu")
	)
	(gr_line
		(start 279.636728 -337.35645)
		(end 278.236934 -337.35645)
		(stroke
			(width 0.2)
			(type default)
		)
		(layer "In5.Cu")
	)
	(gr_arc
		(start 279.636728 -334.853788)
		(mid 280.185368 -334.305148)
		(end 279.636728 -333.756508)
		(stroke
			(width 0.2)
			(type default)
		)
		(layer "In5.Cu")
	)
	(gr_line
		(start 279.636728 -333.756508)
		(end 278.236934 -333.756508)
		(stroke
			(width 0.2)
			(type default)
		)
		(layer "In5.Cu")
	)
	(gr_arc
		(start 279.636728 -331.253846)
		(mid 280.185368 -330.705206)
		(end 279.636728 -330.156566)
		(stroke
			(width 0.2)
			(type default)
		)
		(layer "In5.Cu")
	)
	(gr_line
		(start 279.636728 -330.156566)
		(end 278.236934 -330.156566)
		(stroke
			(width 0.2)
			(type default)
		)
		(layer "In5.Cu")
	)
	(gr_arc
		(start 279.636728 -327.653904)
		(mid 280.185368 -327.105264)
		(end 279.636728 -326.556624)
		(stroke
			(width 0.2)
			(type default)
		)
		(layer "In5.Cu")
	)
	(gr_line
		(start 279.636728 -326.556624)
		(end 278.236934 -326.556624)
		(stroke
			(width 0.2)
			(type default)
		)
		(layer "In5.Cu")
	)
	(gr_arc
		(start 279.636728 -324.053708)
		(mid 280.185368 -323.505068)
		(end 279.636728 -322.956428)
		(stroke
			(width 0.2)
			(type default)
		)
		(layer "In5.Cu")
	)
	(gr_line
		(start 279.636728 -322.956428)
		(end 278.236934 -322.956428)
		(stroke
			(width 0.2)
			(type default)
		)
		(layer "In5.Cu")
	)
	(gr_arc
		(start 279.636728 -320.453766)
		(mid 280.185368 -319.905126)
		(end 279.636728 -319.356486)
		(stroke
			(width 0.2)
			(type default)
		)
		(layer "In5.Cu")
	)
	(gr_line
		(start 279.636728 -319.356486)
		(end 278.236934 -319.356486)
		(stroke
			(width 0.2)
			(type default)
		)
		(layer "In5.Cu")
	)
	(gr_arc
		(start 279.636728 -316.853824)
		(mid 280.185368 -316.305184)
		(end 279.636728 -315.756544)
		(stroke
			(width 0.2)
			(type default)
		)
		(layer "In5.Cu")
	)
	(gr_line
		(start 279.636728 -315.756544)
		(end 278.236934 -315.756544)
		(stroke
			(width 0.2)
			(type default)
		)
		(layer "In5.Cu")
	)
	(gr_arc
		(start 279.636728 -313.253882)
		(mid 280.185368 -312.705242)
		(end 279.636728 -312.156602)
		(stroke
			(width 0.2)
			(type default)
		)
		(layer "In5.Cu")
	)
	(gr_line
		(start 279.636728 -312.156602)
		(end 278.236934 -312.156602)
		(stroke
			(width 0.2)
			(type default)
		)
		(layer "In5.Cu")
	)
	(gr_arc
		(start 279.636728 -309.653686)
		(mid 280.185368 -309.105046)
		(end 279.636728 -308.556406)
		(stroke
			(width 0.2)
			(type default)
		)
		(layer "In5.Cu")
	)
	(gr_line
		(start 279.636728 -308.556406)
		(end 278.236934 -308.556406)
		(stroke
			(width 0.2)
			(type default)
		)
		(layer "In5.Cu")
	)
	(gr_arc
		(start 279.636728 -306.053744)
		(mid 280.185368 -305.505104)
		(end 279.636728 -304.956464)
		(stroke
			(width 0.2)
			(type default)
		)
		(layer "In5.Cu")
	)
	(gr_line
		(start 279.636728 -304.956464)
		(end 278.236934 -304.956464)
		(stroke
			(width 0.2)
			(type default)
		)
		(layer "In5.Cu")
	)
	(gr_arc
		(start 279.636728 -302.453802)
		(mid 280.185368 -301.905162)
		(end 279.636728 -301.356522)
		(stroke
			(width 0.2)
			(type default)
		)
		(layer "In5.Cu")
	)
	(gr_line
		(start 279.636728 -301.356522)
		(end 278.236934 -301.356522)
		(stroke
			(width 0.2)
			(type default)
		)
		(layer "In5.Cu")
	)
	(gr_arc
		(start 279.636728 -298.85386)
		(mid 280.185368 -298.30522)
		(end 279.636728 -297.75658)
		(stroke
			(width 0.2)
			(type default)
		)
		(layer "In5.Cu")
	)
	(gr_line
		(start 279.636728 -297.75658)
		(end 278.236934 -297.75658)
		(stroke
			(width 0.2)
			(type default)
		)
		(layer "In5.Cu")
	)
	(gr_arc
		(start 279.636728 -295.253918)
		(mid 280.185368 -294.705278)
		(end 279.636728 -294.156638)
		(stroke
			(width 0.2)
			(type default)
		)
		(layer "In5.Cu")
	)
	(gr_line
		(start 279.636728 -294.156638)
		(end 278.236934 -294.156638)
		(stroke
			(width 0.2)
			(type default)
		)
		(layer "In5.Cu")
	)
	(gr_arc
		(start 279.636728 -262.453374)
		(mid 280.187908 -261.902194)
		(end 279.636728 -261.351014)
		(stroke
			(width 0.2)
			(type default)
		)
		(layer "In5.Cu")
	)
	(gr_line
		(start 279.636728 -261.351014)
		(end 278.236934 -261.351014)
		(stroke
			(width 0.2)
			(type default)
		)
		(layer "In5.Cu")
	)
	(gr_arc
		(start 279.636728 -258.853432)
		(mid 280.187908 -258.302252)
		(end 279.636728 -257.751072)
		(stroke
			(width 0.2)
			(type default)
		)
		(layer "In5.Cu")
	)
	(gr_line
		(start 279.636728 -257.751072)
		(end 278.236934 -257.751072)
		(stroke
			(width 0.2)
			(type default)
		)
		(layer "In5.Cu")
	)
	(gr_arc
		(start 279.636728 -255.25349)
		(mid 280.187908 -254.70231)
		(end 279.636728 -254.15113)
		(stroke
			(width 0.2)
			(type default)
		)
		(layer "In5.Cu")
	)
	(gr_line
		(start 279.636728 -254.15113)
		(end 278.236934 -254.15113)
		(stroke
			(width 0.2)
			(type default)
		)
		(layer "In5.Cu")
	)
	(gr_arc
		(start 279.636728 -251.653548)
		(mid 280.187908 -251.102368)
		(end 279.636728 -250.551188)
		(stroke
			(width 0.2)
			(type default)
		)
		(layer "In5.Cu")
	)
	(gr_line
		(start 279.636728 -250.551188)
		(end 278.236934 -250.551188)
		(stroke
			(width 0.2)
			(type default)
		)
		(layer "In5.Cu")
	)
	(gr_line
		(start 279.999948 -180.128926)
		(end 281.016964 -180.128926)
		(stroke
			(width 0.381)
			(type default)
		)
		(layer "In5.Cu")
	)
	(gr_line
		(start 279.999948 -83.829144)
		(end 281.016964 -83.829144)
		(stroke
			(width 0.381)
			(type default)
		)
		(layer "In5.Cu")
	)
	(gr_line
		(start 280.17851 -102.539038)
		(end 279.182068 -101.542596)
		(stroke
			(width 0.381)
			(type default)
		)
		(layer "In5.Cu")
	)
	(gr_line
		(start 280.17851 -6.239256)
		(end 279.182068 -5.242814)
		(stroke
			(width 0.381)
			(type default)
		)
		(layer "In5.Cu")
	)
	(gr_line
		(start 280.422858 -10.545826)
		(end 278.433784 -11.54049)
		(stroke
			(width 0.2)
			(type default)
		)
		(layer "In5.Cu")
	)
	(gr_line
		(start 280.423874 -176.847754)
		(end 278.424132 -177.847752)
		(stroke
			(width 0.2)
			(type default)
		)
		(layer "In5.Cu")
	)
	(gr_line
		(start 280.423874 -172.847762)
		(end 278.424132 -173.84776)
		(stroke
			(width 0.2)
			(type default)
		)
		(layer "In5.Cu")
	)
	(gr_line
		(start 280.423874 -168.84777)
		(end 278.424132 -169.847768)
		(stroke
			(width 0.2)
			(type default)
		)
		(layer "In5.Cu")
	)
	(gr_line
		(start 280.423874 -164.847778)
		(end 278.424132 -165.847776)
		(stroke
			(width 0.2)
			(type default)
		)
		(layer "In5.Cu")
	)
	(gr_line
		(start 280.423874 -136.847834)
		(end 278.424132 -137.847832)
		(stroke
			(width 0.2)
			(type default)
		)
		(layer "In5.Cu")
	)
	(gr_line
		(start 280.423874 -80.547972)
		(end 278.424132 -81.54797)
		(stroke
			(width 0.2)
			(type default)
		)
		(layer "In5.Cu")
	)
	(gr_line
		(start 280.423874 -76.54798)
		(end 278.424132 -77.547978)
		(stroke
			(width 0.2)
			(type default)
		)
		(layer "In5.Cu")
	)
	(gr_line
		(start 280.423874 -72.547988)
		(end 278.424132 -73.547986)
		(stroke
			(width 0.2)
			(type default)
		)
		(layer "In5.Cu")
	)
	(gr_line
		(start 280.423874 -68.547996)
		(end 278.424132 -69.547994)
		(stroke
			(width 0.2)
			(type default)
		)
		(layer "In5.Cu")
	)
	(gr_line
		(start 280.423874 -64.548004)
		(end 278.424132 -65.548002)
		(stroke
			(width 0.2)
			(type default)
		)
		(layer "In5.Cu")
	)
	(gr_line
		(start 280.423874 -60.548012)
		(end 278.424132 -61.54801)
		(stroke
			(width 0.2)
			(type default)
		)
		(layer "In5.Cu")
	)
	(gr_line
		(start 280.423874 -56.54802)
		(end 278.424132 -57.548018)
		(stroke
			(width 0.2)
			(type default)
		)
		(layer "In5.Cu")
	)
	(gr_line
		(start 280.423874 -52.548028)
		(end 278.424132 -53.548026)
		(stroke
			(width 0.2)
			(type default)
		)
		(layer "In5.Cu")
	)
	(gr_line
		(start 280.423874 -48.548036)
		(end 278.424132 -49.548034)
		(stroke
			(width 0.2)
			(type default)
		)
		(layer "In5.Cu")
	)
	(gr_line
		(start 280.423874 -44.548044)
		(end 278.424132 -45.548042)
		(stroke
			(width 0.2)
			(type default)
		)
		(layer "In5.Cu")
	)
	(gr_line
		(start 280.423874 -40.548052)
		(end 278.424132 -41.54805)
		(stroke
			(width 0.2)
			(type default)
		)
		(layer "In5.Cu")
	)
	(gr_line
		(start 280.423874 -36.54806)
		(end 278.424132 -37.548058)
		(stroke
			(width 0.2)
			(type default)
		)
		(layer "In5.Cu")
	)
	(gr_line
		(start 280.423874 -16.5481)
		(end 278.424132 -17.548098)
		(stroke
			(width 0.2)
			(type default)
		)
		(layer "In5.Cu")
	)
	(gr_line
		(start 280.425144 -176.85004)
		(end 280.423874 -176.847754)
		(stroke
			(width 0.2)
			(type default)
		)
		(layer "In5.Cu")
	)
	(gr_line
		(start 280.425144 -172.850048)
		(end 280.423874 -172.847762)
		(stroke
			(width 0.2)
			(type default)
		)
		(layer "In5.Cu")
	)
	(gr_line
		(start 280.425144 -168.850056)
		(end 280.423874 -168.84777)
		(stroke
			(width 0.2)
			(type default)
		)
		(layer "In5.Cu")
	)
	(gr_line
		(start 280.425144 -164.850064)
		(end 280.423874 -164.847778)
		(stroke
			(width 0.2)
			(type default)
		)
		(layer "In5.Cu")
	)
	(gr_line
		(start 280.425144 -136.85012)
		(end 280.423874 -136.847834)
		(stroke
			(width 0.2)
			(type default)
		)
		(layer "In5.Cu")
	)
	(gr_line
		(start 280.425144 -80.550258)
		(end 280.423874 -80.547972)
		(stroke
			(width 0.2)
			(type default)
		)
		(layer "In5.Cu")
	)
	(gr_line
		(start 280.425144 -76.550266)
		(end 280.423874 -76.54798)
		(stroke
			(width 0.2)
			(type default)
		)
		(layer "In5.Cu")
	)
	(gr_line
		(start 280.425144 -72.550274)
		(end 280.423874 -72.547988)
		(stroke
			(width 0.2)
			(type default)
		)
		(layer "In5.Cu")
	)
	(gr_line
		(start 280.425144 -68.550282)
		(end 280.423874 -68.547996)
		(stroke
			(width 0.2)
			(type default)
		)
		(layer "In5.Cu")
	)
	(gr_line
		(start 280.425144 -64.55029)
		(end 280.423874 -64.548004)
		(stroke
			(width 0.2)
			(type default)
		)
		(layer "In5.Cu")
	)
	(gr_line
		(start 280.425144 -60.550298)
		(end 280.423874 -60.548012)
		(stroke
			(width 0.2)
			(type default)
		)
		(layer "In5.Cu")
	)
	(gr_line
		(start 280.425144 -56.550306)
		(end 280.423874 -56.54802)
		(stroke
			(width 0.2)
			(type default)
		)
		(layer "In5.Cu")
	)
	(gr_line
		(start 280.425144 -52.550314)
		(end 280.423874 -52.548028)
		(stroke
			(width 0.2)
			(type default)
		)
		(layer "In5.Cu")
	)
	(gr_line
		(start 280.425144 -48.550322)
		(end 280.423874 -48.548036)
		(stroke
			(width 0.2)
			(type default)
		)
		(layer "In5.Cu")
	)
	(gr_line
		(start 280.425144 -44.55033)
		(end 280.423874 -44.548044)
		(stroke
			(width 0.2)
			(type default)
		)
		(layer "In5.Cu")
	)
	(gr_line
		(start 280.425144 -40.550338)
		(end 280.423874 -40.548052)
		(stroke
			(width 0.2)
			(type default)
		)
		(layer "In5.Cu")
	)
	(gr_line
		(start 280.425144 -36.550346)
		(end 280.423874 -36.54806)
		(stroke
			(width 0.2)
			(type default)
		)
		(layer "In5.Cu")
	)
	(gr_line
		(start 280.425144 -16.550386)
		(end 280.423874 -16.5481)
		(stroke
			(width 0.2)
			(type default)
		)
		(layer "In5.Cu")
	)
	(gr_line
		(start 280.42616 -160.852358)
		(end 278.426418 -161.852102)
		(stroke
			(width 0.2)
			(type default)
		)
		(layer "In5.Cu")
	)
	(gr_line
		(start 280.42616 -156.852366)
		(end 278.426418 -157.85211)
		(stroke
			(width 0.2)
			(type default)
		)
		(layer "In5.Cu")
	)
	(gr_line
		(start 280.42616 -152.852374)
		(end 278.426418 -153.852118)
		(stroke
			(width 0.2)
			(type default)
		)
		(layer "In5.Cu")
	)
	(gr_line
		(start 280.42616 -148.852382)
		(end 278.426418 -149.852126)
		(stroke
			(width 0.2)
			(type default)
		)
		(layer "In5.Cu")
	)
	(gr_line
		(start 280.42616 -128.852422)
		(end 278.426418 -129.852166)
		(stroke
			(width 0.2)
			(type default)
		)
		(layer "In5.Cu")
	)
	(gr_line
		(start 280.42616 -124.85243)
		(end 278.426418 -125.852174)
		(stroke
			(width 0.2)
			(type default)
		)
		(layer "In5.Cu")
	)
	(gr_line
		(start 280.42616 -120.852438)
		(end 278.426418 -121.852182)
		(stroke
			(width 0.2)
			(type default)
		)
		(layer "In5.Cu")
	)
	(gr_line
		(start 280.42616 -116.852446)
		(end 278.426418 -117.85219)
		(stroke
			(width 0.2)
			(type default)
		)
		(layer "In5.Cu")
	)
	(gr_line
		(start 280.436574 -112.872774)
		(end 278.44496 -113.868708)
		(stroke
			(width 0.2)
			(type default)
		)
		(layer "In5.Cu")
	)
	(gr_arc
		(start 280.636726 -358.253792)
		(mid 281.185366 -357.705152)
		(end 280.636726 -357.156512)
		(stroke
			(width 0.2)
			(type default)
		)
		(layer "In5.Cu")
	)
	(gr_line
		(start 280.636726 -357.156512)
		(end 279.236932 -357.156512)
		(stroke
			(width 0.2)
			(type default)
		)
		(layer "In5.Cu")
	)
	(gr_arc
		(start 280.636726 -354.65385)
		(mid 281.185366 -354.10521)
		(end 280.636726 -353.55657)
		(stroke
			(width 0.2)
			(type default)
		)
		(layer "In5.Cu")
	)
	(gr_line
		(start 280.636726 -353.55657)
		(end 279.236932 -353.55657)
		(stroke
			(width 0.2)
			(type default)
		)
		(layer "In5.Cu")
	)
	(gr_arc
		(start 280.636726 -351.053908)
		(mid 281.185366 -350.505268)
		(end 280.636726 -349.956628)
		(stroke
			(width 0.2)
			(type default)
		)
		(layer "In5.Cu")
	)
	(gr_line
		(start 280.636726 -349.956628)
		(end 279.236932 -349.956628)
		(stroke
			(width 0.2)
			(type default)
		)
		(layer "In5.Cu")
	)
	(gr_arc
		(start 280.636726 -347.453712)
		(mid 281.185366 -346.905072)
		(end 280.636726 -346.356432)
		(stroke
			(width 0.2)
			(type default)
		)
		(layer "In5.Cu")
	)
	(gr_line
		(start 280.636726 -346.356432)
		(end 279.236932 -346.356432)
		(stroke
			(width 0.2)
			(type default)
		)
		(layer "In5.Cu")
	)
	(gr_arc
		(start 280.636726 -343.85377)
		(mid 281.185366 -343.30513)
		(end 280.636726 -342.75649)
		(stroke
			(width 0.2)
			(type default)
		)
		(layer "In5.Cu")
	)
	(gr_line
		(start 280.636726 -342.75649)
		(end 279.236932 -342.75649)
		(stroke
			(width 0.2)
			(type default)
		)
		(layer "In5.Cu")
	)
	(gr_arc
		(start 280.636726 -340.253828)
		(mid 281.185366 -339.705188)
		(end 280.636726 -339.156548)
		(stroke
			(width 0.2)
			(type default)
		)
		(layer "In5.Cu")
	)
	(gr_line
		(start 280.636726 -339.156548)
		(end 279.236932 -339.156548)
		(stroke
			(width 0.2)
			(type default)
		)
		(layer "In5.Cu")
	)
	(gr_arc
		(start 280.636726 -336.653886)
		(mid 281.185366 -336.105246)
		(end 280.636726 -335.556606)
		(stroke
			(width 0.2)
			(type default)
		)
		(layer "In5.Cu")
	)
	(gr_line
		(start 280.636726 -335.556606)
		(end 279.236932 -335.556606)
		(stroke
			(width 0.2)
			(type default)
		)
		(layer "In5.Cu")
	)
	(gr_arc
		(start 280.636726 -333.05369)
		(mid 281.185366 -332.50505)
		(end 280.636726 -331.95641)
		(stroke
			(width 0.2)
			(type default)
		)
		(layer "In5.Cu")
	)
	(gr_line
		(start 280.636726 -331.95641)
		(end 279.236932 -331.95641)
		(stroke
			(width 0.2)
			(type default)
		)
		(layer "In5.Cu")
	)
	(gr_arc
		(start 280.636726 -329.453748)
		(mid 281.185366 -328.905108)
		(end 280.636726 -328.356468)
		(stroke
			(width 0.2)
			(type default)
		)
		(layer "In5.Cu")
	)
	(gr_line
		(start 280.636726 -328.356468)
		(end 279.236932 -328.356468)
		(stroke
			(width 0.2)
			(type default)
		)
		(layer "In5.Cu")
	)
	(gr_arc
		(start 280.636726 -325.853806)
		(mid 281.185366 -325.305166)
		(end 280.636726 -324.756526)
		(stroke
			(width 0.2)
			(type default)
		)
		(layer "In5.Cu")
	)
	(gr_line
		(start 280.636726 -324.756526)
		(end 279.236932 -324.756526)
		(stroke
			(width 0.2)
			(type default)
		)
		(layer "In5.Cu")
	)
	(gr_arc
		(start 280.636726 -322.253864)
		(mid 281.185366 -321.705224)
		(end 280.636726 -321.156584)
		(stroke
			(width 0.2)
			(type default)
		)
		(layer "In5.Cu")
	)
	(gr_line
		(start 280.636726 -321.156584)
		(end 279.236932 -321.156584)
		(stroke
			(width 0.2)
			(type default)
		)
		(layer "In5.Cu")
	)
	(gr_arc
		(start 280.636726 -318.653668)
		(mid 281.185366 -318.105028)
		(end 280.636726 -317.556388)
		(stroke
			(width 0.2)
			(type default)
		)
		(layer "In5.Cu")
	)
	(gr_line
		(start 280.636726 -317.556388)
		(end 279.236932 -317.556388)
		(stroke
			(width 0.2)
			(type default)
		)
		(layer "In5.Cu")
	)
	(gr_arc
		(start 280.636726 -315.053726)
		(mid 281.185366 -314.505086)
		(end 280.636726 -313.956446)
		(stroke
			(width 0.2)
			(type default)
		)
		(layer "In5.Cu")
	)
	(gr_line
		(start 280.636726 -313.956446)
		(end 279.236932 -313.956446)
		(stroke
			(width 0.2)
			(type default)
		)
		(layer "In5.Cu")
	)
	(gr_arc
		(start 280.636726 -311.453784)
		(mid 281.185366 -310.905144)
		(end 280.636726 -310.356504)
		(stroke
			(width 0.2)
			(type default)
		)
		(layer "In5.Cu")
	)
	(gr_line
		(start 280.636726 -310.356504)
		(end 279.236932 -310.356504)
		(stroke
			(width 0.2)
			(type default)
		)
		(layer "In5.Cu")
	)
	(gr_arc
		(start 280.636726 -307.853842)
		(mid 281.185366 -307.305202)
		(end 280.636726 -306.756562)
		(stroke
			(width 0.2)
			(type default)
		)
		(layer "In5.Cu")
	)
	(gr_line
		(start 280.636726 -306.756562)
		(end 279.236932 -306.756562)
		(stroke
			(width 0.2)
			(type default)
		)
		(layer "In5.Cu")
	)
	(gr_arc
		(start 280.636726 -304.2539)
		(mid 281.185366 -303.70526)
		(end 280.636726 -303.15662)
		(stroke
			(width 0.2)
			(type default)
		)
		(layer "In5.Cu")
	)
	(gr_line
		(start 280.636726 -303.15662)
		(end 279.236932 -303.15662)
		(stroke
			(width 0.2)
			(type default)
		)
		(layer "In5.Cu")
	)
	(gr_arc
		(start 280.636726 -300.653704)
		(mid 281.185366 -300.105064)
		(end 280.636726 -299.556424)
		(stroke
			(width 0.2)
			(type default)
		)
		(layer "In5.Cu")
	)
	(gr_line
		(start 280.636726 -299.556424)
		(end 279.236932 -299.556424)
		(stroke
			(width 0.2)
			(type default)
		)
		(layer "In5.Cu")
	)
	(gr_arc
		(start 280.636726 -297.053762)
		(mid 281.185366 -296.505122)
		(end 280.636726 -295.956482)
		(stroke
			(width 0.2)
			(type default)
		)
		(layer "In5.Cu")
	)
	(gr_line
		(start 280.636726 -295.956482)
		(end 279.236932 -295.956482)
		(stroke
			(width 0.2)
			(type default)
		)
		(layer "In5.Cu")
	)
	(gr_arc
		(start 280.636726 -264.253472)
		(mid 281.187906 -263.702292)
		(end 280.636726 -263.151112)
		(stroke
			(width 0.2)
			(type default)
		)
		(layer "In5.Cu")
	)
	(gr_line
		(start 280.636726 -263.151112)
		(end 279.236932 -263.151112)
		(stroke
			(width 0.2)
			(type default)
		)
		(layer "In5.Cu")
	)
	(gr_arc
		(start 280.636726 -260.65353)
		(mid 281.187906 -260.10235)
		(end 280.636726 -259.55117)
		(stroke
			(width 0.2)
			(type default)
		)
		(layer "In5.Cu")
	)
	(gr_line
		(start 280.636726 -259.55117)
		(end 279.236932 -259.55117)
		(stroke
			(width 0.2)
			(type default)
		)
		(layer "In5.Cu")
	)
	(gr_arc
		(start 280.636726 -257.053588)
		(mid 281.187906 -256.502408)
		(end 280.636726 -255.951228)
		(stroke
			(width 0.2)
			(type default)
		)
		(layer "In5.Cu")
	)
	(gr_line
		(start 280.636726 -255.951228)
		(end 279.236932 -255.951228)
		(stroke
			(width 0.2)
			(type default)
		)
		(layer "In5.Cu")
	)
	(gr_arc
		(start 280.636726 -253.453392)
		(mid 281.187906 -252.902212)
		(end 280.636726 -252.351032)
		(stroke
			(width 0.2)
			(type default)
		)
		(layer "In5.Cu")
	)
	(gr_line
		(start 280.636726 -252.351032)
		(end 279.236932 -252.351032)
		(stroke
			(width 0.2)
			(type default)
		)
		(layer "In5.Cu")
	)
	(gr_line
		(start 281.016964 -180.128926)
		(end 284.521402 -183.633364)
		(stroke
			(width 0.381)
			(type default)
		)
		(layer "In5.Cu")
	)
	(gr_line
		(start 281.016964 -83.829144)
		(end 284.521402 -87.333582)
		(stroke
			(width 0.381)
			(type default)
		)
		(layer "In5.Cu")
	)
	(gr_arc
		(start 281.063446 -114.127026)
		(mid 281.377136 -113.186464)
		(end 280.436574 -112.872774)
		(stroke
			(width 0.2)
			(type default)
		)
		(layer "In5.Cu")
	)
	(gr_arc
		(start 281.07386 -162.14725)
		(mid 281.397456 -161.175954)
		(end 280.42616 -160.852358)
		(stroke
			(width 0.2)
			(type default)
		)
		(layer "In5.Cu")
	)
	(gr_arc
		(start 281.07386 -158.147258)
		(mid 281.397456 -157.175962)
		(end 280.42616 -156.852366)
		(stroke
			(width 0.2)
			(type default)
		)
		(layer "In5.Cu")
	)
	(gr_arc
		(start 281.07386 -154.147266)
		(mid 281.397456 -153.17597)
		(end 280.42616 -152.852374)
		(stroke
			(width 0.2)
			(type default)
		)
		(layer "In5.Cu")
	)
	(gr_arc
		(start 281.07386 -150.147274)
		(mid 281.397456 -149.175978)
		(end 280.42616 -148.852382)
		(stroke
			(width 0.2)
			(type default)
		)
		(layer "In5.Cu")
	)
	(gr_arc
		(start 281.07386 -130.147314)
		(mid 281.397456 -129.176018)
		(end 280.42616 -128.852422)
		(stroke
			(width 0.2)
			(type default)
		)
		(layer "In5.Cu")
	)
	(gr_arc
		(start 281.07386 -126.147322)
		(mid 281.397456 -125.176026)
		(end 280.42616 -124.85243)
		(stroke
			(width 0.2)
			(type default)
		)
		(layer "In5.Cu")
	)
	(gr_arc
		(start 281.07386 -122.14733)
		(mid 281.397456 -121.176034)
		(end 280.42616 -120.852438)
		(stroke
			(width 0.2)
			(type default)
		)
		(layer "In5.Cu")
	)
	(gr_arc
		(start 281.07386 -118.147338)
		(mid 281.397456 -117.176042)
		(end 280.42616 -116.852446)
		(stroke
			(width 0.2)
			(type default)
		)
		(layer "In5.Cu")
	)
	(gr_arc
		(start 281.074876 -178.149504)
		(mid 281.399742 -177.174906)
		(end 280.425144 -176.85004)
		(stroke
			(width 0.2)
			(type default)
		)
		(layer "In5.Cu")
	)
	(gr_arc
		(start 281.074876 -174.149512)
		(mid 281.399742 -173.174914)
		(end 280.425144 -172.850048)
		(stroke
			(width 0.2)
			(type default)
		)
		(layer "In5.Cu")
	)
	(gr_arc
		(start 281.074876 -170.14952)
		(mid 281.399742 -169.174922)
		(end 280.425144 -168.850056)
		(stroke
			(width 0.2)
			(type default)
		)
		(layer "In5.Cu")
	)
	(gr_arc
		(start 281.074876 -166.149528)
		(mid 281.399742 -165.17493)
		(end 280.425144 -164.850064)
		(stroke
			(width 0.2)
			(type default)
		)
		(layer "In5.Cu")
	)
	(gr_arc
		(start 281.074876 -138.149584)
		(mid 281.399742 -137.174986)
		(end 280.425144 -136.85012)
		(stroke
			(width 0.2)
			(type default)
		)
		(layer "In5.Cu")
	)
	(gr_arc
		(start 281.074876 -81.849722)
		(mid 281.399742 -80.875124)
		(end 280.425144 -80.550258)
		(stroke
			(width 0.2)
			(type default)
		)
		(layer "In5.Cu")
	)
	(gr_arc
		(start 281.074876 -77.84973)
		(mid 281.399742 -76.875132)
		(end 280.425144 -76.550266)
		(stroke
			(width 0.2)
			(type default)
		)
		(layer "In5.Cu")
	)
	(gr_arc
		(start 281.074876 -73.849738)
		(mid 281.399742 -72.87514)
		(end 280.425144 -72.550274)
		(stroke
			(width 0.2)
			(type default)
		)
		(layer "In5.Cu")
	)
	(gr_arc
		(start 281.074876 -69.849746)
		(mid 281.399742 -68.875148)
		(end 280.425144 -68.550282)
		(stroke
			(width 0.2)
			(type default)
		)
		(layer "In5.Cu")
	)
	(gr_arc
		(start 281.074876 -65.849754)
		(mid 281.399742 -64.875156)
		(end 280.425144 -64.55029)
		(stroke
			(width 0.2)
			(type default)
		)
		(layer "In5.Cu")
	)
	(gr_arc
		(start 281.074876 -61.849762)
		(mid 281.399742 -60.875164)
		(end 280.425144 -60.550298)
		(stroke
			(width 0.2)
			(type default)
		)
		(layer "In5.Cu")
	)
	(gr_arc
		(start 281.074876 -57.84977)
		(mid 281.399742 -56.875172)
		(end 280.425144 -56.550306)
		(stroke
			(width 0.2)
			(type default)
		)
		(layer "In5.Cu")
	)
	(gr_arc
		(start 281.074876 -53.849778)
		(mid 281.399742 -52.87518)
		(end 280.425144 -52.550314)
		(stroke
			(width 0.2)
			(type default)
		)
		(layer "In5.Cu")
	)
	(gr_arc
		(start 281.074876 -49.849786)
		(mid 281.399742 -48.875188)
		(end 280.425144 -48.550322)
		(stroke
			(width 0.2)
			(type default)
		)
		(layer "In5.Cu")
	)
	(gr_arc
		(start 281.074876 -45.849794)
		(mid 281.399742 -44.875196)
		(end 280.425144 -44.55033)
		(stroke
			(width 0.2)
			(type default)
		)
		(layer "In5.Cu")
	)
	(gr_arc
		(start 281.074876 -41.849802)
		(mid 281.399742 -40.875204)
		(end 280.425144 -40.550338)
		(stroke
			(width 0.2)
			(type default)
		)
		(layer "In5.Cu")
	)
	(gr_arc
		(start 281.074876 -37.84981)
		(mid 281.399742 -36.875212)
		(end 280.425144 -36.550346)
		(stroke
			(width 0.2)
			(type default)
		)
		(layer "In5.Cu")
	)
	(gr_arc
		(start 281.074876 -17.84985)
		(mid 281.399742 -16.875252)
		(end 280.425144 -16.550386)
		(stroke
			(width 0.2)
			(type default)
		)
		(layer "In5.Cu")
	)
	(gr_line
		(start 281.076146 -178.15179)
		(end 281.074876 -178.149504)
		(stroke
			(width 0.2)
			(type default)
		)
		(layer "In5.Cu")
	)
	(gr_line
		(start 281.076146 -174.151798)
		(end 281.074876 -174.149512)
		(stroke
			(width 0.2)
			(type default)
		)
		(layer "In5.Cu")
	)
	(gr_line
		(start 281.076146 -170.151806)
		(end 281.074876 -170.14952)
		(stroke
			(width 0.2)
			(type default)
		)
		(layer "In5.Cu")
	)
	(gr_line
		(start 281.076146 -166.151814)
		(end 281.074876 -166.149528)
		(stroke
			(width 0.2)
			(type default)
		)
		(layer "In5.Cu")
	)
	(gr_line
		(start 281.076146 -138.15187)
		(end 281.074876 -138.149584)
		(stroke
			(width 0.2)
			(type default)
		)
		(layer "In5.Cu")
	)
	(gr_line
		(start 281.076146 -81.852008)
		(end 281.074876 -81.849722)
		(stroke
			(width 0.2)
			(type default)
		)
		(layer "In5.Cu")
	)
	(gr_line
		(start 281.076146 -77.852016)
		(end 281.074876 -77.84973)
		(stroke
			(width 0.2)
			(type default)
		)
		(layer "In5.Cu")
	)
	(gr_line
		(start 281.076146 -73.852024)
		(end 281.074876 -73.849738)
		(stroke
			(width 0.2)
			(type default)
		)
		(layer "In5.Cu")
	)
	(gr_line
		(start 281.076146 -69.852032)
		(end 281.074876 -69.849746)
		(stroke
			(width 0.2)
			(type default)
		)
		(layer "In5.Cu")
	)
	(gr_line
		(start 281.076146 -65.85204)
		(end 281.074876 -65.849754)
		(stroke
			(width 0.2)
			(type default)
		)
		(layer "In5.Cu")
	)
	(gr_line
		(start 281.076146 -61.852048)
		(end 281.074876 -61.849762)
		(stroke
			(width 0.2)
			(type default)
		)
		(layer "In5.Cu")
	)
	(gr_line
		(start 281.076146 -57.852056)
		(end 281.074876 -57.84977)
		(stroke
			(width 0.2)
			(type default)
		)
		(layer "In5.Cu")
	)
	(gr_line
		(start 281.076146 -53.852064)
		(end 281.074876 -53.849778)
		(stroke
			(width 0.2)
			(type default)
		)
		(layer "In5.Cu")
	)
	(gr_line
		(start 281.076146 -49.852072)
		(end 281.074876 -49.849786)
		(stroke
			(width 0.2)
			(type default)
		)
		(layer "In5.Cu")
	)
	(gr_line
		(start 281.076146 -45.85208)
		(end 281.074876 -45.849794)
		(stroke
			(width 0.2)
			(type default)
		)
		(layer "In5.Cu")
	)
	(gr_line
		(start 281.076146 -41.852088)
		(end 281.074876 -41.849802)
		(stroke
			(width 0.2)
			(type default)
		)
		(layer "In5.Cu")
	)
	(gr_line
		(start 281.076146 -37.852096)
		(end 281.074876 -37.84981)
		(stroke
			(width 0.2)
			(type default)
		)
		(layer "In5.Cu")
	)
	(gr_line
		(start 281.076146 -17.852136)
		(end 281.074876 -17.84985)
		(stroke
			(width 0.2)
			(type default)
		)
		(layer "In5.Cu")
	)
	(gr_arc
		(start 281.077162 -11.854434)
		(mid 281.404314 -10.872978)
		(end 280.422858 -10.545826)
		(stroke
			(width 0.2)
			(type default)
		)
		(layer "In5.Cu")
	)
	(gr_line
		(start 282.83662 -264.250932)
		(end 284.236668 -264.250932)
		(stroke
			(width 0.2)
			(type default)
		)
		(layer "In5.Cu")
	)
	(gr_arc
		(start 282.83662 -263.153652)
		(mid 282.28798 -263.702292)
		(end 282.83662 -264.250932)
		(stroke
			(width 0.2)
			(type default)
		)
		(layer "In5.Cu")
	)
	(gr_line
		(start 282.922726 -35.854386)
		(end 284.922468 -36.854384)
		(stroke
			(width 0.2)
			(type default)
		)
		(layer "In5.Cu")
	)
	(gr_line
		(start 282.923742 -136.151874)
		(end 284.923738 -137.151872)
		(stroke
			(width 0.2)
			(type default)
		)
		(layer "In5.Cu")
	)
	(gr_line
		(start 282.923742 -108.15193)
		(end 284.923738 -109.151928)
		(stroke
			(width 0.2)
			(type default)
		)
		(layer "In5.Cu")
	)
	(gr_line
		(start 282.925012 -136.149588)
		(end 282.923742 -136.151874)
		(stroke
			(width 0.2)
			(type default)
		)
		(layer "In5.Cu")
	)
	(gr_line
		(start 282.936442 -180.126894)
		(end 284.928056 -181.122574)
		(stroke
			(width 0.2)
			(type default)
		)
		(layer "In5.Cu")
	)
	(gr_line
		(start 282.936442 -176.126902)
		(end 284.928056 -177.122582)
		(stroke
			(width 0.2)
			(type default)
		)
		(layer "In5.Cu")
	)
	(gr_line
		(start 282.936442 -172.12691)
		(end 284.928056 -173.12259)
		(stroke
			(width 0.2)
			(type default)
		)
		(layer "In5.Cu")
	)
	(gr_line
		(start 282.936442 -168.126918)
		(end 284.928056 -169.122598)
		(stroke
			(width 0.2)
			(type default)
		)
		(layer "In5.Cu")
	)
	(gr_line
		(start 282.936442 -164.126926)
		(end 284.928056 -165.122606)
		(stroke
			(width 0.2)
			(type default)
		)
		(layer "In5.Cu")
	)
	(gr_line
		(start 282.936442 -160.126934)
		(end 284.936438 -161.126932)
		(stroke
			(width 0.2)
			(type default)
		)
		(layer "In5.Cu")
	)
	(gr_line
		(start 282.936442 -156.126942)
		(end 284.928056 -157.122622)
		(stroke
			(width 0.2)
			(type default)
		)
		(layer "In5.Cu")
	)
	(gr_line
		(start 282.936442 -152.12695)
		(end 284.928056 -153.12263)
		(stroke
			(width 0.2)
			(type default)
		)
		(layer "In5.Cu")
	)
	(gr_line
		(start 282.936442 -128.126998)
		(end 284.928056 -129.122678)
		(stroke
			(width 0.2)
			(type default)
		)
		(layer "In5.Cu")
	)
	(gr_line
		(start 282.936442 -124.127006)
		(end 284.928056 -125.122686)
		(stroke
			(width 0.2)
			(type default)
		)
		(layer "In5.Cu")
	)
	(gr_line
		(start 282.936442 -120.127014)
		(end 284.928056 -121.122694)
		(stroke
			(width 0.2)
			(type default)
		)
		(layer "In5.Cu")
	)
	(gr_line
		(start 282.936442 -116.127022)
		(end 284.928056 -117.122702)
		(stroke
			(width 0.2)
			(type default)
		)
		(layer "In5.Cu")
	)
	(gr_line
		(start 282.936442 -83.827112)
		(end 284.928056 -84.822792)
		(stroke
			(width 0.2)
			(type default)
		)
		(layer "In5.Cu")
	)
	(gr_line
		(start 282.936442 -79.82712)
		(end 284.928056 -80.8228)
		(stroke
			(width 0.2)
			(type default)
		)
		(layer "In5.Cu")
	)
	(gr_line
		(start 282.936442 -75.827128)
		(end 284.928056 -76.822808)
		(stroke
			(width 0.2)
			(type default)
		)
		(layer "In5.Cu")
	)
	(gr_line
		(start 282.936442 -71.827136)
		(end 284.928056 -72.822816)
		(stroke
			(width 0.2)
			(type default)
		)
		(layer "In5.Cu")
	)
	(gr_line
		(start 282.936442 -67.827144)
		(end 284.928056 -68.822824)
		(stroke
			(width 0.2)
			(type default)
		)
		(layer "In5.Cu")
	)
	(gr_line
		(start 282.936442 -63.827152)
		(end 284.928056 -64.822832)
		(stroke
			(width 0.2)
			(type default)
		)
		(layer "In5.Cu")
	)
	(gr_line
		(start 282.936442 -59.82716)
		(end 284.928056 -60.82284)
		(stroke
			(width 0.2)
			(type default)
		)
		(layer "In5.Cu")
	)
	(gr_line
		(start 282.936442 -55.827168)
		(end 284.928056 -56.822848)
		(stroke
			(width 0.2)
			(type default)
		)
		(layer "In5.Cu")
	)
	(gr_line
		(start 282.936442 -51.827176)
		(end 284.928056 -52.822856)
		(stroke
			(width 0.2)
			(type default)
		)
		(layer "In5.Cu")
	)
	(gr_line
		(start 282.936442 -47.827184)
		(end 284.928056 -48.822864)
		(stroke
			(width 0.2)
			(type default)
		)
		(layer "In5.Cu")
	)
	(gr_line
		(start 282.936442 -43.827192)
		(end 284.928056 -44.822872)
		(stroke
			(width 0.2)
			(type default)
		)
		(layer "In5.Cu")
	)
	(gr_line
		(start 282.936442 -39.8272)
		(end 284.928056 -40.82288)
		(stroke
			(width 0.2)
			(type default)
		)
		(layer "In5.Cu")
	)
	(gr_arc
		(start 283.563314 -178.872642)
		(mid 282.622752 -179.186332)
		(end 282.936442 -180.126894)
		(stroke
			(width 0.2)
			(type default)
		)
		(layer "In5.Cu")
	)
	(gr_arc
		(start 283.563314 -174.87265)
		(mid 282.622752 -175.18634)
		(end 282.936442 -176.126902)
		(stroke
			(width 0.2)
			(type default)
		)
		(layer "In5.Cu")
	)
	(gr_arc
		(start 283.563314 -170.872658)
		(mid 282.622752 -171.186348)
		(end 282.936442 -172.12691)
		(stroke
			(width 0.2)
			(type default)
		)
		(layer "In5.Cu")
	)
	(gr_arc
		(start 283.563314 -166.872666)
		(mid 282.622752 -167.186356)
		(end 282.936442 -168.126918)
		(stroke
			(width 0.2)
			(type default)
		)
		(layer "In5.Cu")
	)
	(gr_arc
		(start 283.563314 -162.872674)
		(mid 282.622752 -163.186364)
		(end 282.936442 -164.126926)
		(stroke
			(width 0.2)
			(type default)
		)
		(layer "In5.Cu")
	)
	(gr_arc
		(start 283.563314 -154.87269)
		(mid 282.622752 -155.18638)
		(end 282.936442 -156.126942)
		(stroke
			(width 0.2)
			(type default)
		)
		(layer "In5.Cu")
	)
	(gr_arc
		(start 283.563314 -150.872698)
		(mid 282.622752 -151.186388)
		(end 282.936442 -152.12695)
		(stroke
			(width 0.2)
			(type default)
		)
		(layer "In5.Cu")
	)
	(gr_arc
		(start 283.563314 -126.872746)
		(mid 282.622752 -127.186436)
		(end 282.936442 -128.126998)
		(stroke
			(width 0.2)
			(type default)
		)
		(layer "In5.Cu")
	)
	(gr_arc
		(start 283.563314 -122.872754)
		(mid 282.622752 -123.186444)
		(end 282.936442 -124.127006)
		(stroke
			(width 0.2)
			(type default)
		)
		(layer "In5.Cu")
	)
	(gr_arc
		(start 283.563314 -118.872762)
		(mid 282.622752 -119.186452)
		(end 282.936442 -120.127014)
		(stroke
			(width 0.2)
			(type default)
		)
		(layer "In5.Cu")
	)
	(gr_arc
		(start 283.563314 -114.87277)
		(mid 282.622752 -115.18646)
		(end 282.936442 -116.127022)
		(stroke
			(width 0.2)
			(type default)
		)
		(layer "In5.Cu")
	)
	(gr_arc
		(start 283.563314 -82.57286)
		(mid 282.622752 -82.88655)
		(end 282.936442 -83.827112)
		(stroke
			(width 0.2)
			(type default)
		)
		(layer "In5.Cu")
	)
	(gr_arc
		(start 283.563314 -78.572868)
		(mid 282.622752 -78.886558)
		(end 282.936442 -79.82712)
		(stroke
			(width 0.2)
			(type default)
		)
		(layer "In5.Cu")
	)
	(gr_arc
		(start 283.563314 -74.572876)
		(mid 282.622752 -74.886566)
		(end 282.936442 -75.827128)
		(stroke
			(width 0.2)
			(type default)
		)
		(layer "In5.Cu")
	)
	(gr_arc
		(start 283.563314 -70.572884)
		(mid 282.622752 -70.886574)
		(end 282.936442 -71.827136)
		(stroke
			(width 0.2)
			(type default)
		)
		(layer "In5.Cu")
	)
	(gr_arc
		(start 283.563314 -66.572892)
		(mid 282.622752 -66.886582)
		(end 282.936442 -67.827144)
		(stroke
			(width 0.2)
			(type default)
		)
		(layer "In5.Cu")
	)
	(gr_arc
		(start 283.563314 -62.5729)
		(mid 282.622752 -62.88659)
		(end 282.936442 -63.827152)
		(stroke
			(width 0.2)
			(type default)
		)
		(layer "In5.Cu")
	)
	(gr_arc
		(start 283.563314 -58.572908)
		(mid 282.622752 -58.886598)
		(end 282.936442 -59.82716)
		(stroke
			(width 0.2)
			(type default)
		)
		(layer "In5.Cu")
	)
	(gr_arc
		(start 283.563314 -54.572916)
		(mid 282.622752 -54.886606)
		(end 282.936442 -55.827168)
		(stroke
			(width 0.2)
			(type default)
		)
		(layer "In5.Cu")
	)
	(gr_arc
		(start 283.563314 -50.572924)
		(mid 282.622752 -50.886614)
		(end 282.936442 -51.827176)
		(stroke
			(width 0.2)
			(type default)
		)
		(layer "In5.Cu")
	)
	(gr_arc
		(start 283.563314 -46.572932)
		(mid 282.622752 -46.886622)
		(end 282.936442 -47.827184)
		(stroke
			(width 0.2)
			(type default)
		)
		(layer "In5.Cu")
	)
	(gr_arc
		(start 283.563314 -42.57294)
		(mid 282.622752 -42.88663)
		(end 282.936442 -43.827192)
		(stroke
			(width 0.2)
			(type default)
		)
		(layer "In5.Cu")
	)
	(gr_arc
		(start 283.563314 -38.572948)
		(mid 282.622752 -38.886638)
		(end 282.936442 -39.8272)
		(stroke
			(width 0.2)
			(type default)
		)
		(layer "In5.Cu")
	)
	(gr_arc
		(start 283.571696 -158.877)
		(mid 282.62492 -159.182185)
		(end 282.936442 -160.126934)
		(stroke
			(width 0.2)
			(type default)
		)
		(layer "In5.Cu")
	)
	(gr_arc
		(start 283.574744 -134.850124)
		(mid 282.600146 -135.17499)
		(end 282.925012 -136.149588)
		(stroke
			(width 0.2)
			(type default)
		)
		(layer "In5.Cu")
	)
	(gr_line
		(start 283.576014 -134.847838)
		(end 283.574744 -134.850124)
		(stroke
			(width 0.2)
			(type default)
		)
		(layer "In5.Cu")
	)
	(gr_arc
		(start 283.576014 -106.847894)
		(mid 282.59786 -107.173776)
		(end 282.923742 -108.15193)
		(stroke
			(width 0.2)
			(type default)
		)
		(layer "In5.Cu")
	)
	(gr_arc
		(start 283.57703 -34.545778)
		(mid 282.595574 -34.87293)
		(end 282.922726 -35.854386)
		(stroke
			(width 0.2)
			(type default)
		)
		(layer "In5.Cu")
	)
	(gr_line
		(start 283.814774 -102.539038)
		(end 280.17851 -102.539038)
		(stroke
			(width 0.381)
			(type default)
		)
		(layer "In5.Cu")
	)
	(gr_line
		(start 283.814774 -6.239256)
		(end 280.17851 -6.239256)
		(stroke
			(width 0.381)
			(type default)
		)
		(layer "In5.Cu")
	)
	(gr_arc
		(start 284.236668 -264.250932)
		(mid 284.785308 -263.702292)
		(end 284.236668 -263.153652)
		(stroke
			(width 0.2)
			(type default)
		)
		(layer "In5.Cu")
	)
	(gr_line
		(start 284.236668 -263.153652)
		(end 282.83662 -263.153652)
		(stroke
			(width 0.2)
			(type default)
		)
		(layer "In5.Cu")
	)
	(gr_line
		(start 284.521402 -183.633364)
		(end 287.023048 -183.633364)
		(stroke
			(width 0.381)
			(type default)
		)
		(layer "In5.Cu")
	)
	(gr_line
		(start 284.521402 -87.333582)
		(end 287.023048 -87.333582)
		(stroke
			(width 0.381)
			(type default)
		)
		(layer "In5.Cu")
	)
	(gr_line
		(start 284.6324 -198.0184)
		(end 293.8526 -198.0184)
		(stroke
			(width 0.381)
			(type default)
		)
		(layer "In5.Cu")
	)
	(gr_line
		(start 284.863032 -101.49078)
		(end 283.814774 -102.539038)
		(stroke
			(width 0.381)
			(type default)
		)
		(layer "In5.Cu")
	)
	(gr_line
		(start 284.863032 -5.190998)
		(end 283.814774 -6.239256)
		(stroke
			(width 0.381)
			(type default)
		)
		(layer "In5.Cu")
	)
	(gr_arc
		(start 284.922468 -36.854384)
		(mid 285.904229 -36.527384)
		(end 285.577026 -35.545776)
		(stroke
			(width 0.2)
			(type default)
		)
		(layer "In5.Cu")
	)
	(gr_line
		(start 284.923738 -137.151872)
		(end 284.923992 -137.151618)
		(stroke
			(width 0.2)
			(type default)
		)
		(layer "In5.Cu")
	)
	(gr_arc
		(start 284.923738 -109.151928)
		(mid 285.901892 -108.826046)
		(end 285.57601 -107.847892)
		(stroke
			(width 0.2)
			(type default)
		)
		(layer "In5.Cu")
	)
	(gr_line
		(start 284.923992 -137.151618)
		(end 284.925008 -137.149586)
		(stroke
			(width 0.2)
			(type default)
		)
		(layer "In5.Cu")
	)
	(gr_arc
		(start 284.925008 -137.149586)
		(mid 285.899606 -136.82472)
		(end 285.57474 -135.850122)
		(stroke
			(width 0.2)
			(type default)
		)
		(layer "In5.Cu")
	)
	(gr_arc
		(start 284.928056 -181.122574)
		(mid 285.874832 -180.817389)
		(end 285.56331 -179.87264)
		(stroke
			(width 0.2)
			(type default)
		)
		(layer "In5.Cu")
	)
	(gr_arc
		(start 284.928056 -177.122582)
		(mid 285.874832 -176.817397)
		(end 285.56331 -175.872648)
		(stroke
			(width 0.2)
			(type default)
		)
		(layer "In5.Cu")
	)
	(gr_arc
		(start 284.928056 -173.12259)
		(mid 285.874832 -172.817405)
		(end 285.56331 -171.872656)
		(stroke
			(width 0.2)
			(type default)
		)
		(layer "In5.Cu")
	)
	(gr_arc
		(start 284.928056 -169.122598)
		(mid 285.874832 -168.817413)
		(end 285.56331 -167.872664)
		(stroke
			(width 0.2)
			(type default)
		)
		(layer "In5.Cu")
	)
	(gr_arc
		(start 284.928056 -165.122606)
		(mid 285.874832 -164.817421)
		(end 285.56331 -163.872672)
		(stroke
			(width 0.2)
			(type default)
		)
		(layer "In5.Cu")
	)
	(gr_arc
		(start 284.928056 -157.122622)
		(mid 285.874832 -156.817437)
		(end 285.56331 -155.872688)
		(stroke
			(width 0.2)
			(type default)
		)
		(layer "In5.Cu")
	)
	(gr_arc
		(start 284.928056 -153.12263)
		(mid 285.874832 -152.817445)
		(end 285.56331 -151.872696)
		(stroke
			(width 0.2)
			(type default)
		)
		(layer "In5.Cu")
	)
	(gr_arc
		(start 284.928056 -129.122678)
		(mid 285.874832 -128.817493)
		(end 285.56331 -127.872744)
		(stroke
			(width 0.2)
			(type default)
		)
		(layer "In5.Cu")
	)
	(gr_arc
		(start 284.928056 -125.122686)
		(mid 285.874832 -124.817501)
		(end 285.56331 -123.872752)
		(stroke
			(width 0.2)
			(type default)
		)
		(layer "In5.Cu")
	)
	(gr_arc
		(start 284.928056 -121.122694)
		(mid 285.874832 -120.817509)
		(end 285.56331 -119.87276)
		(stroke
			(width 0.2)
			(type default)
		)
		(layer "In5.Cu")
	)
	(gr_arc
		(start 284.928056 -117.122702)
		(mid 285.874832 -116.817517)
		(end 285.56331 -115.872768)
		(stroke
			(width 0.2)
			(type default)
		)
		(layer "In5.Cu")
	)
	(gr_arc
		(start 284.928056 -84.822792)
		(mid 285.874832 -84.517607)
		(end 285.56331 -83.572858)
		(stroke
			(width 0.2)
			(type default)
		)
		(layer "In5.Cu")
	)
	(gr_arc
		(start 284.928056 -80.8228)
		(mid 285.874832 -80.517615)
		(end 285.56331 -79.572866)
		(stroke
			(width 0.2)
			(type default)
		)
		(layer "In5.Cu")
	)
	(gr_arc
		(start 284.928056 -76.822808)
		(mid 285.874832 -76.517623)
		(end 285.56331 -75.572874)
		(stroke
			(width 0.2)
			(type default)
		)
		(layer "In5.Cu")
	)
	(gr_arc
		(start 284.928056 -72.822816)
		(mid 285.874832 -72.517631)
		(end 285.56331 -71.572882)
		(stroke
			(width 0.2)
			(type default)
		)
		(layer "In5.Cu")
	)
	(gr_arc
		(start 284.928056 -68.822824)
		(mid 285.874832 -68.517639)
		(end 285.56331 -67.57289)
		(stroke
			(width 0.2)
			(type default)
		)
		(layer "In5.Cu")
	)
	(gr_arc
		(start 284.928056 -64.822832)
		(mid 285.874832 -64.517647)
		(end 285.56331 -63.572898)
		(stroke
			(width 0.2)
			(type default)
		)
		(layer "In5.Cu")
	)
	(gr_arc
		(start 284.928056 -60.82284)
		(mid 285.874832 -60.517655)
		(end 285.56331 -59.572906)
		(stroke
			(width 0.2)
			(type default)
		)
		(layer "In5.Cu")
	)
	(gr_arc
		(start 284.928056 -56.822848)
		(mid 285.874832 -56.517663)
		(end 285.56331 -55.572914)
		(stroke
			(width 0.2)
			(type default)
		)
		(layer "In5.Cu")
	)
	(gr_arc
		(start 284.928056 -52.822856)
		(mid 285.874832 -52.517671)
		(end 285.56331 -51.572922)
		(stroke
			(width 0.2)
			(type default)
		)
		(layer "In5.Cu")
	)
	(gr_arc
		(start 284.928056 -48.822864)
		(mid 285.874832 -48.517679)
		(end 285.56331 -47.57293)
		(stroke
			(width 0.2)
			(type default)
		)
		(layer "In5.Cu")
	)
	(gr_arc
		(start 284.928056 -44.822872)
		(mid 285.874832 -44.517687)
		(end 285.56331 -43.572938)
		(stroke
			(width 0.2)
			(type default)
		)
		(layer "In5.Cu")
	)
	(gr_arc
		(start 284.928056 -40.82288)
		(mid 285.874832 -40.517695)
		(end 285.56331 -39.572946)
		(stroke
			(width 0.2)
			(type default)
		)
		(layer "In5.Cu")
	)
	(gr_arc
		(start 284.936438 -161.126932)
		(mid 285.877 -160.813242)
		(end 285.56331 -159.87268)
		(stroke
			(width 0.2)
			(type default)
		)
		(layer "In5.Cu")
	)
	(gr_line
		(start 285.436564 -356.456234)
		(end 286.836612 -356.456234)
		(stroke
			(width 0.2)
			(type default)
		)
		(layer "In5.Cu")
	)
	(gr_arc
		(start 285.436564 -355.353874)
		(mid 284.885384 -355.905054)
		(end 285.436564 -356.456234)
		(stroke
			(width 0.2)
			(type default)
		)
		(layer "In5.Cu")
	)
	(gr_line
		(start 285.436564 -352.856292)
		(end 286.836612 -352.856292)
		(stroke
			(width 0.2)
			(type default)
		)
		(layer "In5.Cu")
	)
	(gr_arc
		(start 285.436564 -351.753932)
		(mid 284.885384 -352.305112)
		(end 285.436564 -352.856292)
		(stroke
			(width 0.2)
			(type default)
		)
		(layer "In5.Cu")
	)
	(gr_line
		(start 285.436564 -349.25635)
		(end 286.836612 -349.25635)
		(stroke
			(width 0.2)
			(type default)
		)
		(layer "In5.Cu")
	)
	(gr_arc
		(start 285.436564 -348.15399)
		(mid 284.885384 -348.70517)
		(end 285.436564 -349.25635)
		(stroke
			(width 0.2)
			(type default)
		)
		(layer "In5.Cu")
	)
	(gr_line
		(start 285.436564 -345.653868)
		(end 286.836612 -345.653868)
		(stroke
			(width 0.2)
			(type default)
		)
		(layer "In5.Cu")
	)
	(gr_arc
		(start 285.436564 -344.556588)
		(mid 284.887924 -345.105228)
		(end 285.436564 -345.653868)
		(stroke
			(width 0.2)
			(type default)
		)
		(layer "In5.Cu")
	)
	(gr_line
		(start 285.436564 -342.053672)
		(end 286.836612 -342.053672)
		(stroke
			(width 0.2)
			(type default)
		)
		(layer "In5.Cu")
	)
	(gr_arc
		(start 285.436564 -340.956392)
		(mid 284.887924 -341.505032)
		(end 285.436564 -342.053672)
		(stroke
			(width 0.2)
			(type default)
		)
		(layer "In5.Cu")
	)
	(gr_line
		(start 285.436564 -338.45373)
		(end 286.836612 -338.45373)
		(stroke
			(width 0.2)
			(type default)
		)
		(layer "In5.Cu")
	)
	(gr_arc
		(start 285.436564 -337.35645)
		(mid 284.887924 -337.90509)
		(end 285.436564 -338.45373)
		(stroke
			(width 0.2)
			(type default)
		)
		(layer "In5.Cu")
	)
	(gr_line
		(start 285.436564 -334.856328)
		(end 286.836612 -334.856328)
		(stroke
			(width 0.2)
			(type default)
		)
		(layer "In5.Cu")
	)
	(gr_arc
		(start 285.436564 -333.753968)
		(mid 284.885384 -334.305148)
		(end 285.436564 -334.856328)
		(stroke
			(width 0.2)
			(type default)
		)
		(layer "In5.Cu")
	)
	(gr_line
		(start 285.436564 -331.256386)
		(end 286.836612 -331.256386)
		(stroke
			(width 0.2)
			(type default)
		)
		(layer "In5.Cu")
	)
	(gr_arc
		(start 285.436564 -330.154026)
		(mid 284.885384 -330.705206)
		(end 285.436564 -331.256386)
		(stroke
			(width 0.2)
			(type default)
		)
		(layer "In5.Cu")
	)
	(gr_line
		(start 285.436564 -327.656444)
		(end 286.836612 -327.656444)
		(stroke
			(width 0.2)
			(type default)
		)
		(layer "In5.Cu")
	)
	(gr_arc
		(start 285.436564 -326.554084)
		(mid 284.885384 -327.105264)
		(end 285.436564 -327.656444)
		(stroke
			(width 0.2)
			(type default)
		)
		(layer "In5.Cu")
	)
	(gr_line
		(start 285.436564 -324.053708)
		(end 286.836612 -324.053708)
		(stroke
			(width 0.2)
			(type default)
		)
		(layer "In5.Cu")
	)
	(gr_arc
		(start 285.436564 -322.956428)
		(mid 284.887924 -323.505068)
		(end 285.436564 -324.053708)
		(stroke
			(width 0.2)
			(type default)
		)
		(layer "In5.Cu")
	)
	(gr_line
		(start 285.436564 -320.453766)
		(end 286.836612 -320.453766)
		(stroke
			(width 0.2)
			(type default)
		)
		(layer "In5.Cu")
	)
	(gr_arc
		(start 285.436564 -319.356486)
		(mid 284.887924 -319.905126)
		(end 285.436564 -320.453766)
		(stroke
			(width 0.2)
			(type default)
		)
		(layer "In5.Cu")
	)
	(gr_line
		(start 285.436564 -316.853824)
		(end 286.836612 -316.853824)
		(stroke
			(width 0.2)
			(type default)
		)
		(layer "In5.Cu")
	)
	(gr_arc
		(start 285.436564 -315.756544)
		(mid 284.887924 -316.305184)
		(end 285.436564 -316.853824)
		(stroke
			(width 0.2)
			(type default)
		)
		(layer "In5.Cu")
	)
	(gr_line
		(start 285.436564 -313.256422)
		(end 286.836612 -313.256422)
		(stroke
			(width 0.2)
			(type default)
		)
		(layer "In5.Cu")
	)
	(gr_arc
		(start 285.436564 -312.154062)
		(mid 284.885384 -312.705242)
		(end 285.436564 -313.256422)
		(stroke
			(width 0.2)
			(type default)
		)
		(layer "In5.Cu")
	)
	(gr_line
		(start 285.436564 -309.656226)
		(end 286.836612 -309.656226)
		(stroke
			(width 0.2)
			(type default)
		)
		(layer "In5.Cu")
	)
	(gr_arc
		(start 285.436564 -308.553866)
		(mid 284.885384 -309.105046)
		(end 285.436564 -309.656226)
		(stroke
			(width 0.2)
			(type default)
		)
		(layer "In5.Cu")
	)
	(gr_line
		(start 285.436564 -306.056284)
		(end 286.836612 -306.056284)
		(stroke
			(width 0.2)
			(type default)
		)
		(layer "In5.Cu")
	)
	(gr_arc
		(start 285.436564 -304.953924)
		(mid 284.885384 -305.505104)
		(end 285.436564 -306.056284)
		(stroke
			(width 0.2)
			(type default)
		)
		(layer "In5.Cu")
	)
	(gr_line
		(start 285.436564 -302.453802)
		(end 286.836612 -302.453802)
		(stroke
			(width 0.2)
			(type default)
		)
		(layer "In5.Cu")
	)
	(gr_arc
		(start 285.436564 -301.356522)
		(mid 284.887924 -301.905162)
		(end 285.436564 -302.453802)
		(stroke
			(width 0.2)
			(type default)
		)
		(layer "In5.Cu")
	)
	(gr_line
		(start 285.436564 -298.85386)
		(end 286.836612 -298.85386)
		(stroke
			(width 0.2)
			(type default)
		)
		(layer "In5.Cu")
	)
	(gr_arc
		(start 285.436564 -297.75658)
		(mid 284.887924 -298.30522)
		(end 285.436564 -298.85386)
		(stroke
			(width 0.2)
			(type default)
		)
		(layer "In5.Cu")
	)
	(gr_line
		(start 285.436564 -295.256458)
		(end 286.836612 -295.256458)
		(stroke
			(width 0.2)
			(type default)
		)
		(layer "In5.Cu")
	)
	(gr_arc
		(start 285.436564 -294.154098)
		(mid 284.885384 -294.705278)
		(end 285.436564 -295.256458)
		(stroke
			(width 0.2)
			(type default)
		)
		(layer "In5.Cu")
	)
	(gr_line
		(start 285.436564 -262.453374)
		(end 286.836612 -262.453374)
		(stroke
			(width 0.2)
			(type default)
		)
		(layer "In5.Cu")
	)
	(gr_arc
		(start 285.436564 -261.351014)
		(mid 284.885384 -261.902194)
		(end 285.436564 -262.453374)
		(stroke
			(width 0.2)
			(type default)
		)
		(layer "In5.Cu")
	)
	(gr_line
		(start 285.436564 -258.853432)
		(end 286.836612 -258.853432)
		(stroke
			(width 0.2)
			(type default)
		)
		(layer "In5.Cu")
	)
	(gr_arc
		(start 285.436564 -257.751072)
		(mid 284.885384 -258.302252)
		(end 285.436564 -258.853432)
		(stroke
			(width 0.2)
			(type default)
		)
		(layer "In5.Cu")
	)
	(gr_line
		(start 285.436564 -255.25349)
		(end 286.836612 -255.25349)
		(stroke
			(width 0.2)
			(type default)
		)
		(layer "In5.Cu")
	)
	(gr_arc
		(start 285.436564 -254.15113)
		(mid 284.885384 -254.70231)
		(end 285.436564 -255.25349)
		(stroke
			(width 0.2)
			(type default)
		)
		(layer "In5.Cu")
	)
	(gr_line
		(start 285.436564 -251.653548)
		(end 286.836612 -251.653548)
		(stroke
			(width 0.2)
			(type default)
		)
		(layer "In5.Cu")
	)
	(gr_arc
		(start 285.436564 -250.551188)
		(mid 284.885384 -251.102368)
		(end 285.436564 -251.653548)
		(stroke
			(width 0.2)
			(type default)
		)
		(layer "In5.Cu")
	)
	(gr_line
		(start 285.436818 -355.353874)
		(end 285.436564 -355.353874)
		(stroke
			(width 0.2)
			(type default)
		)
		(layer "In5.Cu")
	)
	(gr_line
		(start 285.436818 -351.753932)
		(end 285.436564 -351.753932)
		(stroke
			(width 0.2)
			(type default)
		)
		(layer "In5.Cu")
	)
	(gr_line
		(start 285.436818 -348.15399)
		(end 285.436564 -348.15399)
		(stroke
			(width 0.2)
			(type default)
		)
		(layer "In5.Cu")
	)
	(gr_line
		(start 285.436818 -344.556588)
		(end 285.436564 -344.556588)
		(stroke
			(width 0.2)
			(type default)
		)
		(layer "In5.Cu")
	)
	(gr_line
		(start 285.436818 -340.956392)
		(end 285.436564 -340.956392)
		(stroke
			(width 0.2)
			(type default)
		)
		(layer "In5.Cu")
	)
	(gr_line
		(start 285.436818 -337.35645)
		(end 285.436564 -337.35645)
		(stroke
			(width 0.2)
			(type default)
		)
		(layer "In5.Cu")
	)
	(gr_line
		(start 285.436818 -333.753968)
		(end 285.436564 -333.753968)
		(stroke
			(width 0.2)
			(type default)
		)
		(layer "In5.Cu")
	)
	(gr_line
		(start 285.436818 -330.154026)
		(end 285.436564 -330.154026)
		(stroke
			(width 0.2)
			(type default)
		)
		(layer "In5.Cu")
	)
	(gr_line
		(start 285.436818 -326.554084)
		(end 285.436564 -326.554084)
		(stroke
			(width 0.2)
			(type default)
		)
		(layer "In5.Cu")
	)
	(gr_line
		(start 285.436818 -322.956428)
		(end 285.436564 -322.956428)
		(stroke
			(width 0.2)
			(type default)
		)
		(layer "In5.Cu")
	)
	(gr_line
		(start 285.436818 -319.356486)
		(end 285.436564 -319.356486)
		(stroke
			(width 0.2)
			(type default)
		)
		(layer "In5.Cu")
	)
	(gr_line
		(start 285.436818 -315.756544)
		(end 285.436564 -315.756544)
		(stroke
			(width 0.2)
			(type default)
		)
		(layer "In5.Cu")
	)
	(gr_line
		(start 285.436818 -312.154062)
		(end 285.436564 -312.154062)
		(stroke
			(width 0.2)
			(type default)
		)
		(layer "In5.Cu")
	)
	(gr_line
		(start 285.436818 -308.553866)
		(end 285.436564 -308.553866)
		(stroke
			(width 0.2)
			(type default)
		)
		(layer "In5.Cu")
	)
	(gr_line
		(start 285.436818 -304.953924)
		(end 285.436564 -304.953924)
		(stroke
			(width 0.2)
			(type default)
		)
		(layer "In5.Cu")
	)
	(gr_line
		(start 285.436818 -301.356522)
		(end 285.436564 -301.356522)
		(stroke
			(width 0.2)
			(type default)
		)
		(layer "In5.Cu")
	)
	(gr_line
		(start 285.436818 -297.75658)
		(end 285.436564 -297.75658)
		(stroke
			(width 0.2)
			(type default)
		)
		(layer "In5.Cu")
	)
	(gr_line
		(start 285.436818 -294.154098)
		(end 285.436564 -294.154098)
		(stroke
			(width 0.2)
			(type default)
		)
		(layer "In5.Cu")
	)
	(gr_line
		(start 285.436818 -261.351014)
		(end 285.436564 -261.351014)
		(stroke
			(width 0.2)
			(type default)
		)
		(layer "In5.Cu")
	)
	(gr_line
		(start 285.436818 -257.751072)
		(end 285.436564 -257.751072)
		(stroke
			(width 0.2)
			(type default)
		)
		(layer "In5.Cu")
	)
	(gr_line
		(start 285.436818 -254.15113)
		(end 285.436564 -254.15113)
		(stroke
			(width 0.2)
			(type default)
		)
		(layer "In5.Cu")
	)
	(gr_line
		(start 285.436818 -250.551188)
		(end 285.436564 -250.551188)
		(stroke
			(width 0.2)
			(type default)
		)
		(layer "In5.Cu")
	)
	(gr_line
		(start 285.56331 -179.87264)
		(end 283.563314 -178.872642)
		(stroke
			(width 0.2)
			(type default)
		)
		(layer "In5.Cu")
	)
	(gr_line
		(start 285.56331 -175.872648)
		(end 283.563314 -174.87265)
		(stroke
			(width 0.2)
			(type default)
		)
		(layer "In5.Cu")
	)
	(gr_line
		(start 285.56331 -171.872656)
		(end 283.563314 -170.872658)
		(stroke
			(width 0.2)
			(type default)
		)
		(layer "In5.Cu")
	)
	(gr_line
		(start 285.56331 -167.872664)
		(end 283.563314 -166.872666)
		(stroke
			(width 0.2)
			(type default)
		)
		(layer "In5.Cu")
	)
	(gr_line
		(start 285.56331 -163.872672)
		(end 283.563314 -162.872674)
		(stroke
			(width 0.2)
			(type default)
		)
		(layer "In5.Cu")
	)
	(gr_line
		(start 285.56331 -159.87268)
		(end 283.571696 -158.877)
		(stroke
			(width 0.2)
			(type default)
		)
		(layer "In5.Cu")
	)
	(gr_line
		(start 285.56331 -155.872688)
		(end 283.563314 -154.87269)
		(stroke
			(width 0.2)
			(type default)
		)
		(layer "In5.Cu")
	)
	(gr_line
		(start 285.56331 -151.872696)
		(end 283.563314 -150.872698)
		(stroke
			(width 0.2)
			(type default)
		)
		(layer "In5.Cu")
	)
	(gr_line
		(start 285.56331 -127.872744)
		(end 283.563314 -126.872746)
		(stroke
			(width 0.2)
			(type default)
		)
		(layer "In5.Cu")
	)
	(gr_line
		(start 285.56331 -123.872752)
		(end 283.563314 -122.872754)
		(stroke
			(width 0.2)
			(type default)
		)
		(layer "In5.Cu")
	)
	(gr_line
		(start 285.56331 -119.87276)
		(end 283.563314 -118.872762)
		(stroke
			(width 0.2)
			(type default)
		)
		(layer "In5.Cu")
	)
	(gr_line
		(start 285.56331 -115.872768)
		(end 283.563314 -114.87277)
		(stroke
			(width 0.2)
			(type default)
		)
		(layer "In5.Cu")
	)
	(gr_line
		(start 285.56331 -83.572858)
		(end 283.563314 -82.57286)
		(stroke
			(width 0.2)
			(type default)
		)
		(layer "In5.Cu")
	)
	(gr_line
		(start 285.56331 -79.572866)
		(end 283.563314 -78.572868)
		(stroke
			(width 0.2)
			(type default)
		)
		(layer "In5.Cu")
	)
	(gr_line
		(start 285.56331 -75.572874)
		(end 283.563314 -74.572876)
		(stroke
			(width 0.2)
			(type default)
		)
		(layer "In5.Cu")
	)
	(gr_line
		(start 285.56331 -71.572882)
		(end 283.563314 -70.572884)
		(stroke
			(width 0.2)
			(type default)
		)
		(layer "In5.Cu")
	)
	(gr_line
		(start 285.56331 -67.57289)
		(end 283.563314 -66.572892)
		(stroke
			(width 0.2)
			(type default)
		)
		(layer "In5.Cu")
	)
	(gr_line
		(start 285.56331 -63.572898)
		(end 283.563314 -62.5729)
		(stroke
			(width 0.2)
			(type default)
		)
		(layer "In5.Cu")
	)
	(gr_line
		(start 285.56331 -59.572906)
		(end 283.563314 -58.572908)
		(stroke
			(width 0.2)
			(type default)
		)
		(layer "In5.Cu")
	)
	(gr_line
		(start 285.56331 -55.572914)
		(end 283.563314 -54.572916)
		(stroke
			(width 0.2)
			(type default)
		)
		(layer "In5.Cu")
	)
	(gr_line
		(start 285.56331 -51.572922)
		(end 283.563314 -50.572924)
		(stroke
			(width 0.2)
			(type default)
		)
		(layer "In5.Cu")
	)
	(gr_line
		(start 285.56331 -47.57293)
		(end 283.563314 -46.572932)
		(stroke
			(width 0.2)
			(type default)
		)
		(layer "In5.Cu")
	)
	(gr_line
		(start 285.56331 -43.572938)
		(end 283.563314 -42.57294)
		(stroke
			(width 0.2)
			(type default)
		)
		(layer "In5.Cu")
	)
	(gr_line
		(start 285.56331 -39.572946)
		(end 283.563314 -38.572948)
		(stroke
			(width 0.2)
			(type default)
		)
		(layer "In5.Cu")
	)
	(gr_line
		(start 285.57474 -135.850122)
		(end 285.57601 -135.847836)
		(stroke
			(width 0.2)
			(type default)
		)
		(layer "In5.Cu")
	)
	(gr_line
		(start 285.57601 -135.847836)
		(end 283.576014 -134.847838)
		(stroke
			(width 0.2)
			(type default)
		)
		(layer "In5.Cu")
	)
	(gr_line
		(start 285.57601 -107.847892)
		(end 283.576014 -106.847894)
		(stroke
			(width 0.2)
			(type default)
		)
		(layer "In5.Cu")
	)
	(gr_line
		(start 285.577026 -35.545776)
		(end 283.57703 -34.545778)
		(stroke
			(width 0.2)
			(type default)
		)
		(layer "In5.Cu")
	)
	(gr_line
		(start 286.234378 -101.49078)
		(end 284.863032 -101.49078)
		(stroke
			(width 0.381)
			(type default)
		)
		(layer "In5.Cu")
	)
	(gr_line
		(start 286.234378 -5.190998)
		(end 284.863032 -5.190998)
		(stroke
			(width 0.381)
			(type default)
		)
		(layer "In5.Cu")
	)
	(gr_line
		(start 286.436562 -358.256332)
		(end 287.83661 -358.256332)
		(stroke
			(width 0.2)
			(type default)
		)
		(layer "In5.Cu")
	)
	(gr_arc
		(start 286.436562 -357.153972)
		(mid 285.885382 -357.705152)
		(end 286.436562 -358.256332)
		(stroke
			(width 0.2)
			(type default)
		)
		(layer "In5.Cu")
	)
	(gr_line
		(start 286.436562 -354.65639)
		(end 287.83661 -354.65639)
		(stroke
			(width 0.2)
			(type default)
		)
		(layer "In5.Cu")
	)
	(gr_arc
		(start 286.436562 -353.55403)
		(mid 285.885382 -354.10521)
		(end 286.436562 -354.65639)
		(stroke
			(width 0.2)
			(type default)
		)
		(layer "In5.Cu")
	)
	(gr_line
		(start 286.436562 -351.056448)
		(end 287.83661 -351.056448)
		(stroke
			(width 0.2)
			(type default)
		)
		(layer "In5.Cu")
	)
	(gr_arc
		(start 286.436562 -349.954088)
		(mid 285.885382 -350.505268)
		(end 286.436562 -351.056448)
		(stroke
			(width 0.2)
			(type default)
		)
		(layer "In5.Cu")
	)
	(gr_line
		(start 286.436562 -347.453712)
		(end 287.83661 -347.453712)
		(stroke
			(width 0.2)
			(type default)
		)
		(layer "In5.Cu")
	)
	(gr_arc
		(start 286.436562 -346.356432)
		(mid 285.887922 -346.905072)
		(end 286.436562 -347.453712)
		(stroke
			(width 0.2)
			(type default)
		)
		(layer "In5.Cu")
	)
	(gr_line
		(start 286.436562 -343.85377)
		(end 287.83661 -343.85377)
		(stroke
			(width 0.2)
			(type default)
		)
		(layer "In5.Cu")
	)
	(gr_arc
		(start 286.436562 -342.75649)
		(mid 285.887922 -343.30513)
		(end 286.436562 -343.85377)
		(stroke
			(width 0.2)
			(type default)
		)
		(layer "In5.Cu")
	)
	(gr_line
		(start 286.436562 -340.253828)
		(end 287.83661 -340.253828)
		(stroke
			(width 0.2)
			(type default)
		)
		(layer "In5.Cu")
	)
	(gr_arc
		(start 286.436562 -339.156548)
		(mid 285.887922 -339.705188)
		(end 286.436562 -340.253828)
		(stroke
			(width 0.2)
			(type default)
		)
		(layer "In5.Cu")
	)
	(gr_line
		(start 286.436562 -336.656426)
		(end 287.83661 -336.656426)
		(stroke
			(width 0.2)
			(type default)
		)
		(layer "In5.Cu")
	)
	(gr_arc
		(start 286.436562 -335.554066)
		(mid 285.885382 -336.105246)
		(end 286.436562 -336.656426)
		(stroke
			(width 0.2)
			(type default)
		)
		(layer "In5.Cu")
	)
	(gr_line
		(start 286.436562 -333.05623)
		(end 287.83661 -333.05623)
		(stroke
			(width 0.2)
			(type default)
		)
		(layer "In5.Cu")
	)
	(gr_arc
		(start 286.436562 -331.95387)
		(mid 285.885382 -332.50505)
		(end 286.436562 -333.05623)
		(stroke
			(width 0.2)
			(type default)
		)
		(layer "In5.Cu")
	)
	(gr_line
		(start 286.436562 -329.456288)
		(end 287.83661 -329.456288)
		(stroke
			(width 0.2)
			(type default)
		)
		(layer "In5.Cu")
	)
	(gr_arc
		(start 286.436562 -328.353928)
		(mid 285.885382 -328.905108)
		(end 286.436562 -329.456288)
		(stroke
			(width 0.2)
			(type default)
		)
		(layer "In5.Cu")
	)
	(gr_line
		(start 286.436562 -325.853806)
		(end 287.83661 -325.853806)
		(stroke
			(width 0.2)
			(type default)
		)
		(layer "In5.Cu")
	)
	(gr_arc
		(start 286.436562 -324.756526)
		(mid 285.887922 -325.305166)
		(end 286.436562 -325.853806)
		(stroke
			(width 0.2)
			(type default)
		)
		(layer "In5.Cu")
	)
	(gr_line
		(start 286.436562 -322.253864)
		(end 287.83661 -322.253864)
		(stroke
			(width 0.2)
			(type default)
		)
		(layer "In5.Cu")
	)
	(gr_arc
		(start 286.436562 -321.156584)
		(mid 285.887922 -321.705224)
		(end 286.436562 -322.253864)
		(stroke
			(width 0.2)
			(type default)
		)
		(layer "In5.Cu")
	)
	(gr_line
		(start 286.436562 -318.653668)
		(end 287.83661 -318.653668)
		(stroke
			(width 0.2)
			(type default)
		)
		(layer "In5.Cu")
	)
	(gr_arc
		(start 286.436562 -317.556388)
		(mid 285.887922 -318.105028)
		(end 286.436562 -318.653668)
		(stroke
			(width 0.2)
			(type default)
		)
		(layer "In5.Cu")
	)
	(gr_line
		(start 286.436562 -315.056266)
		(end 287.83661 -315.056266)
		(stroke
			(width 0.2)
			(type default)
		)
		(layer "In5.Cu")
	)
	(gr_arc
		(start 286.436562 -313.953906)
		(mid 285.885382 -314.505086)
		(end 286.436562 -315.056266)
		(stroke
			(width 0.2)
			(type default)
		)
		(layer "In5.Cu")
	)
	(gr_line
		(start 286.436562 -311.456324)
		(end 287.83661 -311.456324)
		(stroke
			(width 0.2)
			(type default)
		)
		(layer "In5.Cu")
	)
	(gr_arc
		(start 286.436562 -310.353964)
		(mid 285.885382 -310.905144)
		(end 286.436562 -311.456324)
		(stroke
			(width 0.2)
			(type default)
		)
		(layer "In5.Cu")
	)
	(gr_line
		(start 286.436562 -307.856382)
		(end 287.83661 -307.856382)
		(stroke
			(width 0.2)
			(type default)
		)
		(layer "In5.Cu")
	)
	(gr_arc
		(start 286.436562 -306.754022)
		(mid 285.885382 -307.305202)
		(end 286.436562 -307.856382)
		(stroke
			(width 0.2)
			(type default)
		)
		(layer "In5.Cu")
	)
	(gr_line
		(start 286.436562 -304.2539)
		(end 287.83661 -304.2539)
		(stroke
			(width 0.2)
			(type default)
		)
		(layer "In5.Cu")
	)
	(gr_arc
		(start 286.436562 -303.15662)
		(mid 285.887922 -303.70526)
		(end 286.436562 -304.2539)
		(stroke
			(width 0.2)
			(type default)
		)
		(layer "In5.Cu")
	)
	(gr_line
		(start 286.436562 -300.653704)
		(end 287.83661 -300.653704)
		(stroke
			(width 0.2)
			(type default)
		)
		(layer "In5.Cu")
	)
	(gr_arc
		(start 286.436562 -299.556424)
		(mid 285.887922 -300.105064)
		(end 286.436562 -300.653704)
		(stroke
			(width 0.2)
			(type default)
		)
		(layer "In5.Cu")
	)
	(gr_line
		(start 286.436562 -297.056302)
		(end 287.83661 -297.056302)
		(stroke
			(width 0.2)
			(type default)
		)
		(layer "In5.Cu")
	)
	(gr_arc
		(start 286.436562 -295.953942)
		(mid 285.885382 -296.505122)
		(end 286.436562 -297.056302)
		(stroke
			(width 0.2)
			(type default)
		)
		(layer "In5.Cu")
	)
	(gr_line
		(start 286.436562 -264.253472)
		(end 287.83661 -264.253472)
		(stroke
			(width 0.2)
			(type default)
		)
		(layer "In5.Cu")
	)
	(gr_arc
		(start 286.436562 -263.151112)
		(mid 285.885382 -263.702292)
		(end 286.436562 -264.253472)
		(stroke
			(width 0.2)
			(type default)
		)
		(layer "In5.Cu")
	)
	(gr_line
		(start 286.436562 -260.65353)
		(end 287.83661 -260.65353)
		(stroke
			(width 0.2)
			(type default)
		)
		(layer "In5.Cu")
	)
	(gr_arc
		(start 286.436562 -259.55117)
		(mid 285.885382 -260.10235)
		(end 286.436562 -260.65353)
		(stroke
			(width 0.2)
			(type default)
		)
		(layer "In5.Cu")
	)
	(gr_line
		(start 286.436562 -257.053588)
		(end 287.83661 -257.053588)
		(stroke
			(width 0.2)
			(type default)
		)
		(layer "In5.Cu")
	)
	(gr_arc
		(start 286.436562 -255.951228)
		(mid 285.885382 -256.502408)
		(end 286.436562 -257.053588)
		(stroke
			(width 0.2)
			(type default)
		)
		(layer "In5.Cu")
	)
	(gr_line
		(start 286.436562 -253.453392)
		(end 287.83661 -253.453392)
		(stroke
			(width 0.2)
			(type default)
		)
		(layer "In5.Cu")
	)
	(gr_arc
		(start 286.436562 -252.351032)
		(mid 285.885382 -252.902212)
		(end 286.436562 -253.453392)
		(stroke
			(width 0.2)
			(type default)
		)
		(layer "In5.Cu")
	)
	(gr_line
		(start 286.436816 -357.153972)
		(end 286.436562 -357.153972)
		(stroke
			(width 0.2)
			(type default)
		)
		(layer "In5.Cu")
	)
	(gr_line
		(start 286.436816 -353.55403)
		(end 286.436562 -353.55403)
		(stroke
			(width 0.2)
			(type default)
		)
		(layer "In5.Cu")
	)
	(gr_line
		(start 286.436816 -349.954088)
		(end 286.436562 -349.954088)
		(stroke
			(width 0.2)
			(type default)
		)
		(layer "In5.Cu")
	)
	(gr_line
		(start 286.436816 -346.356432)
		(end 286.436562 -346.356432)
		(stroke
			(width 0.2)
			(type default)
		)
		(layer "In5.Cu")
	)
	(gr_line
		(start 286.436816 -342.75649)
		(end 286.436562 -342.75649)
		(stroke
			(width 0.2)
			(type default)
		)
		(layer "In5.Cu")
	)
	(gr_line
		(start 286.436816 -339.156548)
		(end 286.436562 -339.156548)
		(stroke
			(width 0.2)
			(type default)
		)
		(layer "In5.Cu")
	)
	(gr_line
		(start 286.436816 -335.554066)
		(end 286.436562 -335.554066)
		(stroke
			(width 0.2)
			(type default)
		)
		(layer "In5.Cu")
	)
	(gr_line
		(start 286.436816 -331.95387)
		(end 286.436562 -331.95387)
		(stroke
			(width 0.2)
			(type default)
		)
		(layer "In5.Cu")
	)
	(gr_line
		(start 286.436816 -328.353928)
		(end 286.436562 -328.353928)
		(stroke
			(width 0.2)
			(type default)
		)
		(layer "In5.Cu")
	)
	(gr_line
		(start 286.436816 -324.756526)
		(end 286.436562 -324.756526)
		(stroke
			(width 0.2)
			(type default)
		)
		(layer "In5.Cu")
	)
	(gr_line
		(start 286.436816 -321.156584)
		(end 286.436562 -321.156584)
		(stroke
			(width 0.2)
			(type default)
		)
		(layer "In5.Cu")
	)
	(gr_line
		(start 286.436816 -317.556388)
		(end 286.436562 -317.556388)
		(stroke
			(width 0.2)
			(type default)
		)
		(layer "In5.Cu")
	)
	(gr_line
		(start 286.436816 -313.953906)
		(end 286.436562 -313.953906)
		(stroke
			(width 0.2)
			(type default)
		)
		(layer "In5.Cu")
	)
	(gr_line
		(start 286.436816 -310.353964)
		(end 286.436562 -310.353964)
		(stroke
			(width 0.2)
			(type default)
		)
		(layer "In5.Cu")
	)
	(gr_line
		(start 286.436816 -306.754022)
		(end 286.436562 -306.754022)
		(stroke
			(width 0.2)
			(type default)
		)
		(layer "In5.Cu")
	)
	(gr_line
		(start 286.436816 -303.15662)
		(end 286.436562 -303.15662)
		(stroke
			(width 0.2)
			(type default)
		)
		(layer "In5.Cu")
	)
	(gr_line
		(start 286.436816 -299.556424)
		(end 286.436562 -299.556424)
		(stroke
			(width 0.2)
			(type default)
		)
		(layer "In5.Cu")
	)
	(gr_line
		(start 286.436816 -295.953942)
		(end 286.436562 -295.953942)
		(stroke
			(width 0.2)
			(type default)
		)
		(layer "In5.Cu")
	)
	(gr_line
		(start 286.436816 -263.151112)
		(end 286.436562 -263.151112)
		(stroke
			(width 0.2)
			(type default)
		)
		(layer "In5.Cu")
	)
	(gr_line
		(start 286.436816 -259.55117)
		(end 286.436562 -259.55117)
		(stroke
			(width 0.2)
			(type default)
		)
		(layer "In5.Cu")
	)
	(gr_line
		(start 286.436816 -255.951228)
		(end 286.436562 -255.951228)
		(stroke
			(width 0.2)
			(type default)
		)
		(layer "In5.Cu")
	)
	(gr_line
		(start 286.436816 -252.351032)
		(end 286.436562 -252.351032)
		(stroke
			(width 0.2)
			(type default)
		)
		(layer "In5.Cu")
	)
	(gr_arc
		(start 286.836612 -356.456234)
		(mid 287.387792 -355.905054)
		(end 286.836612 -355.353874)
		(stroke
			(width 0.2)
			(type default)
		)
		(layer "In5.Cu")
	)
	(gr_line
		(start 286.836612 -355.353874)
		(end 285.436818 -355.353874)
		(stroke
			(width 0.2)
			(type default)
		)
		(layer "In5.Cu")
	)
	(gr_arc
		(start 286.836612 -352.856292)
		(mid 287.387792 -352.305112)
		(end 286.836612 -351.753932)
		(stroke
			(width 0.2)
			(type default)
		)
		(layer "In5.Cu")
	)
	(gr_line
		(start 286.836612 -351.753932)
		(end 285.436818 -351.753932)
		(stroke
			(width 0.2)
			(type default)
		)
		(layer "In5.Cu")
	)
	(gr_arc
		(start 286.836612 -349.25635)
		(mid 287.387792 -348.70517)
		(end 286.836612 -348.15399)
		(stroke
			(width 0.2)
			(type default)
		)
		(layer "In5.Cu")
	)
	(gr_line
		(start 286.836612 -348.15399)
		(end 285.436818 -348.15399)
		(stroke
			(width 0.2)
			(type default)
		)
		(layer "In5.Cu")
	)
	(gr_arc
		(start 286.836612 -345.653868)
		(mid 287.385252 -345.105228)
		(end 286.836612 -344.556588)
		(stroke
			(width 0.2)
			(type default)
		)
		(layer "In5.Cu")
	)
	(gr_line
		(start 286.836612 -344.556588)
		(end 285.436818 -344.556588)
		(stroke
			(width 0.2)
			(type default)
		)
		(layer "In5.Cu")
	)
	(gr_arc
		(start 286.836612 -342.053672)
		(mid 287.385252 -341.505032)
		(end 286.836612 -340.956392)
		(stroke
			(width 0.2)
			(type default)
		)
		(layer "In5.Cu")
	)
	(gr_line
		(start 286.836612 -340.956392)
		(end 285.436818 -340.956392)
		(stroke
			(width 0.2)
			(type default)
		)
		(layer "In5.Cu")
	)
	(gr_arc
		(start 286.836612 -338.45373)
		(mid 287.385252 -337.90509)
		(end 286.836612 -337.35645)
		(stroke
			(width 0.2)
			(type default)
		)
		(layer "In5.Cu")
	)
	(gr_line
		(start 286.836612 -337.35645)
		(end 285.436818 -337.35645)
		(stroke
			(width 0.2)
			(type default)
		)
		(layer "In5.Cu")
	)
	(gr_arc
		(start 286.836612 -334.856328)
		(mid 287.387792 -334.305148)
		(end 286.836612 -333.753968)
		(stroke
			(width 0.2)
			(type default)
		)
		(layer "In5.Cu")
	)
	(gr_line
		(start 286.836612 -333.753968)
		(end 285.436818 -333.753968)
		(stroke
			(width 0.2)
			(type default)
		)
		(layer "In5.Cu")
	)
	(gr_arc
		(start 286.836612 -331.256386)
		(mid 287.387792 -330.705206)
		(end 286.836612 -330.154026)
		(stroke
			(width 0.2)
			(type default)
		)
		(layer "In5.Cu")
	)
	(gr_line
		(start 286.836612 -330.154026)
		(end 285.436818 -330.154026)
		(stroke
			(width 0.2)
			(type default)
		)
		(layer "In5.Cu")
	)
	(gr_arc
		(start 286.836612 -327.656444)
		(mid 287.387792 -327.105264)
		(end 286.836612 -326.554084)
		(stroke
			(width 0.2)
			(type default)
		)
		(layer "In5.Cu")
	)
	(gr_line
		(start 286.836612 -326.554084)
		(end 285.436818 -326.554084)
		(stroke
			(width 0.2)
			(type default)
		)
		(layer "In5.Cu")
	)
	(gr_arc
		(start 286.836612 -324.053708)
		(mid 287.385252 -323.505068)
		(end 286.836612 -322.956428)
		(stroke
			(width 0.2)
			(type default)
		)
		(layer "In5.Cu")
	)
	(gr_line
		(start 286.836612 -322.956428)
		(end 285.436818 -322.956428)
		(stroke
			(width 0.2)
			(type default)
		)
		(layer "In5.Cu")
	)
	(gr_arc
		(start 286.836612 -320.453766)
		(mid 287.385252 -319.905126)
		(end 286.836612 -319.356486)
		(stroke
			(width 0.2)
			(type default)
		)
		(layer "In5.Cu")
	)
	(gr_line
		(start 286.836612 -319.356486)
		(end 285.436818 -319.356486)
		(stroke
			(width 0.2)
			(type default)
		)
		(layer "In5.Cu")
	)
	(gr_arc
		(start 286.836612 -316.853824)
		(mid 287.385252 -316.305184)
		(end 286.836612 -315.756544)
		(stroke
			(width 0.2)
			(type default)
		)
		(layer "In5.Cu")
	)
	(gr_line
		(start 286.836612 -315.756544)
		(end 285.436818 -315.756544)
		(stroke
			(width 0.2)
			(type default)
		)
		(layer "In5.Cu")
	)
	(gr_arc
		(start 286.836612 -313.256422)
		(mid 287.387792 -312.705242)
		(end 286.836612 -312.154062)
		(stroke
			(width 0.2)
			(type default)
		)
		(layer "In5.Cu")
	)
	(gr_line
		(start 286.836612 -312.154062)
		(end 285.436818 -312.154062)
		(stroke
			(width 0.2)
			(type default)
		)
		(layer "In5.Cu")
	)
	(gr_arc
		(start 286.836612 -309.656226)
		(mid 287.387792 -309.105046)
		(end 286.836612 -308.553866)
		(stroke
			(width 0.2)
			(type default)
		)
		(layer "In5.Cu")
	)
	(gr_line
		(start 286.836612 -308.553866)
		(end 285.436818 -308.553866)
		(stroke
			(width 0.2)
			(type default)
		)
		(layer "In5.Cu")
	)
	(gr_arc
		(start 286.836612 -306.056284)
		(mid 287.387792 -305.505104)
		(end 286.836612 -304.953924)
		(stroke
			(width 0.2)
			(type default)
		)
		(layer "In5.Cu")
	)
	(gr_line
		(start 286.836612 -304.953924)
		(end 285.436818 -304.953924)
		(stroke
			(width 0.2)
			(type default)
		)
		(layer "In5.Cu")
	)
	(gr_arc
		(start 286.836612 -302.453802)
		(mid 287.385252 -301.905162)
		(end 286.836612 -301.356522)
		(stroke
			(width 0.2)
			(type default)
		)
		(layer "In5.Cu")
	)
	(gr_line
		(start 286.836612 -301.356522)
		(end 285.436818 -301.356522)
		(stroke
			(width 0.2)
			(type default)
		)
		(layer "In5.Cu")
	)
	(gr_arc
		(start 286.836612 -298.85386)
		(mid 287.385252 -298.30522)
		(end 286.836612 -297.75658)
		(stroke
			(width 0.2)
			(type default)
		)
		(layer "In5.Cu")
	)
	(gr_line
		(start 286.836612 -297.75658)
		(end 285.436818 -297.75658)
		(stroke
			(width 0.2)
			(type default)
		)
		(layer "In5.Cu")
	)
	(gr_arc
		(start 286.836612 -295.256458)
		(mid 287.387792 -294.705278)
		(end 286.836612 -294.154098)
		(stroke
			(width 0.2)
			(type default)
		)
		(layer "In5.Cu")
	)
	(gr_line
		(start 286.836612 -294.154098)
		(end 285.436818 -294.154098)
		(stroke
			(width 0.2)
			(type default)
		)
		(layer "In5.Cu")
	)
	(gr_arc
		(start 286.836612 -262.453374)
		(mid 287.387792 -261.902194)
		(end 286.836612 -261.351014)
		(stroke
			(width 0.2)
			(type default)
		)
		(layer "In5.Cu")
	)
	(gr_line
		(start 286.836612 -261.351014)
		(end 285.436818 -261.351014)
		(stroke
			(width 0.2)
			(type default)
		)
		(layer "In5.Cu")
	)
	(gr_arc
		(start 286.836612 -258.853432)
		(mid 287.387792 -258.302252)
		(end 286.836612 -257.751072)
		(stroke
			(width 0.2)
			(type default)
		)
		(layer "In5.Cu")
	)
	(gr_line
		(start 286.836612 -257.751072)
		(end 285.436818 -257.751072)
		(stroke
			(width 0.2)
			(type default)
		)
		(layer "In5.Cu")
	)
	(gr_arc
		(start 286.836612 -255.25349)
		(mid 287.387792 -254.70231)
		(end 286.836612 -254.15113)
		(stroke
			(width 0.2)
			(type default)
		)
		(layer "In5.Cu")
	)
	(gr_line
		(start 286.836612 -254.15113)
		(end 285.436818 -254.15113)
		(stroke
			(width 0.2)
			(type default)
		)
		(layer "In5.Cu")
	)
	(gr_arc
		(start 286.836612 -251.653548)
		(mid 287.387792 -251.102368)
		(end 286.836612 -250.551188)
		(stroke
			(width 0.2)
			(type default)
		)
		(layer "In5.Cu")
	)
	(gr_line
		(start 286.836612 -250.551188)
		(end 285.436818 -250.551188)
		(stroke
			(width 0.2)
			(type default)
		)
		(layer "In5.Cu")
	)
	(gr_line
		(start 287.023048 -183.633364)
		(end 287.67024 -182.986172)
		(stroke
			(width 0.381)
			(type default)
		)
		(layer "In5.Cu")
	)
	(gr_line
		(start 287.023048 -87.333582)
		(end 287.67024 -86.68639)
		(stroke
			(width 0.381)
			(type default)
		)
		(layer "In5.Cu")
	)
	(gr_line
		(start 287.67024 -182.986172)
		(end 287.67024 -102.926642)
		(stroke
			(width 0.381)
			(type default)
		)
		(layer "In5.Cu")
	)
	(gr_line
		(start 287.67024 -102.926642)
		(end 286.234378 -101.49078)
		(stroke
			(width 0.381)
			(type default)
		)
		(layer "In5.Cu")
	)
	(gr_line
		(start 287.67024 -86.68639)
		(end 287.67024 -6.62686)
		(stroke
			(width 0.381)
			(type default)
		)
		(layer "In5.Cu")
	)
	(gr_line
		(start 287.67024 -6.62686)
		(end 286.234378 -5.190998)
		(stroke
			(width 0.381)
			(type default)
		)
		(layer "In5.Cu")
	)
	(gr_arc
		(start 287.83661 -358.256332)
		(mid 288.38779 -357.705152)
		(end 287.83661 -357.153972)
		(stroke
			(width 0.2)
			(type default)
		)
		(layer "In5.Cu")
	)
	(gr_line
		(start 287.83661 -357.153972)
		(end 286.436816 -357.153972)
		(stroke
			(width 0.2)
			(type default)
		)
		(layer "In5.Cu")
	)
	(gr_arc
		(start 287.83661 -354.65639)
		(mid 288.38779 -354.10521)
		(end 287.83661 -353.55403)
		(stroke
			(width 0.2)
			(type default)
		)
		(layer "In5.Cu")
	)
	(gr_line
		(start 287.83661 -353.55403)
		(end 286.436816 -353.55403)
		(stroke
			(width 0.2)
			(type default)
		)
		(layer "In5.Cu")
	)
	(gr_arc
		(start 287.83661 -351.056448)
		(mid 288.38779 -350.505268)
		(end 287.83661 -349.954088)
		(stroke
			(width 0.2)
			(type default)
		)
		(layer "In5.Cu")
	)
	(gr_line
		(start 287.83661 -349.954088)
		(end 286.436816 -349.954088)
		(stroke
			(width 0.2)
			(type default)
		)
		(layer "In5.Cu")
	)
	(gr_arc
		(start 287.83661 -347.453712)
		(mid 288.38525 -346.905072)
		(end 287.83661 -346.356432)
		(stroke
			(width 0.2)
			(type default)
		)
		(layer "In5.Cu")
	)
	(gr_line
		(start 287.83661 -346.356432)
		(end 286.436816 -346.356432)
		(stroke
			(width 0.2)
			(type default)
		)
		(layer "In5.Cu")
	)
	(gr_arc
		(start 287.83661 -343.85377)
		(mid 288.38525 -343.30513)
		(end 287.83661 -342.75649)
		(stroke
			(width 0.2)
			(type default)
		)
		(layer "In5.Cu")
	)
	(gr_line
		(start 287.83661 -342.75649)
		(end 286.436816 -342.75649)
		(stroke
			(width 0.2)
			(type default)
		)
		(layer "In5.Cu")
	)
	(gr_arc
		(start 287.83661 -340.253828)
		(mid 288.38525 -339.705188)
		(end 287.83661 -339.156548)
		(stroke
			(width 0.2)
			(type default)
		)
		(layer "In5.Cu")
	)
	(gr_line
		(start 287.83661 -339.156548)
		(end 286.436816 -339.156548)
		(stroke
			(width 0.2)
			(type default)
		)
		(layer "In5.Cu")
	)
	(gr_arc
		(start 287.83661 -336.656426)
		(mid 288.38779 -336.105246)
		(end 287.83661 -335.554066)
		(stroke
			(width 0.2)
			(type default)
		)
		(layer "In5.Cu")
	)
	(gr_line
		(start 287.83661 -335.554066)
		(end 286.436816 -335.554066)
		(stroke
			(width 0.2)
			(type default)
		)
		(layer "In5.Cu")
	)
	(gr_arc
		(start 287.83661 -333.05623)
		(mid 288.38779 -332.50505)
		(end 287.83661 -331.95387)
		(stroke
			(width 0.2)
			(type default)
		)
		(layer "In5.Cu")
	)
	(gr_line
		(start 287.83661 -331.95387)
		(end 286.436816 -331.95387)
		(stroke
			(width 0.2)
			(type default)
		)
		(layer "In5.Cu")
	)
	(gr_arc
		(start 287.83661 -329.456288)
		(mid 288.38779 -328.905108)
		(end 287.83661 -328.353928)
		(stroke
			(width 0.2)
			(type default)
		)
		(layer "In5.Cu")
	)
	(gr_line
		(start 287.83661 -328.353928)
		(end 286.436816 -328.353928)
		(stroke
			(width 0.2)
			(type default)
		)
		(layer "In5.Cu")
	)
	(gr_arc
		(start 287.83661 -325.853806)
		(mid 288.38525 -325.305166)
		(end 287.83661 -324.756526)
		(stroke
			(width 0.2)
			(type default)
		)
		(layer "In5.Cu")
	)
	(gr_line
		(start 287.83661 -324.756526)
		(end 286.436816 -324.756526)
		(stroke
			(width 0.2)
			(type default)
		)
		(layer "In5.Cu")
	)
	(gr_arc
		(start 287.83661 -322.253864)
		(mid 288.38525 -321.705224)
		(end 287.83661 -321.156584)
		(stroke
			(width 0.2)
			(type default)
		)
		(layer "In5.Cu")
	)
	(gr_line
		(start 287.83661 -321.156584)
		(end 286.436816 -321.156584)
		(stroke
			(width 0.2)
			(type default)
		)
		(layer "In5.Cu")
	)
	(gr_arc
		(start 287.83661 -318.653668)
		(mid 288.38525 -318.105028)
		(end 287.83661 -317.556388)
		(stroke
			(width 0.2)
			(type default)
		)
		(layer "In5.Cu")
	)
	(gr_line
		(start 287.83661 -317.556388)
		(end 286.436816 -317.556388)
		(stroke
			(width 0.2)
			(type default)
		)
		(layer "In5.Cu")
	)
	(gr_arc
		(start 287.83661 -315.056266)
		(mid 288.38779 -314.505086)
		(end 287.83661 -313.953906)
		(stroke
			(width 0.2)
			(type default)
		)
		(layer "In5.Cu")
	)
	(gr_line
		(start 287.83661 -313.953906)
		(end 286.436816 -313.953906)
		(stroke
			(width 0.2)
			(type default)
		)
		(layer "In5.Cu")
	)
	(gr_arc
		(start 287.83661 -311.456324)
		(mid 288.38779 -310.905144)
		(end 287.83661 -310.353964)
		(stroke
			(width 0.2)
			(type default)
		)
		(layer "In5.Cu")
	)
	(gr_line
		(start 287.83661 -310.353964)
		(end 286.436816 -310.353964)
		(stroke
			(width 0.2)
			(type default)
		)
		(layer "In5.Cu")
	)
	(gr_arc
		(start 287.83661 -307.856382)
		(mid 288.38779 -307.305202)
		(end 287.83661 -306.754022)
		(stroke
			(width 0.2)
			(type default)
		)
		(layer "In5.Cu")
	)
	(gr_line
		(start 287.83661 -306.754022)
		(end 286.436816 -306.754022)
		(stroke
			(width 0.2)
			(type default)
		)
		(layer "In5.Cu")
	)
	(gr_arc
		(start 287.83661 -304.2539)
		(mid 288.38525 -303.70526)
		(end 287.83661 -303.15662)
		(stroke
			(width 0.2)
			(type default)
		)
		(layer "In5.Cu")
	)
	(gr_line
		(start 287.83661 -303.15662)
		(end 286.436816 -303.15662)
		(stroke
			(width 0.2)
			(type default)
		)
		(layer "In5.Cu")
	)
	(gr_arc
		(start 287.83661 -300.653704)
		(mid 288.38525 -300.105064)
		(end 287.83661 -299.556424)
		(stroke
			(width 0.2)
			(type default)
		)
		(layer "In5.Cu")
	)
	(gr_line
		(start 287.83661 -299.556424)
		(end 286.436816 -299.556424)
		(stroke
			(width 0.2)
			(type default)
		)
		(layer "In5.Cu")
	)
	(gr_arc
		(start 287.83661 -297.056302)
		(mid 288.38779 -296.505122)
		(end 287.83661 -295.953942)
		(stroke
			(width 0.2)
			(type default)
		)
		(layer "In5.Cu")
	)
	(gr_line
		(start 287.83661 -295.953942)
		(end 286.436816 -295.953942)
		(stroke
			(width 0.2)
			(type default)
		)
		(layer "In5.Cu")
	)
	(gr_arc
		(start 287.83661 -264.253472)
		(mid 288.38779 -263.702292)
		(end 287.83661 -263.151112)
		(stroke
			(width 0.2)
			(type default)
		)
		(layer "In5.Cu")
	)
	(gr_line
		(start 287.83661 -263.151112)
		(end 286.436816 -263.151112)
		(stroke
			(width 0.2)
			(type default)
		)
		(layer "In5.Cu")
	)
	(gr_arc
		(start 287.83661 -260.65353)
		(mid 288.38779 -260.10235)
		(end 287.83661 -259.55117)
		(stroke
			(width 0.2)
			(type default)
		)
		(layer "In5.Cu")
	)
	(gr_line
		(start 287.83661 -259.55117)
		(end 286.436816 -259.55117)
		(stroke
			(width 0.2)
			(type default)
		)
		(layer "In5.Cu")
	)
	(gr_arc
		(start 287.83661 -257.053588)
		(mid 288.38779 -256.502408)
		(end 287.83661 -255.951228)
		(stroke
			(width 0.2)
			(type default)
		)
		(layer "In5.Cu")
	)
	(gr_line
		(start 287.83661 -255.951228)
		(end 286.436816 -255.951228)
		(stroke
			(width 0.2)
			(type default)
		)
		(layer "In5.Cu")
	)
	(gr_arc
		(start 287.83661 -253.453392)
		(mid 288.38779 -252.902212)
		(end 287.83661 -252.351032)
		(stroke
			(width 0.2)
			(type default)
		)
		(layer "In5.Cu")
	)
	(gr_line
		(start 287.83661 -252.351032)
		(end 286.436816 -252.351032)
		(stroke
			(width 0.2)
			(type default)
		)
		(layer "In5.Cu")
	)
	(gr_line
		(start 290.403788 -248.78919)
		(end 291.231828 -249.61723)
		(stroke
			(width 0.381)
			(type default)
		)
		(layer "In5.Cu")
	)
	(gr_line
		(start 290.628578 -291.573458)
		(end 275.972016 -291.573458)
		(stroke
			(width 0.381)
			(type default)
		)
		(layer "In5.Cu")
	)
	(gr_line
		(start 290.628578 -291.573458)
		(end 291.212524 -292.157404)
		(stroke
			(width 0.381)
			(type default)
		)
		(layer "In5.Cu")
	)
	(gr_line
		(start 290.647374 -266.5984)
		(end 276.9362 -266.5984)
		(stroke
			(width 0.381)
			(type default)
		)
		(layer "In5.Cu")
	)
	(gr_line
		(start 291.212524 -347.808296)
		(end 293.604188 -350.19996)
		(stroke
			(width 0.381)
			(type default)
		)
		(layer "In5.Cu")
	)
	(gr_line
		(start 291.212524 -292.157404)
		(end 291.212524 -347.808296)
		(stroke
			(width 0.381)
			(type default)
		)
		(layer "In5.Cu")
	)
	(gr_line
		(start 291.231828 -266.013946)
		(end 290.647374 -266.5984)
		(stroke
			(width 0.381)
			(type default)
		)
		(layer "In5.Cu")
	)
	(gr_line
		(start 291.231828 -249.61723)
		(end 291.231828 -266.013946)
		(stroke
			(width 0.381)
			(type default)
		)
		(layer "In5.Cu")
	)
	(gr_line
		(start 292.354 6.2992)
		(end 266.6492 6.2992)
		(stroke
			(width 0.381)
			(type default)
		)
		(layer "In5.Cu")
	)
	(gr_line
		(start 293.604188 -350.19996)
		(end 295.699942 -350.19996)
		(stroke
			(width 0.381)
			(type default)
		)
		(layer "In5.Cu")
	)
	(gr_line
		(start 293.8526 -198.0184)
		(end 297.4086 -194.4624)
		(stroke
			(width 0.381)
			(type default)
		)
		(layer "In5.Cu")
	)
	(gr_arc
		(start 295.699942 -373.000016)
		(mid 295.992835 -373.707121)
		(end 296.69994 -374.000014)
		(stroke
			(width 2.54)
			(type default)
		)
		(layer "In5.Cu")
	)
	(gr_line
		(start 295.699942 -350.19996)
		(end 295.699942 -373.000016)
		(stroke
			(width 2.54)
			(type default)
		)
		(layer "In5.Cu")
	)
	(gr_line
		(start 296.69994 -374.000014)
		(end 308.99989 -374.000014)
		(stroke
			(width 2.54)
			(type default)
		)
		(layer "In5.Cu")
	)
	(gr_arc
		(start 296.69994 -349.199962)
		(mid 295.992835 -349.492855)
		(end 295.699942 -350.19996)
		(stroke
			(width 2.54)
			(type default)
		)
		(layer "In5.Cu")
	)
	(gr_line
		(start 296.7736 -89.5604)
		(end 296.7736 1.8796)
		(stroke
			(width 0.381)
			(type default)
		)
		(layer "In5.Cu")
	)
	(gr_line
		(start 296.7736 1.8796)
		(end 292.354 6.2992)
		(stroke
			(width 0.381)
			(type default)
		)
		(layer "In5.Cu")
	)
	(gr_line
		(start 297.4086 -194.4624)
		(end 297.4086 -175.0568)
		(stroke
			(width 0.381)
			(type default)
		)
		(layer "In5.Cu")
	)
	(gr_line
		(start 297.4086 -175.0568)
		(end 326.136 -146.3294)
		(stroke
			(width 0.381)
			(type default)
		)
		(layer "In5.Cu")
	)
	(gr_arc
		(start 299.999908 0.999998)
		(mid 300.292801 0.292893)
		(end 300.999906 0)
		(stroke
			(width 2.54)
			(type default)
		)
		(layer "In5.Cu")
	)
	(gr_arc
		(start 299.999908 37.800026)
		(mid 299.707007 38.507118)
		(end 298.99991 38.800024)
		(stroke
			(width 2.54)
			(type default)
		)
		(layer "In5.Cu")
	)
	(gr_line
		(start 299.999908 37.800026)
		(end 299.999908 0.999998)
		(stroke
			(width 2.54)
			(type default)
		)
		(layer "In5.Cu")
	)
	(gr_line
		(start 300.999906 0)
		(end 347.000068 0)
		(stroke
			(width 2.54)
			(type default)
		)
		(layer "In5.Cu")
	)
	(gr_line
		(start 308.99989 -421.200072)
		(end 201.000106 -421.200072)
		(stroke
			(width 2.54)
			(type default)
		)
		(layer "In5.Cu")
	)
	(gr_arc
		(start 308.99989 -421.200072)
		(mid 309.706993 -420.907181)
		(end 309.999888 -420.200074)
		(stroke
			(width 2.54)
			(type default)
		)
		(layer "In5.Cu")
	)
	(gr_arc
		(start 309.999888 -375.000012)
		(mid 309.706999 -374.292902)
		(end 308.99989 -374.000014)
		(stroke
			(width 2.54)
			(type default)
		)
		(layer "In5.Cu")
	)
	(gr_line
		(start 309.999888 -375.000012)
		(end 309.999888 -420.200074)
		(stroke
			(width 2.54)
			(type default)
		)
		(layer "In5.Cu")
	)
	(gr_line
		(start 319.2145 -43.008042)
		(end 320.3575 -43.008042)
		(stroke
			(width 0.2)
			(type default)
		)
		(layer "In5.Cu")
	)
	(gr_arc
		(start 319.214754 -42.246042)
		(mid 318.8335 -42.626915)
		(end 319.2145 -43.008042)
		(stroke
			(width 0.2)
			(type default)
		)
		(layer "In5.Cu")
	)
	(gr_arc
		(start 319.56756 -274.511516)
		(mid 319.9892 -274.933156)
		(end 320.41084 -274.511516)
		(stroke
			(width 0.2)
			(type default)
		)
		(layer "In5.Cu")
	)
	(gr_line
		(start 319.56756 -273.368516)
		(end 319.56756 -274.511516)
		(stroke
			(width 0.2)
			(type default)
		)
		(layer "In5.Cu")
	)
	(gr_arc
		(start 319.6082 -159.511238)
		(mid 319.989073 -159.892492)
		(end 320.3702 -159.511492)
		(stroke
			(width 0.2)
			(type default)
		)
		(layer "In5.Cu")
	)
	(gr_line
		(start 319.6082 -158.368492)
		(end 319.6082 -159.511238)
		(stroke
			(width 0.2)
			(type default)
		)
		(layer "In5.Cu")
	)
	(gr_arc
		(start 320.3575 -43.008042)
		(mid 320.7385 -42.627042)
		(end 320.3575 -42.246042)
		(stroke
			(width 0.2)
			(type default)
		)
		(layer "In5.Cu")
	)
	(gr_line
		(start 320.3575 -42.246042)
		(end 319.214754 -42.246042)
		(stroke
			(width 0.2)
			(type default)
		)
		(layer "In5.Cu")
	)
	(gr_line
		(start 320.3702 -159.511492)
		(end 320.3702 -158.368492)
		(stroke
			(width 0.2)
			(type default)
		)
		(layer "In5.Cu")
	)
	(gr_arc
		(start 320.3702 -158.368492)
		(mid 319.9892 -157.987492)
		(end 319.6082 -158.368492)
		(stroke
			(width 0.2)
			(type default)
		)
		(layer "In5.Cu")
	)
	(gr_line
		(start 320.41084 -274.511516)
		(end 320.41084 -273.36877)
		(stroke
			(width 0.2)
			(type default)
		)
		(layer "In5.Cu")
	)
	(gr_arc
		(start 320.41084 -273.36877)
		(mid 319.989327 -272.946876)
		(end 319.56756 -273.368516)
		(stroke
			(width 0.2)
			(type default)
		)
		(layer "In5.Cu")
	)
	(gr_line
		(start 322.6816 -46.818042)
		(end 323.824346 -46.818042)
		(stroke
			(width 0.2)
			(type default)
		)
		(layer "In5.Cu")
	)
	(gr_arc
		(start 322.6816 -46.056042)
		(mid 322.3006 -46.437042)
		(end 322.6816 -46.818042)
		(stroke
			(width 0.2)
			(type default)
		)
		(layer "In5.Cu")
	)
	(gr_arc
		(start 323.824346 -46.818042)
		(mid 324.2056 -46.437169)
		(end 323.8246 -46.056042)
		(stroke
			(width 0.2)
			(type default)
		)
		(layer "In5.Cu")
	)
	(gr_line
		(start 323.8246 -46.056042)
		(end 322.6816 -46.056042)
		(stroke
			(width 0.2)
			(type default)
		)
		(layer "In5.Cu")
	)
	(gr_arc
		(start 324.358 -278.321516)
		(mid 324.739 -278.702516)
		(end 325.12 -278.321516)
		(stroke
			(width 0.2)
			(type default)
		)
		(layer "In5.Cu")
	)
	(gr_line
		(start 324.358 -277.178516)
		(end 324.358 -278.321516)
		(stroke
			(width 0.2)
			(type default)
		)
		(layer "In5.Cu")
	)
	(gr_arc
		(start 324.358 -163.321492)
		(mid 324.739 -163.702492)
		(end 325.12 -163.321492)
		(stroke
			(width 0.2)
			(type default)
		)
		(layer "In5.Cu")
	)
	(gr_line
		(start 324.358 -162.178492)
		(end 324.358 -163.321492)
		(stroke
			(width 0.2)
			(type default)
		)
		(layer "In5.Cu")
	)
	(gr_line
		(start 325.12 -278.321516)
		(end 325.12 -277.17877)
		(stroke
			(width 0.2)
			(type default)
		)
		(layer "In5.Cu")
	)
	(gr_arc
		(start 325.12 -277.17877)
		(mid 324.739127 -276.797516)
		(end 324.358 -277.178516)
		(stroke
			(width 0.2)
			(type default)
		)
		(layer "In5.Cu")
	)
	(gr_line
		(start 325.12 -163.321492)
		(end 325.12 -162.178746)
		(stroke
			(width 0.2)
			(type default)
		)
		(layer "In5.Cu")
	)
	(gr_arc
		(start 325.12 -162.178746)
		(mid 324.739127 -161.797492)
		(end 324.358 -162.178492)
		(stroke
			(width 0.2)
			(type default)
		)
		(layer "In5.Cu")
	)
	(gr_line
		(start 326.136 -146.3294)
		(end 351.410778 -146.3294)
		(stroke
			(width 0.381)
			(type default)
		)
		(layer "In5.Cu")
	)
	(gr_line
		(start 326.4662 -119.253)
		(end 296.7736 -89.5604)
		(stroke
			(width 0.381)
			(type default)
		)
		(layer "In5.Cu")
	)
	(gr_arc
		(start 348.000066 -13.999972)
		(mid 348.292959 -14.707077)
		(end 349.000064 -14.99997)
		(stroke
			(width 2.54)
			(type default)
		)
		(layer "In5.Cu")
	)
	(gr_arc
		(start 348.000066 -0.999998)
		(mid 347.707171 -0.292905)
		(end 347.000068 0)
		(stroke
			(width 2.54)
			(type default)
		)
		(layer "In5.Cu")
	)
	(gr_line
		(start 348.000066 -0.999998)
		(end 348.000066 -13.999972)
		(stroke
			(width 2.54)
			(type default)
		)
		(layer "In5.Cu")
	)
	(gr_line
		(start 349.000064 -14.99997)
		(end 394.999972 -14.99997)
		(stroke
			(width 2.54)
			(type default)
		)
		(layer "In5.Cu")
	)
	(gr_line
		(start 349.205804 -35.438842)
		(end 349.205804 -15.174976)
		(stroke
			(width 0.381)
			(type default)
		)
		(layer "In5.Cu")
	)
	(gr_line
		(start 349.205804 -15.174976)
		(end 350.380808 -13.999972)
		(stroke
			(width 0.381)
			(type default)
		)
		(layer "In5.Cu")
	)
	(gr_line
		(start 349.775526 -36.008564)
		(end 349.205804 -35.438842)
		(stroke
			(width 0.381)
			(type default)
		)
		(layer "In5.Cu")
	)
	(gr_line
		(start 350.012 -119.253)
		(end 326.4662 -119.253)
		(stroke
			(width 0.381)
			(type default)
		)
		(layer "In5.Cu")
	)
	(gr_line
		(start 350.380808 -13.999972)
		(end 353.000056 -13.999972)
		(stroke
			(width 0.381)
			(type default)
		)
		(layer "In5.Cu")
	)
	(gr_line
		(start 350.764602 -43.013122)
		(end 351.907602 -43.013122)
		(stroke
			(width 0.2)
			(type default)
		)
		(layer "In5.Cu")
	)
	(gr_arc
		(start 350.764856 -42.240962)
		(mid 350.378522 -42.626915)
		(end 350.764602 -43.013122)
		(stroke
			(width 0.2)
			(type default)
		)
		(layer "In5.Cu")
	)
	(gr_arc
		(start 351.158302 -274.511262)
		(mid 351.539175 -274.892516)
		(end 351.920302 -274.511516)
		(stroke
			(width 0.2)
			(type default)
		)
		(layer "In5.Cu")
	)
	(gr_line
		(start 351.158302 -273.368516)
		(end 351.158302 -274.511262)
		(stroke
			(width 0.2)
			(type default)
		)
		(layer "In5.Cu")
	)
	(gr_arc
		(start 351.158302 -159.511238)
		(mid 351.539175 -159.892492)
		(end 351.920302 -159.511492)
		(stroke
			(width 0.2)
			(type default)
		)
		(layer "In5.Cu")
	)
	(gr_line
		(start 351.158302 -158.368492)
		(end 351.158302 -159.511238)
		(stroke
			(width 0.2)
			(type default)
		)
		(layer "In5.Cu")
	)
	(gr_line
		(start 351.410778 -146.3294)
		(end 353.296728 -144.44345)
		(stroke
			(width 0.381)
			(type default)
		)
		(layer "In5.Cu")
	)
	(gr_arc
		(start 351.907602 -43.013122)
		(mid 352.293682 -42.627042)
		(end 351.907602 -42.240962)
		(stroke
			(width 0.2)
			(type default)
		)
		(layer "In5.Cu")
	)
	(gr_line
		(start 351.907602 -42.240962)
		(end 350.764856 -42.240962)
		(stroke
			(width 0.2)
			(type default)
		)
		(layer "In5.Cu")
	)
	(gr_line
		(start 351.920302 -274.511516)
		(end 351.920302 -273.368516)
		(stroke
			(width 0.2)
			(type default)
		)
		(layer "In5.Cu")
	)
	(gr_arc
		(start 351.920302 -273.368516)
		(mid 351.539302 -272.987516)
		(end 351.158302 -273.368516)
		(stroke
			(width 0.2)
			(type default)
		)
		(layer "In5.Cu")
	)
	(gr_line
		(start 351.920302 -159.511492)
		(end 351.920302 -158.368492)
		(stroke
			(width 0.2)
			(type default)
		)
		(layer "In5.Cu")
	)
	(gr_arc
		(start 351.920302 -158.368492)
		(mid 351.539302 -157.987492)
		(end 351.158302 -158.368492)
		(stroke
			(width 0.2)
			(type default)
		)
		(layer "In5.Cu")
	)
	(gr_line
		(start 353.296728 -144.44345)
		(end 353.296728 -122.537728)
		(stroke
			(width 0.381)
			(type default)
		)
		(layer "In5.Cu")
	)
	(gr_line
		(start 353.296728 -122.537728)
		(end 350.012 -119.253)
		(stroke
			(width 0.381)
			(type default)
		)
		(layer "In5.Cu")
	)
	(gr_arc
		(start 354.601272 -22.350222)
		(mid 355.149912 -22.898862)
		(end 355.698552 -22.350222)
		(stroke
			(width 0.2)
			(type default)
		)
		(layer "In5.Cu")
	)
	(gr_line
		(start 354.601272 -20.950174)
		(end 354.601272 -22.350222)
		(stroke
			(width 0.2)
			(type default)
		)
		(layer "In5.Cu")
	)
	(gr_arc
		(start 354.601272 -18.750026)
		(mid 355.149912 -19.298666)
		(end 355.698552 -18.750026)
		(stroke
			(width 0.2)
			(type default)
		)
		(layer "In5.Cu")
	)
	(gr_line
		(start 354.601272 -17.349978)
		(end 354.601272 -18.750026)
		(stroke
			(width 0.2)
			(type default)
		)
		(layer "In5.Cu")
	)
	(gr_line
		(start 355.698552 -22.350222)
		(end 355.698552 -20.950428)
		(stroke
			(width 0.2)
			(type default)
		)
		(layer "In5.Cu")
	)
	(gr_arc
		(start 355.698552 -20.950428)
		(mid 355.150039 -20.401534)
		(end 354.601272 -20.950174)
		(stroke
			(width 0.2)
			(type default)
		)
		(layer "In5.Cu")
	)
	(gr_line
		(start 355.698552 -18.750026)
		(end 355.698552 -17.350232)
		(stroke
			(width 0.2)
			(type default)
		)
		(layer "In5.Cu")
	)
	(gr_arc
		(start 355.698552 -17.350232)
		(mid 355.150039 -16.801338)
		(end 354.601272 -17.349978)
		(stroke
			(width 0.2)
			(type default)
		)
		(layer "In5.Cu")
	)
	(gr_arc
		(start 355.903022 -48.321468)
		(mid 356.289102 -48.707548)
		(end 356.675182 -48.321468)
		(stroke
			(width 0.2)
			(type default)
		)
		(layer "In5.Cu")
	)
	(gr_line
		(start 355.903022 -47.178468)
		(end 355.903022 -48.321468)
		(stroke
			(width 0.2)
			(type default)
		)
		(layer "In5.Cu")
	)
	(gr_arc
		(start 355.908102 -278.321516)
		(mid 356.289102 -278.702516)
		(end 356.670102 -278.321516)
		(stroke
			(width 0.2)
			(type default)
		)
		(layer "In5.Cu")
	)
	(gr_line
		(start 355.908102 -277.178516)
		(end 355.908102 -278.321516)
		(stroke
			(width 0.2)
			(type default)
		)
		(layer "In5.Cu")
	)
	(gr_arc
		(start 355.908102 -163.321492)
		(mid 356.289102 -163.702492)
		(end 356.670102 -163.321492)
		(stroke
			(width 0.2)
			(type default)
		)
		(layer "In5.Cu")
	)
	(gr_line
		(start 355.908102 -162.178492)
		(end 355.908102 -163.321492)
		(stroke
			(width 0.2)
			(type default)
		)
		(layer "In5.Cu")
	)
	(gr_arc
		(start 356.40137 -23.35022)
		(mid 356.95001 -23.89886)
		(end 357.49865 -23.35022)
		(stroke
			(width 0.2)
			(type default)
		)
		(layer "In5.Cu")
	)
	(gr_line
		(start 356.40137 -21.950172)
		(end 356.40137 -23.35022)
		(stroke
			(width 0.2)
			(type default)
		)
		(layer "In5.Cu")
	)
	(gr_arc
		(start 356.40137 -19.750024)
		(mid 356.95001 -20.298664)
		(end 357.49865 -19.750024)
		(stroke
			(width 0.2)
			(type default)
		)
		(layer "In5.Cu")
	)
	(gr_line
		(start 356.40137 -18.35023)
		(end 356.40137 -19.750024)
		(stroke
			(width 0.2)
			(type default)
		)
		(layer "In5.Cu")
	)
	(gr_line
		(start 356.670102 -278.321516)
		(end 356.670102 -277.17877)
		(stroke
			(width 0.2)
			(type default)
		)
		(layer "In5.Cu")
	)
	(gr_arc
		(start 356.670102 -277.17877)
		(mid 356.289229 -276.797516)
		(end 355.908102 -277.178516)
		(stroke
			(width 0.2)
			(type default)
		)
		(layer "In5.Cu")
	)
	(gr_line
		(start 356.670102 -163.321492)
		(end 356.670102 -162.178746)
		(stroke
			(width 0.2)
			(type default)
		)
		(layer "In5.Cu")
	)
	(gr_arc
		(start 356.670102 -162.178746)
		(mid 356.289229 -161.797492)
		(end 355.908102 -162.178492)
		(stroke
			(width 0.2)
			(type default)
		)
		(layer "In5.Cu")
	)
	(gr_line
		(start 356.675182 -48.321468)
		(end 356.675182 -47.178722)
		(stroke
			(width 0.2)
			(type default)
		)
		(layer "In5.Cu")
	)
	(gr_arc
		(start 356.675182 -47.178722)
		(mid 356.289229 -46.792388)
		(end 355.903022 -47.178468)
		(stroke
			(width 0.2)
			(type default)
		)
		(layer "In5.Cu")
	)
	(gr_line
		(start 357.49865 -23.35022)
		(end 357.49865 -21.950426)
		(stroke
			(width 0.2)
			(type default)
		)
		(layer "In5.Cu")
	)
	(gr_arc
		(start 357.49865 -21.950426)
		(mid 356.950137 -21.401532)
		(end 356.40137 -21.950172)
		(stroke
			(width 0.2)
			(type default)
		)
		(layer "In5.Cu")
	)
	(gr_line
		(start 357.49865 -19.750024)
		(end 357.49865 -18.350484)
		(stroke
			(width 0.2)
			(type default)
		)
		(layer "In5.Cu")
	)
	(gr_arc
		(start 357.49865 -18.350484)
		(mid 356.950137 -17.80159)
		(end 356.40137 -18.35023)
		(stroke
			(width 0.2)
			(type default)
		)
		(layer "In5.Cu")
	)
	(gr_arc
		(start 358.201468 -22.350222)
		(mid 358.750108 -22.898862)
		(end 359.298748 -22.350222)
		(stroke
			(width 0.2)
			(type default)
		)
		(layer "In5.Cu")
	)
	(gr_line
		(start 358.201468 -20.950174)
		(end 358.201468 -22.350222)
		(stroke
			(width 0.2)
			(type default)
		)
		(layer "In5.Cu")
	)
	(gr_arc
		(start 358.201468 -18.750026)
		(mid 358.750108 -19.298666)
		(end 359.298748 -18.750026)
		(stroke
			(width 0.2)
			(type default)
		)
		(layer "In5.Cu")
	)
	(gr_line
		(start 358.201468 -17.349978)
		(end 358.201468 -18.750026)
		(stroke
			(width 0.2)
			(type default)
		)
		(layer "In5.Cu")
	)
	(gr_line
		(start 359.298748 -22.350222)
		(end 359.298748 -20.950428)
		(stroke
			(width 0.2)
			(type default)
		)
		(layer "In5.Cu")
	)
	(gr_arc
		(start 359.298748 -20.950428)
		(mid 358.750235 -20.401534)
		(end 358.201468 -20.950174)
		(stroke
			(width 0.2)
			(type default)
		)
		(layer "In5.Cu")
	)
	(gr_line
		(start 359.298748 -18.750026)
		(end 359.298748 -17.350232)
		(stroke
			(width 0.2)
			(type default)
		)
		(layer "In5.Cu")
	)
	(gr_arc
		(start 359.298748 -17.350232)
		(mid 358.750235 -16.801338)
		(end 358.201468 -17.349978)
		(stroke
			(width 0.2)
			(type default)
		)
		(layer "In5.Cu")
	)
	(gr_arc
		(start 360.001312 -23.35022)
		(mid 360.549952 -23.89886)
		(end 361.098592 -23.35022)
		(stroke
			(width 0.2)
			(type default)
		)
		(layer "In5.Cu")
	)
	(gr_line
		(start 360.001312 -21.950172)
		(end 360.001312 -23.35022)
		(stroke
			(width 0.2)
			(type default)
		)
		(layer "In5.Cu")
	)
	(gr_arc
		(start 360.001312 -19.750024)
		(mid 360.549952 -20.298664)
		(end 361.098592 -19.750024)
		(stroke
			(width 0.2)
			(type default)
		)
		(layer "In5.Cu")
	)
	(gr_line
		(start 360.001312 -18.35023)
		(end 360.001312 -19.750024)
		(stroke
			(width 0.2)
			(type default)
		)
		(layer "In5.Cu")
	)
	(gr_line
		(start 361.098592 -23.35022)
		(end 361.098592 -21.950426)
		(stroke
			(width 0.2)
			(type default)
		)
		(layer "In5.Cu")
	)
	(gr_arc
		(start 361.098592 -21.950426)
		(mid 360.550079 -21.401532)
		(end 360.001312 -21.950172)
		(stroke
			(width 0.2)
			(type default)
		)
		(layer "In5.Cu")
	)
	(gr_line
		(start 361.098592 -19.750024)
		(end 361.098592 -18.350484)
		(stroke
			(width 0.2)
			(type default)
		)
		(layer "In5.Cu")
	)
	(gr_arc
		(start 361.098592 -18.350484)
		(mid 360.550079 -17.80159)
		(end 360.001312 -18.35023)
		(stroke
			(width 0.2)
			(type default)
		)
		(layer "In5.Cu")
	)
	(gr_arc
		(start 361.80141 -29.550106)
		(mid 362.35005 -30.098746)
		(end 362.89869 -29.550106)
		(stroke
			(width 0.2)
			(type default)
		)
		(layer "In5.Cu")
	)
	(gr_line
		(start 361.80141 -28.150058)
		(end 361.80141 -29.550106)
		(stroke
			(width 0.2)
			(type default)
		)
		(layer "In5.Cu")
	)
	(gr_arc
		(start 361.80141 -22.350222)
		(mid 362.35005 -22.898862)
		(end 362.89869 -22.350222)
		(stroke
			(width 0.2)
			(type default)
		)
		(layer "In5.Cu")
	)
	(gr_line
		(start 361.80141 -20.950174)
		(end 361.80141 -22.350222)
		(stroke
			(width 0.2)
			(type default)
		)
		(layer "In5.Cu")
	)
	(gr_arc
		(start 361.80141 -18.750026)
		(mid 362.35005 -19.298666)
		(end 362.89869 -18.750026)
		(stroke
			(width 0.2)
			(type default)
		)
		(layer "In5.Cu")
	)
	(gr_line
		(start 361.80141 -17.349978)
		(end 361.80141 -18.750026)
		(stroke
			(width 0.2)
			(type default)
		)
		(layer "In5.Cu")
	)
	(gr_line
		(start 362.89869 -29.550106)
		(end 362.89869 -28.150312)
		(stroke
			(width 0.2)
			(type default)
		)
		(layer "In5.Cu")
	)
	(gr_arc
		(start 362.89869 -28.150312)
		(mid 362.350177 -27.601418)
		(end 361.80141 -28.150058)
		(stroke
			(width 0.2)
			(type default)
		)
		(layer "In5.Cu")
	)
	(gr_line
		(start 362.89869 -22.350222)
		(end 362.89869 -20.950428)
		(stroke
			(width 0.2)
			(type default)
		)
		(layer "In5.Cu")
	)
	(gr_arc
		(start 362.89869 -20.950428)
		(mid 362.350177 -20.401534)
		(end 361.80141 -20.950174)
		(stroke
			(width 0.2)
			(type default)
		)
		(layer "In5.Cu")
	)
	(gr_line
		(start 362.89869 -18.750026)
		(end 362.89869 -17.350232)
		(stroke
			(width 0.2)
			(type default)
		)
		(layer "In5.Cu")
	)
	(gr_arc
		(start 362.89869 -17.350232)
		(mid 362.350177 -16.801338)
		(end 361.80141 -17.349978)
		(stroke
			(width 0.2)
			(type default)
		)
		(layer "In5.Cu")
	)
	(gr_arc
		(start 363.601254 -23.35022)
		(mid 364.149894 -23.89886)
		(end 364.698534 -23.35022)
		(stroke
			(width 0.2)
			(type default)
		)
		(layer "In5.Cu")
	)
	(gr_line
		(start 363.601254 -21.950172)
		(end 363.601254 -23.35022)
		(stroke
			(width 0.2)
			(type default)
		)
		(layer "In5.Cu")
	)
	(gr_arc
		(start 363.601254 -19.750024)
		(mid 364.149894 -20.298664)
		(end 364.698534 -19.750024)
		(stroke
			(width 0.2)
			(type default)
		)
		(layer "In5.Cu")
	)
	(gr_line
		(start 363.601254 -18.35023)
		(end 363.601254 -19.750024)
		(stroke
			(width 0.2)
			(type default)
		)
		(layer "In5.Cu")
	)
	(gr_line
		(start 364.698534 -23.35022)
		(end 364.698534 -21.950426)
		(stroke
			(width 0.2)
			(type default)
		)
		(layer "In5.Cu")
	)
	(gr_arc
		(start 364.698534 -21.950426)
		(mid 364.150021 -21.401532)
		(end 363.601254 -21.950172)
		(stroke
			(width 0.2)
			(type default)
		)
		(layer "In5.Cu")
	)
	(gr_line
		(start 364.698534 -19.750024)
		(end 364.698534 -18.350484)
		(stroke
			(width 0.2)
			(type default)
		)
		(layer "In5.Cu")
	)
	(gr_arc
		(start 364.698534 -18.350484)
		(mid 364.150021 -17.80159)
		(end 363.601254 -18.35023)
		(stroke
			(width 0.2)
			(type default)
		)
		(layer "In5.Cu")
	)
	(gr_arc
		(start 365.401352 -22.350222)
		(mid 365.949992 -22.898862)
		(end 366.498632 -22.350222)
		(stroke
			(width 0.2)
			(type default)
		)
		(layer "In5.Cu")
	)
	(gr_line
		(start 365.401352 -20.950174)
		(end 365.401352 -22.350222)
		(stroke
			(width 0.2)
			(type default)
		)
		(layer "In5.Cu")
	)
	(gr_arc
		(start 365.401352 -18.750026)
		(mid 365.949992 -19.298666)
		(end 366.498632 -18.750026)
		(stroke
			(width 0.2)
			(type default)
		)
		(layer "In5.Cu")
	)
	(gr_line
		(start 365.401352 -17.349978)
		(end 365.401352 -18.750026)
		(stroke
			(width 0.2)
			(type default)
		)
		(layer "In5.Cu")
	)
	(gr_line
		(start 366.498632 -22.350222)
		(end 366.498632 -20.950428)
		(stroke
			(width 0.2)
			(type default)
		)
		(layer "In5.Cu")
	)
	(gr_arc
		(start 366.498632 -20.950428)
		(mid 365.950119 -20.401534)
		(end 365.401352 -20.950174)
		(stroke
			(width 0.2)
			(type default)
		)
		(layer "In5.Cu")
	)
	(gr_line
		(start 366.498632 -18.750026)
		(end 366.498632 -17.350232)
		(stroke
			(width 0.2)
			(type default)
		)
		(layer "In5.Cu")
	)
	(gr_arc
		(start 366.498632 -17.350232)
		(mid 365.950119 -16.801338)
		(end 365.401352 -17.349978)
		(stroke
			(width 0.2)
			(type default)
		)
		(layer "In5.Cu")
	)
	(gr_arc
		(start 367.19891 -30.54985)
		(mid 367.749963 -31.101284)
		(end 368.30127 -30.550104)
		(stroke
			(width 0.2)
			(type default)
		)
		(layer "In5.Cu")
	)
	(gr_line
		(start 367.19891 -29.150056)
		(end 367.19891 -30.54985)
		(stroke
			(width 0.2)
			(type default)
		)
		(layer "In5.Cu")
	)
	(gr_arc
		(start 367.20145 -23.35022)
		(mid 367.75009 -23.89886)
		(end 368.29873 -23.35022)
		(stroke
			(width 0.2)
			(type default)
		)
		(layer "In5.Cu")
	)
	(gr_line
		(start 367.20145 -21.950172)
		(end 367.20145 -23.35022)
		(stroke
			(width 0.2)
			(type default)
		)
		(layer "In5.Cu")
	)
	(gr_arc
		(start 367.20145 -19.750024)
		(mid 367.75009 -20.298664)
		(end 368.29873 -19.750024)
		(stroke
			(width 0.2)
			(type default)
		)
		(layer "In5.Cu")
	)
	(gr_line
		(start 367.20145 -18.35023)
		(end 367.20145 -19.750024)
		(stroke
			(width 0.2)
			(type default)
		)
		(layer "In5.Cu")
	)
	(gr_line
		(start 368.29873 -23.35022)
		(end 368.29873 -21.950426)
		(stroke
			(width 0.2)
			(type default)
		)
		(layer "In5.Cu")
	)
	(gr_arc
		(start 368.29873 -21.950426)
		(mid 367.750217 -21.401532)
		(end 367.20145 -21.950172)
		(stroke
			(width 0.2)
			(type default)
		)
		(layer "In5.Cu")
	)
	(gr_line
		(start 368.29873 -19.750024)
		(end 368.29873 -18.350484)
		(stroke
			(width 0.2)
			(type default)
		)
		(layer "In5.Cu")
	)
	(gr_arc
		(start 368.29873 -18.350484)
		(mid 367.750217 -17.80159)
		(end 367.20145 -18.35023)
		(stroke
			(width 0.2)
			(type default)
		)
		(layer "In5.Cu")
	)
	(gr_line
		(start 368.30127 -30.550104)
		(end 368.30127 -29.150056)
		(stroke
			(width 0.2)
			(type default)
		)
		(layer "In5.Cu")
	)
	(gr_arc
		(start 368.30127 -29.150056)
		(mid 367.75009 -28.598876)
		(end 367.19891 -29.150056)
		(stroke
			(width 0.2)
			(type default)
		)
		(layer "In5.Cu")
	)
	(gr_arc
		(start 376.201432 -22.350222)
		(mid 376.750072 -22.898862)
		(end 377.298712 -22.350222)
		(stroke
			(width 0.2)
			(type default)
		)
		(layer "In5.Cu")
	)
	(gr_line
		(start 376.201432 -20.950174)
		(end 376.201432 -22.350222)
		(stroke
			(width 0.2)
			(type default)
		)
		(layer "In5.Cu")
	)
	(gr_arc
		(start 376.201432 -18.750026)
		(mid 376.750072 -19.298666)
		(end 377.298712 -18.750026)
		(stroke
			(width 0.2)
			(type default)
		)
		(layer "In5.Cu")
	)
	(gr_line
		(start 376.201432 -17.349978)
		(end 376.201432 -18.750026)
		(stroke
			(width 0.2)
			(type default)
		)
		(layer "In5.Cu")
	)
	(gr_line
		(start 377.298712 -22.350222)
		(end 377.298712 -20.950428)
		(stroke
			(width 0.2)
			(type default)
		)
		(layer "In5.Cu")
	)
	(gr_arc
		(start 377.298712 -20.950428)
		(mid 376.750199 -20.401534)
		(end 376.201432 -20.950174)
		(stroke
			(width 0.2)
			(type default)
		)
		(layer "In5.Cu")
	)
	(gr_line
		(start 377.298712 -18.750026)
		(end 377.298712 -17.350232)
		(stroke
			(width 0.2)
			(type default)
		)
		(layer "In5.Cu")
	)
	(gr_arc
		(start 377.298712 -17.350232)
		(mid 376.750199 -16.801338)
		(end 376.201432 -17.349978)
		(stroke
			(width 0.2)
			(type default)
		)
		(layer "In5.Cu")
	)
	(gr_arc
		(start 378.001276 -23.35022)
		(mid 378.549916 -23.89886)
		(end 379.098556 -23.35022)
		(stroke
			(width 0.2)
			(type default)
		)
		(layer "In5.Cu")
	)
	(gr_line
		(start 378.001276 -21.950172)
		(end 378.001276 -23.35022)
		(stroke
			(width 0.2)
			(type default)
		)
		(layer "In5.Cu")
	)
	(gr_arc
		(start 378.001276 -19.750024)
		(mid 378.549916 -20.298664)
		(end 379.098556 -19.750024)
		(stroke
			(width 0.2)
			(type default)
		)
		(layer "In5.Cu")
	)
	(gr_line
		(start 378.001276 -18.35023)
		(end 378.001276 -19.750024)
		(stroke
			(width 0.2)
			(type default)
		)
		(layer "In5.Cu")
	)
	(gr_line
		(start 379.098556 -23.35022)
		(end 379.098556 -21.950426)
		(stroke
			(width 0.2)
			(type default)
		)
		(layer "In5.Cu")
	)
	(gr_arc
		(start 379.098556 -21.950426)
		(mid 378.550043 -21.401532)
		(end 378.001276 -21.950172)
		(stroke
			(width 0.2)
			(type default)
		)
		(layer "In5.Cu")
	)
	(gr_line
		(start 379.098556 -19.750024)
		(end 379.098556 -18.350484)
		(stroke
			(width 0.2)
			(type default)
		)
		(layer "In5.Cu")
	)
	(gr_arc
		(start 379.098556 -18.350484)
		(mid 378.550043 -17.80159)
		(end 378.001276 -18.35023)
		(stroke
			(width 0.2)
			(type default)
		)
		(layer "In5.Cu")
	)
	(gr_arc
		(start 379.801374 -22.350222)
		(mid 380.350014 -22.898862)
		(end 380.898654 -22.350222)
		(stroke
			(width 0.2)
			(type default)
		)
		(layer "In5.Cu")
	)
	(gr_line
		(start 379.801374 -20.950174)
		(end 379.801374 -22.350222)
		(stroke
			(width 0.2)
			(type default)
		)
		(layer "In5.Cu")
	)
	(gr_arc
		(start 379.801374 -18.750026)
		(mid 380.350014 -19.298666)
		(end 380.898654 -18.750026)
		(stroke
			(width 0.2)
			(type default)
		)
		(layer "In5.Cu")
	)
	(gr_line
		(start 379.801374 -17.349978)
		(end 379.801374 -18.750026)
		(stroke
			(width 0.2)
			(type default)
		)
		(layer "In5.Cu")
	)
	(gr_line
		(start 380.898654 -22.350222)
		(end 380.898654 -20.950428)
		(stroke
			(width 0.2)
			(type default)
		)
		(layer "In5.Cu")
	)
	(gr_arc
		(start 380.898654 -20.950428)
		(mid 380.350141 -20.401534)
		(end 379.801374 -20.950174)
		(stroke
			(width 0.2)
			(type default)
		)
		(layer "In5.Cu")
	)
	(gr_line
		(start 380.898654 -18.750026)
		(end 380.898654 -17.350232)
		(stroke
			(width 0.2)
			(type default)
		)
		(layer "In5.Cu")
	)
	(gr_arc
		(start 380.898654 -17.350232)
		(mid 380.350141 -16.801338)
		(end 379.801374 -17.349978)
		(stroke
			(width 0.2)
			(type default)
		)
		(layer "In5.Cu")
	)
	(gr_arc
		(start 381.598932 -30.550104)
		(mid 382.150112 -31.101284)
		(end 382.701292 -30.550104)
		(stroke
			(width 0.2)
			(type default)
		)
		(layer "In5.Cu")
	)
	(gr_line
		(start 381.598932 -29.150056)
		(end 381.598932 -30.550104)
		(stroke
			(width 0.2)
			(type default)
		)
		(layer "In5.Cu")
	)
	(gr_arc
		(start 381.601472 -23.35022)
		(mid 382.150112 -23.89886)
		(end 382.698752 -23.35022)
		(stroke
			(width 0.2)
			(type default)
		)
		(layer "In5.Cu")
	)
	(gr_line
		(start 381.601472 -21.950172)
		(end 381.601472 -23.35022)
		(stroke
			(width 0.2)
			(type default)
		)
		(layer "In5.Cu")
	)
	(gr_arc
		(start 381.601472 -19.750024)
		(mid 382.150112 -20.298664)
		(end 382.698752 -19.750024)
		(stroke
			(width 0.2)
			(type default)
		)
		(layer "In5.Cu")
	)
	(gr_line
		(start 381.601472 -18.35023)
		(end 381.601472 -19.750024)
		(stroke
			(width 0.2)
			(type default)
		)
		(layer "In5.Cu")
	)
	(gr_line
		(start 382.698752 -23.35022)
		(end 382.698752 -21.950426)
		(stroke
			(width 0.2)
			(type default)
		)
		(layer "In5.Cu")
	)
	(gr_arc
		(start 382.698752 -21.950426)
		(mid 382.150239 -21.401532)
		(end 381.601472 -21.950172)
		(stroke
			(width 0.2)
			(type default)
		)
		(layer "In5.Cu")
	)
	(gr_line
		(start 382.698752 -19.750024)
		(end 382.698752 -18.350484)
		(stroke
			(width 0.2)
			(type default)
		)
		(layer "In5.Cu")
	)
	(gr_arc
		(start 382.698752 -18.350484)
		(mid 382.150239 -17.80159)
		(end 381.601472 -18.35023)
		(stroke
			(width 0.2)
			(type default)
		)
		(layer "In5.Cu")
	)
	(gr_line
		(start 382.701292 -30.550104)
		(end 382.701292 -29.15031)
		(stroke
			(width 0.2)
			(type default)
		)
		(layer "In5.Cu")
	)
	(gr_arc
		(start 382.701292 -29.15031)
		(mid 382.150239 -28.598876)
		(end 381.598932 -29.150056)
		(stroke
			(width 0.2)
			(type default)
		)
		(layer "In5.Cu")
	)
	(gr_arc
		(start 382.70815 -274.511262)
		(mid 383.089023 -274.892516)
		(end 383.47015 -274.511516)
		(stroke
			(width 0.2)
			(type default)
		)
		(layer "In5.Cu")
	)
	(gr_line
		(start 382.70815 -273.368516)
		(end 382.70815 -274.511262)
		(stroke
			(width 0.2)
			(type default)
		)
		(layer "In5.Cu")
	)
	(gr_arc
		(start 382.70815 -159.511238)
		(mid 383.089023 -159.892492)
		(end 383.47015 -159.511492)
		(stroke
			(width 0.2)
			(type default)
		)
		(layer "In5.Cu")
	)
	(gr_line
		(start 382.70815 -158.368492)
		(end 382.70815 -159.511238)
		(stroke
			(width 0.2)
			(type default)
		)
		(layer "In5.Cu")
	)
	(gr_line
		(start 382.7653 -46.5328)
		(end 383.908046 -46.5328)
		(stroke
			(width 0.2)
			(type default)
		)
		(layer "In5.Cu")
	)
	(gr_arc
		(start 382.7653 -45.7708)
		(mid 382.3843 -46.1518)
		(end 382.7653 -46.5328)
		(stroke
			(width 0.2)
			(type default)
		)
		(layer "In5.Cu")
	)
	(gr_arc
		(start 383.401316 -22.350222)
		(mid 383.949956 -22.898862)
		(end 384.498596 -22.350222)
		(stroke
			(width 0.2)
			(type default)
		)
		(layer "In5.Cu")
	)
	(gr_line
		(start 383.401316 -20.950174)
		(end 383.401316 -22.350222)
		(stroke
			(width 0.2)
			(type default)
		)
		(layer "In5.Cu")
	)
	(gr_arc
		(start 383.401316 -18.750026)
		(mid 383.949956 -19.298666)
		(end 384.498596 -18.750026)
		(stroke
			(width 0.2)
			(type default)
		)
		(layer "In5.Cu")
	)
	(gr_line
		(start 383.401316 -17.349978)
		(end 383.401316 -18.750026)
		(stroke
			(width 0.2)
			(type default)
		)
		(layer "In5.Cu")
	)
	(gr_line
		(start 383.47015 -274.511516)
		(end 383.47015 -273.368516)
		(stroke
			(width 0.2)
			(type default)
		)
		(layer "In5.Cu")
	)
	(gr_arc
		(start 383.47015 -273.368516)
		(mid 383.08915 -272.987516)
		(end 382.70815 -273.368516)
		(stroke
			(width 0.2)
			(type default)
		)
		(layer "In5.Cu")
	)
	(gr_line
		(start 383.47015 -159.511492)
		(end 383.47015 -158.368492)
		(stroke
			(width 0.2)
			(type default)
		)
		(layer "In5.Cu")
	)
	(gr_arc
		(start 383.47015 -158.368492)
		(mid 383.08915 -157.987492)
		(end 382.70815 -158.368492)
		(stroke
			(width 0.2)
			(type default)
		)
		(layer "In5.Cu")
	)
	(gr_arc
		(start 383.908046 -46.5328)
		(mid 384.2893 -46.151927)
		(end 383.9083 -45.7708)
		(stroke
			(width 0.2)
			(type default)
		)
		(layer "In5.Cu")
	)
	(gr_line
		(start 383.9083 -45.7708)
		(end 382.7653 -45.7708)
		(stroke
			(width 0.2)
			(type default)
		)
		(layer "In5.Cu")
	)
	(gr_line
		(start 384.498596 -22.350222)
		(end 384.498596 -20.950428)
		(stroke
			(width 0.2)
			(type default)
		)
		(layer "In5.Cu")
	)
	(gr_arc
		(start 384.498596 -20.950428)
		(mid 383.950083 -20.401534)
		(end 383.401316 -20.950174)
		(stroke
			(width 0.2)
			(type default)
		)
		(layer "In5.Cu")
	)
	(gr_line
		(start 384.498596 -18.750026)
		(end 384.498596 -17.350232)
		(stroke
			(width 0.2)
			(type default)
		)
		(layer "In5.Cu")
	)
	(gr_arc
		(start 384.498596 -17.350232)
		(mid 383.950083 -16.801338)
		(end 383.401316 -17.349978)
		(stroke
			(width 0.2)
			(type default)
		)
		(layer "In5.Cu")
	)
	(gr_arc
		(start 385.201414 -23.35022)
		(mid 385.750054 -23.89886)
		(end 386.298694 -23.35022)
		(stroke
			(width 0.2)
			(type default)
		)
		(layer "In5.Cu")
	)
	(gr_line
		(start 385.201414 -21.950172)
		(end 385.201414 -23.35022)
		(stroke
			(width 0.2)
			(type default)
		)
		(layer "In5.Cu")
	)
	(gr_arc
		(start 385.201414 -19.750024)
		(mid 385.750054 -20.298664)
		(end 386.298694 -19.750024)
		(stroke
			(width 0.2)
			(type default)
		)
		(layer "In5.Cu")
	)
	(gr_line
		(start 385.201414 -18.35023)
		(end 385.201414 -19.750024)
		(stroke
			(width 0.2)
			(type default)
		)
		(layer "In5.Cu")
	)
	(gr_line
		(start 386.298694 -23.35022)
		(end 386.298694 -21.950426)
		(stroke
			(width 0.2)
			(type default)
		)
		(layer "In5.Cu")
	)
	(gr_arc
		(start 386.298694 -21.950426)
		(mid 385.750181 -21.401532)
		(end 385.201414 -21.950172)
		(stroke
			(width 0.2)
			(type default)
		)
		(layer "In5.Cu")
	)
	(gr_line
		(start 386.298694 -19.750024)
		(end 386.298694 -18.350484)
		(stroke
			(width 0.2)
			(type default)
		)
		(layer "In5.Cu")
	)
	(gr_arc
		(start 386.298694 -18.350484)
		(mid 385.750181 -17.80159)
		(end 385.201414 -18.35023)
		(stroke
			(width 0.2)
			(type default)
		)
		(layer "In5.Cu")
	)
	(gr_arc
		(start 387.001258 -22.350222)
		(mid 387.549898 -22.898862)
		(end 388.098538 -22.350222)
		(stroke
			(width 0.2)
			(type default)
		)
		(layer "In5.Cu")
	)
	(gr_line
		(start 387.001258 -20.950174)
		(end 387.001258 -22.350222)
		(stroke
			(width 0.2)
			(type default)
		)
		(layer "In5.Cu")
	)
	(gr_arc
		(start 387.001258 -18.750026)
		(mid 387.549898 -19.298666)
		(end 388.098538 -18.750026)
		(stroke
			(width 0.2)
			(type default)
		)
		(layer "In5.Cu")
	)
	(gr_line
		(start 387.001258 -17.349978)
		(end 387.001258 -18.750026)
		(stroke
			(width 0.2)
			(type default)
		)
		(layer "In5.Cu")
	)
	(gr_arc
		(start 387.45795 -278.321516)
		(mid 387.83895 -278.702516)
		(end 388.21995 -278.321516)
		(stroke
			(width 0.2)
			(type default)
		)
		(layer "In5.Cu")
	)
	(gr_line
		(start 387.45795 -277.178516)
		(end 387.45795 -278.321516)
		(stroke
			(width 0.2)
			(type default)
		)
		(layer "In5.Cu")
	)
	(gr_arc
		(start 387.45795 -163.321492)
		(mid 387.83895 -163.702492)
		(end 388.21995 -163.321492)
		(stroke
			(width 0.2)
			(type default)
		)
		(layer "In5.Cu")
	)
	(gr_line
		(start 387.45795 -162.178492)
		(end 387.45795 -163.321492)
		(stroke
			(width 0.2)
			(type default)
		)
		(layer "In5.Cu")
	)
	(gr_arc
		(start 387.45795 -48.321468)
		(mid 387.83895 -48.702468)
		(end 388.21995 -48.321468)
		(stroke
			(width 0.2)
			(type default)
		)
		(layer "In5.Cu")
	)
	(gr_line
		(start 387.45795 -47.178468)
		(end 387.45795 -48.321468)
		(stroke
			(width 0.2)
			(type default)
		)
		(layer "In5.Cu")
	)
	(gr_line
		(start 388.098538 -22.350222)
		(end 388.098538 -20.950428)
		(stroke
			(width 0.2)
			(type default)
		)
		(layer "In5.Cu")
	)
	(gr_arc
		(start 388.098538 -20.950428)
		(mid 387.550025 -20.401534)
		(end 387.001258 -20.950174)
		(stroke
			(width 0.2)
			(type default)
		)
		(layer "In5.Cu")
	)
	(gr_line
		(start 388.098538 -18.750026)
		(end 388.098538 -17.350232)
		(stroke
			(width 0.2)
			(type default)
		)
		(layer "In5.Cu")
	)
	(gr_arc
		(start 388.098538 -17.350232)
		(mid 387.550025 -16.801338)
		(end 387.001258 -17.349978)
		(stroke
			(width 0.2)
			(type default)
		)
		(layer "In5.Cu")
	)
	(gr_line
		(start 388.21995 -278.321516)
		(end 388.21995 -277.17877)
		(stroke
			(width 0.2)
			(type default)
		)
		(layer "In5.Cu")
	)
	(gr_arc
		(start 388.21995 -277.17877)
		(mid 387.839077 -276.797516)
		(end 387.45795 -277.178516)
		(stroke
			(width 0.2)
			(type default)
		)
		(layer "In5.Cu")
	)
	(gr_line
		(start 388.21995 -163.321492)
		(end 388.21995 -162.178746)
		(stroke
			(width 0.2)
			(type default)
		)
		(layer "In5.Cu")
	)
	(gr_arc
		(start 388.21995 -162.178746)
		(mid 387.839077 -161.797492)
		(end 387.45795 -162.178492)
		(stroke
			(width 0.2)
			(type default)
		)
		(layer "In5.Cu")
	)
	(gr_line
		(start 388.21995 -48.321468)
		(end 388.21995 -47.178722)
		(stroke
			(width 0.2)
			(type default)
		)
		(layer "In5.Cu")
	)
	(gr_arc
		(start 388.21995 -47.178722)
		(mid 387.839077 -46.797468)
		(end 387.45795 -47.178468)
		(stroke
			(width 0.2)
			(type default)
		)
		(layer "In5.Cu")
	)
	(gr_arc
		(start 388.801356 -30.550104)
		(mid 389.349996 -31.098744)
		(end 389.898636 -30.550104)
		(stroke
			(width 0.2)
			(type default)
		)
		(layer "In5.Cu")
	)
	(gr_line
		(start 388.801356 -29.150056)
		(end 388.801356 -30.550104)
		(stroke
			(width 0.2)
			(type default)
		)
		(layer "In5.Cu")
	)
	(gr_arc
		(start 388.801356 -23.35022)
		(mid 389.349996 -23.89886)
		(end 389.898636 -23.35022)
		(stroke
			(width 0.2)
			(type default)
		)
		(layer "In5.Cu")
	)
	(gr_line
		(start 388.801356 -21.950172)
		(end 388.801356 -23.35022)
		(stroke
			(width 0.2)
			(type default)
		)
		(layer "In5.Cu")
	)
	(gr_arc
		(start 388.801356 -19.750024)
		(mid 389.349996 -20.298664)
		(end 389.898636 -19.750024)
		(stroke
			(width 0.2)
			(type default)
		)
		(layer "In5.Cu")
	)
	(gr_line
		(start 388.801356 -18.35023)
		(end 388.801356 -19.750024)
		(stroke
			(width 0.2)
			(type default)
		)
		(layer "In5.Cu")
	)
	(gr_line
		(start 389.898636 -30.550104)
		(end 389.898636 -29.15031)
		(stroke
			(width 0.2)
			(type default)
		)
		(layer "In5.Cu")
	)
	(gr_arc
		(start 389.898636 -29.15031)
		(mid 389.350123 -28.601416)
		(end 388.801356 -29.150056)
		(stroke
			(width 0.2)
			(type default)
		)
		(layer "In5.Cu")
	)
	(gr_line
		(start 389.898636 -23.35022)
		(end 389.898636 -21.950426)
		(stroke
			(width 0.2)
			(type default)
		)
		(layer "In5.Cu")
	)
	(gr_arc
		(start 389.898636 -21.950426)
		(mid 389.350123 -21.401532)
		(end 388.801356 -21.950172)
		(stroke
			(width 0.2)
			(type default)
		)
		(layer "In5.Cu")
	)
	(gr_line
		(start 389.898636 -19.750024)
		(end 389.898636 -18.350484)
		(stroke
			(width 0.2)
			(type default)
		)
		(layer "In5.Cu")
	)
	(gr_arc
		(start 389.898636 -18.350484)
		(mid 389.350123 -17.80159)
		(end 388.801356 -18.35023)
		(stroke
			(width 0.2)
			(type default)
		)
		(layer "In5.Cu")
	)
	(gr_line
		(start 390.99998 -13.999972)
		(end 394.744702 -13.999972)
		(stroke
			(width 0.381)
			(type default)
		)
		(layer "In5.Cu")
	)
	(gr_line
		(start 394.744702 -13.999972)
		(end 395.32433 -14.5796)
		(stroke
			(width 0.381)
			(type default)
		)
		(layer "In5.Cu")
	)
	(gr_line
		(start 394.767816 -36.008564)
		(end 349.775526 -36.008564)
		(stroke
			(width 0.381)
			(type default)
		)
		(layer "In5.Cu")
	)
	(gr_arc
		(start 394.999972 -14.99997)
		(mid 395.707077 -14.707077)
		(end 395.99997 -13.999972)
		(stroke
			(width 2.54)
			(type default)
		)
		(layer "In5.Cu")
	)
	(gr_line
		(start 395.32433 -35.45205)
		(end 394.767816 -36.008564)
		(stroke
			(width 0.381)
			(type default)
		)
		(layer "In5.Cu")
	)
	(gr_line
		(start 395.32433 -14.5796)
		(end 395.32433 -35.45205)
		(stroke
			(width 0.381)
			(type default)
		)
		(layer "In5.Cu")
	)
	(gr_line
		(start 395.99997 -13.999972)
		(end 395.99997 -0.999998)
		(stroke
			(width 2.54)
			(type default)
		)
		(layer "In5.Cu")
	)
	(gr_arc
		(start 396.999968 0)
		(mid 396.292883 -0.292904)
		(end 395.99997 -0.999998)
		(stroke
			(width 2.54)
			(type default)
		)
		(layer "In5.Cu")
	)
	(gr_line
		(start 396.999968 0)
		(end 490.450124 0)
		(stroke
			(width 2.54)
			(type default)
		)
		(layer "In5.Cu")
	)
	(gr_arc
		(start 414.258252 -274.511262)
		(mid 414.639125 -274.892516)
		(end 415.020252 -274.511516)
		(stroke
			(width 0.2)
			(type default)
		)
		(layer "In5.Cu")
	)
	(gr_line
		(start 414.258252 -273.368516)
		(end 414.258252 -274.511262)
		(stroke
			(width 0.2)
			(type default)
		)
		(layer "In5.Cu")
	)
	(gr_arc
		(start 414.258252 -159.511238)
		(mid 414.639125 -159.892492)
		(end 415.020252 -159.511492)
		(stroke
			(width 0.2)
			(type default)
		)
		(layer "In5.Cu")
	)
	(gr_line
		(start 414.258252 -158.368492)
		(end 414.258252 -159.511238)
		(stroke
			(width 0.2)
			(type default)
		)
		(layer "In5.Cu")
	)
	(gr_arc
		(start 414.258252 -44.511214)
		(mid 414.639125 -44.892468)
		(end 415.020252 -44.511468)
		(stroke
			(width 0.2)
			(type default)
		)
		(layer "In5.Cu")
	)
	(gr_line
		(start 414.258252 -43.368468)
		(end 414.258252 -44.511214)
		(stroke
			(width 0.2)
			(type default)
		)
		(layer "In5.Cu")
	)
	(gr_line
		(start 415.020252 -274.511516)
		(end 415.020252 -273.368516)
		(stroke
			(width 0.2)
			(type default)
		)
		(layer "In5.Cu")
	)
	(gr_arc
		(start 415.020252 -273.368516)
		(mid 414.639252 -272.987516)
		(end 414.258252 -273.368516)
		(stroke
			(width 0.2)
			(type default)
		)
		(layer "In5.Cu")
	)
	(gr_line
		(start 415.020252 -159.511492)
		(end 415.020252 -158.368492)
		(stroke
			(width 0.2)
			(type default)
		)
		(layer "In5.Cu")
	)
	(gr_arc
		(start 415.020252 -158.368492)
		(mid 414.639252 -157.987492)
		(end 414.258252 -158.368492)
		(stroke
			(width 0.2)
			(type default)
		)
		(layer "In5.Cu")
	)
	(gr_line
		(start 415.020252 -44.511468)
		(end 415.020252 -43.368468)
		(stroke
			(width 0.2)
			(type default)
		)
		(layer "In5.Cu")
	)
	(gr_arc
		(start 415.020252 -43.368468)
		(mid 414.639252 -42.987468)
		(end 414.258252 -43.368468)
		(stroke
			(width 0.2)
			(type default)
		)
		(layer "In5.Cu")
	)
	(gr_arc
		(start 419.008052 -278.321516)
		(mid 419.389052 -278.702516)
		(end 419.770052 -278.321516)
		(stroke
			(width 0.2)
			(type default)
		)
		(layer "In5.Cu")
	)
	(gr_line
		(start 419.008052 -277.178516)
		(end 419.008052 -278.321516)
		(stroke
			(width 0.2)
			(type default)
		)
		(layer "In5.Cu")
	)
	(gr_arc
		(start 419.008052 -163.321492)
		(mid 419.389052 -163.702492)
		(end 419.770052 -163.321492)
		(stroke
			(width 0.2)
			(type default)
		)
		(layer "In5.Cu")
	)
	(gr_line
		(start 419.008052 -162.178492)
		(end 419.008052 -163.321492)
		(stroke
			(width 0.2)
			(type default)
		)
		(layer "In5.Cu")
	)
	(gr_arc
		(start 419.008052 -48.321468)
		(mid 419.389052 -48.702468)
		(end 419.770052 -48.321468)
		(stroke
			(width 0.2)
			(type default)
		)
		(layer "In5.Cu")
	)
	(gr_line
		(start 419.008052 -47.178468)
		(end 419.008052 -48.321468)
		(stroke
			(width 0.2)
			(type default)
		)
		(layer "In5.Cu")
	)
	(gr_line
		(start 419.770052 -278.321516)
		(end 419.770052 -277.17877)
		(stroke
			(width 0.2)
			(type default)
		)
		(layer "In5.Cu")
	)
	(gr_arc
		(start 419.770052 -277.17877)
		(mid 419.389179 -276.797516)
		(end 419.008052 -277.178516)
		(stroke
			(width 0.2)
			(type default)
		)
		(layer "In5.Cu")
	)
	(gr_line
		(start 419.770052 -163.321492)
		(end 419.770052 -162.178746)
		(stroke
			(width 0.2)
			(type default)
		)
		(layer "In5.Cu")
	)
	(gr_arc
		(start 419.770052 -162.178746)
		(mid 419.389179 -161.797492)
		(end 419.008052 -162.178492)
		(stroke
			(width 0.2)
			(type default)
		)
		(layer "In5.Cu")
	)
	(gr_line
		(start 419.770052 -48.321468)
		(end 419.770052 -47.178722)
		(stroke
			(width 0.2)
			(type default)
		)
		(layer "In5.Cu")
	)
	(gr_arc
		(start 419.770052 -47.178722)
		(mid 419.389179 -46.797468)
		(end 419.008052 -47.178468)
		(stroke
			(width 0.2)
			(type default)
		)
		(layer "In5.Cu")
	)
	(gr_arc
		(start 437.8579 -163.321492)
		(mid 438.2389 -163.702492)
		(end 438.6199 -163.321492)
		(stroke
			(width 0.2)
			(type default)
		)
		(layer "In5.Cu")
	)
	(gr_line
		(start 437.8579 -162.178492)
		(end 437.8579 -163.321492)
		(stroke
			(width 0.2)
			(type default)
		)
		(layer "In5.Cu")
	)
	(gr_line
		(start 438.6199 -163.321492)
		(end 438.6199 -162.178746)
		(stroke
			(width 0.2)
			(type default)
		)
		(layer "In5.Cu")
	)
	(gr_arc
		(start 438.6199 -162.178746)
		(mid 438.239027 -161.797492)
		(end 437.8579 -162.178492)
		(stroke
			(width 0.2)
			(type default)
		)
		(layer "In5.Cu")
	)
	(gr_arc
		(start 439.4581 -159.511238)
		(mid 439.838973 -159.892492)
		(end 440.2201 -159.511492)
		(stroke
			(width 0.2)
			(type default)
		)
		(layer "In5.Cu")
	)
	(gr_line
		(start 439.4581 -158.368492)
		(end 439.4581 -159.511238)
		(stroke
			(width 0.2)
			(type default)
		)
		(layer "In5.Cu")
	)
	(gr_line
		(start 440.2201 -159.511492)
		(end 440.2201 -158.368492)
		(stroke
			(width 0.2)
			(type default)
		)
		(layer "In5.Cu")
	)
	(gr_arc
		(start 440.2201 -158.368492)
		(mid 439.8391 -157.987492)
		(end 439.4581 -158.368492)
		(stroke
			(width 0.2)
			(type default)
		)
		(layer "In5.Cu")
	)
	(gr_arc
		(start 445.8081 -274.511262)
		(mid 446.188973 -274.892516)
		(end 446.5701 -274.511516)
		(stroke
			(width 0.2)
			(type default)
		)
		(layer "In5.Cu")
	)
	(gr_line
		(start 445.8081 -273.368516)
		(end 445.8081 -274.511262)
		(stroke
			(width 0.2)
			(type default)
		)
		(layer "In5.Cu")
	)
	(gr_arc
		(start 445.8081 -44.511214)
		(mid 446.188973 -44.892468)
		(end 446.5701 -44.511468)
		(stroke
			(width 0.2)
			(type default)
		)
		(layer "In5.Cu")
	)
	(gr_line
		(start 445.8081 -43.368468)
		(end 445.8081 -44.511214)
		(stroke
			(width 0.2)
			(type default)
		)
		(layer "In5.Cu")
	)
	(gr_line
		(start 446.5701 -274.511516)
		(end 446.5701 -273.368516)
		(stroke
			(width 0.2)
			(type default)
		)
		(layer "In5.Cu")
	)
	(gr_arc
		(start 446.5701 -273.368516)
		(mid 446.1891 -272.987516)
		(end 445.8081 -273.368516)
		(stroke
			(width 0.2)
			(type default)
		)
		(layer "In5.Cu")
	)
	(gr_line
		(start 446.5701 -44.511468)
		(end 446.5701 -43.368468)
		(stroke
			(width 0.2)
			(type default)
		)
		(layer "In5.Cu")
	)
	(gr_arc
		(start 446.5701 -43.368468)
		(mid 446.1891 -42.987468)
		(end 445.8081 -43.368468)
		(stroke
			(width 0.2)
			(type default)
		)
		(layer "In5.Cu")
	)
	(gr_arc
		(start 450.5579 -278.321516)
		(mid 450.9389 -278.702516)
		(end 451.3199 -278.321516)
		(stroke
			(width 0.2)
			(type default)
		)
		(layer "In5.Cu")
	)
	(gr_line
		(start 450.5579 -277.178516)
		(end 450.5579 -278.321516)
		(stroke
			(width 0.2)
			(type default)
		)
		(layer "In5.Cu")
	)
	(gr_arc
		(start 450.5579 -48.321468)
		(mid 450.9389 -48.702468)
		(end 451.3199 -48.321468)
		(stroke
			(width 0.2)
			(type default)
		)
		(layer "In5.Cu")
	)
	(gr_line
		(start 450.5579 -47.178468)
		(end 450.5579 -48.321468)
		(stroke
			(width 0.2)
			(type default)
		)
		(layer "In5.Cu")
	)
	(gr_line
		(start 451.3199 -278.321516)
		(end 451.3199 -277.17877)
		(stroke
			(width 0.2)
			(type default)
		)
		(layer "In5.Cu")
	)
	(gr_arc
		(start 451.3199 -277.17877)
		(mid 450.939027 -276.797516)
		(end 450.5579 -277.178516)
		(stroke
			(width 0.2)
			(type default)
		)
		(layer "In5.Cu")
	)
	(gr_line
		(start 451.3199 -48.321468)
		(end 451.3199 -47.178722)
		(stroke
			(width 0.2)
			(type default)
		)
		(layer "In5.Cu")
	)
	(gr_arc
		(start 451.3199 -47.178722)
		(mid 450.939027 -46.797468)
		(end 450.5579 -47.178468)
		(stroke
			(width 0.2)
			(type default)
		)
		(layer "In5.Cu")
	)
	(gr_arc
		(start 477.358202 -274.511262)
		(mid 477.739075 -274.892516)
		(end 478.120202 -274.511516)
		(stroke
			(width 0.2)
			(type default)
		)
		(layer "In5.Cu")
	)
	(gr_line
		(start 477.358202 -273.368516)
		(end 477.358202 -274.511262)
		(stroke
			(width 0.2)
			(type default)
		)
		(layer "In5.Cu")
	)
	(gr_arc
		(start 477.358202 -159.511238)
		(mid 477.739075 -159.892492)
		(end 478.120202 -159.511492)
		(stroke
			(width 0.2)
			(type default)
		)
		(layer "In5.Cu")
	)
	(gr_line
		(start 477.358202 -158.368492)
		(end 477.358202 -159.511238)
		(stroke
			(width 0.2)
			(type default)
		)
		(layer "In5.Cu")
	)
	(gr_arc
		(start 477.358202 -44.511214)
		(mid 477.739075 -44.892468)
		(end 478.120202 -44.511468)
		(stroke
			(width 0.2)
			(type default)
		)
		(layer "In5.Cu")
	)
	(gr_line
		(start 477.358202 -43.368468)
		(end 477.358202 -44.511214)
		(stroke
			(width 0.2)
			(type default)
		)
		(layer "In5.Cu")
	)
	(gr_line
		(start 478.120202 -274.511516)
		(end 478.120202 -273.368516)
		(stroke
			(width 0.2)
			(type default)
		)
		(layer "In5.Cu")
	)
	(gr_arc
		(start 478.120202 -273.368516)
		(mid 477.739202 -272.987516)
		(end 477.358202 -273.368516)
		(stroke
			(width 0.2)
			(type default)
		)
		(layer "In5.Cu")
	)
	(gr_line
		(start 478.120202 -159.511492)
		(end 478.120202 -158.368492)
		(stroke
			(width 0.2)
			(type default)
		)
		(layer "In5.Cu")
	)
	(gr_arc
		(start 478.120202 -158.368492)
		(mid 477.739202 -157.987492)
		(end 477.358202 -158.368492)
		(stroke
			(width 0.2)
			(type default)
		)
		(layer "In5.Cu")
	)
	(gr_line
		(start 478.120202 -44.511468)
		(end 478.120202 -43.368468)
		(stroke
			(width 0.2)
			(type default)
		)
		(layer "In5.Cu")
	)
	(gr_arc
		(start 478.120202 -43.368468)
		(mid 477.739202 -42.987468)
		(end 477.358202 -43.368468)
		(stroke
			(width 0.2)
			(type default)
		)
		(layer "In5.Cu")
	)
	(gr_arc
		(start 482.108002 -278.321516)
		(mid 482.489002 -278.702516)
		(end 482.870002 -278.321516)
		(stroke
			(width 0.2)
			(type default)
		)
		(layer "In5.Cu")
	)
	(gr_line
		(start 482.108002 -277.178516)
		(end 482.108002 -278.321516)
		(stroke
			(width 0.2)
			(type default)
		)
		(layer "In5.Cu")
	)
	(gr_arc
		(start 482.108002 -163.321492)
		(mid 482.489002 -163.702492)
		(end 482.870002 -163.321492)
		(stroke
			(width 0.2)
			(type default)
		)
		(layer "In5.Cu")
	)
	(gr_line
		(start 482.108002 -162.178492)
		(end 482.108002 -163.321492)
		(stroke
			(width 0.2)
			(type default)
		)
		(layer "In5.Cu")
	)
	(gr_arc
		(start 482.108002 -48.321468)
		(mid 482.489002 -48.702468)
		(end 482.870002 -48.321468)
		(stroke
			(width 0.2)
			(type default)
		)
		(layer "In5.Cu")
	)
	(gr_line
		(start 482.108002 -47.178468)
		(end 482.108002 -48.321468)
		(stroke
			(width 0.2)
			(type default)
		)
		(layer "In5.Cu")
	)
	(gr_line
		(start 482.870002 -278.321516)
		(end 482.870002 -277.17877)
		(stroke
			(width 0.2)
			(type default)
		)
		(layer "In5.Cu")
	)
	(gr_arc
		(start 482.870002 -277.17877)
		(mid 482.489129 -276.797516)
		(end 482.108002 -277.178516)
		(stroke
			(width 0.2)
			(type default)
		)
		(layer "In5.Cu")
	)
	(gr_line
		(start 482.870002 -163.321492)
		(end 482.870002 -162.178746)
		(stroke
			(width 0.2)
			(type default)
		)
		(layer "In5.Cu")
	)
	(gr_arc
		(start 482.870002 -162.178746)
		(mid 482.489129 -161.797492)
		(end 482.108002 -162.178492)
		(stroke
			(width 0.2)
			(type default)
		)
		(layer "In5.Cu")
	)
	(gr_line
		(start 482.870002 -48.321468)
		(end 482.870002 -47.178722)
		(stroke
			(width 0.2)
			(type default)
		)
		(layer "In5.Cu")
	)
	(gr_arc
		(start 482.870002 -47.178722)
		(mid 482.489129 -46.797468)
		(end 482.108002 -47.178468)
		(stroke
			(width 0.2)
			(type default)
		)
		(layer "In5.Cu")
	)
	(gr_line
		(start 490.450124 -349.199962)
		(end 296.69994 -349.199962)
		(stroke
			(width 2.54)
			(type default)
		)
		(layer "In5.Cu")
	)
	(gr_arc
		(start 490.450124 -349.199962)
		(mid 491.157201 -348.907059)
		(end 491.450122 -348.199964)
		(stroke
			(width 2.54)
			(type default)
		)
		(layer "In5.Cu")
	)
	(gr_arc
		(start 491.450122 -0.999998)
		(mid 491.15723 -0.292885)
		(end 490.450124 0)
		(stroke
			(width 2.54)
			(type default)
		)
		(layer "In5.Cu")
	)
	(gr_line
		(start 491.450122 -0.999998)
		(end 491.450122 -348.199964)
		(stroke
			(width 2.54)
			(type default)
		)
		(layer "In5.Cu")
	)
	(gr_line
		(start 0 -348.199964)
		(end 0 -0.999998)
		(stroke
			(width 2.54)
			(type default)
		)
		(layer "In6.Cu")
	)
	(gr_arc
		(start 0 -348.199964)
		(mid 0.292894 -348.907067)
		(end 0.999998 -349.199962)
		(stroke
			(width 2.54)
			(type default)
		)
		(layer "In6.Cu")
	)
	(gr_arc
		(start 0.999998 0)
		(mid 0.292893 -0.292893)
		(end 0 -0.999998)
		(stroke
			(width 2.54)
			(type default)
		)
		(layer "In6.Cu")
	)
	(gr_line
		(start 0.999998 0)
		(end 101.000052 0)
		(stroke
			(width 2.54)
			(type default)
		)
		(layer "In6.Cu")
	)
	(gr_line
		(start 5.461 -309.1942)
		(end 6.8072 -310.5404)
		(stroke
			(width 0.381)
			(type default)
		)
		(layer "In6.Cu")
	)
	(gr_line
		(start 5.461 -298.958)
		(end 5.461 -309.1942)
		(stroke
			(width 0.381)
			(type default)
		)
		(layer "In6.Cu")
	)
	(gr_line
		(start 6.8072 -310.5404)
		(end 143.0274 -310.5404)
		(stroke
			(width 0.381)
			(type default)
		)
		(layer "In6.Cu")
	)
	(gr_line
		(start 14.2494 -290.1696)
		(end 5.461 -298.958)
		(stroke
			(width 0.381)
			(type default)
		)
		(layer "In6.Cu")
	)
	(gr_line
		(start 15.130018 -290.164012)
		(end 15.130018 -290.1696)
		(stroke
			(width 0.381)
			(type default)
		)
		(layer "In6.Cu")
	)
	(gr_line
		(start 15.748 -290.16071)
		(end 15.73911 -290.1696)
		(stroke
			(width 0.381)
			(type default)
		)
		(layer "In6.Cu")
	)
	(gr_line
		(start 15.748 -289.54603)
		(end 15.130018 -290.164012)
		(stroke
			(width 0.381)
			(type default)
		)
		(layer "In6.Cu")
	)
	(gr_line
		(start 15.748 -165.3032)
		(end 15.748 -290.16071)
		(stroke
			(width 0.381)
			(type default)
		)
		(layer "In6.Cu")
	)
	(gr_line
		(start 16.37157 -290.1696)
		(end 15.748 -289.54603)
		(stroke
			(width 0.381)
			(type default)
		)
		(layer "In6.Cu")
	)
	(gr_line
		(start 16.387572 -290.1696)
		(end 16.37157 -290.1696)
		(stroke
			(width 0.381)
			(type default)
		)
		(layer "In6.Cu")
	)
	(gr_line
		(start 17.431258 -163.619942)
		(end 15.748 -165.3032)
		(stroke
			(width 0.381)
			(type default)
		)
		(layer "In6.Cu")
	)
	(gr_line
		(start 17.4752 -110.4646)
		(end 54.605428 -147.594828)
		(stroke
			(width 0.381)
			(type default)
		)
		(layer "In6.Cu")
	)
	(gr_line
		(start 17.4752 -50.8254)
		(end 17.4752 -110.4646)
		(stroke
			(width 0.381)
			(type default)
		)
		(layer "In6.Cu")
	)
	(gr_line
		(start 20.4216 -47.879)
		(end 17.4752 -50.8254)
		(stroke
			(width 0.381)
			(type default)
		)
		(layer "In6.Cu")
	)
	(gr_line
		(start 28.023058 -163.619942)
		(end 17.431258 -163.619942)
		(stroke
			(width 0.381)
			(type default)
		)
		(layer "In6.Cu")
	)
	(gr_line
		(start 28.321 -47.879)
		(end 20.4216 -47.879)
		(stroke
			(width 0.381)
			(type default)
		)
		(layer "In6.Cu")
	)
	(gr_line
		(start 29.4894 -290.1696)
		(end 14.2494 -290.1696)
		(stroke
			(width 0.381)
			(type default)
		)
		(layer "In6.Cu")
	)
	(gr_line
		(start 30.734 -45.466)
		(end 28.321 -47.879)
		(stroke
			(width 0.381)
			(type default)
		)
		(layer "In6.Cu")
	)
	(gr_line
		(start 31.115 -160.528)
		(end 28.023058 -163.619942)
		(stroke
			(width 0.381)
			(type default)
		)
		(layer "In6.Cu")
	)
	(gr_line
		(start 31.369 -288.29)
		(end 29.4894 -290.1696)
		(stroke
			(width 0.381)
			(type default)
		)
		(layer "In6.Cu")
	)
	(gr_line
		(start 31.369 -275.971)
		(end 31.369 -288.29)
		(stroke
			(width 0.381)
			(type default)
		)
		(layer "In6.Cu")
	)
	(gr_arc
		(start 32.127952 -278.321516)
		(mid 32.508952 -278.702516)
		(end 32.889952 -278.321516)
		(stroke
			(width 0.2)
			(type default)
		)
		(layer "In6.Cu")
	)
	(gr_line
		(start 32.127952 -277.178516)
		(end 32.127952 -278.321516)
		(stroke
			(width 0.2)
			(type default)
		)
		(layer "In6.Cu")
	)
	(gr_arc
		(start 32.127952 -163.321492)
		(mid 32.508952 -163.702492)
		(end 32.889952 -163.321492)
		(stroke
			(width 0.2)
			(type default)
		)
		(layer "In6.Cu")
	)
	(gr_line
		(start 32.127952 -162.178492)
		(end 32.127952 -163.321492)
		(stroke
			(width 0.2)
			(type default)
		)
		(layer "In6.Cu")
	)
	(gr_arc
		(start 32.127952 -48.321468)
		(mid 32.508952 -48.702468)
		(end 32.889952 -48.321468)
		(stroke
			(width 0.2)
			(type default)
		)
		(layer "In6.Cu")
	)
	(gr_line
		(start 32.127952 -47.178468)
		(end 32.127952 -48.321468)
		(stroke
			(width 0.2)
			(type default)
		)
		(layer "In6.Cu")
	)
	(gr_line
		(start 32.131 -275.209)
		(end 31.369 -275.971)
		(stroke
			(width 0.381)
			(type default)
		)
		(layer "In6.Cu")
	)
	(gr_line
		(start 32.889952 -278.321516)
		(end 32.889952 -277.17877)
		(stroke
			(width 0.2)
			(type default)
		)
		(layer "In6.Cu")
	)
	(gr_arc
		(start 32.889952 -277.17877)
		(mid 32.509079 -276.797516)
		(end 32.127952 -277.178516)
		(stroke
			(width 0.2)
			(type default)
		)
		(layer "In6.Cu")
	)
	(gr_line
		(start 32.889952 -163.321492)
		(end 32.889952 -162.178746)
		(stroke
			(width 0.2)
			(type default)
		)
		(layer "In6.Cu")
	)
	(gr_arc
		(start 32.889952 -162.178746)
		(mid 32.509079 -161.797492)
		(end 32.127952 -162.178492)
		(stroke
			(width 0.2)
			(type default)
		)
		(layer "In6.Cu")
	)
	(gr_line
		(start 32.889952 -48.321468)
		(end 32.889952 -47.178722)
		(stroke
			(width 0.2)
			(type default)
		)
		(layer "In6.Cu")
	)
	(gr_arc
		(start 32.889952 -47.178722)
		(mid 32.509079 -46.797468)
		(end 32.127952 -47.178468)
		(stroke
			(width 0.2)
			(type default)
		)
		(layer "In6.Cu")
	)
	(gr_line
		(start 33.401 -275.209)
		(end 32.131 -275.209)
		(stroke
			(width 0.381)
			(type default)
		)
		(layer "In6.Cu")
	)
	(gr_line
		(start 34.29 -160.528)
		(end 31.115 -160.528)
		(stroke
			(width 0.381)
			(type default)
		)
		(layer "In6.Cu")
	)
	(gr_line
		(start 38.227 -45.466)
		(end 30.734 -45.466)
		(stroke
			(width 0.381)
			(type default)
		)
		(layer "In6.Cu")
	)
	(gr_line
		(start 39.1668 -165.4048)
		(end 34.29 -160.528)
		(stroke
			(width 0.381)
			(type default)
		)
		(layer "In6.Cu")
	)
	(gr_line
		(start 42.7482 -49.9872)
		(end 38.227 -45.466)
		(stroke
			(width 0.381)
			(type default)
		)
		(layer "In6.Cu")
	)
	(gr_line
		(start 43.18 -284.988)
		(end 33.401 -275.209)
		(stroke
			(width 0.381)
			(type default)
		)
		(layer "In6.Cu")
	)
	(gr_line
		(start 49.142142 -165.4048)
		(end 39.1668 -165.4048)
		(stroke
			(width 0.381)
			(type default)
		)
		(layer "In6.Cu")
	)
	(gr_line
		(start 49.911 -49.9872)
		(end 42.7482 -49.9872)
		(stroke
			(width 0.381)
			(type default)
		)
		(layer "In6.Cu")
	)
	(gr_line
		(start 51.5874 -48.3108)
		(end 49.911 -49.9872)
		(stroke
			(width 0.381)
			(type default)
		)
		(layer "In6.Cu")
	)
	(gr_line
		(start 51.816 -162.730942)
		(end 49.142142 -165.4048)
		(stroke
			(width 0.381)
			(type default)
		)
		(layer "In6.Cu")
	)
	(gr_line
		(start 54.605428 -147.594828)
		(end 68.747132 -147.594828)
		(stroke
			(width 0.381)
			(type default)
		)
		(layer "In6.Cu")
	)
	(gr_line
		(start 57.785 -284.988)
		(end 43.18 -284.988)
		(stroke
			(width 0.381)
			(type default)
		)
		(layer "In6.Cu")
	)
	(gr_line
		(start 60.1472 -48.3108)
		(end 51.5874 -48.3108)
		(stroke
			(width 0.381)
			(type default)
		)
		(layer "In6.Cu")
	)
	(gr_line
		(start 60.789058 -162.730942)
		(end 51.816 -162.730942)
		(stroke
			(width 0.381)
			(type default)
		)
		(layer "In6.Cu")
	)
	(gr_line
		(start 62.738 -280.035)
		(end 57.785 -284.988)
		(stroke
			(width 0.381)
			(type default)
		)
		(layer "In6.Cu")
	)
	(gr_line
		(start 62.738 -276.225)
		(end 62.738 -280.035)
		(stroke
			(width 0.381)
			(type default)
		)
		(layer "In6.Cu")
	)
	(gr_line
		(start 62.865 -45.593)
		(end 60.1472 -48.3108)
		(stroke
			(width 0.381)
			(type default)
		)
		(layer "In6.Cu")
	)
	(gr_line
		(start 62.992 -160.528)
		(end 60.789058 -162.730942)
		(stroke
			(width 0.381)
			(type default)
		)
		(layer "In6.Cu")
	)
	(gr_line
		(start 63.627 -275.336)
		(end 62.738 -276.225)
		(stroke
			(width 0.381)
			(type default)
		)
		(layer "In6.Cu")
	)
	(gr_arc
		(start 63.6778 -278.321516)
		(mid 64.0588 -278.702516)
		(end 64.4398 -278.321516)
		(stroke
			(width 0.2)
			(type default)
		)
		(layer "In6.Cu")
	)
	(gr_line
		(start 63.6778 -277.178516)
		(end 63.6778 -278.321516)
		(stroke
			(width 0.2)
			(type default)
		)
		(layer "In6.Cu")
	)
	(gr_arc
		(start 63.6778 -163.321492)
		(mid 64.0588 -163.702492)
		(end 64.4398 -163.321492)
		(stroke
			(width 0.2)
			(type default)
		)
		(layer "In6.Cu")
	)
	(gr_line
		(start 63.6778 -162.178492)
		(end 63.6778 -163.321492)
		(stroke
			(width 0.2)
			(type default)
		)
		(layer "In6.Cu")
	)
	(gr_arc
		(start 63.6778 -48.321468)
		(mid 64.0588 -48.702468)
		(end 64.4398 -48.321468)
		(stroke
			(width 0.2)
			(type default)
		)
		(layer "In6.Cu")
	)
	(gr_line
		(start 63.6778 -47.178468)
		(end 63.6778 -48.321468)
		(stroke
			(width 0.2)
			(type default)
		)
		(layer "In6.Cu")
	)
	(gr_line
		(start 64.4398 -278.321516)
		(end 64.4398 -277.17877)
		(stroke
			(width 0.2)
			(type default)
		)
		(layer "In6.Cu")
	)
	(gr_arc
		(start 64.4398 -277.17877)
		(mid 64.058927 -276.797516)
		(end 63.6778 -277.178516)
		(stroke
			(width 0.2)
			(type default)
		)
		(layer "In6.Cu")
	)
	(gr_line
		(start 64.4398 -163.321492)
		(end 64.4398 -162.178746)
		(stroke
			(width 0.2)
			(type default)
		)
		(layer "In6.Cu")
	)
	(gr_arc
		(start 64.4398 -162.178746)
		(mid 64.058927 -161.797492)
		(end 63.6778 -162.178492)
		(stroke
			(width 0.2)
			(type default)
		)
		(layer "In6.Cu")
	)
	(gr_line
		(start 64.4398 -48.321468)
		(end 64.4398 -47.178722)
		(stroke
			(width 0.2)
			(type default)
		)
		(layer "In6.Cu")
	)
	(gr_arc
		(start 64.4398 -47.178722)
		(mid 64.058927 -46.797468)
		(end 63.6778 -47.178468)
		(stroke
			(width 0.2)
			(type default)
		)
		(layer "In6.Cu")
	)
	(gr_line
		(start 64.897 -160.528)
		(end 62.992 -160.528)
		(stroke
			(width 0.381)
			(type default)
		)
		(layer "In6.Cu")
	)
	(gr_line
		(start 67.691 -45.593)
		(end 62.865 -45.593)
		(stroke
			(width 0.381)
			(type default)
		)
		(layer "In6.Cu")
	)
	(gr_line
		(start 68.747132 -147.594828)
		(end 70.39356 -145.9484)
		(stroke
			(width 0.381)
			(type default)
		)
		(layer "In6.Cu")
	)
	(gr_line
		(start 69.4182 -165.0492)
		(end 64.897 -160.528)
		(stroke
			(width 0.381)
			(type default)
		)
		(layer "In6.Cu")
	)
	(gr_line
		(start 70.39356 -145.9484)
		(end 104.1908 -145.9484)
		(stroke
			(width 0.381)
			(type default)
		)
		(layer "In6.Cu")
	)
	(gr_line
		(start 72.4916 -50.3936)
		(end 67.691 -45.593)
		(stroke
			(width 0.381)
			(type default)
		)
		(layer "In6.Cu")
	)
	(gr_line
		(start 72.517 -275.336)
		(end 63.627 -275.336)
		(stroke
			(width 0.381)
			(type default)
		)
		(layer "In6.Cu")
	)
	(gr_line
		(start 79.502 -282.321)
		(end 72.517 -275.336)
		(stroke
			(width 0.381)
			(type default)
		)
		(layer "In6.Cu")
	)
	(gr_line
		(start 80.9498 -50.3936)
		(end 72.4916 -50.3936)
		(stroke
			(width 0.381)
			(type default)
		)
		(layer "In6.Cu")
	)
	(gr_line
		(start 81.501742 -165.0492)
		(end 69.4182 -165.0492)
		(stroke
			(width 0.381)
			(type default)
		)
		(layer "In6.Cu")
	)
	(gr_line
		(start 82.677 -48.6664)
		(end 80.9498 -50.3936)
		(stroke
			(width 0.381)
			(type default)
		)
		(layer "In6.Cu")
	)
	(gr_line
		(start 83.312 -163.238942)
		(end 81.501742 -165.0492)
		(stroke
			(width 0.381)
			(type default)
		)
		(layer "In6.Cu")
	)
	(gr_line
		(start 85.217 -282.321)
		(end 79.502 -282.321)
		(stroke
			(width 0.381)
			(type default)
		)
		(layer "In6.Cu")
	)
	(gr_line
		(start 87.63 -163.238942)
		(end 83.312 -163.238942)
		(stroke
			(width 0.381)
			(type default)
		)
		(layer "In6.Cu")
	)
	(gr_line
		(start 88.773 -240.54816)
		(end 88.773 -164.381942)
		(stroke
			(width 0.381)
			(type default)
		)
		(layer "In6.Cu")
	)
	(gr_line
		(start 88.773 -164.381942)
		(end 87.63 -163.238942)
		(stroke
			(width 0.381)
			(type default)
		)
		(layer "In6.Cu")
	)
	(gr_line
		(start 91.142058 -242.917218)
		(end 88.773 -240.54816)
		(stroke
			(width 0.381)
			(type default)
		)
		(layer "In6.Cu")
	)
	(gr_line
		(start 91.7956 -48.6664)
		(end 82.677 -48.6664)
		(stroke
			(width 0.381)
			(type default)
		)
		(layer "In6.Cu")
	)
	(gr_line
		(start 93.0656 -290.1696)
		(end 85.217 -282.321)
		(stroke
			(width 0.381)
			(type default)
		)
		(layer "In6.Cu")
	)
	(gr_line
		(start 94.996 -45.466)
		(end 91.7956 -48.6664)
		(stroke
			(width 0.381)
			(type default)
		)
		(layer "In6.Cu")
	)
	(gr_arc
		(start 95.227902 -278.321516)
		(mid 95.608902 -278.702516)
		(end 95.989902 -278.321516)
		(stroke
			(width 0.2)
			(type default)
		)
		(layer "In6.Cu")
	)
	(gr_line
		(start 95.227902 -277.178516)
		(end 95.227902 -278.321516)
		(stroke
			(width 0.2)
			(type default)
		)
		(layer "In6.Cu")
	)
	(gr_arc
		(start 95.227902 -163.321492)
		(mid 95.608902 -163.702492)
		(end 95.989902 -163.321492)
		(stroke
			(width 0.2)
			(type default)
		)
		(layer "In6.Cu")
	)
	(gr_line
		(start 95.227902 -162.178492)
		(end 95.227902 -163.321492)
		(stroke
			(width 0.2)
			(type default)
		)
		(layer "In6.Cu")
	)
	(gr_arc
		(start 95.227902 -48.321468)
		(mid 95.608902 -48.702468)
		(end 95.989902 -48.321468)
		(stroke
			(width 0.2)
			(type default)
		)
		(layer "In6.Cu")
	)
	(gr_line
		(start 95.227902 -47.178468)
		(end 95.227902 -48.321468)
		(stroke
			(width 0.2)
			(type default)
		)
		(layer "In6.Cu")
	)
	(gr_line
		(start 95.989902 -278.321516)
		(end 95.989902 -277.17877)
		(stroke
			(width 0.2)
			(type default)
		)
		(layer "In6.Cu")
	)
	(gr_arc
		(start 95.989902 -277.17877)
		(mid 95.609029 -276.797516)
		(end 95.227902 -277.178516)
		(stroke
			(width 0.2)
			(type default)
		)
		(layer "In6.Cu")
	)
	(gr_line
		(start 95.989902 -163.321492)
		(end 95.989902 -162.178746)
		(stroke
			(width 0.2)
			(type default)
		)
		(layer "In6.Cu")
	)
	(gr_arc
		(start 95.989902 -162.178746)
		(mid 95.609029 -161.797492)
		(end 95.227902 -162.178492)
		(stroke
			(width 0.2)
			(type default)
		)
		(layer "In6.Cu")
	)
	(gr_line
		(start 95.989902 -48.321468)
		(end 95.989902 -47.178722)
		(stroke
			(width 0.2)
			(type default)
		)
		(layer "In6.Cu")
	)
	(gr_arc
		(start 95.989902 -47.178722)
		(mid 95.609029 -46.797468)
		(end 95.227902 -47.178468)
		(stroke
			(width 0.2)
			(type default)
		)
		(layer "In6.Cu")
	)
	(gr_line
		(start 96.266 -45.466)
		(end 94.996 -45.466)
		(stroke
			(width 0.381)
			(type default)
		)
		(layer "In6.Cu")
	)
	(gr_line
		(start 100.8634 -50.0634)
		(end 96.266 -45.466)
		(stroke
			(width 0.381)
			(type default)
		)
		(layer "In6.Cu")
	)
	(gr_arc
		(start 102.00005 -13.999972)
		(mid 102.292943 -14.707077)
		(end 103.000048 -14.99997)
		(stroke
			(width 2.54)
			(type default)
		)
		(layer "In6.Cu")
	)
	(gr_arc
		(start 102.00005 -0.999998)
		(mid 101.707154 -0.292911)
		(end 101.000052 0)
		(stroke
			(width 2.54)
			(type default)
		)
		(layer "In6.Cu")
	)
	(gr_line
		(start 102.00005 -0.999998)
		(end 102.00005 -13.999972)
		(stroke
			(width 2.54)
			(type default)
		)
		(layer "In6.Cu")
	)
	(gr_line
		(start 103.000048 -14.99997)
		(end 148.999956 -14.99997)
		(stroke
			(width 2.54)
			(type default)
		)
		(layer "In6.Cu")
	)
	(gr_line
		(start 104.1908 -145.9484)
		(end 111.6838 -153.4414)
		(stroke
			(width 0.381)
			(type default)
		)
		(layer "In6.Cu")
	)
	(gr_arc
		(start 108.601256 -22.350222)
		(mid 109.149896 -22.898862)
		(end 109.698536 -22.350222)
		(stroke
			(width 0.2)
			(type default)
		)
		(layer "In6.Cu")
	)
	(gr_line
		(start 108.601256 -20.950174)
		(end 108.601256 -22.350222)
		(stroke
			(width 0.2)
			(type default)
		)
		(layer "In6.Cu")
	)
	(gr_arc
		(start 108.601256 -18.750026)
		(mid 109.149896 -19.298666)
		(end 109.698536 -18.750026)
		(stroke
			(width 0.2)
			(type default)
		)
		(layer "In6.Cu")
	)
	(gr_line
		(start 108.601256 -17.349978)
		(end 108.601256 -18.750026)
		(stroke
			(width 0.2)
			(type default)
		)
		(layer "In6.Cu")
	)
	(gr_line
		(start 109.698536 -22.350222)
		(end 109.698536 -20.950428)
		(stroke
			(width 0.2)
			(type default)
		)
		(layer "In6.Cu")
	)
	(gr_arc
		(start 109.698536 -20.950428)
		(mid 109.150023 -20.401534)
		(end 108.601256 -20.950174)
		(stroke
			(width 0.2)
			(type default)
		)
		(layer "In6.Cu")
	)
	(gr_line
		(start 109.698536 -18.750026)
		(end 109.698536 -17.350232)
		(stroke
			(width 0.2)
			(type default)
		)
		(layer "In6.Cu")
	)
	(gr_arc
		(start 109.698536 -17.350232)
		(mid 109.150023 -16.801338)
		(end 108.601256 -17.349978)
		(stroke
			(width 0.2)
			(type default)
		)
		(layer "In6.Cu")
	)
	(gr_arc
		(start 110.401354 -23.35022)
		(mid 110.949994 -23.89886)
		(end 111.498634 -23.35022)
		(stroke
			(width 0.2)
			(type default)
		)
		(layer "In6.Cu")
	)
	(gr_line
		(start 110.401354 -21.950172)
		(end 110.401354 -23.35022)
		(stroke
			(width 0.2)
			(type default)
		)
		(layer "In6.Cu")
	)
	(gr_arc
		(start 110.401354 -19.750024)
		(mid 110.949994 -20.298664)
		(end 111.498634 -19.750024)
		(stroke
			(width 0.2)
			(type default)
		)
		(layer "In6.Cu")
	)
	(gr_line
		(start 110.401354 -18.35023)
		(end 110.401354 -19.750024)
		(stroke
			(width 0.2)
			(type default)
		)
		(layer "In6.Cu")
	)
	(gr_line
		(start 111.498634 -23.35022)
		(end 111.498634 -21.950426)
		(stroke
			(width 0.2)
			(type default)
		)
		(layer "In6.Cu")
	)
	(gr_arc
		(start 111.498634 -21.950426)
		(mid 110.950121 -21.401532)
		(end 110.401354 -21.950172)
		(stroke
			(width 0.2)
			(type default)
		)
		(layer "In6.Cu")
	)
	(gr_line
		(start 111.498634 -19.750024)
		(end 111.498634 -18.350484)
		(stroke
			(width 0.2)
			(type default)
		)
		(layer "In6.Cu")
	)
	(gr_arc
		(start 111.498634 -18.350484)
		(mid 110.950121 -17.80159)
		(end 110.401354 -18.35023)
		(stroke
			(width 0.2)
			(type default)
		)
		(layer "In6.Cu")
	)
	(gr_line
		(start 111.6838 -167.767)
		(end 112.3696 -168.4528)
		(stroke
			(width 0.381)
			(type default)
		)
		(layer "In6.Cu")
	)
	(gr_line
		(start 111.6838 -153.4414)
		(end 111.6838 -167.767)
		(stroke
			(width 0.381)
			(type default)
		)
		(layer "In6.Cu")
	)
	(gr_arc
		(start 112.201452 -22.350222)
		(mid 112.750092 -22.898862)
		(end 113.298732 -22.350222)
		(stroke
			(width 0.2)
			(type default)
		)
		(layer "In6.Cu")
	)
	(gr_line
		(start 112.201452 -20.950174)
		(end 112.201452 -22.350222)
		(stroke
			(width 0.2)
			(type default)
		)
		(layer "In6.Cu")
	)
	(gr_arc
		(start 112.201452 -18.750026)
		(mid 112.750092 -19.298666)
		(end 113.298732 -18.750026)
		(stroke
			(width 0.2)
			(type default)
		)
		(layer "In6.Cu")
	)
	(gr_line
		(start 112.201452 -17.349978)
		(end 112.201452 -18.750026)
		(stroke
			(width 0.2)
			(type default)
		)
		(layer "In6.Cu")
	)
	(gr_line
		(start 112.3696 -168.4528)
		(end 124.1552 -168.4528)
		(stroke
			(width 0.381)
			(type default)
		)
		(layer "In6.Cu")
	)
	(gr_line
		(start 112.5982 -50.0634)
		(end 100.8634 -50.0634)
		(stroke
			(width 0.381)
			(type default)
		)
		(layer "In6.Cu")
	)
	(gr_line
		(start 113.298732 -22.350222)
		(end 113.298732 -20.950428)
		(stroke
			(width 0.2)
			(type default)
		)
		(layer "In6.Cu")
	)
	(gr_arc
		(start 113.298732 -20.950428)
		(mid 112.750219 -20.401534)
		(end 112.201452 -20.950174)
		(stroke
			(width 0.2)
			(type default)
		)
		(layer "In6.Cu")
	)
	(gr_line
		(start 113.298732 -18.750026)
		(end 113.298732 -17.350232)
		(stroke
			(width 0.2)
			(type default)
		)
		(layer "In6.Cu")
	)
	(gr_arc
		(start 113.298732 -17.350232)
		(mid 112.750219 -16.801338)
		(end 112.201452 -17.349978)
		(stroke
			(width 0.2)
			(type default)
		)
		(layer "In6.Cu")
	)
	(gr_arc
		(start 114.001296 -23.35022)
		(mid 114.549936 -23.89886)
		(end 115.098576 -23.35022)
		(stroke
			(width 0.2)
			(type default)
		)
		(layer "In6.Cu")
	)
	(gr_line
		(start 114.001296 -21.950172)
		(end 114.001296 -23.35022)
		(stroke
			(width 0.2)
			(type default)
		)
		(layer "In6.Cu")
	)
	(gr_arc
		(start 114.001296 -19.750024)
		(mid 114.549936 -20.298664)
		(end 115.098576 -19.750024)
		(stroke
			(width 0.2)
			(type default)
		)
		(layer "In6.Cu")
	)
	(gr_line
		(start 114.001296 -18.35023)
		(end 114.001296 -19.750024)
		(stroke
			(width 0.2)
			(type default)
		)
		(layer "In6.Cu")
	)
	(gr_line
		(start 114.2492 -48.4124)
		(end 112.5982 -50.0634)
		(stroke
			(width 0.381)
			(type default)
		)
		(layer "In6.Cu")
	)
	(gr_line
		(start 115.098576 -23.35022)
		(end 115.098576 -21.950426)
		(stroke
			(width 0.2)
			(type default)
		)
		(layer "In6.Cu")
	)
	(gr_arc
		(start 115.098576 -21.950426)
		(mid 114.550063 -21.401532)
		(end 114.001296 -21.950172)
		(stroke
			(width 0.2)
			(type default)
		)
		(layer "In6.Cu")
	)
	(gr_line
		(start 115.098576 -19.750024)
		(end 115.098576 -18.350484)
		(stroke
			(width 0.2)
			(type default)
		)
		(layer "In6.Cu")
	)
	(gr_arc
		(start 115.098576 -18.350484)
		(mid 114.550063 -17.80159)
		(end 114.001296 -18.35023)
		(stroke
			(width 0.2)
			(type default)
		)
		(layer "In6.Cu")
	)
	(gr_arc
		(start 115.801394 -29.550106)
		(mid 116.350034 -30.098746)
		(end 116.898674 -29.550106)
		(stroke
			(width 0.2)
			(type default)
		)
		(layer "In6.Cu")
	)
	(gr_line
		(start 115.801394 -28.150058)
		(end 115.801394 -29.550106)
		(stroke
			(width 0.2)
			(type default)
		)
		(layer "In6.Cu")
	)
	(gr_arc
		(start 115.801394 -22.350222)
		(mid 116.350034 -22.898862)
		(end 116.898674 -22.350222)
		(stroke
			(width 0.2)
			(type default)
		)
		(layer "In6.Cu")
	)
	(gr_line
		(start 115.801394 -20.950174)
		(end 115.801394 -22.350222)
		(stroke
			(width 0.2)
			(type default)
		)
		(layer "In6.Cu")
	)
	(gr_arc
		(start 115.801394 -18.750026)
		(mid 116.350034 -19.298666)
		(end 116.898674 -18.750026)
		(stroke
			(width 0.2)
			(type default)
		)
		(layer "In6.Cu")
	)
	(gr_line
		(start 115.801394 -17.349978)
		(end 115.801394 -18.750026)
		(stroke
			(width 0.2)
			(type default)
		)
		(layer "In6.Cu")
	)
	(gr_line
		(start 116.898674 -29.550106)
		(end 116.898674 -28.150312)
		(stroke
			(width 0.2)
			(type default)
		)
		(layer "In6.Cu")
	)
	(gr_arc
		(start 116.898674 -28.150312)
		(mid 116.350161 -27.601418)
		(end 115.801394 -28.150058)
		(stroke
			(width 0.2)
			(type default)
		)
		(layer "In6.Cu")
	)
	(gr_line
		(start 116.898674 -22.350222)
		(end 116.898674 -20.950428)
		(stroke
			(width 0.2)
			(type default)
		)
		(layer "In6.Cu")
	)
	(gr_arc
		(start 116.898674 -20.950428)
		(mid 116.350161 -20.401534)
		(end 115.801394 -20.950174)
		(stroke
			(width 0.2)
			(type default)
		)
		(layer "In6.Cu")
	)
	(gr_line
		(start 116.898674 -18.750026)
		(end 116.898674 -17.350232)
		(stroke
			(width 0.2)
			(type default)
		)
		(layer "In6.Cu")
	)
	(gr_arc
		(start 116.898674 -17.350232)
		(mid 116.350161 -16.801338)
		(end 115.801394 -17.349978)
		(stroke
			(width 0.2)
			(type default)
		)
		(layer "In6.Cu")
	)
	(gr_arc
		(start 117.601238 -23.35022)
		(mid 118.149878 -23.89886)
		(end 118.698518 -23.35022)
		(stroke
			(width 0.2)
			(type default)
		)
		(layer "In6.Cu")
	)
	(gr_line
		(start 117.601238 -21.950172)
		(end 117.601238 -23.35022)
		(stroke
			(width 0.2)
			(type default)
		)
		(layer "In6.Cu")
	)
	(gr_arc
		(start 117.601238 -19.750024)
		(mid 118.149878 -20.298664)
		(end 118.698518 -19.750024)
		(stroke
			(width 0.2)
			(type default)
		)
		(layer "In6.Cu")
	)
	(gr_line
		(start 117.601238 -18.35023)
		(end 117.601238 -19.750024)
		(stroke
			(width 0.2)
			(type default)
		)
		(layer "In6.Cu")
	)
	(gr_line
		(start 118.698518 -23.35022)
		(end 118.698518 -21.950426)
		(stroke
			(width 0.2)
			(type default)
		)
		(layer "In6.Cu")
	)
	(gr_arc
		(start 118.698518 -21.950426)
		(mid 118.150005 -21.401532)
		(end 117.601238 -21.950172)
		(stroke
			(width 0.2)
			(type default)
		)
		(layer "In6.Cu")
	)
	(gr_line
		(start 118.698518 -19.750024)
		(end 118.698518 -18.350484)
		(stroke
			(width 0.2)
			(type default)
		)
		(layer "In6.Cu")
	)
	(gr_arc
		(start 118.698518 -18.350484)
		(mid 118.150005 -17.80159)
		(end 117.601238 -18.35023)
		(stroke
			(width 0.2)
			(type default)
		)
		(layer "In6.Cu")
	)
	(gr_arc
		(start 119.401336 -22.350222)
		(mid 119.949976 -22.898862)
		(end 120.498616 -22.350222)
		(stroke
			(width 0.2)
			(type default)
		)
		(layer "In6.Cu")
	)
	(gr_line
		(start 119.401336 -20.950174)
		(end 119.401336 -22.350222)
		(stroke
			(width 0.2)
			(type default)
		)
		(layer "In6.Cu")
	)
	(gr_arc
		(start 119.401336 -18.750026)
		(mid 119.949976 -19.298666)
		(end 120.498616 -18.750026)
		(stroke
			(width 0.2)
			(type default)
		)
		(layer "In6.Cu")
	)
	(gr_line
		(start 119.401336 -17.349978)
		(end 119.401336 -18.750026)
		(stroke
			(width 0.2)
			(type default)
		)
		(layer "In6.Cu")
	)
	(gr_line
		(start 120.498616 -22.350222)
		(end 120.498616 -20.950428)
		(stroke
			(width 0.2)
			(type default)
		)
		(layer "In6.Cu")
	)
	(gr_arc
		(start 120.498616 -20.950428)
		(mid 119.950103 -20.401534)
		(end 119.401336 -20.950174)
		(stroke
			(width 0.2)
			(type default)
		)
		(layer "In6.Cu")
	)
	(gr_line
		(start 120.498616 -18.750026)
		(end 120.498616 -17.350232)
		(stroke
			(width 0.2)
			(type default)
		)
		(layer "In6.Cu")
	)
	(gr_arc
		(start 120.498616 -17.350232)
		(mid 119.950103 -16.801338)
		(end 119.401336 -17.349978)
		(stroke
			(width 0.2)
			(type default)
		)
		(layer "In6.Cu")
	)
	(gr_arc
		(start 121.198894 -30.54985)
		(mid 121.749947 -31.101284)
		(end 122.301254 -30.550104)
		(stroke
			(width 0.2)
			(type default)
		)
		(layer "In6.Cu")
	)
	(gr_line
		(start 121.198894 -29.150056)
		(end 121.198894 -30.54985)
		(stroke
			(width 0.2)
			(type default)
		)
		(layer "In6.Cu")
	)
	(gr_arc
		(start 121.201434 -23.35022)
		(mid 121.750074 -23.89886)
		(end 122.298714 -23.35022)
		(stroke
			(width 0.2)
			(type default)
		)
		(layer "In6.Cu")
	)
	(gr_line
		(start 121.201434 -21.950172)
		(end 121.201434 -23.35022)
		(stroke
			(width 0.2)
			(type default)
		)
		(layer "In6.Cu")
	)
	(gr_arc
		(start 121.201434 -19.750024)
		(mid 121.750074 -20.298664)
		(end 122.298714 -19.750024)
		(stroke
			(width 0.2)
			(type default)
		)
		(layer "In6.Cu")
	)
	(gr_line
		(start 121.201434 -18.35023)
		(end 121.201434 -19.750024)
		(stroke
			(width 0.2)
			(type default)
		)
		(layer "In6.Cu")
	)
	(gr_line
		(start 122.298714 -23.35022)
		(end 122.298714 -21.950426)
		(stroke
			(width 0.2)
			(type default)
		)
		(layer "In6.Cu")
	)
	(gr_arc
		(start 122.298714 -21.950426)
		(mid 121.750201 -21.401532)
		(end 121.201434 -21.950172)
		(stroke
			(width 0.2)
			(type default)
		)
		(layer "In6.Cu")
	)
	(gr_line
		(start 122.298714 -19.750024)
		(end 122.298714 -18.350484)
		(stroke
			(width 0.2)
			(type default)
		)
		(layer "In6.Cu")
	)
	(gr_arc
		(start 122.298714 -18.350484)
		(mid 121.750201 -17.80159)
		(end 121.201434 -18.35023)
		(stroke
			(width 0.2)
			(type default)
		)
		(layer "In6.Cu")
	)
	(gr_line
		(start 122.301254 -30.550104)
		(end 122.301254 -29.150056)
		(stroke
			(width 0.2)
			(type default)
		)
		(layer "In6.Cu")
	)
	(gr_arc
		(start 122.301254 -29.150056)
		(mid 121.750074 -28.598876)
		(end 121.198894 -29.150056)
		(stroke
			(width 0.2)
			(type default)
		)
		(layer "In6.Cu")
	)
	(gr_line
		(start 122.9106 -48.4124)
		(end 114.2492 -48.4124)
		(stroke
			(width 0.381)
			(type default)
		)
		(layer "In6.Cu")
	)
	(gr_line
		(start 124.1552 -168.4528)
		(end 125.984 -166.624)
		(stroke
			(width 0.381)
			(type default)
		)
		(layer "In6.Cu")
	)
	(gr_line
		(start 125.73 -45.593)
		(end 122.9106 -48.4124)
		(stroke
			(width 0.381)
			(type default)
		)
		(layer "In6.Cu")
	)
	(gr_line
		(start 125.984 -166.624)
		(end 125.984 -160.782)
		(stroke
			(width 0.381)
			(type default)
		)
		(layer "In6.Cu")
	)
	(gr_line
		(start 125.984 -160.782)
		(end 126.492 -160.274)
		(stroke
			(width 0.381)
			(type default)
		)
		(layer "In6.Cu")
	)
	(gr_line
		(start 126.492 -160.274)
		(end 127.762 -160.274)
		(stroke
			(width 0.381)
			(type default)
		)
		(layer "In6.Cu")
	)
	(gr_arc
		(start 126.77775 -278.321516)
		(mid 127.15875 -278.702516)
		(end 127.53975 -278.321516)
		(stroke
			(width 0.2)
			(type default)
		)
		(layer "In6.Cu")
	)
	(gr_line
		(start 126.77775 -277.178516)
		(end 126.77775 -278.321516)
		(stroke
			(width 0.2)
			(type default)
		)
		(layer "In6.Cu")
	)
	(gr_arc
		(start 126.77775 -163.321492)
		(mid 127.15875 -163.702492)
		(end 127.53975 -163.321492)
		(stroke
			(width 0.2)
			(type default)
		)
		(layer "In6.Cu")
	)
	(gr_line
		(start 126.77775 -162.178492)
		(end 126.77775 -163.321492)
		(stroke
			(width 0.2)
			(type default)
		)
		(layer "In6.Cu")
	)
	(gr_arc
		(start 126.77775 -48.321468)
		(mid 127.15875 -48.702468)
		(end 127.53975 -48.321468)
		(stroke
			(width 0.2)
			(type default)
		)
		(layer "In6.Cu")
	)
	(gr_line
		(start 126.77775 -47.178468)
		(end 126.77775 -48.321468)
		(stroke
			(width 0.2)
			(type default)
		)
		(layer "In6.Cu")
	)
	(gr_line
		(start 127.53975 -278.321516)
		(end 127.53975 -277.17877)
		(stroke
			(width 0.2)
			(type default)
		)
		(layer "In6.Cu")
	)
	(gr_arc
		(start 127.53975 -277.17877)
		(mid 127.158877 -276.797516)
		(end 126.77775 -277.178516)
		(stroke
			(width 0.2)
			(type default)
		)
		(layer "In6.Cu")
	)
	(gr_line
		(start 127.53975 -163.321492)
		(end 127.53975 -162.178746)
		(stroke
			(width 0.2)
			(type default)
		)
		(layer "In6.Cu")
	)
	(gr_arc
		(start 127.53975 -162.178746)
		(mid 127.158877 -161.797492)
		(end 126.77775 -162.178492)
		(stroke
			(width 0.2)
			(type default)
		)
		(layer "In6.Cu")
	)
	(gr_line
		(start 127.53975 -48.321468)
		(end 127.53975 -47.178722)
		(stroke
			(width 0.2)
			(type default)
		)
		(layer "In6.Cu")
	)
	(gr_arc
		(start 127.53975 -47.178722)
		(mid 127.158877 -46.797468)
		(end 126.77775 -47.178468)
		(stroke
			(width 0.2)
			(type default)
		)
		(layer "In6.Cu")
	)
	(gr_line
		(start 127.635 -45.593)
		(end 125.73 -45.593)
		(stroke
			(width 0.381)
			(type default)
		)
		(layer "In6.Cu")
	)
	(gr_line
		(start 127.762 -160.274)
		(end 135.9408 -168.4528)
		(stroke
			(width 0.381)
			(type default)
		)
		(layer "In6.Cu")
	)
	(gr_arc
		(start 130.201416 -22.350222)
		(mid 130.750056 -22.898862)
		(end 131.298696 -22.350222)
		(stroke
			(width 0.2)
			(type default)
		)
		(layer "In6.Cu")
	)
	(gr_line
		(start 130.201416 -20.950174)
		(end 130.201416 -22.350222)
		(stroke
			(width 0.2)
			(type default)
		)
		(layer "In6.Cu")
	)
	(gr_arc
		(start 130.201416 -18.750026)
		(mid 130.750056 -19.298666)
		(end 131.298696 -18.750026)
		(stroke
			(width 0.2)
			(type default)
		)
		(layer "In6.Cu")
	)
	(gr_line
		(start 130.201416 -17.349978)
		(end 130.201416 -18.750026)
		(stroke
			(width 0.2)
			(type default)
		)
		(layer "In6.Cu")
	)
	(gr_line
		(start 131.298696 -22.350222)
		(end 131.298696 -20.950428)
		(stroke
			(width 0.2)
			(type default)
		)
		(layer "In6.Cu")
	)
	(gr_arc
		(start 131.298696 -20.950428)
		(mid 130.750183 -20.401534)
		(end 130.201416 -20.950174)
		(stroke
			(width 0.2)
			(type default)
		)
		(layer "In6.Cu")
	)
	(gr_line
		(start 131.298696 -18.750026)
		(end 131.298696 -17.350232)
		(stroke
			(width 0.2)
			(type default)
		)
		(layer "In6.Cu")
	)
	(gr_arc
		(start 131.298696 -17.350232)
		(mid 130.750183 -16.801338)
		(end 130.201416 -17.349978)
		(stroke
			(width 0.2)
			(type default)
		)
		(layer "In6.Cu")
	)
	(gr_arc
		(start 132.00126 -23.35022)
		(mid 132.5499 -23.89886)
		(end 133.09854 -23.35022)
		(stroke
			(width 0.2)
			(type default)
		)
		(layer "In6.Cu")
	)
	(gr_line
		(start 132.00126 -21.950172)
		(end 132.00126 -23.35022)
		(stroke
			(width 0.2)
			(type default)
		)
		(layer "In6.Cu")
	)
	(gr_arc
		(start 132.00126 -19.74977)
		(mid 132.549773 -20.298664)
		(end 133.09854 -19.750024)
		(stroke
			(width 0.2)
			(type default)
		)
		(layer "In6.Cu")
	)
	(gr_line
		(start 132.00126 -18.35023)
		(end 132.00126 -19.74977)
		(stroke
			(width 0.2)
			(type default)
		)
		(layer "In6.Cu")
	)
	(gr_line
		(start 132.3594 -50.3174)
		(end 127.635 -45.593)
		(stroke
			(width 0.381)
			(type default)
		)
		(layer "In6.Cu")
	)
	(gr_line
		(start 133.09854 -23.35022)
		(end 133.09854 -21.950426)
		(stroke
			(width 0.2)
			(type default)
		)
		(layer "In6.Cu")
	)
	(gr_arc
		(start 133.09854 -21.950426)
		(mid 132.550027 -21.401532)
		(end 132.00126 -21.950172)
		(stroke
			(width 0.2)
			(type default)
		)
		(layer "In6.Cu")
	)
	(gr_line
		(start 133.09854 -19.750024)
		(end 133.09854 -18.35023)
		(stroke
			(width 0.2)
			(type default)
		)
		(layer "In6.Cu")
	)
	(gr_arc
		(start 133.09854 -18.35023)
		(mid 132.5499 -17.80159)
		(end 132.00126 -18.35023)
		(stroke
			(width 0.2)
			(type default)
		)
		(layer "In6.Cu")
	)
	(gr_arc
		(start 133.801358 -22.350222)
		(mid 134.349998 -22.898862)
		(end 134.898638 -22.350222)
		(stroke
			(width 0.2)
			(type default)
		)
		(layer "In6.Cu")
	)
	(gr_line
		(start 133.801358 -20.950174)
		(end 133.801358 -22.350222)
		(stroke
			(width 0.2)
			(type default)
		)
		(layer "In6.Cu")
	)
	(gr_arc
		(start 133.801358 -18.750026)
		(mid 134.349998 -19.298666)
		(end 134.898638 -18.750026)
		(stroke
			(width 0.2)
			(type default)
		)
		(layer "In6.Cu")
	)
	(gr_line
		(start 133.801358 -17.349978)
		(end 133.801358 -18.750026)
		(stroke
			(width 0.2)
			(type default)
		)
		(layer "In6.Cu")
	)
	(gr_line
		(start 134.898638 -22.350222)
		(end 134.898638 -20.950428)
		(stroke
			(width 0.2)
			(type default)
		)
		(layer "In6.Cu")
	)
	(gr_arc
		(start 134.898638 -20.950428)
		(mid 134.350125 -20.401534)
		(end 133.801358 -20.950174)
		(stroke
			(width 0.2)
			(type default)
		)
		(layer "In6.Cu")
	)
	(gr_line
		(start 134.898638 -18.750026)
		(end 134.898638 -17.350232)
		(stroke
			(width 0.2)
			(type default)
		)
		(layer "In6.Cu")
	)
	(gr_arc
		(start 134.898638 -17.350232)
		(mid 134.350125 -16.801338)
		(end 133.801358 -17.349978)
		(stroke
			(width 0.2)
			(type default)
		)
		(layer "In6.Cu")
	)
	(gr_arc
		(start 135.601456 -30.550104)
		(mid 136.150096 -31.098744)
		(end 136.698736 -30.550104)
		(stroke
			(width 0.2)
			(type default)
		)
		(layer "In6.Cu")
	)
	(gr_line
		(start 135.601456 -29.150056)
		(end 135.601456 -30.550104)
		(stroke
			(width 0.2)
			(type default)
		)
		(layer "In6.Cu")
	)
	(gr_arc
		(start 135.601456 -23.35022)
		(mid 136.150096 -23.89886)
		(end 136.698736 -23.35022)
		(stroke
			(width 0.2)
			(type default)
		)
		(layer "In6.Cu")
	)
	(gr_line
		(start 135.601456 -21.950172)
		(end 135.601456 -23.35022)
		(stroke
			(width 0.2)
			(type default)
		)
		(layer "In6.Cu")
	)
	(gr_arc
		(start 135.601456 -19.750024)
		(mid 136.150096 -20.298664)
		(end 136.698736 -19.750024)
		(stroke
			(width 0.2)
			(type default)
		)
		(layer "In6.Cu")
	)
	(gr_line
		(start 135.601456 -18.35023)
		(end 135.601456 -19.750024)
		(stroke
			(width 0.2)
			(type default)
		)
		(layer "In6.Cu")
	)
	(gr_line
		(start 135.9408 -168.4528)
		(end 154.7622 -168.4528)
		(stroke
			(width 0.381)
			(type default)
		)
		(layer "In6.Cu")
	)
	(gr_line
		(start 136.698736 -30.550104)
		(end 136.698736 -29.15031)
		(stroke
			(width 0.2)
			(type default)
		)
		(layer "In6.Cu")
	)
	(gr_arc
		(start 136.698736 -29.15031)
		(mid 136.150223 -28.601416)
		(end 135.601456 -29.150056)
		(stroke
			(width 0.2)
			(type default)
		)
		(layer "In6.Cu")
	)
	(gr_line
		(start 136.698736 -23.35022)
		(end 136.698736 -21.950426)
		(stroke
			(width 0.2)
			(type default)
		)
		(layer "In6.Cu")
	)
	(gr_arc
		(start 136.698736 -21.950426)
		(mid 136.150223 -21.401532)
		(end 135.601456 -21.950172)
		(stroke
			(width 0.2)
			(type default)
		)
		(layer "In6.Cu")
	)
	(gr_line
		(start 136.698736 -19.750024)
		(end 136.698736 -18.350484)
		(stroke
			(width 0.2)
			(type default)
		)
		(layer "In6.Cu")
	)
	(gr_arc
		(start 136.698736 -18.350484)
		(mid 136.150223 -17.80159)
		(end 135.601456 -18.35023)
		(stroke
			(width 0.2)
			(type default)
		)
		(layer "In6.Cu")
	)
	(gr_arc
		(start 137.4013 -22.350222)
		(mid 137.94994 -22.898862)
		(end 138.49858 -22.350222)
		(stroke
			(width 0.2)
			(type default)
		)
		(layer "In6.Cu")
	)
	(gr_line
		(start 137.4013 -20.950174)
		(end 137.4013 -22.350222)
		(stroke
			(width 0.2)
			(type default)
		)
		(layer "In6.Cu")
	)
	(gr_arc
		(start 137.4013 -18.750026)
		(mid 137.94994 -19.298666)
		(end 138.49858 -18.750026)
		(stroke
			(width 0.2)
			(type default)
		)
		(layer "In6.Cu")
	)
	(gr_line
		(start 137.4013 -17.349978)
		(end 137.4013 -18.750026)
		(stroke
			(width 0.2)
			(type default)
		)
		(layer "In6.Cu")
	)
	(gr_line
		(start 138.49858 -22.350222)
		(end 138.49858 -20.950428)
		(stroke
			(width 0.2)
			(type default)
		)
		(layer "In6.Cu")
	)
	(gr_arc
		(start 138.49858 -20.950428)
		(mid 137.950067 -20.401534)
		(end 137.4013 -20.950174)
		(stroke
			(width 0.2)
			(type default)
		)
		(layer "In6.Cu")
	)
	(gr_line
		(start 138.49858 -18.750026)
		(end 138.49858 -17.350232)
		(stroke
			(width 0.2)
			(type default)
		)
		(layer "In6.Cu")
	)
	(gr_arc
		(start 138.49858 -17.350232)
		(mid 137.950067 -16.801338)
		(end 137.4013 -17.349978)
		(stroke
			(width 0.2)
			(type default)
		)
		(layer "In6.Cu")
	)
	(gr_arc
		(start 139.201398 -23.35022)
		(mid 139.750038 -23.89886)
		(end 140.298678 -23.35022)
		(stroke
			(width 0.2)
			(type default)
		)
		(layer "In6.Cu")
	)
	(gr_line
		(start 139.201398 -21.950172)
		(end 139.201398 -23.35022)
		(stroke
			(width 0.2)
			(type default)
		)
		(layer "In6.Cu")
	)
	(gr_arc
		(start 139.201398 -19.750024)
		(mid 139.750038 -20.298664)
		(end 140.298678 -19.750024)
		(stroke
			(width 0.2)
			(type default)
		)
		(layer "In6.Cu")
	)
	(gr_line
		(start 139.201398 -18.35023)
		(end 139.201398 -19.750024)
		(stroke
			(width 0.2)
			(type default)
		)
		(layer "In6.Cu")
	)
	(gr_line
		(start 139.954 -50.3174)
		(end 132.3594 -50.3174)
		(stroke
			(width 0.381)
			(type default)
		)
		(layer "In6.Cu")
	)
	(gr_line
		(start 140.298678 -23.35022)
		(end 140.298678 -21.950426)
		(stroke
			(width 0.2)
			(type default)
		)
		(layer "In6.Cu")
	)
	(gr_arc
		(start 140.298678 -21.950426)
		(mid 139.750165 -21.401532)
		(end 139.201398 -21.950172)
		(stroke
			(width 0.2)
			(type default)
		)
		(layer "In6.Cu")
	)
	(gr_line
		(start 140.298678 -19.750024)
		(end 140.298678 -18.350484)
		(stroke
			(width 0.2)
			(type default)
		)
		(layer "In6.Cu")
	)
	(gr_arc
		(start 140.298678 -18.350484)
		(mid 139.750165 -17.80159)
		(end 139.201398 -18.35023)
		(stroke
			(width 0.2)
			(type default)
		)
		(layer "In6.Cu")
	)
	(gr_arc
		(start 141.001242 -22.350222)
		(mid 141.549882 -22.898862)
		(end 142.098522 -22.350222)
		(stroke
			(width 0.2)
			(type default)
		)
		(layer "In6.Cu")
	)
	(gr_line
		(start 141.001242 -20.950174)
		(end 141.001242 -22.350222)
		(stroke
			(width 0.2)
			(type default)
		)
		(layer "In6.Cu")
	)
	(gr_arc
		(start 141.001242 -18.750026)
		(mid 141.549882 -19.298666)
		(end 142.098522 -18.750026)
		(stroke
			(width 0.2)
			(type default)
		)
		(layer "In6.Cu")
	)
	(gr_line
		(start 141.001242 -17.349978)
		(end 141.001242 -18.750026)
		(stroke
			(width 0.2)
			(type default)
		)
		(layer "In6.Cu")
	)
	(gr_line
		(start 142.098522 -22.350222)
		(end 142.098522 -20.950428)
		(stroke
			(width 0.2)
			(type default)
		)
		(layer "In6.Cu")
	)
	(gr_arc
		(start 142.098522 -20.950428)
		(mid 141.550009 -20.401534)
		(end 141.001242 -20.950174)
		(stroke
			(width 0.2)
			(type default)
		)
		(layer "In6.Cu")
	)
	(gr_line
		(start 142.098522 -18.750026)
		(end 142.098522 -17.350232)
		(stroke
			(width 0.2)
			(type default)
		)
		(layer "In6.Cu")
	)
	(gr_arc
		(start 142.098522 -17.350232)
		(mid 141.550009 -16.801338)
		(end 141.001242 -17.349978)
		(stroke
			(width 0.2)
			(type default)
		)
		(layer "In6.Cu")
	)
	(gr_line
		(start 142.2146 -48.0568)
		(end 139.954 -50.3174)
		(stroke
			(width 0.381)
			(type default)
		)
		(layer "In6.Cu")
	)
	(gr_arc
		(start 142.80134 -30.550104)
		(mid 143.34998 -31.098744)
		(end 143.89862 -30.550104)
		(stroke
			(width 0.2)
			(type default)
		)
		(layer "In6.Cu")
	)
	(gr_line
		(start 142.80134 -29.150056)
		(end 142.80134 -30.550104)
		(stroke
			(width 0.2)
			(type default)
		)
		(layer "In6.Cu")
	)
	(gr_arc
		(start 142.80134 -23.35022)
		(mid 143.34998 -23.89886)
		(end 143.89862 -23.35022)
		(stroke
			(width 0.2)
			(type default)
		)
		(layer "In6.Cu")
	)
	(gr_line
		(start 142.80134 -21.950172)
		(end 142.80134 -23.35022)
		(stroke
			(width 0.2)
			(type default)
		)
		(layer "In6.Cu")
	)
	(gr_arc
		(start 142.80134 -19.750024)
		(mid 143.34998 -20.298664)
		(end 143.89862 -19.750024)
		(stroke
			(width 0.2)
			(type default)
		)
		(layer "In6.Cu")
	)
	(gr_line
		(start 142.80134 -18.35023)
		(end 142.80134 -19.750024)
		(stroke
			(width 0.2)
			(type default)
		)
		(layer "In6.Cu")
	)
	(gr_line
		(start 143.0274 -310.5404)
		(end 148.082 -315.595)
		(stroke
			(width 0.381)
			(type default)
		)
		(layer "In6.Cu")
	)
	(gr_line
		(start 143.89862 -30.550104)
		(end 143.89862 -29.15031)
		(stroke
			(width 0.2)
			(type default)
		)
		(layer "In6.Cu")
	)
	(gr_arc
		(start 143.89862 -29.15031)
		(mid 143.350107 -28.601416)
		(end 142.80134 -29.150056)
		(stroke
			(width 0.2)
			(type default)
		)
		(layer "In6.Cu")
	)
	(gr_line
		(start 143.89862 -23.35022)
		(end 143.89862 -21.950426)
		(stroke
			(width 0.2)
			(type default)
		)
		(layer "In6.Cu")
	)
	(gr_arc
		(start 143.89862 -21.950426)
		(mid 143.350107 -21.401532)
		(end 142.80134 -21.950172)
		(stroke
			(width 0.2)
			(type default)
		)
		(layer "In6.Cu")
	)
	(gr_line
		(start 143.89862 -19.750024)
		(end 143.89862 -18.350484)
		(stroke
			(width 0.2)
			(type default)
		)
		(layer "In6.Cu")
	)
	(gr_arc
		(start 143.89862 -18.350484)
		(mid 143.350107 -17.80159)
		(end 142.80134 -18.35023)
		(stroke
			(width 0.2)
			(type default)
		)
		(layer "In6.Cu")
	)
	(gr_line
		(start 148.082 -315.595)
		(end 164.211 -315.595)
		(stroke
			(width 0.381)
			(type default)
		)
		(layer "In6.Cu")
	)
	(gr_arc
		(start 148.999956 -14.99997)
		(mid 149.707061 -14.707077)
		(end 149.999954 -13.999972)
		(stroke
			(width 2.54)
			(type default)
		)
		(layer "In6.Cu")
	)
	(gr_line
		(start 149.999954 -13.999972)
		(end 149.999954 -0.999998)
		(stroke
			(width 2.54)
			(type default)
		)
		(layer "In6.Cu")
	)
	(gr_arc
		(start 150.999952 0)
		(mid 150.292877 -0.292909)
		(end 149.999954 -0.999998)
		(stroke
			(width 2.54)
			(type default)
		)
		(layer "In6.Cu")
	)
	(gr_line
		(start 150.999952 0)
		(end 199.00011 0)
		(stroke
			(width 2.54)
			(type default)
		)
		(layer "In6.Cu")
	)
	(gr_line
		(start 154.144218 -242.917218)
		(end 91.142058 -242.917218)
		(stroke
			(width 0.381)
			(type default)
		)
		(layer "In6.Cu")
	)
	(gr_line
		(start 154.7622 -168.4528)
		(end 157.226 -165.989)
		(stroke
			(width 0.381)
			(type default)
		)
		(layer "In6.Cu")
	)
	(gr_line
		(start 155.5242 -48.0568)
		(end 142.2146 -48.0568)
		(stroke
			(width 0.381)
			(type default)
		)
		(layer "In6.Cu")
	)
	(gr_line
		(start 157.226 -165.989)
		(end 157.226 -161.671)
		(stroke
			(width 0.381)
			(type default)
		)
		(layer "In6.Cu")
	)
	(gr_line
		(start 157.226 -161.671)
		(end 158.369 -160.528)
		(stroke
			(width 0.381)
			(type default)
		)
		(layer "In6.Cu")
	)
	(gr_line
		(start 157.48 -279.908)
		(end 164.338 -286.766)
		(stroke
			(width 0.381)
			(type default)
		)
		(layer "In6.Cu")
	)
	(gr_line
		(start 157.48 -276.098)
		(end 157.48 -279.908)
		(stroke
			(width 0.381)
			(type default)
		)
		(layer "In6.Cu")
	)
	(gr_line
		(start 157.988 -45.593)
		(end 155.5242 -48.0568)
		(stroke
			(width 0.381)
			(type default)
		)
		(layer "In6.Cu")
	)
	(gr_line
		(start 158.242 -275.336)
		(end 157.48 -276.098)
		(stroke
			(width 0.381)
			(type default)
		)
		(layer "In6.Cu")
	)
	(gr_arc
		(start 158.327852 -278.321516)
		(mid 158.708852 -278.702516)
		(end 159.089852 -278.321516)
		(stroke
			(width 0.2)
			(type default)
		)
		(layer "In6.Cu")
	)
	(gr_line
		(start 158.327852 -277.178516)
		(end 158.327852 -278.321516)
		(stroke
			(width 0.2)
			(type default)
		)
		(layer "In6.Cu")
	)
	(gr_arc
		(start 158.327852 -163.321492)
		(mid 158.708852 -163.702492)
		(end 159.089852 -163.321492)
		(stroke
			(width 0.2)
			(type default)
		)
		(layer "In6.Cu")
	)
	(gr_line
		(start 158.327852 -162.178492)
		(end 158.327852 -163.321492)
		(stroke
			(width 0.2)
			(type default)
		)
		(layer "In6.Cu")
	)
	(gr_arc
		(start 158.327852 -48.321468)
		(mid 158.708852 -48.702468)
		(end 159.089852 -48.321468)
		(stroke
			(width 0.2)
			(type default)
		)
		(layer "In6.Cu")
	)
	(gr_line
		(start 158.327852 -47.178468)
		(end 158.327852 -48.321468)
		(stroke
			(width 0.2)
			(type default)
		)
		(layer "In6.Cu")
	)
	(gr_line
		(start 158.369 -160.528)
		(end 160.02 -160.528)
		(stroke
			(width 0.381)
			(type default)
		)
		(layer "In6.Cu")
	)
	(gr_line
		(start 159.089852 -278.321516)
		(end 159.089852 -277.17877)
		(stroke
			(width 0.2)
			(type default)
		)
		(layer "In6.Cu")
	)
	(gr_arc
		(start 159.089852 -277.17877)
		(mid 158.708979 -276.797516)
		(end 158.327852 -277.178516)
		(stroke
			(width 0.2)
			(type default)
		)
		(layer "In6.Cu")
	)
	(gr_line
		(start 159.089852 -163.321492)
		(end 159.089852 -162.178746)
		(stroke
			(width 0.2)
			(type default)
		)
		(layer "In6.Cu")
	)
	(gr_arc
		(start 159.089852 -162.178746)
		(mid 158.708979 -161.797492)
		(end 158.327852 -162.178492)
		(stroke
			(width 0.2)
			(type default)
		)
		(layer "In6.Cu")
	)
	(gr_line
		(start 159.089852 -48.321468)
		(end 159.089852 -47.178722)
		(stroke
			(width 0.2)
			(type default)
		)
		(layer "In6.Cu")
	)
	(gr_arc
		(start 159.089852 -47.178722)
		(mid 158.708979 -46.797468)
		(end 158.327852 -47.178468)
		(stroke
			(width 0.2)
			(type default)
		)
		(layer "In6.Cu")
	)
	(gr_line
		(start 159.766 -275.336)
		(end 158.242 -275.336)
		(stroke
			(width 0.381)
			(type default)
		)
		(layer "In6.Cu")
	)
	(gr_line
		(start 159.766 -45.593)
		(end 157.988 -45.593)
		(stroke
			(width 0.381)
			(type default)
		)
		(layer "In6.Cu")
	)
	(gr_line
		(start 160.02 -160.528)
		(end 167.9448 -168.4528)
		(stroke
			(width 0.381)
			(type default)
		)
		(layer "In6.Cu")
	)
	(gr_line
		(start 163.2204 -290.1696)
		(end 93.0656 -290.1696)
		(stroke
			(width 0.381)
			(type default)
		)
		(layer "In6.Cu")
	)
	(gr_line
		(start 164.084 -252.857)
		(end 154.144218 -242.917218)
		(stroke
			(width 0.381)
			(type default)
		)
		(layer "In6.Cu")
	)
	(gr_line
		(start 164.211 -315.595)
		(end 174.752 -326.136)
		(stroke
			(width 0.381)
			(type default)
		)
		(layer "In6.Cu")
	)
	(gr_line
		(start 164.338 -289.052)
		(end 163.2204 -290.1696)
		(stroke
			(width 0.381)
			(type default)
		)
		(layer "In6.Cu")
	)
	(gr_line
		(start 164.338 -286.766)
		(end 164.338 -289.052)
		(stroke
			(width 0.381)
			(type default)
		)
		(layer "In6.Cu")
	)
	(gr_line
		(start 164.5158 -50.3428)
		(end 159.766 -45.593)
		(stroke
			(width 0.381)
			(type default)
		)
		(layer "In6.Cu")
	)
	(gr_line
		(start 167.132 -284.353)
		(end 167.132 -282.702)
		(stroke
			(width 0.381)
			(type default)
		)
		(layer "In6.Cu")
	)
	(gr_line
		(start 167.132 -282.702)
		(end 159.766 -275.336)
		(stroke
			(width 0.381)
			(type default)
		)
		(layer "In6.Cu")
	)
	(gr_line
		(start 167.9448 -168.4528)
		(end 181.7116 -168.4528)
		(stroke
			(width 0.381)
			(type default)
		)
		(layer "In6.Cu")
	)
	(gr_line
		(start 172.6692 -50.3428)
		(end 164.5158 -50.3428)
		(stroke
			(width 0.381)
			(type default)
		)
		(layer "In6.Cu")
	)
	(gr_line
		(start 172.72 -252.857)
		(end 164.084 -252.857)
		(stroke
			(width 0.381)
			(type default)
		)
		(layer "In6.Cu")
	)
	(gr_line
		(start 172.9486 -290.1696)
		(end 167.132 -284.353)
		(stroke
			(width 0.381)
			(type default)
		)
		(layer "In6.Cu")
	)
	(gr_line
		(start 173.502828 -49.509172)
		(end 172.6692 -50.3428)
		(stroke
			(width 0.381)
			(type default)
		)
		(layer "In6.Cu")
	)
	(gr_line
		(start 173.502828 -32.965136)
		(end 173.502828 -49.509172)
		(stroke
			(width 0.381)
			(type default)
		)
		(layer "In6.Cu")
	)
	(gr_line
		(start 174.752 -326.136)
		(end 208.788 -326.136)
		(stroke
			(width 0.381)
			(type default)
		)
		(layer "In6.Cu")
	)
	(gr_line
		(start 181.7116 -168.4528)
		(end 183.0324 -167.132)
		(stroke
			(width 0.381)
			(type default)
		)
		(layer "In6.Cu")
	)
	(gr_line
		(start 182.368698 -290.1696)
		(end 182.369968 -290.1696)
		(stroke
			(width 0.381)
			(type default)
		)
		(layer "In6.Cu")
	)
	(gr_line
		(start 182.369968 -290.1696)
		(end 182.88 -289.659568)
		(stroke
			(width 0.381)
			(type default)
		)
		(layer "In6.Cu")
	)
	(gr_line
		(start 182.88 -290.165536)
		(end 182.88 -263.017)
		(stroke
			(width 0.381)
			(type default)
		)
		(layer "In6.Cu")
	)
	(gr_line
		(start 182.88 -289.659568)
		(end 182.881778 -289.659568)
		(stroke
			(width 0.381)
			(type default)
		)
		(layer "In6.Cu")
	)
	(gr_line
		(start 182.88 -263.017)
		(end 172.72 -252.857)
		(stroke
			(width 0.381)
			(type default)
		)
		(layer "In6.Cu")
	)
	(gr_line
		(start 182.881778 -289.659568)
		(end 183.39181 -290.1696)
		(stroke
			(width 0.381)
			(type default)
		)
		(layer "In6.Cu")
	)
	(gr_line
		(start 182.884064 -290.1696)
		(end 182.88 -290.165536)
		(stroke
			(width 0.381)
			(type default)
		)
		(layer "In6.Cu")
	)
	(gr_line
		(start 183.0324 -167.132)
		(end 183.0324 -46.619922)
		(stroke
			(width 0.381)
			(type default)
		)
		(layer "In6.Cu")
	)
	(gr_line
		(start 183.0324 -46.619922)
		(end 218.554808 -11.097514)
		(stroke
			(width 0.381)
			(type default)
		)
		(layer "In6.Cu")
	)
	(gr_line
		(start 189.6999 -349.199962)
		(end 0.999998 -349.199962)
		(stroke
			(width 2.54)
			(type default)
		)
		(layer "In6.Cu")
	)
	(gr_arc
		(start 189.877954 -278.321516)
		(mid 190.258954 -278.702516)
		(end 190.639954 -278.321516)
		(stroke
			(width 0.2)
			(type default)
		)
		(layer "In6.Cu")
	)
	(gr_line
		(start 189.877954 -277.178516)
		(end 189.877954 -278.321516)
		(stroke
			(width 0.2)
			(type default)
		)
		(layer "In6.Cu")
	)
	(gr_arc
		(start 189.877954 -163.321492)
		(mid 190.258954 -163.702492)
		(end 190.639954 -163.321492)
		(stroke
			(width 0.2)
			(type default)
		)
		(layer "In6.Cu")
	)
	(gr_line
		(start 189.877954 -162.178492)
		(end 189.877954 -163.321492)
		(stroke
			(width 0.2)
			(type default)
		)
		(layer "In6.Cu")
	)
	(gr_arc
		(start 189.877954 -48.321468)
		(mid 190.258954 -48.702468)
		(end 190.639954 -48.321468)
		(stroke
			(width 0.2)
			(type default)
		)
		(layer "In6.Cu")
	)
	(gr_line
		(start 189.877954 -47.178468)
		(end 189.877954 -48.321468)
		(stroke
			(width 0.2)
			(type default)
		)
		(layer "In6.Cu")
	)
	(gr_line
		(start 190.639954 -278.321516)
		(end 190.639954 -277.17877)
		(stroke
			(width 0.2)
			(type default)
		)
		(layer "In6.Cu")
	)
	(gr_arc
		(start 190.639954 -277.17877)
		(mid 190.259081 -276.797516)
		(end 189.877954 -277.178516)
		(stroke
			(width 0.2)
			(type default)
		)
		(layer "In6.Cu")
	)
	(gr_line
		(start 190.639954 -163.321492)
		(end 190.639954 -162.178746)
		(stroke
			(width 0.2)
			(type default)
		)
		(layer "In6.Cu")
	)
	(gr_arc
		(start 190.639954 -162.178746)
		(mid 190.259081 -161.797492)
		(end 189.877954 -162.178492)
		(stroke
			(width 0.2)
			(type default)
		)
		(layer "In6.Cu")
	)
	(gr_line
		(start 190.639954 -48.321468)
		(end 190.639954 -47.178722)
		(stroke
			(width 0.2)
			(type default)
		)
		(layer "In6.Cu")
	)
	(gr_arc
		(start 190.639954 -47.178722)
		(mid 190.259081 -46.797468)
		(end 189.877954 -47.178468)
		(stroke
			(width 0.2)
			(type default)
		)
		(layer "In6.Cu")
	)
	(gr_line
		(start 190.699898 -372.000018)
		(end 190.699898 -350.19996)
		(stroke
			(width 2.54)
			(type default)
		)
		(layer "In6.Cu")
	)
	(gr_arc
		(start 190.699898 -372.000018)
		(mid 190.992797 -372.707113)
		(end 191.699896 -373.000016)
		(stroke
			(width 2.54)
			(type default)
		)
		(layer "In6.Cu")
	)
	(gr_arc
		(start 190.699898 -350.19996)
		(mid 190.407005 -349.492855)
		(end 189.6999 -349.199962)
		(stroke
			(width 2.54)
			(type default)
		)
		(layer "In6.Cu")
	)
	(gr_line
		(start 197.875906 -8.592058)
		(end 173.502828 -32.965136)
		(stroke
			(width 0.381)
			(type default)
		)
		(layer "In6.Cu")
	)
	(gr_line
		(start 199.00011 -373.000016)
		(end 191.699896 -373.000016)
		(stroke
			(width 2.54)
			(type default)
		)
		(layer "In6.Cu")
	)
	(gr_arc
		(start 199.00011 0)
		(mid 199.707215 0.292893)
		(end 200.000108 0.999998)
		(stroke
			(width 2.54)
			(type default)
		)
		(layer "In6.Cu")
	)
	(gr_line
		(start 200.000108 -420.200074)
		(end 200.000108 -374.000014)
		(stroke
			(width 2.54)
			(type default)
		)
		(layer "In6.Cu")
	)
	(gr_arc
		(start 200.000108 -420.200074)
		(mid 200.292992 -420.907194)
		(end 201.000106 -421.200072)
		(stroke
			(width 2.54)
			(type default)
		)
		(layer "In6.Cu")
	)
	(gr_arc
		(start 200.000108 -374.000014)
		(mid 199.707215 -373.292909)
		(end 199.00011 -373.000016)
		(stroke
			(width 2.54)
			(type default)
		)
		(layer "In6.Cu")
	)
	(gr_arc
		(start 201.000106 1.999996)
		(mid 200.292997 1.707105)
		(end 200.000108 0.999998)
		(stroke
			(width 2.54)
			(type default)
		)
		(layer "In6.Cu")
	)
	(gr_line
		(start 201.000106 1.999996)
		(end 219.00007 1.999996)
		(stroke
			(width 2.54)
			(type default)
		)
		(layer "In6.Cu")
	)
	(gr_line
		(start 207.7212 -290.1696)
		(end 172.9486 -290.1696)
		(stroke
			(width 0.381)
			(type default)
		)
		(layer "In6.Cu")
	)
	(gr_line
		(start 208.788 -326.136)
		(end 210.312 -327.66)
		(stroke
			(width 0.381)
			(type default)
		)
		(layer "In6.Cu")
	)
	(gr_arc
		(start 209.451448 -415.600134)
		(mid 210.000088 -416.148774)
		(end 210.548728 -415.600134)
		(stroke
			(width 0.2)
			(type default)
		)
		(layer "In6.Cu")
	)
	(gr_line
		(start 209.451448 -414.200086)
		(end 209.451448 -415.600134)
		(stroke
			(width 0.2)
			(type default)
		)
		(layer "In6.Cu")
	)
	(gr_arc
		(start 209.451448 -412.000192)
		(mid 210.000088 -412.548832)
		(end 210.548728 -412.000192)
		(stroke
			(width 0.2)
			(type default)
		)
		(layer "In6.Cu")
	)
	(gr_line
		(start 209.451448 -410.600144)
		(end 209.451448 -412.000192)
		(stroke
			(width 0.2)
			(type default)
		)
		(layer "In6.Cu")
	)
	(gr_arc
		(start 209.451448 -408.399996)
		(mid 210.000088 -408.948636)
		(end 210.548728 -408.399996)
		(stroke
			(width 0.2)
			(type default)
		)
		(layer "In6.Cu")
	)
	(gr_line
		(start 209.451448 -407.000202)
		(end 209.451448 -408.399996)
		(stroke
			(width 0.2)
			(type default)
		)
		(layer "In6.Cu")
	)
	(gr_line
		(start 210.312 -379.603)
		(end 224.282 -393.573)
		(stroke
			(width 0.381)
			(type default)
		)
		(layer "In6.Cu")
	)
	(gr_line
		(start 210.312 -327.66)
		(end 210.312 -379.603)
		(stroke
			(width 0.381)
			(type default)
		)
		(layer "In6.Cu")
	)
	(gr_line
		(start 210.548728 -415.600134)
		(end 210.548728 -414.20034)
		(stroke
			(width 0.2)
			(type default)
		)
		(layer "In6.Cu")
	)
	(gr_arc
		(start 210.548728 -414.20034)
		(mid 210.000215 -413.651446)
		(end 209.451448 -414.200086)
		(stroke
			(width 0.2)
			(type default)
		)
		(layer "In6.Cu")
	)
	(gr_line
		(start 210.548728 -412.000192)
		(end 210.548728 -410.600398)
		(stroke
			(width 0.2)
			(type default)
		)
		(layer "In6.Cu")
	)
	(gr_arc
		(start 210.548728 -410.600398)
		(mid 210.000215 -410.051504)
		(end 209.451448 -410.600144)
		(stroke
			(width 0.2)
			(type default)
		)
		(layer "In6.Cu")
	)
	(gr_line
		(start 210.548728 -408.399996)
		(end 210.548728 -407.000456)
		(stroke
			(width 0.2)
			(type default)
		)
		(layer "In6.Cu")
	)
	(gr_arc
		(start 210.548728 -407.000456)
		(mid 210.000215 -406.451562)
		(end 209.451448 -407.000202)
		(stroke
			(width 0.2)
			(type default)
		)
		(layer "In6.Cu")
	)
	(gr_line
		(start 210.693 -287.1978)
		(end 207.7212 -290.1696)
		(stroke
			(width 0.381)
			(type default)
		)
		(layer "In6.Cu")
	)
	(gr_line
		(start 210.693 -224.536)
		(end 210.693 -287.1978)
		(stroke
			(width 0.381)
			(type default)
		)
		(layer "In6.Cu")
	)
	(gr_arc
		(start 211.251546 -418.200078)
		(mid 211.800186 -418.748718)
		(end 212.348826 -418.200078)
		(stroke
			(width 0.2)
			(type default)
		)
		(layer "In6.Cu")
	)
	(gr_line
		(start 211.251546 -416.80003)
		(end 211.251546 -418.200078)
		(stroke
			(width 0.2)
			(type default)
		)
		(layer "In6.Cu")
	)
	(gr_arc
		(start 211.251546 -407.399998)
		(mid 211.800186 -407.948638)
		(end 212.348826 -407.399998)
		(stroke
			(width 0.2)
			(type default)
		)
		(layer "In6.Cu")
	)
	(gr_line
		(start 211.251546 -405.99995)
		(end 211.251546 -407.399998)
		(stroke
			(width 0.2)
			(type default)
		)
		(layer "In6.Cu")
	)
	(gr_line
		(start 212.348826 -418.200078)
		(end 212.348826 -416.800284)
		(stroke
			(width 0.2)
			(type default)
		)
		(layer "In6.Cu")
	)
	(gr_arc
		(start 212.348826 -416.800284)
		(mid 211.800313 -416.25139)
		(end 211.251546 -416.80003)
		(stroke
			(width 0.2)
			(type default)
		)
		(layer "In6.Cu")
	)
	(gr_line
		(start 212.348826 -407.399998)
		(end 212.348826 -406.000204)
		(stroke
			(width 0.2)
			(type default)
		)
		(layer "In6.Cu")
	)
	(gr_arc
		(start 212.348826 -406.000204)
		(mid 211.800313 -405.45131)
		(end 211.251546 -405.99995)
		(stroke
			(width 0.2)
			(type default)
		)
		(layer "In6.Cu")
	)
	(gr_arc
		(start 213.05139 -415.600134)
		(mid 213.60003 -416.148774)
		(end 214.14867 -415.600134)
		(stroke
			(width 0.2)
			(type default)
		)
		(layer "In6.Cu")
	)
	(gr_line
		(start 213.05139 -414.200086)
		(end 213.05139 -415.600134)
		(stroke
			(width 0.2)
			(type default)
		)
		(layer "In6.Cu")
	)
	(gr_arc
		(start 213.05139 -408.399996)
		(mid 213.60003 -408.948636)
		(end 214.14867 -408.399996)
		(stroke
			(width 0.2)
			(type default)
		)
		(layer "In6.Cu")
	)
	(gr_line
		(start 213.05139 -407.000202)
		(end 213.05139 -408.399996)
		(stroke
			(width 0.2)
			(type default)
		)
		(layer "In6.Cu")
	)
	(gr_line
		(start 214.14867 -415.600134)
		(end 214.14867 -414.20034)
		(stroke
			(width 0.2)
			(type default)
		)
		(layer "In6.Cu")
	)
	(gr_arc
		(start 214.14867 -414.20034)
		(mid 213.600157 -413.651446)
		(end 213.05139 -414.200086)
		(stroke
			(width 0.2)
			(type default)
		)
		(layer "In6.Cu")
	)
	(gr_line
		(start 214.14867 -408.399996)
		(end 214.14867 -407.000456)
		(stroke
			(width 0.2)
			(type default)
		)
		(layer "In6.Cu")
	)
	(gr_arc
		(start 214.14867 -407.000456)
		(mid 213.600157 -406.451562)
		(end 213.05139 -407.000202)
		(stroke
			(width 0.2)
			(type default)
		)
		(layer "In6.Cu")
	)
	(gr_arc
		(start 214.851488 -418.200078)
		(mid 215.400128 -418.748718)
		(end 215.948768 -418.200078)
		(stroke
			(width 0.2)
			(type default)
		)
		(layer "In6.Cu")
	)
	(gr_line
		(start 214.851488 -416.80003)
		(end 214.851488 -418.200078)
		(stroke
			(width 0.2)
			(type default)
		)
		(layer "In6.Cu")
	)
	(gr_arc
		(start 214.851488 -407.399998)
		(mid 215.400128 -407.948638)
		(end 215.948768 -407.399998)
		(stroke
			(width 0.2)
			(type default)
		)
		(layer "In6.Cu")
	)
	(gr_line
		(start 214.851488 -405.99995)
		(end 214.851488 -407.399998)
		(stroke
			(width 0.2)
			(type default)
		)
		(layer "In6.Cu")
	)
	(gr_line
		(start 215.948768 -418.200078)
		(end 215.948768 -416.800284)
		(stroke
			(width 0.2)
			(type default)
		)
		(layer "In6.Cu")
	)
	(gr_arc
		(start 215.948768 -416.800284)
		(mid 215.400255 -416.25139)
		(end 214.851488 -416.80003)
		(stroke
			(width 0.2)
			(type default)
		)
		(layer "In6.Cu")
	)
	(gr_line
		(start 215.948768 -407.399998)
		(end 215.948768 -406.000204)
		(stroke
			(width 0.2)
			(type default)
		)
		(layer "In6.Cu")
	)
	(gr_arc
		(start 215.948768 -406.000204)
		(mid 215.400255 -405.45131)
		(end 214.851488 -405.99995)
		(stroke
			(width 0.2)
			(type default)
		)
		(layer "In6.Cu")
	)
	(gr_arc
		(start 216.651332 -415.600134)
		(mid 217.199972 -416.148774)
		(end 217.748612 -415.600134)
		(stroke
			(width 0.2)
			(type default)
		)
		(layer "In6.Cu")
	)
	(gr_line
		(start 216.651332 -414.200086)
		(end 216.651332 -415.600134)
		(stroke
			(width 0.2)
			(type default)
		)
		(layer "In6.Cu")
	)
	(gr_arc
		(start 216.651332 -408.399996)
		(mid 217.199972 -408.948636)
		(end 217.748612 -408.399996)
		(stroke
			(width 0.2)
			(type default)
		)
		(layer "In6.Cu")
	)
	(gr_line
		(start 216.651332 -407.000202)
		(end 216.651332 -408.399996)
		(stroke
			(width 0.2)
			(type default)
		)
		(layer "In6.Cu")
	)
	(gr_line
		(start 217.748612 -415.600134)
		(end 217.748612 -414.20034)
		(stroke
			(width 0.2)
			(type default)
		)
		(layer "In6.Cu")
	)
	(gr_arc
		(start 217.748612 -414.20034)
		(mid 217.200099 -413.651446)
		(end 216.651332 -414.200086)
		(stroke
			(width 0.2)
			(type default)
		)
		(layer "In6.Cu")
	)
	(gr_line
		(start 217.748612 -408.399996)
		(end 217.748612 -407.000456)
		(stroke
			(width 0.2)
			(type default)
		)
		(layer "In6.Cu")
	)
	(gr_arc
		(start 217.748612 -407.000456)
		(mid 217.200099 -406.451562)
		(end 216.651332 -407.000202)
		(stroke
			(width 0.2)
			(type default)
		)
		(layer "In6.Cu")
	)
	(gr_line
		(start 218.137994 -8.592058)
		(end 197.875906 -8.592058)
		(stroke
			(width 0.381)
			(type default)
		)
		(layer "In6.Cu")
	)
	(gr_arc
		(start 218.45143 -418.200078)
		(mid 219.00007 -418.748718)
		(end 219.54871 -418.200078)
		(stroke
			(width 0.2)
			(type default)
		)
		(layer "In6.Cu")
	)
	(gr_line
		(start 218.45143 -416.80003)
		(end 218.45143 -418.200078)
		(stroke
			(width 0.2)
			(type default)
		)
		(layer "In6.Cu")
	)
	(gr_arc
		(start 218.45143 -407.399998)
		(mid 219.00007 -407.948638)
		(end 219.54871 -407.399998)
		(stroke
			(width 0.2)
			(type default)
		)
		(layer "In6.Cu")
	)
	(gr_line
		(start 218.45143 -405.99995)
		(end 218.45143 -407.399998)
		(stroke
			(width 0.2)
			(type default)
		)
		(layer "In6.Cu")
	)
	(gr_line
		(start 218.554808 -11.097514)
		(end 218.554808 -9.008872)
		(stroke
			(width 0.381)
			(type default)
		)
		(layer "In6.Cu")
	)
	(gr_line
		(start 218.554808 -9.008872)
		(end 218.137994 -8.592058)
		(stroke
			(width 0.381)
			(type default)
		)
		(layer "In6.Cu")
	)
	(gr_arc
		(start 219.00007 1.999996)
		(mid 219.707175 2.292889)
		(end 220.000068 2.999994)
		(stroke
			(width 2.54)
			(type default)
		)
		(layer "In6.Cu")
	)
	(gr_line
		(start 219.54871 -418.200078)
		(end 219.54871 -416.800284)
		(stroke
			(width 0.2)
			(type default)
		)
		(layer "In6.Cu")
	)
	(gr_arc
		(start 219.54871 -416.800284)
		(mid 219.000197 -416.25139)
		(end 218.45143 -416.80003)
		(stroke
			(width 0.2)
			(type default)
		)
		(layer "In6.Cu")
	)
	(gr_line
		(start 219.54871 -407.399998)
		(end 219.54871 -406.000204)
		(stroke
			(width 0.2)
			(type default)
		)
		(layer "In6.Cu")
	)
	(gr_arc
		(start 219.54871 -406.000204)
		(mid 219.000197 -405.45131)
		(end 218.45143 -405.99995)
		(stroke
			(width 0.2)
			(type default)
		)
		(layer "In6.Cu")
	)
	(gr_line
		(start 220.000068 2.999994)
		(end 220.000068 37.800026)
		(stroke
			(width 2.54)
			(type default)
		)
		(layer "In6.Cu")
	)
	(gr_arc
		(start 220.251528 -415.600134)
		(mid 220.800168 -416.148774)
		(end 221.348808 -415.600134)
		(stroke
			(width 0.2)
			(type default)
		)
		(layer "In6.Cu")
	)
	(gr_line
		(start 220.251528 -414.200086)
		(end 220.251528 -415.600134)
		(stroke
			(width 0.2)
			(type default)
		)
		(layer "In6.Cu")
	)
	(gr_arc
		(start 220.251528 -408.399996)
		(mid 220.800168 -408.948636)
		(end 221.348808 -408.399996)
		(stroke
			(width 0.2)
			(type default)
		)
		(layer "In6.Cu")
	)
	(gr_line
		(start 220.251528 -407.000202)
		(end 220.251528 -408.399996)
		(stroke
			(width 0.2)
			(type default)
		)
		(layer "In6.Cu")
	)
	(gr_line
		(start 220.472 -374.523)
		(end 220.472 -363.982)
		(stroke
			(width 0.381)
			(type default)
		)
		(layer "In6.Cu")
	)
	(gr_line
		(start 220.472 -363.982)
		(end 225.435414 -359.018586)
		(stroke
			(width 0.381)
			(type default)
		)
		(layer "In6.Cu")
	)
	(gr_arc
		(start 221.000066 38.800024)
		(mid 220.292973 38.507121)
		(end 220.000068 37.800026)
		(stroke
			(width 2.54)
			(type default)
		)
		(layer "In6.Cu")
	)
	(gr_line
		(start 221.000066 38.800024)
		(end 298.99991 38.800024)
		(stroke
			(width 2.54)
			(type default)
		)
		(layer "In6.Cu")
	)
	(gr_line
		(start 221.348808 -415.600134)
		(end 221.348808 -414.20034)
		(stroke
			(width 0.2)
			(type default)
		)
		(layer "In6.Cu")
	)
	(gr_arc
		(start 221.348808 -414.20034)
		(mid 220.800295 -413.651446)
		(end 220.251528 -414.200086)
		(stroke
			(width 0.2)
			(type default)
		)
		(layer "In6.Cu")
	)
	(gr_line
		(start 221.348808 -408.399996)
		(end 221.348808 -407.000456)
		(stroke
			(width 0.2)
			(type default)
		)
		(layer "In6.Cu")
	)
	(gr_arc
		(start 221.348808 -407.000456)
		(mid 220.800295 -406.451562)
		(end 220.251528 -407.000202)
		(stroke
			(width 0.2)
			(type default)
		)
		(layer "In6.Cu")
	)
	(gr_arc
		(start 222.051372 -418.200078)
		(mid 222.600012 -418.748718)
		(end 223.148652 -418.200078)
		(stroke
			(width 0.2)
			(type default)
		)
		(layer "In6.Cu")
	)
	(gr_line
		(start 222.051372 -416.80003)
		(end 222.051372 -418.200078)
		(stroke
			(width 0.2)
			(type default)
		)
		(layer "In6.Cu")
	)
	(gr_arc
		(start 222.051372 -407.399998)
		(mid 222.600012 -407.948638)
		(end 223.148652 -407.399998)
		(stroke
			(width 0.2)
			(type default)
		)
		(layer "In6.Cu")
	)
	(gr_line
		(start 222.051372 -405.99995)
		(end 222.051372 -407.399998)
		(stroke
			(width 0.2)
			(type default)
		)
		(layer "In6.Cu")
	)
	(gr_line
		(start 223.148652 -418.200078)
		(end 223.148652 -416.800284)
		(stroke
			(width 0.2)
			(type default)
		)
		(layer "In6.Cu")
	)
	(gr_arc
		(start 223.148652 -416.800284)
		(mid 222.600139 -416.25139)
		(end 222.051372 -416.80003)
		(stroke
			(width 0.2)
			(type default)
		)
		(layer "In6.Cu")
	)
	(gr_line
		(start 223.148652 -407.399998)
		(end 223.148652 -406.000204)
		(stroke
			(width 0.2)
			(type default)
		)
		(layer "In6.Cu")
	)
	(gr_arc
		(start 223.148652 -406.000204)
		(mid 222.600139 -405.45131)
		(end 222.051372 -405.99995)
		(stroke
			(width 0.2)
			(type default)
		)
		(layer "In6.Cu")
	)
	(gr_line
		(start 224.282 -399.36928)
		(end 230.2764 -405.36368)
		(stroke
			(width 0.381)
			(type default)
		)
		(layer "In6.Cu")
	)
	(gr_line
		(start 224.282 -393.573)
		(end 224.282 -399.36928)
		(stroke
			(width 0.381)
			(type default)
		)
		(layer "In6.Cu")
	)
	(gr_line
		(start 225.435414 -359.018586)
		(end 227.380292 -359.018586)
		(stroke
			(width 0.381)
			(type default)
		)
		(layer "In6.Cu")
	)
	(gr_line
		(start 227.380292 -359.018586)
		(end 229.45725 -356.941628)
		(stroke
			(width 0.381)
			(type default)
		)
		(layer "In6.Cu")
	)
	(gr_line
		(start 229.45725 -356.941628)
		(end 229.45725 -354.99675)
		(stroke
			(width 0.381)
			(type default)
		)
		(layer "In6.Cu")
	)
	(gr_line
		(start 229.45725 -354.99675)
		(end 231.394 -353.06)
		(stroke
			(width 0.381)
			(type default)
		)
		(layer "In6.Cu")
	)
	(gr_line
		(start 229.6414 -420.177214)
		(end 230.271574 -419.54704)
		(stroke
			(width 0.381)
			(type default)
		)
		(layer "In6.Cu")
	)
	(gr_line
		(start 230.271574 -419.54704)
		(end 230.27259 -419.54704)
		(stroke
			(width 0.381)
			(type default)
		)
		(layer "In6.Cu")
	)
	(gr_line
		(start 230.27259 -419.54704)
		(end 230.281226 -419.54704)
		(stroke
			(width 0.381)
			(type default)
		)
		(layer "In6.Cu")
	)
	(gr_line
		(start 230.2764 -405.36368)
		(end 232.608374 -405.36368)
		(stroke
			(width 0.381)
			(type default)
		)
		(layer "In6.Cu")
	)
	(gr_line
		(start 230.281226 -419.54704)
		(end 230.9114 -420.177214)
		(stroke
			(width 0.381)
			(type default)
		)
		(layer "In6.Cu")
	)
	(gr_line
		(start 230.297736 -421.200072)
		(end 230.297736 -405.385016)
		(stroke
			(width 0.381)
			(type default)
		)
		(layer "In6.Cu")
	)
	(gr_line
		(start 230.297736 -405.385016)
		(end 230.2764 -405.36368)
		(stroke
			(width 0.381)
			(type default)
		)
		(layer "In6.Cu")
	)
	(gr_line
		(start 230.773478 -405.36368)
		(end 230.297736 -405.839422)
		(stroke
			(width 0.381)
			(type default)
		)
		(layer "In6.Cu")
	)
	(gr_line
		(start 230.777796 -405.36368)
		(end 230.773478 -405.36368)
		(stroke
			(width 0.381)
			(type default)
		)
		(layer "In6.Cu")
	)
	(gr_line
		(start 230.9114 -420.177214)
		(end 229.6414 -420.177214)
		(stroke
			(width 0.381)
			(type default)
		)
		(layer "In6.Cu")
	)
	(gr_line
		(start 231.394 -353.06)
		(end 231.394 -220.726)
		(stroke
			(width 0.381)
			(type default)
		)
		(layer "In6.Cu")
	)
	(gr_line
		(start 231.394 -220.726)
		(end 263.398 -188.722)
		(stroke
			(width 0.381)
			(type default)
		)
		(layer "In6.Cu")
	)
	(gr_line
		(start 232.608374 -405.36368)
		(end 234.107736 -403.864318)
		(stroke
			(width 0.381)
			(type default)
		)
		(layer "In6.Cu")
	)
	(gr_line
		(start 234.107736 -403.864318)
		(end 234.107736 -388.158736)
		(stroke
			(width 0.381)
			(type default)
		)
		(layer "In6.Cu")
	)
	(gr_line
		(start 234.107736 -388.158736)
		(end 220.472 -374.523)
		(stroke
			(width 0.381)
			(type default)
		)
		(layer "In6.Cu")
	)
	(gr_arc
		(start 235.722922 -121.845578)
		(mid 235.39577 -122.827034)
		(end 236.377226 -123.154186)
		(stroke
			(width 0.2)
			(type default)
		)
		(layer "In6.Cu")
	)
	(gr_line
		(start 235.723938 -65.548002)
		(end 235.725208 -65.550288)
		(stroke
			(width 0.2)
			(type default)
		)
		(layer "In6.Cu")
	)
	(gr_line
		(start 235.724192 -177.848006)
		(end 235.725208 -177.850038)
		(stroke
			(width 0.2)
			(type default)
		)
		(layer "In6.Cu")
	)
	(gr_line
		(start 235.724192 -177.847752)
		(end 235.724192 -177.848006)
		(stroke
			(width 0.2)
			(type default)
		)
		(layer "In6.Cu")
	)
	(gr_line
		(start 235.724192 -173.848014)
		(end 235.725208 -173.850046)
		(stroke
			(width 0.2)
			(type default)
		)
		(layer "In6.Cu")
	)
	(gr_line
		(start 235.724192 -173.84776)
		(end 235.724192 -173.848014)
		(stroke
			(width 0.2)
			(type default)
		)
		(layer "In6.Cu")
	)
	(gr_line
		(start 235.724192 -169.848022)
		(end 235.725208 -169.850054)
		(stroke
			(width 0.2)
			(type default)
		)
		(layer "In6.Cu")
	)
	(gr_line
		(start 235.724192 -169.847768)
		(end 235.724192 -169.848022)
		(stroke
			(width 0.2)
			(type default)
		)
		(layer "In6.Cu")
	)
	(gr_line
		(start 235.724192 -165.84803)
		(end 235.725208 -165.850062)
		(stroke
			(width 0.2)
			(type default)
		)
		(layer "In6.Cu")
	)
	(gr_line
		(start 235.724192 -165.847776)
		(end 235.724192 -165.84803)
		(stroke
			(width 0.2)
			(type default)
		)
		(layer "In6.Cu")
	)
	(gr_line
		(start 235.724192 -137.848086)
		(end 235.725208 -137.850118)
		(stroke
			(width 0.2)
			(type default)
		)
		(layer "In6.Cu")
	)
	(gr_line
		(start 235.724192 -137.847832)
		(end 235.724192 -137.848086)
		(stroke
			(width 0.2)
			(type default)
		)
		(layer "In6.Cu")
	)
	(gr_line
		(start 235.724192 -81.548224)
		(end 235.725208 -81.550256)
		(stroke
			(width 0.2)
			(type default)
		)
		(layer "In6.Cu")
	)
	(gr_line
		(start 235.724192 -81.54797)
		(end 235.724192 -81.548224)
		(stroke
			(width 0.2)
			(type default)
		)
		(layer "In6.Cu")
	)
	(gr_line
		(start 235.724192 -77.548232)
		(end 235.725208 -77.550264)
		(stroke
			(width 0.2)
			(type default)
		)
		(layer "In6.Cu")
	)
	(gr_line
		(start 235.724192 -77.547978)
		(end 235.724192 -77.548232)
		(stroke
			(width 0.2)
			(type default)
		)
		(layer "In6.Cu")
	)
	(gr_line
		(start 235.724192 -73.54824)
		(end 235.725208 -73.550272)
		(stroke
			(width 0.2)
			(type default)
		)
		(layer "In6.Cu")
	)
	(gr_line
		(start 235.724192 -73.547986)
		(end 235.724192 -73.54824)
		(stroke
			(width 0.2)
			(type default)
		)
		(layer "In6.Cu")
	)
	(gr_line
		(start 235.724192 -69.548248)
		(end 235.725208 -69.55028)
		(stroke
			(width 0.2)
			(type default)
		)
		(layer "In6.Cu")
	)
	(gr_line
		(start 235.724192 -69.547994)
		(end 235.724192 -69.548248)
		(stroke
			(width 0.2)
			(type default)
		)
		(layer "In6.Cu")
	)
	(gr_line
		(start 235.724192 -61.548264)
		(end 235.725208 -61.550296)
		(stroke
			(width 0.2)
			(type default)
		)
		(layer "In6.Cu")
	)
	(gr_line
		(start 235.724192 -61.54801)
		(end 235.724192 -61.548264)
		(stroke
			(width 0.2)
			(type default)
		)
		(layer "In6.Cu")
	)
	(gr_line
		(start 235.724192 -57.548272)
		(end 235.725208 -57.550304)
		(stroke
			(width 0.2)
			(type default)
		)
		(layer "In6.Cu")
	)
	(gr_line
		(start 235.724192 -57.548018)
		(end 235.724192 -57.548272)
		(stroke
			(width 0.2)
			(type default)
		)
		(layer "In6.Cu")
	)
	(gr_line
		(start 235.724192 -53.54828)
		(end 235.725208 -53.550312)
		(stroke
			(width 0.2)
			(type default)
		)
		(layer "In6.Cu")
	)
	(gr_line
		(start 235.724192 -53.548026)
		(end 235.724192 -53.54828)
		(stroke
			(width 0.2)
			(type default)
		)
		(layer "In6.Cu")
	)
	(gr_line
		(start 235.724192 -49.548288)
		(end 235.725208 -49.55032)
		(stroke
			(width 0.2)
			(type default)
		)
		(layer "In6.Cu")
	)
	(gr_line
		(start 235.724192 -49.548034)
		(end 235.724192 -49.548288)
		(stroke
			(width 0.2)
			(type default)
		)
		(layer "In6.Cu")
	)
	(gr_line
		(start 235.724192 -45.548296)
		(end 235.725208 -45.550328)
		(stroke
			(width 0.2)
			(type default)
		)
		(layer "In6.Cu")
	)
	(gr_line
		(start 235.724192 -45.548042)
		(end 235.724192 -45.548296)
		(stroke
			(width 0.2)
			(type default)
		)
		(layer "In6.Cu")
	)
	(gr_line
		(start 235.724192 -41.548304)
		(end 235.725208 -41.550336)
		(stroke
			(width 0.2)
			(type default)
		)
		(layer "In6.Cu")
	)
	(gr_line
		(start 235.724192 -41.54805)
		(end 235.724192 -41.548304)
		(stroke
			(width 0.2)
			(type default)
		)
		(layer "In6.Cu")
	)
	(gr_line
		(start 235.724192 -37.548312)
		(end 235.725208 -37.550344)
		(stroke
			(width 0.2)
			(type default)
		)
		(layer "In6.Cu")
	)
	(gr_line
		(start 235.724192 -37.548058)
		(end 235.724192 -37.548312)
		(stroke
			(width 0.2)
			(type default)
		)
		(layer "In6.Cu")
	)
	(gr_line
		(start 235.724192 -17.548352)
		(end 235.725208 -17.550384)
		(stroke
			(width 0.2)
			(type default)
		)
		(layer "In6.Cu")
	)
	(gr_line
		(start 235.724192 -17.548098)
		(end 235.724192 -17.548352)
		(stroke
			(width 0.2)
			(type default)
		)
		(layer "In6.Cu")
	)
	(gr_arc
		(start 235.725208 -177.850038)
		(mid 235.400342 -178.824636)
		(end 236.37494 -179.149502)
		(stroke
			(width 0.2)
			(type default)
		)
		(layer "In6.Cu")
	)
	(gr_arc
		(start 235.725208 -173.850046)
		(mid 235.400342 -174.824644)
		(end 236.37494 -175.14951)
		(stroke
			(width 0.2)
			(type default)
		)
		(layer "In6.Cu")
	)
	(gr_arc
		(start 235.725208 -169.850054)
		(mid 235.400342 -170.824652)
		(end 236.37494 -171.149518)
		(stroke
			(width 0.2)
			(type default)
		)
		(layer "In6.Cu")
	)
	(gr_arc
		(start 235.725208 -165.850062)
		(mid 235.400342 -166.82466)
		(end 236.37494 -167.149526)
		(stroke
			(width 0.2)
			(type default)
		)
		(layer "In6.Cu")
	)
	(gr_arc
		(start 235.725208 -137.850118)
		(mid 235.400342 -138.824716)
		(end 236.37494 -139.149582)
		(stroke
			(width 0.2)
			(type default)
		)
		(layer "In6.Cu")
	)
	(gr_arc
		(start 235.725208 -81.550256)
		(mid 235.400342 -82.524854)
		(end 236.37494 -82.84972)
		(stroke
			(width 0.2)
			(type default)
		)
		(layer "In6.Cu")
	)
	(gr_arc
		(start 235.725208 -77.550264)
		(mid 235.400342 -78.524862)
		(end 236.37494 -78.849728)
		(stroke
			(width 0.2)
			(type default)
		)
		(layer "In6.Cu")
	)
	(gr_arc
		(start 235.725208 -73.550272)
		(mid 235.400342 -74.52487)
		(end 236.37494 -74.849736)
		(stroke
			(width 0.2)
			(type default)
		)
		(layer "In6.Cu")
	)
	(gr_arc
		(start 235.725208 -69.55028)
		(mid 235.400342 -70.524878)
		(end 236.37494 -70.849744)
		(stroke
			(width 0.2)
			(type default)
		)
		(layer "In6.Cu")
	)
	(gr_arc
		(start 235.725208 -65.550288)
		(mid 235.400342 -66.524886)
		(end 236.37494 -66.849752)
		(stroke
			(width 0.2)
			(type default)
		)
		(layer "In6.Cu")
	)
	(gr_arc
		(start 235.725208 -61.550296)
		(mid 235.400342 -62.524894)
		(end 236.37494 -62.84976)
		(stroke
			(width 0.2)
			(type default)
		)
		(layer "In6.Cu")
	)
	(gr_arc
		(start 235.725208 -57.550304)
		(mid 235.400342 -58.524902)
		(end 236.37494 -58.849768)
		(stroke
			(width 0.2)
			(type default)
		)
		(layer "In6.Cu")
	)
	(gr_arc
		(start 235.725208 -53.550312)
		(mid 235.400342 -54.52491)
		(end 236.37494 -54.849776)
		(stroke
			(width 0.2)
			(type default)
		)
		(layer "In6.Cu")
	)
	(gr_arc
		(start 235.725208 -49.55032)
		(mid 235.400342 -50.524918)
		(end 236.37494 -50.849784)
		(stroke
			(width 0.2)
			(type default)
		)
		(layer "In6.Cu")
	)
	(gr_arc
		(start 235.725208 -45.550328)
		(mid 235.400342 -46.524926)
		(end 236.37494 -46.849792)
		(stroke
			(width 0.2)
			(type default)
		)
		(layer "In6.Cu")
	)
	(gr_arc
		(start 235.725208 -41.550336)
		(mid 235.400342 -42.524934)
		(end 236.37494 -42.8498)
		(stroke
			(width 0.2)
			(type default)
		)
		(layer "In6.Cu")
	)
	(gr_arc
		(start 235.725208 -37.550344)
		(mid 235.400342 -38.524942)
		(end 236.37494 -38.849808)
		(stroke
			(width 0.2)
			(type default)
		)
		(layer "In6.Cu")
	)
	(gr_arc
		(start 235.725208 -17.550384)
		(mid 235.400342 -18.524982)
		(end 236.37494 -18.849848)
		(stroke
			(width 0.2)
			(type default)
		)
		(layer "In6.Cu")
	)
	(gr_arc
		(start 235.733844 -161.840164)
		(mid 235.393447 -162.821194)
		(end 236.377226 -163.154106)
		(stroke
			(width 0.2)
			(type default)
		)
		(layer "In6.Cu")
	)
	(gr_arc
		(start 235.733844 -157.840172)
		(mid 235.393447 -158.821202)
		(end 236.377226 -159.154114)
		(stroke
			(width 0.2)
			(type default)
		)
		(layer "In6.Cu")
	)
	(gr_arc
		(start 235.733844 -153.84018)
		(mid 235.393447 -154.82121)
		(end 236.377226 -155.154122)
		(stroke
			(width 0.2)
			(type default)
		)
		(layer "In6.Cu")
	)
	(gr_arc
		(start 235.733844 -149.840188)
		(mid 235.393447 -150.821218)
		(end 236.377226 -151.15413)
		(stroke
			(width 0.2)
			(type default)
		)
		(layer "In6.Cu")
	)
	(gr_arc
		(start 235.733844 -129.840228)
		(mid 235.393447 -130.821258)
		(end 236.377226 -131.15417)
		(stroke
			(width 0.2)
			(type default)
		)
		(layer "In6.Cu")
	)
	(gr_arc
		(start 235.733844 -125.840236)
		(mid 235.393447 -126.821266)
		(end 236.377226 -127.154178)
		(stroke
			(width 0.2)
			(type default)
		)
		(layer "In6.Cu")
	)
	(gr_arc
		(start 235.733844 -117.840252)
		(mid 235.393447 -118.821282)
		(end 236.377226 -119.154194)
		(stroke
			(width 0.2)
			(type default)
		)
		(layer "In6.Cu")
	)
	(gr_arc
		(start 235.733844 -113.84026)
		(mid 235.393447 -114.82129)
		(end 236.377226 -115.154202)
		(stroke
			(width 0.2)
			(type default)
		)
		(layer "In6.Cu")
	)
	(gr_arc
		(start 235.733844 -11.54049)
		(mid 235.393447 -12.52152)
		(end 236.377226 -12.854432)
		(stroke
			(width 0.2)
			(type default)
		)
		(layer "In6.Cu")
	)
	(gr_line
		(start 236.37494 -179.149502)
		(end 236.37621 -179.151788)
		(stroke
			(width 0.2)
			(type default)
		)
		(layer "In6.Cu")
	)
	(gr_line
		(start 236.37494 -175.14951)
		(end 236.37621 -175.151796)
		(stroke
			(width 0.2)
			(type default)
		)
		(layer "In6.Cu")
	)
	(gr_line
		(start 236.37494 -171.149518)
		(end 236.37621 -171.151804)
		(stroke
			(width 0.2)
			(type default)
		)
		(layer "In6.Cu")
	)
	(gr_line
		(start 236.37494 -167.149526)
		(end 236.37621 -167.151812)
		(stroke
			(width 0.2)
			(type default)
		)
		(layer "In6.Cu")
	)
	(gr_line
		(start 236.37494 -139.149582)
		(end 236.37621 -139.151868)
		(stroke
			(width 0.2)
			(type default)
		)
		(layer "In6.Cu")
	)
	(gr_line
		(start 236.37494 -82.84972)
		(end 236.37621 -82.852006)
		(stroke
			(width 0.2)
			(type default)
		)
		(layer "In6.Cu")
	)
	(gr_line
		(start 236.37494 -78.849728)
		(end 236.37621 -78.852014)
		(stroke
			(width 0.2)
			(type default)
		)
		(layer "In6.Cu")
	)
	(gr_line
		(start 236.37494 -74.849736)
		(end 236.37621 -74.852022)
		(stroke
			(width 0.2)
			(type default)
		)
		(layer "In6.Cu")
	)
	(gr_line
		(start 236.37494 -70.849744)
		(end 236.37621 -70.85203)
		(stroke
			(width 0.2)
			(type default)
		)
		(layer "In6.Cu")
	)
	(gr_line
		(start 236.37494 -66.849752)
		(end 236.37621 -66.852038)
		(stroke
			(width 0.2)
			(type default)
		)
		(layer "In6.Cu")
	)
	(gr_line
		(start 236.37494 -62.84976)
		(end 236.37621 -62.852046)
		(stroke
			(width 0.2)
			(type default)
		)
		(layer "In6.Cu")
	)
	(gr_line
		(start 236.37494 -58.849768)
		(end 236.37621 -58.852054)
		(stroke
			(width 0.2)
			(type default)
		)
		(layer "In6.Cu")
	)
	(gr_line
		(start 236.37494 -54.849776)
		(end 236.37621 -54.852062)
		(stroke
			(width 0.2)
			(type default)
		)
		(layer "In6.Cu")
	)
	(gr_line
		(start 236.37494 -50.849784)
		(end 236.37621 -50.85207)
		(stroke
			(width 0.2)
			(type default)
		)
		(layer "In6.Cu")
	)
	(gr_line
		(start 236.37494 -46.849792)
		(end 236.37621 -46.852078)
		(stroke
			(width 0.2)
			(type default)
		)
		(layer "In6.Cu")
	)
	(gr_line
		(start 236.37494 -42.8498)
		(end 236.37621 -42.852086)
		(stroke
			(width 0.2)
			(type default)
		)
		(layer "In6.Cu")
	)
	(gr_line
		(start 236.37494 -38.849808)
		(end 236.37621 -38.852094)
		(stroke
			(width 0.2)
			(type default)
		)
		(layer "In6.Cu")
	)
	(gr_line
		(start 236.37494 -18.849848)
		(end 236.37621 -18.852134)
		(stroke
			(width 0.2)
			(type default)
		)
		(layer "In6.Cu")
	)
	(gr_line
		(start 236.37621 -179.151788)
		(end 238.376206 -178.15179)
		(stroke
			(width 0.2)
			(type default)
		)
		(layer "In6.Cu")
	)
	(gr_line
		(start 236.37621 -175.151796)
		(end 238.376206 -174.151798)
		(stroke
			(width 0.2)
			(type default)
		)
		(layer "In6.Cu")
	)
	(gr_line
		(start 236.37621 -171.151804)
		(end 238.376206 -170.151806)
		(stroke
			(width 0.2)
			(type default)
		)
		(layer "In6.Cu")
	)
	(gr_line
		(start 236.37621 -167.151812)
		(end 238.376206 -166.151814)
		(stroke
			(width 0.2)
			(type default)
		)
		(layer "In6.Cu")
	)
	(gr_line
		(start 236.37621 -139.151868)
		(end 238.376206 -138.15187)
		(stroke
			(width 0.2)
			(type default)
		)
		(layer "In6.Cu")
	)
	(gr_line
		(start 236.37621 -82.852006)
		(end 238.376206 -81.852008)
		(stroke
			(width 0.2)
			(type default)
		)
		(layer "In6.Cu")
	)
	(gr_line
		(start 236.37621 -78.852014)
		(end 238.376206 -77.852016)
		(stroke
			(width 0.2)
			(type default)
		)
		(layer "In6.Cu")
	)
	(gr_line
		(start 236.37621 -74.852022)
		(end 238.376206 -73.852024)
		(stroke
			(width 0.2)
			(type default)
		)
		(layer "In6.Cu")
	)
	(gr_line
		(start 236.37621 -70.85203)
		(end 238.376206 -69.852032)
		(stroke
			(width 0.2)
			(type default)
		)
		(layer "In6.Cu")
	)
	(gr_line
		(start 236.37621 -66.852038)
		(end 238.375952 -65.85204)
		(stroke
			(width 0.2)
			(type default)
		)
		(layer "In6.Cu")
	)
	(gr_line
		(start 236.37621 -62.852046)
		(end 238.376206 -61.852048)
		(stroke
			(width 0.2)
			(type default)
		)
		(layer "In6.Cu")
	)
	(gr_line
		(start 236.37621 -58.852054)
		(end 238.376206 -57.852056)
		(stroke
			(width 0.2)
			(type default)
		)
		(layer "In6.Cu")
	)
	(gr_line
		(start 236.37621 -54.852062)
		(end 238.376206 -53.852064)
		(stroke
			(width 0.2)
			(type default)
		)
		(layer "In6.Cu")
	)
	(gr_line
		(start 236.37621 -50.85207)
		(end 238.376206 -49.852072)
		(stroke
			(width 0.2)
			(type default)
		)
		(layer "In6.Cu")
	)
	(gr_line
		(start 236.37621 -46.852078)
		(end 238.376206 -45.85208)
		(stroke
			(width 0.2)
			(type default)
		)
		(layer "In6.Cu")
	)
	(gr_line
		(start 236.37621 -42.852086)
		(end 238.376206 -41.852088)
		(stroke
			(width 0.2)
			(type default)
		)
		(layer "In6.Cu")
	)
	(gr_line
		(start 236.37621 -38.852094)
		(end 238.376206 -37.852096)
		(stroke
			(width 0.2)
			(type default)
		)
		(layer "In6.Cu")
	)
	(gr_line
		(start 236.37621 -18.852134)
		(end 238.376206 -17.852136)
		(stroke
			(width 0.2)
			(type default)
		)
		(layer "In6.Cu")
	)
	(gr_line
		(start 236.377226 -163.154106)
		(end 238.377222 -162.154108)
		(stroke
			(width 0.2)
			(type default)
		)
		(layer "In6.Cu")
	)
	(gr_line
		(start 236.377226 -159.154114)
		(end 238.377222 -158.154116)
		(stroke
			(width 0.2)
			(type default)
		)
		(layer "In6.Cu")
	)
	(gr_line
		(start 236.377226 -155.154122)
		(end 238.377222 -154.154124)
		(stroke
			(width 0.2)
			(type default)
		)
		(layer "In6.Cu")
	)
	(gr_line
		(start 236.377226 -151.15413)
		(end 238.377222 -150.154132)
		(stroke
			(width 0.2)
			(type default)
		)
		(layer "In6.Cu")
	)
	(gr_line
		(start 236.377226 -131.15417)
		(end 238.377222 -130.154172)
		(stroke
			(width 0.2)
			(type default)
		)
		(layer "In6.Cu")
	)
	(gr_line
		(start 236.377226 -127.154178)
		(end 238.377222 -126.15418)
		(stroke
			(width 0.2)
			(type default)
		)
		(layer "In6.Cu")
	)
	(gr_line
		(start 236.377226 -123.154186)
		(end 238.3663 -122.159522)
		(stroke
			(width 0.2)
			(type default)
		)
		(layer "In6.Cu")
	)
	(gr_line
		(start 236.377226 -119.154194)
		(end 238.377222 -118.154196)
		(stroke
			(width 0.2)
			(type default)
		)
		(layer "In6.Cu")
	)
	(gr_line
		(start 236.377226 -115.154202)
		(end 238.377222 -114.154204)
		(stroke
			(width 0.2)
			(type default)
		)
		(layer "In6.Cu")
	)
	(gr_line
		(start 236.377226 -12.854432)
		(end 238.377222 -11.854434)
		(stroke
			(width 0.2)
			(type default)
		)
		(layer "In6.Cu")
	)
	(gr_line
		(start 237.722918 -160.8455)
		(end 235.733844 -161.840164)
		(stroke
			(width 0.2)
			(type default)
		)
		(layer "In6.Cu")
	)
	(gr_line
		(start 237.722918 -156.845508)
		(end 235.733844 -157.840172)
		(stroke
			(width 0.2)
			(type default)
		)
		(layer "In6.Cu")
	)
	(gr_line
		(start 237.722918 -152.845516)
		(end 235.733844 -153.84018)
		(stroke
			(width 0.2)
			(type default)
		)
		(layer "In6.Cu")
	)
	(gr_line
		(start 237.722918 -148.845524)
		(end 235.733844 -149.840188)
		(stroke
			(width 0.2)
			(type default)
		)
		(layer "In6.Cu")
	)
	(gr_line
		(start 237.722918 -128.845564)
		(end 235.733844 -129.840228)
		(stroke
			(width 0.2)
			(type default)
		)
		(layer "In6.Cu")
	)
	(gr_line
		(start 237.722918 -124.845572)
		(end 235.733844 -125.840236)
		(stroke
			(width 0.2)
			(type default)
		)
		(layer "In6.Cu")
	)
	(gr_line
		(start 237.722918 -120.84558)
		(end 235.722922 -121.845578)
		(stroke
			(width 0.2)
			(type default)
		)
		(layer "In6.Cu")
	)
	(gr_line
		(start 237.722918 -116.845588)
		(end 235.733844 -117.840252)
		(stroke
			(width 0.2)
			(type default)
		)
		(layer "In6.Cu")
	)
	(gr_line
		(start 237.722918 -112.845596)
		(end 235.733844 -113.84026)
		(stroke
			(width 0.2)
			(type default)
		)
		(layer "In6.Cu")
	)
	(gr_line
		(start 237.722918 -10.545826)
		(end 235.733844 -11.54049)
		(stroke
			(width 0.2)
			(type default)
		)
		(layer "In6.Cu")
	)
	(gr_line
		(start 237.723934 -176.847754)
		(end 235.724192 -177.847752)
		(stroke
			(width 0.2)
			(type default)
		)
		(layer "In6.Cu")
	)
	(gr_line
		(start 237.723934 -172.847762)
		(end 235.724192 -173.84776)
		(stroke
			(width 0.2)
			(type default)
		)
		(layer "In6.Cu")
	)
	(gr_line
		(start 237.723934 -168.84777)
		(end 235.724192 -169.847768)
		(stroke
			(width 0.2)
			(type default)
		)
		(layer "In6.Cu")
	)
	(gr_line
		(start 237.723934 -164.847778)
		(end 235.724192 -165.847776)
		(stroke
			(width 0.2)
			(type default)
		)
		(layer "In6.Cu")
	)
	(gr_line
		(start 237.723934 -136.847834)
		(end 235.724192 -137.847832)
		(stroke
			(width 0.2)
			(type default)
		)
		(layer "In6.Cu")
	)
	(gr_line
		(start 237.723934 -80.547972)
		(end 235.724192 -81.54797)
		(stroke
			(width 0.2)
			(type default)
		)
		(layer "In6.Cu")
	)
	(gr_line
		(start 237.723934 -76.54798)
		(end 235.724192 -77.547978)
		(stroke
			(width 0.2)
			(type default)
		)
		(layer "In6.Cu")
	)
	(gr_line
		(start 237.723934 -72.547988)
		(end 235.724192 -73.547986)
		(stroke
			(width 0.2)
			(type default)
		)
		(layer "In6.Cu")
	)
	(gr_line
		(start 237.723934 -68.547996)
		(end 235.724192 -69.547994)
		(stroke
			(width 0.2)
			(type default)
		)
		(layer "In6.Cu")
	)
	(gr_line
		(start 237.723934 -64.548004)
		(end 235.723938 -65.548002)
		(stroke
			(width 0.2)
			(type default)
		)
		(layer "In6.Cu")
	)
	(gr_line
		(start 237.723934 -60.548012)
		(end 235.724192 -61.54801)
		(stroke
			(width 0.2)
			(type default)
		)
		(layer "In6.Cu")
	)
	(gr_line
		(start 237.723934 -56.54802)
		(end 235.724192 -57.548018)
		(stroke
			(width 0.2)
			(type default)
		)
		(layer "In6.Cu")
	)
	(gr_line
		(start 237.723934 -52.548028)
		(end 235.724192 -53.548026)
		(stroke
			(width 0.2)
			(type default)
		)
		(layer "In6.Cu")
	)
	(gr_line
		(start 237.723934 -48.548036)
		(end 235.724192 -49.548034)
		(stroke
			(width 0.2)
			(type default)
		)
		(layer "In6.Cu")
	)
	(gr_line
		(start 237.723934 -44.548044)
		(end 235.724192 -45.548042)
		(stroke
			(width 0.2)
			(type default)
		)
		(layer "In6.Cu")
	)
	(gr_line
		(start 237.723934 -40.548052)
		(end 235.724192 -41.54805)
		(stroke
			(width 0.2)
			(type default)
		)
		(layer "In6.Cu")
	)
	(gr_line
		(start 237.723934 -36.54806)
		(end 235.724192 -37.548058)
		(stroke
			(width 0.2)
			(type default)
		)
		(layer "In6.Cu")
	)
	(gr_line
		(start 237.723934 -16.5481)
		(end 235.724192 -17.548098)
		(stroke
			(width 0.2)
			(type default)
		)
		(layer "In6.Cu")
	)
	(gr_line
		(start 237.725204 -176.85004)
		(end 237.723934 -176.847754)
		(stroke
			(width 0.2)
			(type default)
		)
		(layer "In6.Cu")
	)
	(gr_line
		(start 237.725204 -172.850048)
		(end 237.723934 -172.847762)
		(stroke
			(width 0.2)
			(type default)
		)
		(layer "In6.Cu")
	)
	(gr_line
		(start 237.725204 -168.850056)
		(end 237.723934 -168.84777)
		(stroke
			(width 0.2)
			(type default)
		)
		(layer "In6.Cu")
	)
	(gr_line
		(start 237.725204 -164.850064)
		(end 237.723934 -164.847778)
		(stroke
			(width 0.2)
			(type default)
		)
		(layer "In6.Cu")
	)
	(gr_line
		(start 237.725204 -136.85012)
		(end 237.723934 -136.847834)
		(stroke
			(width 0.2)
			(type default)
		)
		(layer "In6.Cu")
	)
	(gr_line
		(start 237.725204 -80.550258)
		(end 237.723934 -80.547972)
		(stroke
			(width 0.2)
			(type default)
		)
		(layer "In6.Cu")
	)
	(gr_line
		(start 237.725204 -76.550266)
		(end 237.723934 -76.54798)
		(stroke
			(width 0.2)
			(type default)
		)
		(layer "In6.Cu")
	)
	(gr_line
		(start 237.725204 -72.550274)
		(end 237.723934 -72.547988)
		(stroke
			(width 0.2)
			(type default)
		)
		(layer "In6.Cu")
	)
	(gr_line
		(start 237.725204 -68.550282)
		(end 237.723934 -68.547996)
		(stroke
			(width 0.2)
			(type default)
		)
		(layer "In6.Cu")
	)
	(gr_line
		(start 237.725204 -64.55029)
		(end 237.723934 -64.548004)
		(stroke
			(width 0.2)
			(type default)
		)
		(layer "In6.Cu")
	)
	(gr_line
		(start 237.725204 -60.550298)
		(end 237.723934 -60.548012)
		(stroke
			(width 0.2)
			(type default)
		)
		(layer "In6.Cu")
	)
	(gr_line
		(start 237.725204 -56.550306)
		(end 237.723934 -56.54802)
		(stroke
			(width 0.2)
			(type default)
		)
		(layer "In6.Cu")
	)
	(gr_line
		(start 237.725204 -52.550314)
		(end 237.723934 -52.548028)
		(stroke
			(width 0.2)
			(type default)
		)
		(layer "In6.Cu")
	)
	(gr_line
		(start 237.725204 -48.550322)
		(end 237.723934 -48.548036)
		(stroke
			(width 0.2)
			(type default)
		)
		(layer "In6.Cu")
	)
	(gr_line
		(start 237.725204 -44.55033)
		(end 237.723934 -44.548044)
		(stroke
			(width 0.2)
			(type default)
		)
		(layer "In6.Cu")
	)
	(gr_line
		(start 237.725204 -40.550338)
		(end 237.723934 -40.548052)
		(stroke
			(width 0.2)
			(type default)
		)
		(layer "In6.Cu")
	)
	(gr_line
		(start 237.725204 -36.550346)
		(end 237.723934 -36.54806)
		(stroke
			(width 0.2)
			(type default)
		)
		(layer "In6.Cu")
	)
	(gr_line
		(start 237.725204 -16.550386)
		(end 237.723934 -16.5481)
		(stroke
			(width 0.2)
			(type default)
		)
		(layer "In6.Cu")
	)
	(gr_arc
		(start 238.3663 -122.159522)
		(mid 238.706697 -121.178492)
		(end 237.722918 -120.84558)
		(stroke
			(width 0.2)
			(type default)
		)
		(layer "In6.Cu")
	)
	(gr_arc
		(start 238.374936 -178.149504)
		(mid 238.699802 -177.174906)
		(end 237.725204 -176.85004)
		(stroke
			(width 0.2)
			(type default)
		)
		(layer "In6.Cu")
	)
	(gr_arc
		(start 238.374936 -174.149512)
		(mid 238.699802 -173.174914)
		(end 237.725204 -172.850048)
		(stroke
			(width 0.2)
			(type default)
		)
		(layer "In6.Cu")
	)
	(gr_arc
		(start 238.374936 -170.14952)
		(mid 238.699802 -169.174922)
		(end 237.725204 -168.850056)
		(stroke
			(width 0.2)
			(type default)
		)
		(layer "In6.Cu")
	)
	(gr_arc
		(start 238.374936 -166.149528)
		(mid 238.699802 -165.17493)
		(end 237.725204 -164.850064)
		(stroke
			(width 0.2)
			(type default)
		)
		(layer "In6.Cu")
	)
	(gr_arc
		(start 238.374936 -138.149584)
		(mid 238.699802 -137.174986)
		(end 237.725204 -136.85012)
		(stroke
			(width 0.2)
			(type default)
		)
		(layer "In6.Cu")
	)
	(gr_arc
		(start 238.374936 -81.849722)
		(mid 238.699802 -80.875124)
		(end 237.725204 -80.550258)
		(stroke
			(width 0.2)
			(type default)
		)
		(layer "In6.Cu")
	)
	(gr_arc
		(start 238.374936 -77.84973)
		(mid 238.699802 -76.875132)
		(end 237.725204 -76.550266)
		(stroke
			(width 0.2)
			(type default)
		)
		(layer "In6.Cu")
	)
	(gr_arc
		(start 238.374936 -73.849738)
		(mid 238.699802 -72.87514)
		(end 237.725204 -72.550274)
		(stroke
			(width 0.2)
			(type default)
		)
		(layer "In6.Cu")
	)
	(gr_arc
		(start 238.374936 -69.849746)
		(mid 238.699802 -68.875148)
		(end 237.725204 -68.550282)
		(stroke
			(width 0.2)
			(type default)
		)
		(layer "In6.Cu")
	)
	(gr_arc
		(start 238.374936 -65.849754)
		(mid 238.699802 -64.875156)
		(end 237.725204 -64.55029)
		(stroke
			(width 0.2)
			(type default)
		)
		(layer "In6.Cu")
	)
	(gr_arc
		(start 238.374936 -61.849762)
		(mid 238.699802 -60.875164)
		(end 237.725204 -60.550298)
		(stroke
			(width 0.2)
			(type default)
		)
		(layer "In6.Cu")
	)
	(gr_arc
		(start 238.374936 -57.84977)
		(mid 238.699802 -56.875172)
		(end 237.725204 -56.550306)
		(stroke
			(width 0.2)
			(type default)
		)
		(layer "In6.Cu")
	)
	(gr_arc
		(start 238.374936 -53.849778)
		(mid 238.699802 -52.87518)
		(end 237.725204 -52.550314)
		(stroke
			(width 0.2)
			(type default)
		)
		(layer "In6.Cu")
	)
	(gr_arc
		(start 238.374936 -49.849786)
		(mid 238.699802 -48.875188)
		(end 237.725204 -48.550322)
		(stroke
			(width 0.2)
			(type default)
		)
		(layer "In6.Cu")
	)
	(gr_arc
		(start 238.374936 -45.849794)
		(mid 238.699802 -44.875196)
		(end 237.725204 -44.55033)
		(stroke
			(width 0.2)
			(type default)
		)
		(layer "In6.Cu")
	)
	(gr_arc
		(start 238.374936 -41.849802)
		(mid 238.699802 -40.875204)
		(end 237.725204 -40.550338)
		(stroke
			(width 0.2)
			(type default)
		)
		(layer "In6.Cu")
	)
	(gr_arc
		(start 238.374936 -37.84981)
		(mid 238.699802 -36.875212)
		(end 237.725204 -36.550346)
		(stroke
			(width 0.2)
			(type default)
		)
		(layer "In6.Cu")
	)
	(gr_arc
		(start 238.374936 -17.84985)
		(mid 238.699802 -16.875252)
		(end 237.725204 -16.550386)
		(stroke
			(width 0.2)
			(type default)
		)
		(layer "In6.Cu")
	)
	(gr_line
		(start 238.375952 -65.85204)
		(end 238.375952 -65.851786)
		(stroke
			(width 0.2)
			(type default)
		)
		(layer "In6.Cu")
	)
	(gr_line
		(start 238.375952 -65.851786)
		(end 238.374936 -65.849754)
		(stroke
			(width 0.2)
			(type default)
		)
		(layer "In6.Cu")
	)
	(gr_line
		(start 238.376206 -178.15179)
		(end 238.374936 -178.149504)
		(stroke
			(width 0.2)
			(type default)
		)
		(layer "In6.Cu")
	)
	(gr_line
		(start 238.376206 -174.151798)
		(end 238.374936 -174.149512)
		(stroke
			(width 0.2)
			(type default)
		)
		(layer "In6.Cu")
	)
	(gr_line
		(start 238.376206 -170.151806)
		(end 238.374936 -170.14952)
		(stroke
			(width 0.2)
			(type default)
		)
		(layer "In6.Cu")
	)
	(gr_line
		(start 238.376206 -166.151814)
		(end 238.374936 -166.149528)
		(stroke
			(width 0.2)
			(type default)
		)
		(layer "In6.Cu")
	)
	(gr_line
		(start 238.376206 -138.15187)
		(end 238.374936 -138.149584)
		(stroke
			(width 0.2)
			(type default)
		)
		(layer "In6.Cu")
	)
	(gr_line
		(start 238.376206 -81.852008)
		(end 238.374936 -81.849722)
		(stroke
			(width 0.2)
			(type default)
		)
		(layer "In6.Cu")
	)
	(gr_line
		(start 238.376206 -77.852016)
		(end 238.374936 -77.84973)
		(stroke
			(width 0.2)
			(type default)
		)
		(layer "In6.Cu")
	)
	(gr_line
		(start 238.376206 -73.852024)
		(end 238.374936 -73.849738)
		(stroke
			(width 0.2)
			(type default)
		)
		(layer "In6.Cu")
	)
	(gr_line
		(start 238.376206 -69.852032)
		(end 238.374936 -69.849746)
		(stroke
			(width 0.2)
			(type default)
		)
		(layer "In6.Cu")
	)
	(gr_line
		(start 238.376206 -61.852048)
		(end 238.374936 -61.849762)
		(stroke
			(width 0.2)
			(type default)
		)
		(layer "In6.Cu")
	)
	(gr_line
		(start 238.376206 -57.852056)
		(end 238.374936 -57.84977)
		(stroke
			(width 0.2)
			(type default)
		)
		(layer "In6.Cu")
	)
	(gr_line
		(start 238.376206 -53.852064)
		(end 238.374936 -53.849778)
		(stroke
			(width 0.2)
			(type default)
		)
		(layer "In6.Cu")
	)
	(gr_line
		(start 238.376206 -49.852072)
		(end 238.374936 -49.849786)
		(stroke
			(width 0.2)
			(type default)
		)
		(layer "In6.Cu")
	)
	(gr_line
		(start 238.376206 -45.85208)
		(end 238.374936 -45.849794)
		(stroke
			(width 0.2)
			(type default)
		)
		(layer "In6.Cu")
	)
	(gr_line
		(start 238.376206 -41.852088)
		(end 238.374936 -41.849802)
		(stroke
			(width 0.2)
			(type default)
		)
		(layer "In6.Cu")
	)
	(gr_line
		(start 238.376206 -37.852096)
		(end 238.374936 -37.84981)
		(stroke
			(width 0.2)
			(type default)
		)
		(layer "In6.Cu")
	)
	(gr_line
		(start 238.376206 -17.852136)
		(end 238.374936 -17.84985)
		(stroke
			(width 0.2)
			(type default)
		)
		(layer "In6.Cu")
	)
	(gr_arc
		(start 238.377222 -162.154108)
		(mid 238.704374 -161.172652)
		(end 237.722918 -160.8455)
		(stroke
			(width 0.2)
			(type default)
		)
		(layer "In6.Cu")
	)
	(gr_arc
		(start 238.377222 -158.154116)
		(mid 238.704374 -157.17266)
		(end 237.722918 -156.845508)
		(stroke
			(width 0.2)
			(type default)
		)
		(layer "In6.Cu")
	)
	(gr_arc
		(start 238.377222 -154.154124)
		(mid 238.704374 -153.172668)
		(end 237.722918 -152.845516)
		(stroke
			(width 0.2)
			(type default)
		)
		(layer "In6.Cu")
	)
	(gr_arc
		(start 238.377222 -150.154132)
		(mid 238.704374 -149.172676)
		(end 237.722918 -148.845524)
		(stroke
			(width 0.2)
			(type default)
		)
		(layer "In6.Cu")
	)
	(gr_arc
		(start 238.377222 -130.154172)
		(mid 238.704374 -129.172716)
		(end 237.722918 -128.845564)
		(stroke
			(width 0.2)
			(type default)
		)
		(layer "In6.Cu")
	)
	(gr_arc
		(start 238.377222 -126.15418)
		(mid 238.704374 -125.172724)
		(end 237.722918 -124.845572)
		(stroke
			(width 0.2)
			(type default)
		)
		(layer "In6.Cu")
	)
	(gr_arc
		(start 238.377222 -118.154196)
		(mid 238.704374 -117.17274)
		(end 237.722918 -116.845588)
		(stroke
			(width 0.2)
			(type default)
		)
		(layer "In6.Cu")
	)
	(gr_arc
		(start 238.377222 -114.154204)
		(mid 238.704374 -113.172748)
		(end 237.722918 -112.845596)
		(stroke
			(width 0.2)
			(type default)
		)
		(layer "In6.Cu")
	)
	(gr_arc
		(start 238.377222 -11.854434)
		(mid 238.704374 -10.872978)
		(end 237.722918 -10.545826)
		(stroke
			(width 0.2)
			(type default)
		)
		(layer "In6.Cu")
	)
	(gr_line
		(start 240.219484 -128.161034)
		(end 242.21948 -129.161032)
		(stroke
			(width 0.2)
			(type default)
		)
		(layer "In6.Cu")
	)
	(gr_line
		(start 240.219484 -124.161042)
		(end 242.20805 -125.155198)
		(stroke
			(width 0.2)
			(type default)
		)
		(layer "In6.Cu")
	)
	(gr_line
		(start 240.222786 -164.154104)
		(end 242.222782 -165.154102)
		(stroke
			(width 0.2)
			(type default)
		)
		(layer "In6.Cu")
	)
	(gr_line
		(start 240.222786 -160.154112)
		(end 242.222528 -161.15411)
		(stroke
			(width 0.2)
			(type default)
		)
		(layer "In6.Cu")
	)
	(gr_line
		(start 240.222786 -156.15412)
		(end 242.222528 -157.154118)
		(stroke
			(width 0.2)
			(type default)
		)
		(layer "In6.Cu")
	)
	(gr_line
		(start 240.222786 -152.154128)
		(end 242.222782 -153.154126)
		(stroke
			(width 0.2)
			(type default)
		)
		(layer "In6.Cu")
	)
	(gr_line
		(start 240.222786 -120.154192)
		(end 242.222528 -121.15419)
		(stroke
			(width 0.2)
			(type default)
		)
		(layer "In6.Cu")
	)
	(gr_line
		(start 240.222786 -116.1542)
		(end 242.222782 -117.154198)
		(stroke
			(width 0.2)
			(type default)
		)
		(layer "In6.Cu")
	)
	(gr_line
		(start 240.223802 -136.151874)
		(end 242.223798 -137.151872)
		(stroke
			(width 0.2)
			(type default)
		)
		(layer "In6.Cu")
	)
	(gr_line
		(start 240.223802 -108.15193)
		(end 242.223798 -109.151928)
		(stroke
			(width 0.2)
			(type default)
		)
		(layer "In6.Cu")
	)
	(gr_line
		(start 240.223802 -35.8521)
		(end 242.223798 -36.852098)
		(stroke
			(width 0.2)
			(type default)
		)
		(layer "In6.Cu")
	)
	(gr_line
		(start 240.225072 -136.149588)
		(end 240.223802 -136.151874)
		(stroke
			(width 0.2)
			(type default)
		)
		(layer "In6.Cu")
	)
	(gr_line
		(start 240.225072 -108.149644)
		(end 240.223802 -108.15193)
		(stroke
			(width 0.2)
			(type default)
		)
		(layer "In6.Cu")
	)
	(gr_line
		(start 240.236502 -180.126894)
		(end 242.236498 -181.126892)
		(stroke
			(width 0.2)
			(type default)
		)
		(layer "In6.Cu")
	)
	(gr_line
		(start 240.236502 -176.126902)
		(end 242.236498 -177.1269)
		(stroke
			(width 0.2)
			(type default)
		)
		(layer "In6.Cu")
	)
	(gr_line
		(start 240.236502 -172.12691)
		(end 242.236498 -173.126908)
		(stroke
			(width 0.2)
			(type default)
		)
		(layer "In6.Cu")
	)
	(gr_line
		(start 240.236502 -168.126918)
		(end 242.236498 -169.126916)
		(stroke
			(width 0.2)
			(type default)
		)
		(layer "In6.Cu")
	)
	(gr_line
		(start 240.236502 -83.827112)
		(end 242.236498 -84.82711)
		(stroke
			(width 0.2)
			(type default)
		)
		(layer "In6.Cu")
	)
	(gr_line
		(start 240.236502 -79.82712)
		(end 242.228116 -80.8228)
		(stroke
			(width 0.2)
			(type default)
		)
		(layer "In6.Cu")
	)
	(gr_line
		(start 240.236502 -75.827128)
		(end 242.228116 -76.822808)
		(stroke
			(width 0.2)
			(type default)
		)
		(layer "In6.Cu")
	)
	(gr_line
		(start 240.236502 -71.827136)
		(end 242.228116 -72.822816)
		(stroke
			(width 0.2)
			(type default)
		)
		(layer "In6.Cu")
	)
	(gr_line
		(start 240.236502 -67.827144)
		(end 242.236498 -68.827142)
		(stroke
			(width 0.2)
			(type default)
		)
		(layer "In6.Cu")
	)
	(gr_line
		(start 240.236502 -63.827152)
		(end 242.236498 -64.82715)
		(stroke
			(width 0.2)
			(type default)
		)
		(layer "In6.Cu")
	)
	(gr_line
		(start 240.236502 -59.82716)
		(end 242.236498 -60.827158)
		(stroke
			(width 0.2)
			(type default)
		)
		(layer "In6.Cu")
	)
	(gr_line
		(start 240.236502 -55.827168)
		(end 242.236498 -56.827166)
		(stroke
			(width 0.2)
			(type default)
		)
		(layer "In6.Cu")
	)
	(gr_line
		(start 240.236502 -51.827176)
		(end 242.228116 -52.822856)
		(stroke
			(width 0.2)
			(type default)
		)
		(layer "In6.Cu")
	)
	(gr_line
		(start 240.236502 -47.827184)
		(end 242.236498 -48.827182)
		(stroke
			(width 0.2)
			(type default)
		)
		(layer "In6.Cu")
	)
	(gr_line
		(start 240.236502 -43.827192)
		(end 242.236498 -44.82719)
		(stroke
			(width 0.2)
			(type default)
		)
		(layer "In6.Cu")
	)
	(gr_line
		(start 240.236502 -39.8272)
		(end 242.236498 -40.827198)
		(stroke
			(width 0.2)
			(type default)
		)
		(layer "In6.Cu")
	)
	(gr_arc
		(start 240.863374 -78.572868)
		(mid 239.922812 -78.886558)
		(end 240.236502 -79.82712)
		(stroke
			(width 0.2)
			(type default)
		)
		(layer "In6.Cu")
	)
	(gr_arc
		(start 240.863374 -74.572876)
		(mid 239.922812 -74.886566)
		(end 240.236502 -75.827128)
		(stroke
			(width 0.2)
			(type default)
		)
		(layer "In6.Cu")
	)
	(gr_arc
		(start 240.863374 -70.572884)
		(mid 239.922812 -70.886574)
		(end 240.236502 -71.827136)
		(stroke
			(width 0.2)
			(type default)
		)
		(layer "In6.Cu")
	)
	(gr_arc
		(start 240.863374 -50.572924)
		(mid 239.922812 -50.886614)
		(end 240.236502 -51.827176)
		(stroke
			(width 0.2)
			(type default)
		)
		(layer "In6.Cu")
	)
	(gr_arc
		(start 240.871756 -178.87696)
		(mid 239.92498 -179.182145)
		(end 240.236502 -180.126894)
		(stroke
			(width 0.2)
			(type default)
		)
		(layer "In6.Cu")
	)
	(gr_arc
		(start 240.871756 -174.876968)
		(mid 239.92498 -175.182153)
		(end 240.236502 -176.126902)
		(stroke
			(width 0.2)
			(type default)
		)
		(layer "In6.Cu")
	)
	(gr_arc
		(start 240.871756 -170.876976)
		(mid 239.92498 -171.182161)
		(end 240.236502 -172.12691)
		(stroke
			(width 0.2)
			(type default)
		)
		(layer "In6.Cu")
	)
	(gr_arc
		(start 240.871756 -166.876984)
		(mid 239.92498 -167.182169)
		(end 240.236502 -168.126918)
		(stroke
			(width 0.2)
			(type default)
		)
		(layer "In6.Cu")
	)
	(gr_arc
		(start 240.871756 -82.577178)
		(mid 239.92498 -82.882363)
		(end 240.236502 -83.827112)
		(stroke
			(width 0.2)
			(type default)
		)
		(layer "In6.Cu")
	)
	(gr_arc
		(start 240.871756 -66.57721)
		(mid 239.92498 -66.882395)
		(end 240.236502 -67.827144)
		(stroke
			(width 0.2)
			(type default)
		)
		(layer "In6.Cu")
	)
	(gr_arc
		(start 240.871756 -62.577218)
		(mid 239.92498 -62.882403)
		(end 240.236502 -63.827152)
		(stroke
			(width 0.2)
			(type default)
		)
		(layer "In6.Cu")
	)
	(gr_arc
		(start 240.871756 -58.577226)
		(mid 239.92498 -58.882411)
		(end 240.236502 -59.82716)
		(stroke
			(width 0.2)
			(type default)
		)
		(layer "In6.Cu")
	)
	(gr_arc
		(start 240.871756 -54.577234)
		(mid 239.92498 -54.882419)
		(end 240.236502 -55.827168)
		(stroke
			(width 0.2)
			(type default)
		)
		(layer "In6.Cu")
	)
	(gr_arc
		(start 240.871756 -46.57725)
		(mid 239.92498 -46.882435)
		(end 240.236502 -47.827184)
		(stroke
			(width 0.2)
			(type default)
		)
		(layer "In6.Cu")
	)
	(gr_arc
		(start 240.871756 -42.577258)
		(mid 239.92498 -42.882443)
		(end 240.236502 -43.827192)
		(stroke
			(width 0.2)
			(type default)
		)
		(layer "In6.Cu")
	)
	(gr_arc
		(start 240.871756 -38.577266)
		(mid 239.92498 -38.882451)
		(end 240.236502 -39.8272)
		(stroke
			(width 0.2)
			(type default)
		)
		(layer "In6.Cu")
	)
	(gr_arc
		(start 240.874804 -134.850124)
		(mid 239.900206 -135.17499)
		(end 240.225072 -136.149588)
		(stroke
			(width 0.2)
			(type default)
		)
		(layer "In6.Cu")
	)
	(gr_arc
		(start 240.874804 -106.85018)
		(mid 239.900206 -107.175046)
		(end 240.225072 -108.149644)
		(stroke
			(width 0.2)
			(type default)
		)
		(layer "In6.Cu")
	)
	(gr_line
		(start 240.876074 -134.847838)
		(end 240.874804 -134.850124)
		(stroke
			(width 0.2)
			(type default)
		)
		(layer "In6.Cu")
	)
	(gr_line
		(start 240.876074 -106.847894)
		(end 240.874804 -106.85018)
		(stroke
			(width 0.2)
			(type default)
		)
		(layer "In6.Cu")
	)
	(gr_arc
		(start 240.876074 -34.548064)
		(mid 239.89792 -34.873946)
		(end 240.223802 -35.8521)
		(stroke
			(width 0.2)
			(type default)
		)
		(layer "In6.Cu")
	)
	(gr_arc
		(start 240.87709 -158.845504)
		(mid 239.895634 -159.172656)
		(end 240.222786 -160.154112)
		(stroke
			(width 0.2)
			(type default)
		)
		(layer "In6.Cu")
	)
	(gr_arc
		(start 240.87709 -154.845512)
		(mid 239.895634 -155.172664)
		(end 240.222786 -156.15412)
		(stroke
			(width 0.2)
			(type default)
		)
		(layer "In6.Cu")
	)
	(gr_arc
		(start 240.87709 -118.845584)
		(mid 239.895634 -119.172736)
		(end 240.222786 -120.154192)
		(stroke
			(width 0.2)
			(type default)
		)
		(layer "In6.Cu")
	)
	(gr_arc
		(start 240.877344 -162.845496)
		(mid 239.895939 -163.172546)
		(end 240.222786 -164.154104)
		(stroke
			(width 0.2)
			(type default)
		)
		(layer "In6.Cu")
	)
	(gr_arc
		(start 240.877344 -150.84552)
		(mid 239.895939 -151.17257)
		(end 240.222786 -152.154128)
		(stroke
			(width 0.2)
			(type default)
		)
		(layer "In6.Cu")
	)
	(gr_arc
		(start 240.877344 -114.845592)
		(mid 239.895939 -115.172642)
		(end 240.222786 -116.1542)
		(stroke
			(width 0.2)
			(type default)
		)
		(layer "In6.Cu")
	)
	(gr_arc
		(start 240.880392 -122.838718)
		(mid 239.888776 -123.169426)
		(end 240.219484 -124.161042)
		(stroke
			(width 0.2)
			(type default)
		)
		(layer "In6.Cu")
	)
	(gr_arc
		(start 240.891822 -126.844552)
		(mid 239.891674 -127.163691)
		(end 240.219484 -128.161034)
		(stroke
			(width 0.2)
			(type default)
		)
		(layer "In6.Cu")
	)
	(gr_arc
		(start 242.20805 -125.155198)
		(mid 243.208198 -124.836059)
		(end 242.880388 -123.838716)
		(stroke
			(width 0.2)
			(type default)
		)
		(layer "In6.Cu")
	)
	(gr_arc
		(start 242.21948 -129.161032)
		(mid 243.211096 -128.830324)
		(end 242.880388 -127.838708)
		(stroke
			(width 0.2)
			(type default)
		)
		(layer "In6.Cu")
	)
	(gr_arc
		(start 242.222528 -161.15411)
		(mid 243.204289 -160.82711)
		(end 242.877086 -159.845502)
		(stroke
			(width 0.2)
			(type default)
		)
		(layer "In6.Cu")
	)
	(gr_arc
		(start 242.222528 -157.154118)
		(mid 243.204289 -156.827118)
		(end 242.877086 -155.84551)
		(stroke
			(width 0.2)
			(type default)
		)
		(layer "In6.Cu")
	)
	(gr_arc
		(start 242.222528 -121.15419)
		(mid 243.204289 -120.82719)
		(end 242.877086 -119.845582)
		(stroke
			(width 0.2)
			(type default)
		)
		(layer "In6.Cu")
	)
	(gr_arc
		(start 242.222782 -165.154102)
		(mid 243.204238 -164.82695)
		(end 242.877086 -163.845494)
		(stroke
			(width 0.2)
			(type default)
		)
		(layer "In6.Cu")
	)
	(gr_arc
		(start 242.222782 -153.154126)
		(mid 243.204238 -152.826974)
		(end 242.877086 -151.845518)
		(stroke
			(width 0.2)
			(type default)
		)
		(layer "In6.Cu")
	)
	(gr_arc
		(start 242.222782 -117.154198)
		(mid 243.204238 -116.827046)
		(end 242.877086 -115.84559)
		(stroke
			(width 0.2)
			(type default)
		)
		(layer "In6.Cu")
	)
	(gr_line
		(start 242.223798 -137.151872)
		(end 242.224052 -137.151618)
		(stroke
			(width 0.2)
			(type default)
		)
		(layer "In6.Cu")
	)
	(gr_line
		(start 242.223798 -109.151928)
		(end 242.224052 -109.151674)
		(stroke
			(width 0.2)
			(type default)
		)
		(layer "In6.Cu")
	)
	(gr_arc
		(start 242.223798 -36.852098)
		(mid 243.201952 -36.526216)
		(end 242.87607 -35.548062)
		(stroke
			(width 0.2)
			(type default)
		)
		(layer "In6.Cu")
	)
	(gr_line
		(start 242.224052 -137.151618)
		(end 242.225068 -137.149586)
		(stroke
			(width 0.2)
			(type default)
		)
		(layer "In6.Cu")
	)
	(gr_line
		(start 242.224052 -109.151674)
		(end 242.225068 -109.149642)
		(stroke
			(width 0.2)
			(type default)
		)
		(layer "In6.Cu")
	)
	(gr_arc
		(start 242.225068 -137.149586)
		(mid 243.199666 -136.82472)
		(end 242.8748 -135.850122)
		(stroke
			(width 0.2)
			(type default)
		)
		(layer "In6.Cu")
	)
	(gr_arc
		(start 242.225068 -109.149642)
		(mid 243.199666 -108.824776)
		(end 242.8748 -107.850178)
		(stroke
			(width 0.2)
			(type default)
		)
		(layer "In6.Cu")
	)
	(gr_arc
		(start 242.228116 -80.8228)
		(mid 243.174892 -80.517615)
		(end 242.86337 -79.572866)
		(stroke
			(width 0.2)
			(type default)
		)
		(layer "In6.Cu")
	)
	(gr_arc
		(start 242.228116 -76.822808)
		(mid 243.174892 -76.517623)
		(end 242.86337 -75.572874)
		(stroke
			(width 0.2)
			(type default)
		)
		(layer "In6.Cu")
	)
	(gr_arc
		(start 242.228116 -72.822816)
		(mid 243.174892 -72.517631)
		(end 242.86337 -71.572882)
		(stroke
			(width 0.2)
			(type default)
		)
		(layer "In6.Cu")
	)
	(gr_arc
		(start 242.228116 -52.822856)
		(mid 243.174892 -52.517671)
		(end 242.86337 -51.572922)
		(stroke
			(width 0.2)
			(type default)
		)
		(layer "In6.Cu")
	)
	(gr_arc
		(start 242.236498 -181.126892)
		(mid 243.17706 -180.813202)
		(end 242.86337 -179.87264)
		(stroke
			(width 0.2)
			(type default)
		)
		(layer "In6.Cu")
	)
	(gr_arc
		(start 242.236498 -177.1269)
		(mid 243.17706 -176.81321)
		(end 242.86337 -175.872648)
		(stroke
			(width 0.2)
			(type default)
		)
		(layer "In6.Cu")
	)
	(gr_arc
		(start 242.236498 -173.126908)
		(mid 243.17706 -172.813218)
		(end 242.86337 -171.872656)
		(stroke
			(width 0.2)
			(type default)
		)
		(layer "In6.Cu")
	)
	(gr_arc
		(start 242.236498 -169.126916)
		(mid 243.17706 -168.813226)
		(end 242.86337 -167.872664)
		(stroke
			(width 0.2)
			(type default)
		)
		(layer "In6.Cu")
	)
	(gr_arc
		(start 242.236498 -84.82711)
		(mid 243.17706 -84.51342)
		(end 242.86337 -83.572858)
		(stroke
			(width 0.2)
			(type default)
		)
		(layer "In6.Cu")
	)
	(gr_arc
		(start 242.236498 -68.827142)
		(mid 243.17706 -68.513452)
		(end 242.86337 -67.57289)
		(stroke
			(width 0.2)
			(type default)
		)
		(layer "In6.Cu")
	)
	(gr_arc
		(start 242.236498 -64.82715)
		(mid 243.17706 -64.51346)
		(end 242.86337 -63.572898)
		(stroke
			(width 0.2)
			(type default)
		)
		(layer "In6.Cu")
	)
	(gr_arc
		(start 242.236498 -60.827158)
		(mid 243.17706 -60.513468)
		(end 242.86337 -59.572906)
		(stroke
			(width 0.2)
			(type default)
		)
		(layer "In6.Cu")
	)
	(gr_arc
		(start 242.236498 -56.827166)
		(mid 243.17706 -56.513476)
		(end 242.86337 -55.572914)
		(stroke
			(width 0.2)
			(type default)
		)
		(layer "In6.Cu")
	)
	(gr_arc
		(start 242.236498 -48.827182)
		(mid 243.17706 -48.513492)
		(end 242.86337 -47.57293)
		(stroke
			(width 0.2)
			(type default)
		)
		(layer "In6.Cu")
	)
	(gr_arc
		(start 242.236498 -44.82719)
		(mid 243.17706 -44.5135)
		(end 242.86337 -43.572938)
		(stroke
			(width 0.2)
			(type default)
		)
		(layer "In6.Cu")
	)
	(gr_arc
		(start 242.236498 -40.827198)
		(mid 243.17706 -40.513508)
		(end 242.86337 -39.572946)
		(stroke
			(width 0.2)
			(type default)
		)
		(layer "In6.Cu")
	)
	(gr_line
		(start 242.86337 -179.87264)
		(end 240.871756 -178.87696)
		(stroke
			(width 0.2)
			(type default)
		)
		(layer "In6.Cu")
	)
	(gr_line
		(start 242.86337 -175.872648)
		(end 240.871756 -174.876968)
		(stroke
			(width 0.2)
			(type default)
		)
		(layer "In6.Cu")
	)
	(gr_line
		(start 242.86337 -171.872656)
		(end 240.871756 -170.876976)
		(stroke
			(width 0.2)
			(type default)
		)
		(layer "In6.Cu")
	)
	(gr_line
		(start 242.86337 -167.872664)
		(end 240.871756 -166.876984)
		(stroke
			(width 0.2)
			(type default)
		)
		(layer "In6.Cu")
	)
	(gr_line
		(start 242.86337 -83.572858)
		(end 240.871756 -82.577178)
		(stroke
			(width 0.2)
			(type default)
		)
		(layer "In6.Cu")
	)
	(gr_line
		(start 242.86337 -79.572866)
		(end 240.863374 -78.572868)
		(stroke
			(width 0.2)
			(type default)
		)
		(layer "In6.Cu")
	)
	(gr_line
		(start 242.86337 -75.572874)
		(end 240.863374 -74.572876)
		(stroke
			(width 0.2)
			(type default)
		)
		(layer "In6.Cu")
	)
	(gr_line
		(start 242.86337 -71.572882)
		(end 240.863374 -70.572884)
		(stroke
			(width 0.2)
			(type default)
		)
		(layer "In6.Cu")
	)
	(gr_line
		(start 242.86337 -67.57289)
		(end 240.871756 -66.57721)
		(stroke
			(width 0.2)
			(type default)
		)
		(layer "In6.Cu")
	)
	(gr_line
		(start 242.86337 -63.572898)
		(end 240.871756 -62.577218)
		(stroke
			(width 0.2)
			(type default)
		)
		(layer "In6.Cu")
	)
	(gr_line
		(start 242.86337 -59.572906)
		(end 240.871756 -58.577226)
		(stroke
			(width 0.2)
			(type default)
		)
		(layer "In6.Cu")
	)
	(gr_line
		(start 242.86337 -55.572914)
		(end 240.871756 -54.577234)
		(stroke
			(width 0.2)
			(type default)
		)
		(layer "In6.Cu")
	)
	(gr_line
		(start 242.86337 -51.572922)
		(end 240.863374 -50.572924)
		(stroke
			(width 0.2)
			(type default)
		)
		(layer "In6.Cu")
	)
	(gr_line
		(start 242.86337 -47.57293)
		(end 240.871756 -46.57725)
		(stroke
			(width 0.2)
			(type default)
		)
		(layer "In6.Cu")
	)
	(gr_line
		(start 242.86337 -43.572938)
		(end 240.871756 -42.577258)
		(stroke
			(width 0.2)
			(type default)
		)
		(layer "In6.Cu")
	)
	(gr_line
		(start 242.86337 -39.572946)
		(end 240.871756 -38.577266)
		(stroke
			(width 0.2)
			(type default)
		)
		(layer "In6.Cu")
	)
	(gr_line
		(start 242.8748 -135.850122)
		(end 242.87607 -135.847836)
		(stroke
			(width 0.2)
			(type default)
		)
		(layer "In6.Cu")
	)
	(gr_line
		(start 242.8748 -107.850178)
		(end 242.87607 -107.847892)
		(stroke
			(width 0.2)
			(type default)
		)
		(layer "In6.Cu")
	)
	(gr_line
		(start 242.87607 -135.847836)
		(end 240.876074 -134.847838)
		(stroke
			(width 0.2)
			(type default)
		)
		(layer "In6.Cu")
	)
	(gr_line
		(start 242.87607 -107.847892)
		(end 240.876074 -106.847894)
		(stroke
			(width 0.2)
			(type default)
		)
		(layer "In6.Cu")
	)
	(gr_line
		(start 242.87607 -35.548062)
		(end 240.876074 -34.548064)
		(stroke
			(width 0.2)
			(type default)
		)
		(layer "In6.Cu")
	)
	(gr_line
		(start 242.877086 -163.845494)
		(end 240.877344 -162.845496)
		(stroke
			(width 0.2)
			(type default)
		)
		(layer "In6.Cu")
	)
	(gr_line
		(start 242.877086 -159.845502)
		(end 240.87709 -158.845504)
		(stroke
			(width 0.2)
			(type default)
		)
		(layer "In6.Cu")
	)
	(gr_line
		(start 242.877086 -155.84551)
		(end 240.87709 -154.845512)
		(stroke
			(width 0.2)
			(type default)
		)
		(layer "In6.Cu")
	)
	(gr_line
		(start 242.877086 -151.845518)
		(end 240.877344 -150.84552)
		(stroke
			(width 0.2)
			(type default)
		)
		(layer "In6.Cu")
	)
	(gr_line
		(start 242.877086 -119.845582)
		(end 240.87709 -118.845584)
		(stroke
			(width 0.2)
			(type default)
		)
		(layer "In6.Cu")
	)
	(gr_line
		(start 242.877086 -115.84559)
		(end 240.877344 -114.845592)
		(stroke
			(width 0.2)
			(type default)
		)
		(layer "In6.Cu")
	)
	(gr_line
		(start 242.880388 -127.838708)
		(end 240.891822 -126.844552)
		(stroke
			(width 0.2)
			(type default)
		)
		(layer "In6.Cu")
	)
	(gr_line
		(start 242.880388 -123.838716)
		(end 240.880392 -122.838718)
		(stroke
			(width 0.2)
			(type default)
		)
		(layer "In6.Cu")
	)
	(gr_line
		(start 243.9924 -420.2176)
		(end 244.622574 -419.587426)
		(stroke
			(width 0.381)
			(type default)
		)
		(layer "In6.Cu")
	)
	(gr_line
		(start 244.622574 -419.587426)
		(end 244.62359 -419.587426)
		(stroke
			(width 0.381)
			(type default)
		)
		(layer "In6.Cu")
	)
	(gr_line
		(start 244.62359 -420.96436)
		(end 244.62359 -385.814062)
		(stroke
			(width 0.381)
			(type default)
		)
		(layer "In6.Cu")
	)
	(gr_line
		(start 244.62359 -419.587426)
		(end 244.632226 -419.587426)
		(stroke
			(width 0.381)
			(type default)
		)
		(layer "In6.Cu")
	)
	(gr_line
		(start 244.62359 -385.814062)
		(end 251.62129 -378.816362)
		(stroke
			(width 0.381)
			(type default)
		)
		(layer "In6.Cu")
	)
	(gr_line
		(start 244.632226 -419.587426)
		(end 245.2624 -420.2176)
		(stroke
			(width 0.381)
			(type default)
		)
		(layer "In6.Cu")
	)
	(gr_line
		(start 245.2624 -420.2176)
		(end 243.9924 -420.2176)
		(stroke
			(width 0.381)
			(type default)
		)
		(layer "In6.Cu")
	)
	(gr_line
		(start 251.62129 -378.816362)
		(end 251.62129 -218.83751)
		(stroke
			(width 0.381)
			(type default)
		)
		(layer "In6.Cu")
	)
	(gr_line
		(start 251.62129 -218.83751)
		(end 280.3906 -190.0682)
		(stroke
			(width 0.381)
			(type default)
		)
		(layer "In6.Cu")
	)
	(gr_line
		(start 253.111 -182.118)
		(end 210.693 -224.536)
		(stroke
			(width 0.381)
			(type default)
		)
		(layer "In6.Cu")
	)
	(gr_line
		(start 253.111 21.417788)
		(end 253.111 -182.118)
		(stroke
			(width 0.381)
			(type default)
		)
		(layer "In6.Cu")
	)
	(gr_line
		(start 255.086866 23.393654)
		(end 253.111 21.417788)
		(stroke
			(width 0.381)
			(type default)
		)
		(layer "In6.Cu")
	)
	(gr_line
		(start 261.155942 23.878286)
		(end 260.671056 23.3934)
		(stroke
			(width 0.381)
			(type default)
		)
		(layer "In6.Cu")
	)
	(gr_line
		(start 261.261606 23.398226)
		(end 261.25932 23.39594)
		(stroke
			(width 0.381)
			(type default)
		)
		(layer "In6.Cu")
	)
	(gr_line
		(start 261.261606 38.800024)
		(end 261.261606 23.398226)
		(stroke
			(width 0.381)
			(type default)
		)
		(layer "In6.Cu")
	)
	(gr_line
		(start 261.369048 23.878286)
		(end 261.155942 23.878286)
		(stroke
			(width 0.381)
			(type default)
		)
		(layer "In6.Cu")
	)
	(gr_line
		(start 261.851648 23.393654)
		(end 261.851648 23.395686)
		(stroke
			(width 0.381)
			(type default)
		)
		(layer "In6.Cu")
	)
	(gr_line
		(start 261.851648 23.395686)
		(end 261.369048 23.878286)
		(stroke
			(width 0.381)
			(type default)
		)
		(layer "In6.Cu")
	)
	(gr_line
		(start 263.398 -188.722)
		(end 263.398 -1.524)
		(stroke
			(width 0.381)
			(type default)
		)
		(layer "In6.Cu")
	)
	(gr_line
		(start 263.398 -1.524)
		(end 273.177 8.255)
		(stroke
			(width 0.381)
			(type default)
		)
		(layer "In6.Cu")
	)
	(gr_line
		(start 267.436346 23.393654)
		(end 255.086866 23.393654)
		(stroke
			(width 0.381)
			(type default)
		)
		(layer "In6.Cu")
	)
	(gr_line
		(start 270.026384 -359.637076)
		(end 270.026384 -287.007046)
		(stroke
			(width 0.381)
			(type default)
		)
		(layer "In6.Cu")
	)
	(gr_line
		(start 270.026384 -287.007046)
		(end 270.542512 -286.490918)
		(stroke
			(width 0.381)
			(type default)
		)
		(layer "In6.Cu")
	)
	(gr_line
		(start 270.026384 -263.751314)
		(end 270.026384 -237.906052)
		(stroke
			(width 0.381)
			(type default)
		)
		(layer "In6.Cu")
	)
	(gr_line
		(start 270.026384 -237.906052)
		(end 272.949924 -234.982512)
		(stroke
			(width 0.381)
			(type default)
		)
		(layer "In6.Cu")
	)
	(gr_line
		(start 270.542512 -286.490918)
		(end 304.557176 -286.490918)
		(stroke
			(width 0.381)
			(type default)
		)
		(layer "In6.Cu")
	)
	(gr_line
		(start 271.182084 -360.792776)
		(end 270.026384 -359.637076)
		(stroke
			(width 0.381)
			(type default)
		)
		(layer "In6.Cu")
	)
	(gr_line
		(start 271.9705 -359.885996)
		(end 273.1135 -359.885996)
		(stroke
			(width 0.2)
			(type default)
		)
		(layer "In6.Cu")
	)
	(gr_line
		(start 271.9705 -358.085898)
		(end 273.1135 -358.085898)
		(stroke
			(width 0.2)
			(type default)
		)
		(layer "In6.Cu")
	)
	(gr_line
		(start 271.9705 -356.286054)
		(end 273.1135 -356.286054)
		(stroke
			(width 0.2)
			(type default)
		)
		(layer "In6.Cu")
	)
	(gr_line
		(start 271.9705 -354.485956)
		(end 273.1135 -354.485956)
		(stroke
			(width 0.2)
			(type default)
		)
		(layer "In6.Cu")
	)
	(gr_line
		(start 271.9705 -352.686112)
		(end 273.1135 -352.686112)
		(stroke
			(width 0.2)
			(type default)
		)
		(layer "In6.Cu")
	)
	(gr_line
		(start 271.9705 -350.886014)
		(end 273.1135 -350.886014)
		(stroke
			(width 0.2)
			(type default)
		)
		(layer "In6.Cu")
	)
	(gr_line
		(start 271.9705 -338.28863)
		(end 273.1135 -338.28863)
		(stroke
			(width 0.2)
			(type default)
		)
		(layer "In6.Cu")
	)
	(gr_line
		(start 271.9705 -336.488532)
		(end 273.1135 -336.488532)
		(stroke
			(width 0.2)
			(type default)
		)
		(layer "In6.Cu")
	)
	(gr_line
		(start 271.9705 -334.688434)
		(end 273.1135 -334.688434)
		(stroke
			(width 0.2)
			(type default)
		)
		(layer "In6.Cu")
	)
	(gr_line
		(start 271.9705 -332.88859)
		(end 273.1135 -332.88859)
		(stroke
			(width 0.2)
			(type default)
		)
		(layer "In6.Cu")
	)
	(gr_line
		(start 271.9705 -331.088492)
		(end 273.1135 -331.088492)
		(stroke
			(width 0.2)
			(type default)
		)
		(layer "In6.Cu")
	)
	(gr_line
		(start 271.9705 -329.288648)
		(end 273.1135 -329.288648)
		(stroke
			(width 0.2)
			(type default)
		)
		(layer "In6.Cu")
	)
	(gr_line
		(start 271.9705 -316.68847)
		(end 273.1135 -316.68847)
		(stroke
			(width 0.2)
			(type default)
		)
		(layer "In6.Cu")
	)
	(gr_line
		(start 271.9705 -314.888626)
		(end 273.1135 -314.888626)
		(stroke
			(width 0.2)
			(type default)
		)
		(layer "In6.Cu")
	)
	(gr_line
		(start 271.9705 -313.088528)
		(end 273.1135 -313.088528)
		(stroke
			(width 0.2)
			(type default)
		)
		(layer "In6.Cu")
	)
	(gr_line
		(start 271.9705 -311.28843)
		(end 273.1135 -311.28843)
		(stroke
			(width 0.2)
			(type default)
		)
		(layer "In6.Cu")
	)
	(gr_line
		(start 271.9705 -309.488586)
		(end 273.1135 -309.488586)
		(stroke
			(width 0.2)
			(type default)
		)
		(layer "In6.Cu")
	)
	(gr_line
		(start 271.9705 -307.688488)
		(end 273.1135 -307.688488)
		(stroke
			(width 0.2)
			(type default)
		)
		(layer "In6.Cu")
	)
	(gr_arc
		(start 271.970754 -359.123996)
		(mid 271.5895 -359.504869)
		(end 271.9705 -359.885996)
		(stroke
			(width 0.2)
			(type default)
		)
		(layer "In6.Cu")
	)
	(gr_arc
		(start 271.970754 -357.323898)
		(mid 271.5895 -357.704771)
		(end 271.9705 -358.085898)
		(stroke
			(width 0.2)
			(type default)
		)
		(layer "In6.Cu")
	)
	(gr_arc
		(start 271.970754 -355.524054)
		(mid 271.5895 -355.904927)
		(end 271.9705 -356.286054)
		(stroke
			(width 0.2)
			(type default)
		)
		(layer "In6.Cu")
	)
	(gr_arc
		(start 271.970754 -353.723956)
		(mid 271.5895 -354.104829)
		(end 271.9705 -354.485956)
		(stroke
			(width 0.2)
			(type default)
		)
		(layer "In6.Cu")
	)
	(gr_arc
		(start 271.970754 -351.924112)
		(mid 271.5895 -352.304985)
		(end 271.9705 -352.686112)
		(stroke
			(width 0.2)
			(type default)
		)
		(layer "In6.Cu")
	)
	(gr_arc
		(start 271.970754 -350.124014)
		(mid 271.5895 -350.504887)
		(end 271.9705 -350.886014)
		(stroke
			(width 0.2)
			(type default)
		)
		(layer "In6.Cu")
	)
	(gr_arc
		(start 271.970754 -337.52155)
		(mid 271.58696 -337.904963)
		(end 271.9705 -338.28863)
		(stroke
			(width 0.2)
			(type default)
		)
		(layer "In6.Cu")
	)
	(gr_arc
		(start 271.970754 -335.721452)
		(mid 271.58696 -336.104865)
		(end 271.9705 -336.488532)
		(stroke
			(width 0.2)
			(type default)
		)
		(layer "In6.Cu")
	)
	(gr_arc
		(start 271.970754 -333.921354)
		(mid 271.58696 -334.304767)
		(end 271.9705 -334.688434)
		(stroke
			(width 0.2)
			(type default)
		)
		(layer "In6.Cu")
	)
	(gr_arc
		(start 271.970754 -332.12151)
		(mid 271.58696 -332.504923)
		(end 271.9705 -332.88859)
		(stroke
			(width 0.2)
			(type default)
		)
		(layer "In6.Cu")
	)
	(gr_arc
		(start 271.970754 -330.321412)
		(mid 271.58696 -330.704825)
		(end 271.9705 -331.088492)
		(stroke
			(width 0.2)
			(type default)
		)
		(layer "In6.Cu")
	)
	(gr_arc
		(start 271.970754 -328.521568)
		(mid 271.58696 -328.904981)
		(end 271.9705 -329.288648)
		(stroke
			(width 0.2)
			(type default)
		)
		(layer "In6.Cu")
	)
	(gr_arc
		(start 271.970754 -315.92139)
		(mid 271.58696 -316.304803)
		(end 271.9705 -316.68847)
		(stroke
			(width 0.2)
			(type default)
		)
		(layer "In6.Cu")
	)
	(gr_arc
		(start 271.970754 -314.121546)
		(mid 271.58696 -314.504959)
		(end 271.9705 -314.888626)
		(stroke
			(width 0.2)
			(type default)
		)
		(layer "In6.Cu")
	)
	(gr_arc
		(start 271.970754 -312.321448)
		(mid 271.58696 -312.704861)
		(end 271.9705 -313.088528)
		(stroke
			(width 0.2)
			(type default)
		)
		(layer "In6.Cu")
	)
	(gr_arc
		(start 271.970754 -310.52135)
		(mid 271.58696 -310.904763)
		(end 271.9705 -311.28843)
		(stroke
			(width 0.2)
			(type default)
		)
		(layer "In6.Cu")
	)
	(gr_arc
		(start 271.970754 -308.721506)
		(mid 271.58696 -309.104919)
		(end 271.9705 -309.488586)
		(stroke
			(width 0.2)
			(type default)
		)
		(layer "In6.Cu")
	)
	(gr_arc
		(start 271.970754 -306.921408)
		(mid 271.58696 -307.304821)
		(end 271.9705 -307.688488)
		(stroke
			(width 0.2)
			(type default)
		)
		(layer "In6.Cu")
	)
	(gr_line
		(start 272.114518 -265.839448)
		(end 270.026384 -263.751314)
		(stroke
			(width 0.381)
			(type default)
		)
		(layer "In6.Cu")
	)
	(gr_line
		(start 272.949924 -234.982512)
		(end 304.530506 -234.982512)
		(stroke
			(width 0.381)
			(type default)
		)
		(layer "In6.Cu")
	)
	(gr_arc
		(start 273.1135 -359.885996)
		(mid 273.4945 -359.504996)
		(end 273.1135 -359.123996)
		(stroke
			(width 0.2)
			(type default)
		)
		(layer "In6.Cu")
	)
	(gr_line
		(start 273.1135 -359.123996)
		(end 271.970754 -359.123996)
		(stroke
			(width 0.2)
			(type default)
		)
		(layer "In6.Cu")
	)
	(gr_arc
		(start 273.1135 -358.085898)
		(mid 273.4945 -357.704898)
		(end 273.1135 -357.323898)
		(stroke
			(width 0.2)
			(type default)
		)
		(layer "In6.Cu")
	)
	(gr_line
		(start 273.1135 -357.323898)
		(end 271.970754 -357.323898)
		(stroke
			(width 0.2)
			(type default)
		)
		(layer "In6.Cu")
	)
	(gr_arc
		(start 273.1135 -356.286054)
		(mid 273.4945 -355.905054)
		(end 273.1135 -355.524054)
		(stroke
			(width 0.2)
			(type default)
		)
		(layer "In6.Cu")
	)
	(gr_line
		(start 273.1135 -355.524054)
		(end 271.970754 -355.524054)
		(stroke
			(width 0.2)
			(type default)
		)
		(layer "In6.Cu")
	)
	(gr_arc
		(start 273.1135 -354.485956)
		(mid 273.4945 -354.104956)
		(end 273.1135 -353.723956)
		(stroke
			(width 0.2)
			(type default)
		)
		(layer "In6.Cu")
	)
	(gr_line
		(start 273.1135 -353.723956)
		(end 271.970754 -353.723956)
		(stroke
			(width 0.2)
			(type default)
		)
		(layer "In6.Cu")
	)
	(gr_arc
		(start 273.1135 -352.686112)
		(mid 273.4945 -352.305112)
		(end 273.1135 -351.924112)
		(stroke
			(width 0.2)
			(type default)
		)
		(layer "In6.Cu")
	)
	(gr_line
		(start 273.1135 -351.924112)
		(end 271.970754 -351.924112)
		(stroke
			(width 0.2)
			(type default)
		)
		(layer "In6.Cu")
	)
	(gr_arc
		(start 273.1135 -350.886014)
		(mid 273.4945 -350.505014)
		(end 273.1135 -350.124014)
		(stroke
			(width 0.2)
			(type default)
		)
		(layer "In6.Cu")
	)
	(gr_line
		(start 273.1135 -350.124014)
		(end 271.970754 -350.124014)
		(stroke
			(width 0.2)
			(type default)
		)
		(layer "In6.Cu")
	)
	(gr_arc
		(start 273.1135 -338.28863)
		(mid 273.49704 -337.90509)
		(end 273.1135 -337.52155)
		(stroke
			(width 0.2)
			(type default)
		)
		(layer "In6.Cu")
	)
	(gr_line
		(start 273.1135 -337.52155)
		(end 271.970754 -337.52155)
		(stroke
			(width 0.2)
			(type default)
		)
		(layer "In6.Cu")
	)
	(gr_arc
		(start 273.1135 -336.488532)
		(mid 273.49704 -336.104992)
		(end 273.1135 -335.721452)
		(stroke
			(width 0.2)
			(type default)
		)
		(layer "In6.Cu")
	)
	(gr_line
		(start 273.1135 -335.721452)
		(end 271.970754 -335.721452)
		(stroke
			(width 0.2)
			(type default)
		)
		(layer "In6.Cu")
	)
	(gr_arc
		(start 273.1135 -334.688434)
		(mid 273.49704 -334.304894)
		(end 273.1135 -333.921354)
		(stroke
			(width 0.2)
			(type default)
		)
		(layer "In6.Cu")
	)
	(gr_line
		(start 273.1135 -333.921354)
		(end 271.970754 -333.921354)
		(stroke
			(width 0.2)
			(type default)
		)
		(layer "In6.Cu")
	)
	(gr_arc
		(start 273.1135 -332.88859)
		(mid 273.49704 -332.50505)
		(end 273.1135 -332.12151)
		(stroke
			(width 0.2)
			(type default)
		)
		(layer "In6.Cu")
	)
	(gr_line
		(start 273.1135 -332.12151)
		(end 271.970754 -332.12151)
		(stroke
			(width 0.2)
			(type default)
		)
		(layer "In6.Cu")
	)
	(gr_arc
		(start 273.1135 -331.088492)
		(mid 273.49704 -330.704952)
		(end 273.1135 -330.321412)
		(stroke
			(width 0.2)
			(type default)
		)
		(layer "In6.Cu")
	)
	(gr_line
		(start 273.1135 -330.321412)
		(end 271.970754 -330.321412)
		(stroke
			(width 0.2)
			(type default)
		)
		(layer "In6.Cu")
	)
	(gr_arc
		(start 273.1135 -329.288648)
		(mid 273.49704 -328.905108)
		(end 273.1135 -328.521568)
		(stroke
			(width 0.2)
			(type default)
		)
		(layer "In6.Cu")
	)
	(gr_line
		(start 273.1135 -328.521568)
		(end 271.970754 -328.521568)
		(stroke
			(width 0.2)
			(type default)
		)
		(layer "In6.Cu")
	)
	(gr_arc
		(start 273.1135 -316.68847)
		(mid 273.49704 -316.30493)
		(end 273.1135 -315.92139)
		(stroke
			(width 0.2)
			(type default)
		)
		(layer "In6.Cu")
	)
	(gr_line
		(start 273.1135 -315.92139)
		(end 271.970754 -315.92139)
		(stroke
			(width 0.2)
			(type default)
		)
		(layer "In6.Cu")
	)
	(gr_arc
		(start 273.1135 -314.888626)
		(mid 273.49704 -314.505086)
		(end 273.1135 -314.121546)
		(stroke
			(width 0.2)
			(type default)
		)
		(layer "In6.Cu")
	)
	(gr_line
		(start 273.1135 -314.121546)
		(end 271.970754 -314.121546)
		(stroke
			(width 0.2)
			(type default)
		)
		(layer "In6.Cu")
	)
	(gr_arc
		(start 273.1135 -313.088528)
		(mid 273.49704 -312.704988)
		(end 273.1135 -312.321448)
		(stroke
			(width 0.2)
			(type default)
		)
		(layer "In6.Cu")
	)
	(gr_line
		(start 273.1135 -312.321448)
		(end 271.970754 -312.321448)
		(stroke
			(width 0.2)
			(type default)
		)
		(layer "In6.Cu")
	)
	(gr_arc
		(start 273.1135 -311.28843)
		(mid 273.49704 -310.90489)
		(end 273.1135 -310.52135)
		(stroke
			(width 0.2)
			(type default)
		)
		(layer "In6.Cu")
	)
	(gr_line
		(start 273.1135 -310.52135)
		(end 271.970754 -310.52135)
		(stroke
			(width 0.2)
			(type default)
		)
		(layer "In6.Cu")
	)
	(gr_arc
		(start 273.1135 -309.488586)
		(mid 273.49704 -309.105046)
		(end 273.1135 -308.721506)
		(stroke
			(width 0.2)
			(type default)
		)
		(layer "In6.Cu")
	)
	(gr_line
		(start 273.1135 -308.721506)
		(end 271.970754 -308.721506)
		(stroke
			(width 0.2)
			(type default)
		)
		(layer "In6.Cu")
	)
	(gr_arc
		(start 273.1135 -307.688488)
		(mid 273.49704 -307.304948)
		(end 273.1135 -306.921408)
		(stroke
			(width 0.2)
			(type default)
		)
		(layer "In6.Cu")
	)
	(gr_line
		(start 273.1135 -306.921408)
		(end 271.970754 -306.921408)
		(stroke
			(width 0.2)
			(type default)
		)
		(layer "In6.Cu")
	)
	(gr_line
		(start 273.177 8.255)
		(end 273.177 17.653)
		(stroke
			(width 0.381)
			(type default)
		)
		(layer "In6.Cu")
	)
	(gr_line
		(start 273.177 17.653)
		(end 267.436346 23.393654)
		(stroke
			(width 0.381)
			(type default)
		)
		(layer "In6.Cu")
	)
	(gr_line
		(start 276.777958 -420.348664)
		(end 277.408132 -419.71849)
		(stroke
			(width 0.381)
			(type default)
		)
		(layer "In6.Cu")
	)
	(gr_line
		(start 277.241 -84.6582)
		(end 277.241 -6.1722)
		(stroke
			(width 0.381)
			(type default)
		)
		(layer "In6.Cu")
	)
	(gr_line
		(start 277.241 -6.1722)
		(end 278.1808 -5.2324)
		(stroke
			(width 0.381)
			(type default)
		)
		(layer "In6.Cu")
	)
	(gr_line
		(start 277.247858 -186.9186)
		(end 277.933658 -187.6044)
		(stroke
			(width 0.381)
			(type default)
		)
		(layer "In6.Cu")
	)
	(gr_line
		(start 277.247858 -102.46868)
		(end 277.247858 -186.9186)
		(stroke
			(width 0.381)
			(type default)
		)
		(layer "In6.Cu")
	)
	(gr_line
		(start 277.408132 -419.71849)
		(end 277.409148 -419.71849)
		(stroke
			(width 0.381)
			(type default)
		)
		(layer "In6.Cu")
	)
	(gr_line
		(start 277.409148 -420.351966)
		(end 277.409148 -404.429214)
		(stroke
			(width 0.381)
			(type default)
		)
		(layer "In6.Cu")
	)
	(gr_line
		(start 277.409148 -419.71849)
		(end 277.417784 -419.71849)
		(stroke
			(width 0.381)
			(type default)
		)
		(layer "In6.Cu")
	)
	(gr_line
		(start 277.409148 -404.429214)
		(end 287.191958 -394.646404)
		(stroke
			(width 0.381)
			(type default)
		)
		(layer "In6.Cu")
	)
	(gr_line
		(start 277.417784 -419.71849)
		(end 278.047958 -420.348664)
		(stroke
			(width 0.381)
			(type default)
		)
		(layer "In6.Cu")
	)
	(gr_line
		(start 277.7744 -85.1916)
		(end 277.241 -84.6582)
		(stroke
			(width 0.381)
			(type default)
		)
		(layer "In6.Cu")
	)
	(gr_line
		(start 277.933658 -187.6044)
		(end 282.8544 -187.6044)
		(stroke
			(width 0.381)
			(type default)
		)
		(layer "In6.Cu")
	)
	(gr_line
		(start 278.047958 -420.348664)
		(end 276.777958 -420.348664)
		(stroke
			(width 0.381)
			(type default)
		)
		(layer "In6.Cu")
	)
	(gr_line
		(start 278.173942 -101.542596)
		(end 277.247858 -102.46868)
		(stroke
			(width 0.381)
			(type default)
		)
		(layer "In6.Cu")
	)
	(gr_line
		(start 278.1808 -5.2324)
		(end 279.1714 -5.2324)
		(stroke
			(width 0.381)
			(type default)
		)
		(layer "In6.Cu")
	)
	(gr_line
		(start 278.23668 -356.453694)
		(end 279.636728 -356.453694)
		(stroke
			(width 0.2)
			(type default)
		)
		(layer "In6.Cu")
	)
	(gr_arc
		(start 278.23668 -355.356414)
		(mid 277.68804 -355.905054)
		(end 278.23668 -356.453694)
		(stroke
			(width 0.2)
			(type default)
		)
		(layer "In6.Cu")
	)
	(gr_line
		(start 278.23668 -352.853752)
		(end 279.636728 -352.853752)
		(stroke
			(width 0.2)
			(type default)
		)
		(layer "In6.Cu")
	)
	(gr_arc
		(start 278.23668 -351.756472)
		(mid 277.68804 -352.305112)
		(end 278.23668 -352.853752)
		(stroke
			(width 0.2)
			(type default)
		)
		(layer "In6.Cu")
	)
	(gr_line
		(start 278.23668 -349.25381)
		(end 279.636728 -349.25381)
		(stroke
			(width 0.2)
			(type default)
		)
		(layer "In6.Cu")
	)
	(gr_arc
		(start 278.23668 -348.15653)
		(mid 277.68804 -348.70517)
		(end 278.23668 -349.25381)
		(stroke
			(width 0.2)
			(type default)
		)
		(layer "In6.Cu")
	)
	(gr_line
		(start 278.23668 -345.653868)
		(end 279.636728 -345.653868)
		(stroke
			(width 0.2)
			(type default)
		)
		(layer "In6.Cu")
	)
	(gr_arc
		(start 278.23668 -344.556588)
		(mid 277.68804 -345.105228)
		(end 278.23668 -345.653868)
		(stroke
			(width 0.2)
			(type default)
		)
		(layer "In6.Cu")
	)
	(gr_line
		(start 278.23668 -342.053672)
		(end 279.636728 -342.053672)
		(stroke
			(width 0.2)
			(type default)
		)
		(layer "In6.Cu")
	)
	(gr_arc
		(start 278.23668 -340.956392)
		(mid 277.68804 -341.505032)
		(end 278.23668 -342.053672)
		(stroke
			(width 0.2)
			(type default)
		)
		(layer "In6.Cu")
	)
	(gr_line
		(start 278.23668 -338.45373)
		(end 279.636728 -338.45373)
		(stroke
			(width 0.2)
			(type default)
		)
		(layer "In6.Cu")
	)
	(gr_arc
		(start 278.23668 -337.35645)
		(mid 277.68804 -337.90509)
		(end 278.23668 -338.45373)
		(stroke
			(width 0.2)
			(type default)
		)
		(layer "In6.Cu")
	)
	(gr_line
		(start 278.23668 -334.853788)
		(end 279.636728 -334.853788)
		(stroke
			(width 0.2)
			(type default)
		)
		(layer "In6.Cu")
	)
	(gr_arc
		(start 278.23668 -333.756508)
		(mid 277.68804 -334.305148)
		(end 278.23668 -334.853788)
		(stroke
			(width 0.2)
			(type default)
		)
		(layer "In6.Cu")
	)
	(gr_line
		(start 278.23668 -331.253846)
		(end 279.636728 -331.253846)
		(stroke
			(width 0.2)
			(type default)
		)
		(layer "In6.Cu")
	)
	(gr_arc
		(start 278.23668 -330.156566)
		(mid 277.68804 -330.705206)
		(end 278.23668 -331.253846)
		(stroke
			(width 0.2)
			(type default)
		)
		(layer "In6.Cu")
	)
	(gr_line
		(start 278.23668 -327.653904)
		(end 279.636728 -327.653904)
		(stroke
			(width 0.2)
			(type default)
		)
		(layer "In6.Cu")
	)
	(gr_arc
		(start 278.23668 -326.556624)
		(mid 277.68804 -327.105264)
		(end 278.23668 -327.653904)
		(stroke
			(width 0.2)
			(type default)
		)
		(layer "In6.Cu")
	)
	(gr_line
		(start 278.23668 -324.053708)
		(end 279.636728 -324.053708)
		(stroke
			(width 0.2)
			(type default)
		)
		(layer "In6.Cu")
	)
	(gr_arc
		(start 278.23668 -322.956428)
		(mid 277.68804 -323.505068)
		(end 278.23668 -324.053708)
		(stroke
			(width 0.2)
			(type default)
		)
		(layer "In6.Cu")
	)
	(gr_line
		(start 278.23668 -320.453766)
		(end 279.636728 -320.453766)
		(stroke
			(width 0.2)
			(type default)
		)
		(layer "In6.Cu")
	)
	(gr_arc
		(start 278.23668 -319.356486)
		(mid 277.68804 -319.905126)
		(end 278.23668 -320.453766)
		(stroke
			(width 0.2)
			(type default)
		)
		(layer "In6.Cu")
	)
	(gr_line
		(start 278.23668 -316.853824)
		(end 279.636728 -316.853824)
		(stroke
			(width 0.2)
			(type default)
		)
		(layer "In6.Cu")
	)
	(gr_arc
		(start 278.23668 -315.756544)
		(mid 277.68804 -316.305184)
		(end 278.23668 -316.853824)
		(stroke
			(width 0.2)
			(type default)
		)
		(layer "In6.Cu")
	)
	(gr_line
		(start 278.23668 -313.253882)
		(end 279.636728 -313.253882)
		(stroke
			(width 0.2)
			(type default)
		)
		(layer "In6.Cu")
	)
	(gr_arc
		(start 278.23668 -312.156602)
		(mid 277.68804 -312.705242)
		(end 278.23668 -313.253882)
		(stroke
			(width 0.2)
			(type default)
		)
		(layer "In6.Cu")
	)
	(gr_line
		(start 278.23668 -309.653686)
		(end 279.636728 -309.653686)
		(stroke
			(width 0.2)
			(type default)
		)
		(layer "In6.Cu")
	)
	(gr_arc
		(start 278.23668 -308.556406)
		(mid 277.68804 -309.105046)
		(end 278.23668 -309.653686)
		(stroke
			(width 0.2)
			(type default)
		)
		(layer "In6.Cu")
	)
	(gr_line
		(start 278.23668 -306.053744)
		(end 279.636728 -306.053744)
		(stroke
			(width 0.2)
			(type default)
		)
		(layer "In6.Cu")
	)
	(gr_arc
		(start 278.23668 -304.956464)
		(mid 277.68804 -305.505104)
		(end 278.23668 -306.053744)
		(stroke
			(width 0.2)
			(type default)
		)
		(layer "In6.Cu")
	)
	(gr_line
		(start 278.23668 -302.453802)
		(end 279.636728 -302.453802)
		(stroke
			(width 0.2)
			(type default)
		)
		(layer "In6.Cu")
	)
	(gr_arc
		(start 278.23668 -301.356522)
		(mid 277.68804 -301.905162)
		(end 278.23668 -302.453802)
		(stroke
			(width 0.2)
			(type default)
		)
		(layer "In6.Cu")
	)
	(gr_line
		(start 278.23668 -298.85386)
		(end 279.636728 -298.85386)
		(stroke
			(width 0.2)
			(type default)
		)
		(layer "In6.Cu")
	)
	(gr_arc
		(start 278.23668 -297.75658)
		(mid 277.68804 -298.30522)
		(end 278.23668 -298.85386)
		(stroke
			(width 0.2)
			(type default)
		)
		(layer "In6.Cu")
	)
	(gr_line
		(start 278.23668 -295.253918)
		(end 279.636728 -295.253918)
		(stroke
			(width 0.2)
			(type default)
		)
		(layer "In6.Cu")
	)
	(gr_arc
		(start 278.23668 -294.156638)
		(mid 277.68804 -294.705278)
		(end 278.23668 -295.253918)
		(stroke
			(width 0.2)
			(type default)
		)
		(layer "In6.Cu")
	)
	(gr_line
		(start 278.23668 -262.453374)
		(end 279.636728 -262.453374)
		(stroke
			(width 0.2)
			(type default)
		)
		(layer "In6.Cu")
	)
	(gr_arc
		(start 278.23668 -261.351014)
		(mid 277.6855 -261.902194)
		(end 278.23668 -262.453374)
		(stroke
			(width 0.2)
			(type default)
		)
		(layer "In6.Cu")
	)
	(gr_line
		(start 278.23668 -258.853432)
		(end 279.636728 -258.853432)
		(stroke
			(width 0.2)
			(type default)
		)
		(layer "In6.Cu")
	)
	(gr_arc
		(start 278.23668 -257.751072)
		(mid 277.6855 -258.302252)
		(end 278.23668 -258.853432)
		(stroke
			(width 0.2)
			(type default)
		)
		(layer "In6.Cu")
	)
	(gr_line
		(start 278.23668 -255.25349)
		(end 279.636728 -255.25349)
		(stroke
			(width 0.2)
			(type default)
		)
		(layer "In6.Cu")
	)
	(gr_arc
		(start 278.23668 -254.15113)
		(mid 277.6855 -254.70231)
		(end 278.23668 -255.25349)
		(stroke
			(width 0.2)
			(type default)
		)
		(layer "In6.Cu")
	)
	(gr_line
		(start 278.23668 -251.653548)
		(end 279.636728 -251.653548)
		(stroke
			(width 0.2)
			(type default)
		)
		(layer "In6.Cu")
	)
	(gr_arc
		(start 278.23668 -250.551188)
		(mid 277.6855 -251.102368)
		(end 278.23668 -251.653548)
		(stroke
			(width 0.2)
			(type default)
		)
		(layer "In6.Cu")
	)
	(gr_line
		(start 278.236934 -355.356414)
		(end 278.23668 -355.356414)
		(stroke
			(width 0.2)
			(type default)
		)
		(layer "In6.Cu")
	)
	(gr_line
		(start 278.236934 -351.756472)
		(end 278.23668 -351.756472)
		(stroke
			(width 0.2)
			(type default)
		)
		(layer "In6.Cu")
	)
	(gr_line
		(start 278.236934 -348.15653)
		(end 278.23668 -348.15653)
		(stroke
			(width 0.2)
			(type default)
		)
		(layer "In6.Cu")
	)
	(gr_line
		(start 278.236934 -344.556588)
		(end 278.23668 -344.556588)
		(stroke
			(width 0.2)
			(type default)
		)
		(layer "In6.Cu")
	)
	(gr_line
		(start 278.236934 -340.956392)
		(end 278.23668 -340.956392)
		(stroke
			(width 0.2)
			(type default)
		)
		(layer "In6.Cu")
	)
	(gr_line
		(start 278.236934 -337.35645)
		(end 278.23668 -337.35645)
		(stroke
			(width 0.2)
			(type default)
		)
		(layer "In6.Cu")
	)
	(gr_line
		(start 278.236934 -333.756508)
		(end 278.23668 -333.756508)
		(stroke
			(width 0.2)
			(type default)
		)
		(layer "In6.Cu")
	)
	(gr_line
		(start 278.236934 -330.156566)
		(end 278.23668 -330.156566)
		(stroke
			(width 0.2)
			(type default)
		)
		(layer "In6.Cu")
	)
	(gr_line
		(start 278.236934 -326.556624)
		(end 278.23668 -326.556624)
		(stroke
			(width 0.2)
			(type default)
		)
		(layer "In6.Cu")
	)
	(gr_line
		(start 278.236934 -322.956428)
		(end 278.23668 -322.956428)
		(stroke
			(width 0.2)
			(type default)
		)
		(layer "In6.Cu")
	)
	(gr_line
		(start 278.236934 -319.356486)
		(end 278.23668 -319.356486)
		(stroke
			(width 0.2)
			(type default)
		)
		(layer "In6.Cu")
	)
	(gr_line
		(start 278.236934 -315.756544)
		(end 278.23668 -315.756544)
		(stroke
			(width 0.2)
			(type default)
		)
		(layer "In6.Cu")
	)
	(gr_line
		(start 278.236934 -312.156602)
		(end 278.23668 -312.156602)
		(stroke
			(width 0.2)
			(type default)
		)
		(layer "In6.Cu")
	)
	(gr_line
		(start 278.236934 -308.556406)
		(end 278.23668 -308.556406)
		(stroke
			(width 0.2)
			(type default)
		)
		(layer "In6.Cu")
	)
	(gr_line
		(start 278.236934 -304.956464)
		(end 278.23668 -304.956464)
		(stroke
			(width 0.2)
			(type default)
		)
		(layer "In6.Cu")
	)
	(gr_line
		(start 278.236934 -301.356522)
		(end 278.23668 -301.356522)
		(stroke
			(width 0.2)
			(type default)
		)
		(layer "In6.Cu")
	)
	(gr_line
		(start 278.236934 -297.75658)
		(end 278.23668 -297.75658)
		(stroke
			(width 0.2)
			(type default)
		)
		(layer "In6.Cu")
	)
	(gr_line
		(start 278.236934 -294.156638)
		(end 278.23668 -294.156638)
		(stroke
			(width 0.2)
			(type default)
		)
		(layer "In6.Cu")
	)
	(gr_line
		(start 278.236934 -261.351014)
		(end 278.23668 -261.351014)
		(stroke
			(width 0.2)
			(type default)
		)
		(layer "In6.Cu")
	)
	(gr_line
		(start 278.236934 -257.751072)
		(end 278.23668 -257.751072)
		(stroke
			(width 0.2)
			(type default)
		)
		(layer "In6.Cu")
	)
	(gr_line
		(start 278.236934 -254.15113)
		(end 278.23668 -254.15113)
		(stroke
			(width 0.2)
			(type default)
		)
		(layer "In6.Cu")
	)
	(gr_line
		(start 278.236934 -250.551188)
		(end 278.23668 -250.551188)
		(stroke
			(width 0.2)
			(type default)
		)
		(layer "In6.Cu")
	)
	(gr_line
		(start 278.424132 -177.848006)
		(end 278.425148 -177.850038)
		(stroke
			(width 0.2)
			(type default)
		)
		(layer "In6.Cu")
	)
	(gr_line
		(start 278.424132 -177.847752)
		(end 278.424132 -177.848006)
		(stroke
			(width 0.2)
			(type default)
		)
		(layer "In6.Cu")
	)
	(gr_line
		(start 278.424132 -173.848014)
		(end 278.425148 -173.850046)
		(stroke
			(width 0.2)
			(type default)
		)
		(layer "In6.Cu")
	)
	(gr_line
		(start 278.424132 -173.84776)
		(end 278.424132 -173.848014)
		(stroke
			(width 0.2)
			(type default)
		)
		(layer "In6.Cu")
	)
	(gr_line
		(start 278.424132 -169.848022)
		(end 278.425148 -169.850054)
		(stroke
			(width 0.2)
			(type default)
		)
		(layer "In6.Cu")
	)
	(gr_line
		(start 278.424132 -169.847768)
		(end 278.424132 -169.848022)
		(stroke
			(width 0.2)
			(type default)
		)
		(layer "In6.Cu")
	)
	(gr_line
		(start 278.424132 -165.84803)
		(end 278.425148 -165.850062)
		(stroke
			(width 0.2)
			(type default)
		)
		(layer "In6.Cu")
	)
	(gr_line
		(start 278.424132 -165.847776)
		(end 278.424132 -165.84803)
		(stroke
			(width 0.2)
			(type default)
		)
		(layer "In6.Cu")
	)
	(gr_line
		(start 278.424132 -137.848086)
		(end 278.425148 -137.850118)
		(stroke
			(width 0.2)
			(type default)
		)
		(layer "In6.Cu")
	)
	(gr_line
		(start 278.424132 -137.847832)
		(end 278.424132 -137.848086)
		(stroke
			(width 0.2)
			(type default)
		)
		(layer "In6.Cu")
	)
	(gr_line
		(start 278.424132 -81.548224)
		(end 278.425148 -81.550256)
		(stroke
			(width 0.2)
			(type default)
		)
		(layer "In6.Cu")
	)
	(gr_line
		(start 278.424132 -81.54797)
		(end 278.424132 -81.548224)
		(stroke
			(width 0.2)
			(type default)
		)
		(layer "In6.Cu")
	)
	(gr_line
		(start 278.424132 -77.548232)
		(end 278.425148 -77.550264)
		(stroke
			(width 0.2)
			(type default)
		)
		(layer "In6.Cu")
	)
	(gr_line
		(start 278.424132 -77.547978)
		(end 278.424132 -77.548232)
		(stroke
			(width 0.2)
			(type default)
		)
		(layer "In6.Cu")
	)
	(gr_line
		(start 278.424132 -73.54824)
		(end 278.425148 -73.550272)
		(stroke
			(width 0.2)
			(type default)
		)
		(layer "In6.Cu")
	)
	(gr_line
		(start 278.424132 -73.547986)
		(end 278.424132 -73.54824)
		(stroke
			(width 0.2)
			(type default)
		)
		(layer "In6.Cu")
	)
	(gr_line
		(start 278.424132 -69.548248)
		(end 278.425148 -69.55028)
		(stroke
			(width 0.2)
			(type default)
		)
		(layer "In6.Cu")
	)
	(gr_line
		(start 278.424132 -69.547994)
		(end 278.424132 -69.548248)
		(stroke
			(width 0.2)
			(type default)
		)
		(layer "In6.Cu")
	)
	(gr_line
		(start 278.424132 -65.548256)
		(end 278.425148 -65.550288)
		(stroke
			(width 0.2)
			(type default)
		)
		(layer "In6.Cu")
	)
	(gr_line
		(start 278.424132 -65.548002)
		(end 278.424132 -65.548256)
		(stroke
			(width 0.2)
			(type default)
		)
		(layer "In6.Cu")
	)
	(gr_line
		(start 278.424132 -61.548264)
		(end 278.425148 -61.550296)
		(stroke
			(width 0.2)
			(type default)
		)
		(layer "In6.Cu")
	)
	(gr_line
		(start 278.424132 -61.54801)
		(end 278.424132 -61.548264)
		(stroke
			(width 0.2)
			(type default)
		)
		(layer "In6.Cu")
	)
	(gr_line
		(start 278.424132 -57.548272)
		(end 278.425148 -57.550304)
		(stroke
			(width 0.2)
			(type default)
		)
		(layer "In6.Cu")
	)
	(gr_line
		(start 278.424132 -57.548018)
		(end 278.424132 -57.548272)
		(stroke
			(width 0.2)
			(type default)
		)
		(layer "In6.Cu")
	)
	(gr_line
		(start 278.424132 -53.54828)
		(end 278.425148 -53.550312)
		(stroke
			(width 0.2)
			(type default)
		)
		(layer "In6.Cu")
	)
	(gr_line
		(start 278.424132 -53.548026)
		(end 278.424132 -53.54828)
		(stroke
			(width 0.2)
			(type default)
		)
		(layer "In6.Cu")
	)
	(gr_line
		(start 278.424132 -49.548288)
		(end 278.425148 -49.55032)
		(stroke
			(width 0.2)
			(type default)
		)
		(layer "In6.Cu")
	)
	(gr_line
		(start 278.424132 -49.548034)
		(end 278.424132 -49.548288)
		(stroke
			(width 0.2)
			(type default)
		)
		(layer "In6.Cu")
	)
	(gr_line
		(start 278.424132 -45.548296)
		(end 278.425148 -45.550328)
		(stroke
			(width 0.2)
			(type default)
		)
		(layer "In6.Cu")
	)
	(gr_line
		(start 278.424132 -45.548042)
		(end 278.424132 -45.548296)
		(stroke
			(width 0.2)
			(type default)
		)
		(layer "In6.Cu")
	)
	(gr_line
		(start 278.424132 -41.548304)
		(end 278.425148 -41.550336)
		(stroke
			(width 0.2)
			(type default)
		)
		(layer "In6.Cu")
	)
	(gr_line
		(start 278.424132 -41.54805)
		(end 278.424132 -41.548304)
		(stroke
			(width 0.2)
			(type default)
		)
		(layer "In6.Cu")
	)
	(gr_line
		(start 278.424132 -37.548312)
		(end 278.425148 -37.550344)
		(stroke
			(width 0.2)
			(type default)
		)
		(layer "In6.Cu")
	)
	(gr_line
		(start 278.424132 -37.548058)
		(end 278.424132 -37.548312)
		(stroke
			(width 0.2)
			(type default)
		)
		(layer "In6.Cu")
	)
	(gr_line
		(start 278.424132 -17.548352)
		(end 278.425148 -17.550384)
		(stroke
			(width 0.2)
			(type default)
		)
		(layer "In6.Cu")
	)
	(gr_line
		(start 278.424132 -17.548098)
		(end 278.424132 -17.548352)
		(stroke
			(width 0.2)
			(type default)
		)
		(layer "In6.Cu")
	)
	(gr_arc
		(start 278.425148 -177.850038)
		(mid 278.100282 -178.824636)
		(end 279.07488 -179.149502)
		(stroke
			(width 0.2)
			(type default)
		)
		(layer "In6.Cu")
	)
	(gr_arc
		(start 278.425148 -173.850046)
		(mid 278.100282 -174.824644)
		(end 279.07488 -175.14951)
		(stroke
			(width 0.2)
			(type default)
		)
		(layer "In6.Cu")
	)
	(gr_arc
		(start 278.425148 -169.850054)
		(mid 278.100282 -170.824652)
		(end 279.07488 -171.149518)
		(stroke
			(width 0.2)
			(type default)
		)
		(layer "In6.Cu")
	)
	(gr_arc
		(start 278.425148 -165.850062)
		(mid 278.100282 -166.82466)
		(end 279.07488 -167.149526)
		(stroke
			(width 0.2)
			(type default)
		)
		(layer "In6.Cu")
	)
	(gr_arc
		(start 278.425148 -137.850118)
		(mid 278.100282 -138.824716)
		(end 279.07488 -139.149582)
		(stroke
			(width 0.2)
			(type default)
		)
		(layer "In6.Cu")
	)
	(gr_arc
		(start 278.425148 -81.550256)
		(mid 278.100282 -82.524854)
		(end 279.07488 -82.84972)
		(stroke
			(width 0.2)
			(type default)
		)
		(layer "In6.Cu")
	)
	(gr_arc
		(start 278.425148 -77.550264)
		(mid 278.100282 -78.524862)
		(end 279.07488 -78.849728)
		(stroke
			(width 0.2)
			(type default)
		)
		(layer "In6.Cu")
	)
	(gr_arc
		(start 278.425148 -73.550272)
		(mid 278.100282 -74.52487)
		(end 279.07488 -74.849736)
		(stroke
			(width 0.2)
			(type default)
		)
		(layer "In6.Cu")
	)
	(gr_arc
		(start 278.425148 -69.55028)
		(mid 278.100282 -70.524878)
		(end 279.07488 -70.849744)
		(stroke
			(width 0.2)
			(type default)
		)
		(layer "In6.Cu")
	)
	(gr_arc
		(start 278.425148 -65.550288)
		(mid 278.100282 -66.524886)
		(end 279.07488 -66.849752)
		(stroke
			(width 0.2)
			(type default)
		)
		(layer "In6.Cu")
	)
	(gr_arc
		(start 278.425148 -61.550296)
		(mid 278.100282 -62.524894)
		(end 279.07488 -62.84976)
		(stroke
			(width 0.2)
			(type default)
		)
		(layer "In6.Cu")
	)
	(gr_arc
		(start 278.425148 -57.550304)
		(mid 278.100282 -58.524902)
		(end 279.07488 -58.849768)
		(stroke
			(width 0.2)
			(type default)
		)
		(layer "In6.Cu")
	)
	(gr_arc
		(start 278.425148 -53.550312)
		(mid 278.100282 -54.52491)
		(end 279.07488 -54.849776)
		(stroke
			(width 0.2)
			(type default)
		)
		(layer "In6.Cu")
	)
	(gr_arc
		(start 278.425148 -49.55032)
		(mid 278.100282 -50.524918)
		(end 279.07488 -50.849784)
		(stroke
			(width 0.2)
			(type default)
		)
		(layer "In6.Cu")
	)
	(gr_arc
		(start 278.425148 -45.550328)
		(mid 278.100282 -46.524926)
		(end 279.07488 -46.849792)
		(stroke
			(width 0.2)
			(type default)
		)
		(layer "In6.Cu")
	)
	(gr_arc
		(start 278.425148 -41.550336)
		(mid 278.100282 -42.524934)
		(end 279.07488 -42.8498)
		(stroke
			(width 0.2)
			(type default)
		)
		(layer "In6.Cu")
	)
	(gr_arc
		(start 278.425148 -37.550344)
		(mid 278.100282 -38.524942)
		(end 279.07488 -38.849808)
		(stroke
			(width 0.2)
			(type default)
		)
		(layer "In6.Cu")
	)
	(gr_arc
		(start 278.425148 -17.550384)
		(mid 278.100282 -18.524982)
		(end 279.07488 -18.849848)
		(stroke
			(width 0.2)
			(type default)
		)
		(layer "In6.Cu")
	)
	(gr_arc
		(start 278.426418 -161.852356)
		(mid 278.102619 -162.8235)
		(end 279.073864 -163.147248)
		(stroke
			(width 0.2)
			(type default)
		)
		(layer "In6.Cu")
	)
	(gr_line
		(start 278.426418 -161.852102)
		(end 278.426418 -161.852356)
		(stroke
			(width 0.2)
			(type default)
		)
		(layer "In6.Cu")
	)
	(gr_arc
		(start 278.426418 -157.852364)
		(mid 278.102619 -158.823508)
		(end 279.073864 -159.147256)
		(stroke
			(width 0.2)
			(type default)
		)
		(layer "In6.Cu")
	)
	(gr_line
		(start 278.426418 -157.85211)
		(end 278.426418 -157.852364)
		(stroke
			(width 0.2)
			(type default)
		)
		(layer "In6.Cu")
	)
	(gr_arc
		(start 278.426418 -153.852372)
		(mid 278.102619 -154.823516)
		(end 279.073864 -155.147264)
		(stroke
			(width 0.2)
			(type default)
		)
		(layer "In6.Cu")
	)
	(gr_line
		(start 278.426418 -153.852118)
		(end 278.426418 -153.852372)
		(stroke
			(width 0.2)
			(type default)
		)
		(layer "In6.Cu")
	)
	(gr_arc
		(start 278.426418 -149.85238)
		(mid 278.102619 -150.823524)
		(end 279.073864 -151.147272)
		(stroke
			(width 0.2)
			(type default)
		)
		(layer "In6.Cu")
	)
	(gr_line
		(start 278.426418 -149.852126)
		(end 278.426418 -149.85238)
		(stroke
			(width 0.2)
			(type default)
		)
		(layer "In6.Cu")
	)
	(gr_arc
		(start 278.426418 -129.85242)
		(mid 278.102619 -130.823564)
		(end 279.073864 -131.147312)
		(stroke
			(width 0.2)
			(type default)
		)
		(layer "In6.Cu")
	)
	(gr_line
		(start 278.426418 -129.852166)
		(end 278.426418 -129.85242)
		(stroke
			(width 0.2)
			(type default)
		)
		(layer "In6.Cu")
	)
	(gr_arc
		(start 278.426418 -125.852428)
		(mid 278.102619 -126.823572)
		(end 279.073864 -127.14732)
		(stroke
			(width 0.2)
			(type default)
		)
		(layer "In6.Cu")
	)
	(gr_line
		(start 278.426418 -125.852174)
		(end 278.426418 -125.852428)
		(stroke
			(width 0.2)
			(type default)
		)
		(layer "In6.Cu")
	)
	(gr_arc
		(start 278.426418 -121.852436)
		(mid 278.102619 -122.82358)
		(end 279.073864 -123.147328)
		(stroke
			(width 0.2)
			(type default)
		)
		(layer "In6.Cu")
	)
	(gr_line
		(start 278.426418 -121.852182)
		(end 278.426418 -121.852436)
		(stroke
			(width 0.2)
			(type default)
		)
		(layer "In6.Cu")
	)
	(gr_arc
		(start 278.426418 -117.852444)
		(mid 278.102619 -118.823588)
		(end 279.073864 -119.147336)
		(stroke
			(width 0.2)
			(type default)
		)
		(layer "In6.Cu")
	)
	(gr_line
		(start 278.426418 -117.85219)
		(end 278.426418 -117.852444)
		(stroke
			(width 0.2)
			(type default)
		)
		(layer "In6.Cu")
	)
	(gr_arc
		(start 278.433784 -11.54049)
		(mid 278.093387 -12.52152)
		(end 279.077166 -12.854432)
		(stroke
			(width 0.2)
			(type default)
		)
		(layer "In6.Cu")
	)
	(gr_arc
		(start 278.44496 -113.868708)
		(mid 278.120865 -114.809139)
		(end 279.06345 -115.127024)
		(stroke
			(width 0.2)
			(type default)
		)
		(layer "In6.Cu")
	)
	(gr_line
		(start 279.06345 -115.127024)
		(end 281.063446 -114.127026)
		(stroke
			(width 0.2)
			(type default)
		)
		(layer "In6.Cu")
	)
	(gr_line
		(start 279.073864 -163.147248)
		(end 281.07386 -162.14725)
		(stroke
			(width 0.2)
			(type default)
		)
		(layer "In6.Cu")
	)
	(gr_line
		(start 279.073864 -159.147256)
		(end 281.07386 -158.147258)
		(stroke
			(width 0.2)
			(type default)
		)
		(layer "In6.Cu")
	)
	(gr_line
		(start 279.073864 -155.147264)
		(end 281.07386 -154.147266)
		(stroke
			(width 0.2)
			(type default)
		)
		(layer "In6.Cu")
	)
	(gr_line
		(start 279.073864 -151.147272)
		(end 281.07386 -150.147274)
		(stroke
			(width 0.2)
			(type default)
		)
		(layer "In6.Cu")
	)
	(gr_line
		(start 279.073864 -131.147312)
		(end 281.07386 -130.147314)
		(stroke
			(width 0.2)
			(type default)
		)
		(layer "In6.Cu")
	)
	(gr_line
		(start 279.073864 -127.14732)
		(end 281.07386 -126.147322)
		(stroke
			(width 0.2)
			(type default)
		)
		(layer "In6.Cu")
	)
	(gr_line
		(start 279.073864 -123.147328)
		(end 281.07386 -122.14733)
		(stroke
			(width 0.2)
			(type default)
		)
		(layer "In6.Cu")
	)
	(gr_line
		(start 279.073864 -119.147336)
		(end 281.07386 -118.147338)
		(stroke
			(width 0.2)
			(type default)
		)
		(layer "In6.Cu")
	)
	(gr_line
		(start 279.07488 -179.149502)
		(end 279.07615 -179.151788)
		(stroke
			(width 0.2)
			(type default)
		)
		(layer "In6.Cu")
	)
	(gr_line
		(start 279.07488 -175.14951)
		(end 279.07615 -175.151796)
		(stroke
			(width 0.2)
			(type default)
		)
		(layer "In6.Cu")
	)
	(gr_line
		(start 279.07488 -171.149518)
		(end 279.07615 -171.151804)
		(stroke
			(width 0.2)
			(type default)
		)
		(layer "In6.Cu")
	)
	(gr_line
		(start 279.07488 -167.149526)
		(end 279.07615 -167.151812)
		(stroke
			(width 0.2)
			(type default)
		)
		(layer "In6.Cu")
	)
	(gr_line
		(start 279.07488 -139.149582)
		(end 279.07615 -139.151868)
		(stroke
			(width 0.2)
			(type default)
		)
		(layer "In6.Cu")
	)
	(gr_line
		(start 279.07488 -82.84972)
		(end 279.07615 -82.852006)
		(stroke
			(width 0.2)
			(type default)
		)
		(layer "In6.Cu")
	)
	(gr_line
		(start 279.07488 -78.849728)
		(end 279.07615 -78.852014)
		(stroke
			(width 0.2)
			(type default)
		)
		(layer "In6.Cu")
	)
	(gr_line
		(start 279.07488 -74.849736)
		(end 279.07615 -74.852022)
		(stroke
			(width 0.2)
			(type default)
		)
		(layer "In6.Cu")
	)
	(gr_line
		(start 279.07488 -70.849744)
		(end 279.07615 -70.85203)
		(stroke
			(width 0.2)
			(type default)
		)
		(layer "In6.Cu")
	)
	(gr_line
		(start 279.07488 -66.849752)
		(end 279.07615 -66.852038)
		(stroke
			(width 0.2)
			(type default)
		)
		(layer "In6.Cu")
	)
	(gr_line
		(start 279.07488 -62.84976)
		(end 279.07615 -62.852046)
		(stroke
			(width 0.2)
			(type default)
		)
		(layer "In6.Cu")
	)
	(gr_line
		(start 279.07488 -58.849768)
		(end 279.07615 -58.852054)
		(stroke
			(width 0.2)
			(type default)
		)
		(layer "In6.Cu")
	)
	(gr_line
		(start 279.07488 -54.849776)
		(end 279.07615 -54.852062)
		(stroke
			(width 0.2)
			(type default)
		)
		(layer "In6.Cu")
	)
	(gr_line
		(start 279.07488 -50.849784)
		(end 279.07615 -50.85207)
		(stroke
			(width 0.2)
			(type default)
		)
		(layer "In6.Cu")
	)
	(gr_line
		(start 279.07488 -46.849792)
		(end 279.07615 -46.852078)
		(stroke
			(width 0.2)
			(type default)
		)
		(layer "In6.Cu")
	)
	(gr_line
		(start 279.07488 -42.8498)
		(end 279.07615 -42.852086)
		(stroke
			(width 0.2)
			(type default)
		)
		(layer "In6.Cu")
	)
	(gr_line
		(start 279.07488 -38.849808)
		(end 279.07615 -38.852094)
		(stroke
			(width 0.2)
			(type default)
		)
		(layer "In6.Cu")
	)
	(gr_line
		(start 279.07488 -18.849848)
		(end 279.07615 -18.852134)
		(stroke
			(width 0.2)
			(type default)
		)
		(layer "In6.Cu")
	)
	(gr_line
		(start 279.07615 -179.151788)
		(end 281.076146 -178.15179)
		(stroke
			(width 0.2)
			(type default)
		)
		(layer "In6.Cu")
	)
	(gr_line
		(start 279.07615 -175.151796)
		(end 281.076146 -174.151798)
		(stroke
			(width 0.2)
			(type default)
		)
		(layer "In6.Cu")
	)
	(gr_line
		(start 279.07615 -171.151804)
		(end 281.076146 -170.151806)
		(stroke
			(width 0.2)
			(type default)
		)
		(layer "In6.Cu")
	)
	(gr_line
		(start 279.07615 -167.151812)
		(end 281.076146 -166.151814)
		(stroke
			(width 0.2)
			(type default)
		)
		(layer "In6.Cu")
	)
	(gr_line
		(start 279.07615 -139.151868)
		(end 281.076146 -138.15187)
		(stroke
			(width 0.2)
			(type default)
		)
		(layer "In6.Cu")
	)
	(gr_line
		(start 279.07615 -82.852006)
		(end 281.076146 -81.852008)
		(stroke
			(width 0.2)
			(type default)
		)
		(layer "In6.Cu")
	)
	(gr_line
		(start 279.07615 -78.852014)
		(end 281.076146 -77.852016)
		(stroke
			(width 0.2)
			(type default)
		)
		(layer "In6.Cu")
	)
	(gr_line
		(start 279.07615 -74.852022)
		(end 281.076146 -73.852024)
		(stroke
			(width 0.2)
			(type default)
		)
		(layer "In6.Cu")
	)
	(gr_line
		(start 279.07615 -70.85203)
		(end 281.076146 -69.852032)
		(stroke
			(width 0.2)
			(type default)
		)
		(layer "In6.Cu")
	)
	(gr_line
		(start 279.07615 -66.852038)
		(end 281.076146 -65.85204)
		(stroke
			(width 0.2)
			(type default)
		)
		(layer "In6.Cu")
	)
	(gr_line
		(start 279.07615 -62.852046)
		(end 281.076146 -61.852048)
		(stroke
			(width 0.2)
			(type default)
		)
		(layer "In6.Cu")
	)
	(gr_line
		(start 279.07615 -58.852054)
		(end 281.076146 -57.852056)
		(stroke
			(width 0.2)
			(type default)
		)
		(layer "In6.Cu")
	)
	(gr_line
		(start 279.07615 -54.852062)
		(end 281.076146 -53.852064)
		(stroke
			(width 0.2)
			(type default)
		)
		(layer "In6.Cu")
	)
	(gr_line
		(start 279.07615 -50.85207)
		(end 281.076146 -49.852072)
		(stroke
			(width 0.2)
			(type default)
		)
		(layer "In6.Cu")
	)
	(gr_line
		(start 279.07615 -46.852078)
		(end 281.076146 -45.85208)
		(stroke
			(width 0.2)
			(type default)
		)
		(layer "In6.Cu")
	)
	(gr_line
		(start 279.07615 -42.852086)
		(end 281.076146 -41.852088)
		(stroke
			(width 0.2)
			(type default)
		)
		(layer "In6.Cu")
	)
	(gr_line
		(start 279.07615 -38.852094)
		(end 281.076146 -37.852096)
		(stroke
			(width 0.2)
			(type default)
		)
		(layer "In6.Cu")
	)
	(gr_line
		(start 279.07615 -18.852134)
		(end 281.076146 -17.852136)
		(stroke
			(width 0.2)
			(type default)
		)
		(layer "In6.Cu")
	)
	(gr_line
		(start 279.077166 -12.854432)
		(end 281.077162 -11.854434)
		(stroke
			(width 0.2)
			(type default)
		)
		(layer "In6.Cu")
	)
	(gr_line
		(start 279.1714 -5.2324)
		(end 280.162 -6.223)
		(stroke
			(width 0.381)
			(type default)
		)
		(layer "In6.Cu")
	)
	(gr_line
		(start 279.182068 -101.542596)
		(end 278.173942 -101.542596)
		(stroke
			(width 0.381)
			(type default)
		)
		(layer "In6.Cu")
	)
	(gr_line
		(start 279.236678 -358.253792)
		(end 280.636726 -358.253792)
		(stroke
			(width 0.2)
			(type default)
		)
		(layer "In6.Cu")
	)
	(gr_arc
		(start 279.236678 -357.156512)
		(mid 278.688038 -357.705152)
		(end 279.236678 -358.253792)
		(stroke
			(width 0.2)
			(type default)
		)
		(layer "In6.Cu")
	)
	(gr_line
		(start 279.236678 -354.65385)
		(end 280.636726 -354.65385)
		(stroke
			(width 0.2)
			(type default)
		)
		(layer "In6.Cu")
	)
	(gr_arc
		(start 279.236678 -353.55657)
		(mid 278.688038 -354.10521)
		(end 279.236678 -354.65385)
		(stroke
			(width 0.2)
			(type default)
		)
		(layer "In6.Cu")
	)
	(gr_line
		(start 279.236678 -351.053908)
		(end 280.636726 -351.053908)
		(stroke
			(width 0.2)
			(type default)
		)
		(layer "In6.Cu")
	)
	(gr_arc
		(start 279.236678 -349.956628)
		(mid 278.688038 -350.505268)
		(end 279.236678 -351.053908)
		(stroke
			(width 0.2)
			(type default)
		)
		(layer "In6.Cu")
	)
	(gr_line
		(start 279.236678 -347.453712)
		(end 280.636726 -347.453712)
		(stroke
			(width 0.2)
			(type default)
		)
		(layer "In6.Cu")
	)
	(gr_arc
		(start 279.236678 -346.356432)
		(mid 278.688038 -346.905072)
		(end 279.236678 -347.453712)
		(stroke
			(width 0.2)
			(type default)
		)
		(layer "In6.Cu")
	)
	(gr_line
		(start 279.236678 -343.85377)
		(end 280.636726 -343.85377)
		(stroke
			(width 0.2)
			(type default)
		)
		(layer "In6.Cu")
	)
	(gr_arc
		(start 279.236678 -342.75649)
		(mid 278.688038 -343.30513)
		(end 279.236678 -343.85377)
		(stroke
			(width 0.2)
			(type default)
		)
		(layer "In6.Cu")
	)
	(gr_line
		(start 279.236678 -340.253828)
		(end 280.636726 -340.253828)
		(stroke
			(width 0.2)
			(type default)
		)
		(layer "In6.Cu")
	)
	(gr_arc
		(start 279.236678 -339.156548)
		(mid 278.688038 -339.705188)
		(end 279.236678 -340.253828)
		(stroke
			(width 0.2)
			(type default)
		)
		(layer "In6.Cu")
	)
	(gr_line
		(start 279.236678 -336.653886)
		(end 280.636726 -336.653886)
		(stroke
			(width 0.2)
			(type default)
		)
		(layer "In6.Cu")
	)
	(gr_arc
		(start 279.236678 -335.556606)
		(mid 278.688038 -336.105246)
		(end 279.236678 -336.653886)
		(stroke
			(width 0.2)
			(type default)
		)
		(layer "In6.Cu")
	)
	(gr_line
		(start 279.236678 -333.05369)
		(end 280.636726 -333.05369)
		(stroke
			(width 0.2)
			(type default)
		)
		(layer "In6.Cu")
	)
	(gr_arc
		(start 279.236678 -331.95641)
		(mid 278.688038 -332.50505)
		(end 279.236678 -333.05369)
		(stroke
			(width 0.2)
			(type default)
		)
		(layer "In6.Cu")
	)
	(gr_line
		(start 279.236678 -329.453748)
		(end 280.636726 -329.453748)
		(stroke
			(width 0.2)
			(type default)
		)
		(layer "In6.Cu")
	)
	(gr_arc
		(start 279.236678 -328.356468)
		(mid 278.688038 -328.905108)
		(end 279.236678 -329.453748)
		(stroke
			(width 0.2)
			(type default)
		)
		(layer "In6.Cu")
	)
	(gr_line
		(start 279.236678 -325.853806)
		(end 280.636726 -325.853806)
		(stroke
			(width 0.2)
			(type default)
		)
		(layer "In6.Cu")
	)
	(gr_arc
		(start 279.236678 -324.756526)
		(mid 278.688038 -325.305166)
		(end 279.236678 -325.853806)
		(stroke
			(width 0.2)
			(type default)
		)
		(layer "In6.Cu")
	)
	(gr_line
		(start 279.236678 -322.253864)
		(end 280.636726 -322.253864)
		(stroke
			(width 0.2)
			(type default)
		)
		(layer "In6.Cu")
	)
	(gr_arc
		(start 279.236678 -321.156584)
		(mid 278.688038 -321.705224)
		(end 279.236678 -322.253864)
		(stroke
			(width 0.2)
			(type default)
		)
		(layer "In6.Cu")
	)
	(gr_line
		(start 279.236678 -318.653668)
		(end 280.636726 -318.653668)
		(stroke
			(width 0.2)
			(type default)
		)
		(layer "In6.Cu")
	)
	(gr_arc
		(start 279.236678 -317.556388)
		(mid 278.688038 -318.105028)
		(end 279.236678 -318.653668)
		(stroke
			(width 0.2)
			(type default)
		)
		(layer "In6.Cu")
	)
	(gr_line
		(start 279.236678 -315.053726)
		(end 280.636726 -315.053726)
		(stroke
			(width 0.2)
			(type default)
		)
		(layer "In6.Cu")
	)
	(gr_arc
		(start 279.236678 -313.956446)
		(mid 278.688038 -314.505086)
		(end 279.236678 -315.053726)
		(stroke
			(width 0.2)
			(type default)
		)
		(layer "In6.Cu")
	)
	(gr_line
		(start 279.236678 -311.453784)
		(end 280.636726 -311.453784)
		(stroke
			(width 0.2)
			(type default)
		)
		(layer "In6.Cu")
	)
	(gr_arc
		(start 279.236678 -310.356504)
		(mid 278.688038 -310.905144)
		(end 279.236678 -311.453784)
		(stroke
			(width 0.2)
			(type default)
		)
		(layer "In6.Cu")
	)
	(gr_line
		(start 279.236678 -307.853842)
		(end 280.636726 -307.853842)
		(stroke
			(width 0.2)
			(type default)
		)
		(layer "In6.Cu")
	)
	(gr_arc
		(start 279.236678 -306.756562)
		(mid 278.688038 -307.305202)
		(end 279.236678 -307.853842)
		(stroke
			(width 0.2)
			(type default)
		)
		(layer "In6.Cu")
	)
	(gr_line
		(start 279.236678 -304.2539)
		(end 280.636726 -304.2539)
		(stroke
			(width 0.2)
			(type default)
		)
		(layer "In6.Cu")
	)
	(gr_arc
		(start 279.236678 -303.15662)
		(mid 278.688038 -303.70526)
		(end 279.236678 -304.2539)
		(stroke
			(width 0.2)
			(type default)
		)
		(layer "In6.Cu")
	)
	(gr_line
		(start 279.236678 -300.653704)
		(end 280.636726 -300.653704)
		(stroke
			(width 0.2)
			(type default)
		)
		(layer "In6.Cu")
	)
	(gr_arc
		(start 279.236678 -299.556424)
		(mid 278.688038 -300.105064)
		(end 279.236678 -300.653704)
		(stroke
			(width 0.2)
			(type default)
		)
		(layer "In6.Cu")
	)
	(gr_line
		(start 279.236678 -297.053762)
		(end 280.636726 -297.053762)
		(stroke
			(width 0.2)
			(type default)
		)
		(layer "In6.Cu")
	)
	(gr_arc
		(start 279.236678 -295.956482)
		(mid 278.688038 -296.505122)
		(end 279.236678 -297.053762)
		(stroke
			(width 0.2)
			(type default)
		)
		(layer "In6.Cu")
	)
	(gr_line
		(start 279.236678 -264.253472)
		(end 280.636726 -264.253472)
		(stroke
			(width 0.2)
			(type default)
		)
		(layer "In6.Cu")
	)
	(gr_arc
		(start 279.236678 -263.151112)
		(mid 278.685498 -263.702292)
		(end 279.236678 -264.253472)
		(stroke
			(width 0.2)
			(type default)
		)
		(layer "In6.Cu")
	)
	(gr_line
		(start 279.236678 -260.65353)
		(end 280.636726 -260.65353)
		(stroke
			(width 0.2)
			(type default)
		)
		(layer "In6.Cu")
	)
	(gr_arc
		(start 279.236678 -259.55117)
		(mid 278.685498 -260.10235)
		(end 279.236678 -260.65353)
		(stroke
			(width 0.2)
			(type default)
		)
		(layer "In6.Cu")
	)
	(gr_line
		(start 279.236678 -257.053588)
		(end 280.636726 -257.053588)
		(stroke
			(width 0.2)
			(type default)
		)
		(layer "In6.Cu")
	)
	(gr_arc
		(start 279.236678 -255.951228)
		(mid 278.685498 -256.502408)
		(end 279.236678 -257.053588)
		(stroke
			(width 0.2)
			(type default)
		)
		(layer "In6.Cu")
	)
	(gr_line
		(start 279.236678 -253.453392)
		(end 280.636726 -253.453392)
		(stroke
			(width 0.2)
			(type default)
		)
		(layer "In6.Cu")
	)
	(gr_arc
		(start 279.236678 -252.351032)
		(mid 278.685498 -252.902212)
		(end 279.236678 -253.453392)
		(stroke
			(width 0.2)
			(type default)
		)
		(layer "In6.Cu")
	)
	(gr_line
		(start 279.236932 -357.156512)
		(end 279.236678 -357.156512)
		(stroke
			(width 0.2)
			(type default)
		)
		(layer "In6.Cu")
	)
	(gr_line
		(start 279.236932 -353.55657)
		(end 279.236678 -353.55657)
		(stroke
			(width 0.2)
			(type default)
		)
		(layer "In6.Cu")
	)
	(gr_line
		(start 279.236932 -349.956628)
		(end 279.236678 -349.956628)
		(stroke
			(width 0.2)
			(type default)
		)
		(layer "In6.Cu")
	)
	(gr_line
		(start 279.236932 -346.356432)
		(end 279.236678 -346.356432)
		(stroke
			(width 0.2)
			(type default)
		)
		(layer "In6.Cu")
	)
	(gr_line
		(start 279.236932 -342.75649)
		(end 279.236678 -342.75649)
		(stroke
			(width 0.2)
			(type default)
		)
		(layer "In6.Cu")
	)
	(gr_line
		(start 279.236932 -339.156548)
		(end 279.236678 -339.156548)
		(stroke
			(width 0.2)
			(type default)
		)
		(layer "In6.Cu")
	)
	(gr_line
		(start 279.236932 -335.556606)
		(end 279.236678 -335.556606)
		(stroke
			(width 0.2)
			(type default)
		)
		(layer "In6.Cu")
	)
	(gr_line
		(start 279.236932 -331.95641)
		(end 279.236678 -331.95641)
		(stroke
			(width 0.2)
			(type default)
		)
		(layer "In6.Cu")
	)
	(gr_line
		(start 279.236932 -328.356468)
		(end 279.236678 -328.356468)
		(stroke
			(width 0.2)
			(type default)
		)
		(layer "In6.Cu")
	)
	(gr_line
		(start 279.236932 -324.756526)
		(end 279.236678 -324.756526)
		(stroke
			(width 0.2)
			(type default)
		)
		(layer "In6.Cu")
	)
	(gr_line
		(start 279.236932 -321.156584)
		(end 279.236678 -321.156584)
		(stroke
			(width 0.2)
			(type default)
		)
		(layer "In6.Cu")
	)
	(gr_line
		(start 279.236932 -317.556388)
		(end 279.236678 -317.556388)
		(stroke
			(width 0.2)
			(type default)
		)
		(layer "In6.Cu")
	)
	(gr_line
		(start 279.236932 -313.956446)
		(end 279.236678 -313.956446)
		(stroke
			(width 0.2)
			(type default)
		)
		(layer "In6.Cu")
	)
	(gr_line
		(start 279.236932 -310.356504)
		(end 279.236678 -310.356504)
		(stroke
			(width 0.2)
			(type default)
		)
		(layer "In6.Cu")
	)
	(gr_line
		(start 279.236932 -306.756562)
		(end 279.236678 -306.756562)
		(stroke
			(width 0.2)
			(type default)
		)
		(layer "In6.Cu")
	)
	(gr_line
		(start 279.236932 -303.15662)
		(end 279.236678 -303.15662)
		(stroke
			(width 0.2)
			(type default)
		)
		(layer "In6.Cu")
	)
	(gr_line
		(start 279.236932 -299.556424)
		(end 279.236678 -299.556424)
		(stroke
			(width 0.2)
			(type default)
		)
		(layer "In6.Cu")
	)
	(gr_line
		(start 279.236932 -295.956482)
		(end 279.236678 -295.956482)
		(stroke
			(width 0.2)
			(type default)
		)
		(layer "In6.Cu")
	)
	(gr_line
		(start 279.236932 -263.151112)
		(end 279.236678 -263.151112)
		(stroke
			(width 0.2)
			(type default)
		)
		(layer "In6.Cu")
	)
	(gr_line
		(start 279.236932 -259.55117)
		(end 279.236678 -259.55117)
		(stroke
			(width 0.2)
			(type default)
		)
		(layer "In6.Cu")
	)
	(gr_line
		(start 279.236932 -255.951228)
		(end 279.236678 -255.951228)
		(stroke
			(width 0.2)
			(type default)
		)
		(layer "In6.Cu")
	)
	(gr_line
		(start 279.236932 -252.351032)
		(end 279.236678 -252.351032)
		(stroke
			(width 0.2)
			(type default)
		)
		(layer "In6.Cu")
	)
	(gr_line
		(start 279.3238 -85.1916)
		(end 277.7744 -85.1916)
		(stroke
			(width 0.381)
			(type default)
		)
		(layer "In6.Cu")
	)
	(gr_arc
		(start 279.636728 -356.453694)
		(mid 280.185368 -355.905054)
		(end 279.636728 -355.356414)
		(stroke
			(width 0.2)
			(type default)
		)
		(layer "In6.Cu")
	)
	(gr_line
		(start 279.636728 -355.356414)
		(end 278.236934 -355.356414)
		(stroke
			(width 0.2)
			(type default)
		)
		(layer "In6.Cu")
	)
	(gr_arc
		(start 279.636728 -352.853752)
		(mid 280.185368 -352.305112)
		(end 279.636728 -351.756472)
		(stroke
			(width 0.2)
			(type default)
		)
		(layer "In6.Cu")
	)
	(gr_line
		(start 279.636728 -351.756472)
		(end 278.236934 -351.756472)
		(stroke
			(width 0.2)
			(type default)
		)
		(layer "In6.Cu")
	)
	(gr_arc
		(start 279.636728 -349.25381)
		(mid 280.185368 -348.70517)
		(end 279.636728 -348.15653)
		(stroke
			(width 0.2)
			(type default)
		)
		(layer "In6.Cu")
	)
	(gr_line
		(start 279.636728 -348.15653)
		(end 278.236934 -348.15653)
		(stroke
			(width 0.2)
			(type default)
		)
		(layer "In6.Cu")
	)
	(gr_arc
		(start 279.636728 -345.653868)
		(mid 280.185368 -345.105228)
		(end 279.636728 -344.556588)
		(stroke
			(width 0.2)
			(type default)
		)
		(layer "In6.Cu")
	)
	(gr_line
		(start 279.636728 -344.556588)
		(end 278.236934 -344.556588)
		(stroke
			(width 0.2)
			(type default)
		)
		(layer "In6.Cu")
	)
	(gr_arc
		(start 279.636728 -342.053672)
		(mid 280.185368 -341.505032)
		(end 279.636728 -340.956392)
		(stroke
			(width 0.2)
			(type default)
		)
		(layer "In6.Cu")
	)
	(gr_line
		(start 279.636728 -340.956392)
		(end 278.236934 -340.956392)
		(stroke
			(width 0.2)
			(type default)
		)
		(layer "In6.Cu")
	)
	(gr_arc
		(start 279.636728 -338.45373)
		(mid 280.185368 -337.90509)
		(end 279.636728 -337.35645)
		(stroke
			(width 0.2)
			(type default)
		)
		(layer "In6.Cu")
	)
	(gr_line
		(start 279.636728 -337.35645)
		(end 278.236934 -337.35645)
		(stroke
			(width 0.2)
			(type default)
		)
		(layer "In6.Cu")
	)
	(gr_arc
		(start 279.636728 -334.853788)
		(mid 280.185368 -334.305148)
		(end 279.636728 -333.756508)
		(stroke
			(width 0.2)
			(type default)
		)
		(layer "In6.Cu")
	)
	(gr_line
		(start 279.636728 -333.756508)
		(end 278.236934 -333.756508)
		(stroke
			(width 0.2)
			(type default)
		)
		(layer "In6.Cu")
	)
	(gr_arc
		(start 279.636728 -331.253846)
		(mid 280.185368 -330.705206)
		(end 279.636728 -330.156566)
		(stroke
			(width 0.2)
			(type default)
		)
		(layer "In6.Cu")
	)
	(gr_line
		(start 279.636728 -330.156566)
		(end 278.236934 -330.156566)
		(stroke
			(width 0.2)
			(type default)
		)
		(layer "In6.Cu")
	)
	(gr_arc
		(start 279.636728 -327.653904)
		(mid 280.185368 -327.105264)
		(end 279.636728 -326.556624)
		(stroke
			(width 0.2)
			(type default)
		)
		(layer "In6.Cu")
	)
	(gr_line
		(start 279.636728 -326.556624)
		(end 278.236934 -326.556624)
		(stroke
			(width 0.2)
			(type default)
		)
		(layer "In6.Cu")
	)
	(gr_arc
		(start 279.636728 -324.053708)
		(mid 280.185368 -323.505068)
		(end 279.636728 -322.956428)
		(stroke
			(width 0.2)
			(type default)
		)
		(layer "In6.Cu")
	)
	(gr_line
		(start 279.636728 -322.956428)
		(end 278.236934 -322.956428)
		(stroke
			(width 0.2)
			(type default)
		)
		(layer "In6.Cu")
	)
	(gr_arc
		(start 279.636728 -320.453766)
		(mid 280.185368 -319.905126)
		(end 279.636728 -319.356486)
		(stroke
			(width 0.2)
			(type default)
		)
		(layer "In6.Cu")
	)
	(gr_line
		(start 279.636728 -319.356486)
		(end 278.236934 -319.356486)
		(stroke
			(width 0.2)
			(type default)
		)
		(layer "In6.Cu")
	)
	(gr_arc
		(start 279.636728 -316.853824)
		(mid 280.185368 -316.305184)
		(end 279.636728 -315.756544)
		(stroke
			(width 0.2)
			(type default)
		)
		(layer "In6.Cu")
	)
	(gr_line
		(start 279.636728 -315.756544)
		(end 278.236934 -315.756544)
		(stroke
			(width 0.2)
			(type default)
		)
		(layer "In6.Cu")
	)
	(gr_arc
		(start 279.636728 -313.253882)
		(mid 280.185368 -312.705242)
		(end 279.636728 -312.156602)
		(stroke
			(width 0.2)
			(type default)
		)
		(layer "In6.Cu")
	)
	(gr_line
		(start 279.636728 -312.156602)
		(end 278.236934 -312.156602)
		(stroke
			(width 0.2)
			(type default)
		)
		(layer "In6.Cu")
	)
	(gr_arc
		(start 279.636728 -309.653686)
		(mid 280.185368 -309.105046)
		(end 279.636728 -308.556406)
		(stroke
			(width 0.2)
			(type default)
		)
		(layer "In6.Cu")
	)
	(gr_line
		(start 279.636728 -308.556406)
		(end 278.236934 -308.556406)
		(stroke
			(width 0.2)
			(type default)
		)
		(layer "In6.Cu")
	)
	(gr_arc
		(start 279.636728 -306.053744)
		(mid 280.185368 -305.505104)
		(end 279.636728 -304.956464)
		(stroke
			(width 0.2)
			(type default)
		)
		(layer "In6.Cu")
	)
	(gr_line
		(start 279.636728 -304.956464)
		(end 278.236934 -304.956464)
		(stroke
			(width 0.2)
			(type default)
		)
		(layer "In6.Cu")
	)
	(gr_arc
		(start 279.636728 -302.453802)
		(mid 280.185368 -301.905162)
		(end 279.636728 -301.356522)
		(stroke
			(width 0.2)
			(type default)
		)
		(layer "In6.Cu")
	)
	(gr_line
		(start 279.636728 -301.356522)
		(end 278.236934 -301.356522)
		(stroke
			(width 0.2)
			(type default)
		)
		(layer "In6.Cu")
	)
	(gr_arc
		(start 279.636728 -298.85386)
		(mid 280.185368 -298.30522)
		(end 279.636728 -297.75658)
		(stroke
			(width 0.2)
			(type default)
		)
		(layer "In6.Cu")
	)
	(gr_line
		(start 279.636728 -297.75658)
		(end 278.236934 -297.75658)
		(stroke
			(width 0.2)
			(type default)
		)
		(layer "In6.Cu")
	)
	(gr_arc
		(start 279.636728 -295.253918)
		(mid 280.185368 -294.705278)
		(end 279.636728 -294.156638)
		(stroke
			(width 0.2)
			(type default)
		)
		(layer "In6.Cu")
	)
	(gr_line
		(start 279.636728 -294.156638)
		(end 278.236934 -294.156638)
		(stroke
			(width 0.2)
			(type default)
		)
		(layer "In6.Cu")
	)
	(gr_arc
		(start 279.636728 -262.453374)
		(mid 280.187908 -261.902194)
		(end 279.636728 -261.351014)
		(stroke
			(width 0.2)
			(type default)
		)
		(layer "In6.Cu")
	)
	(gr_line
		(start 279.636728 -261.351014)
		(end 278.236934 -261.351014)
		(stroke
			(width 0.2)
			(type default)
		)
		(layer "In6.Cu")
	)
	(gr_arc
		(start 279.636728 -258.853432)
		(mid 280.187908 -258.302252)
		(end 279.636728 -257.751072)
		(stroke
			(width 0.2)
			(type default)
		)
		(layer "In6.Cu")
	)
	(gr_line
		(start 279.636728 -257.751072)
		(end 278.236934 -257.751072)
		(stroke
			(width 0.2)
			(type default)
		)
		(layer "In6.Cu")
	)
	(gr_arc
		(start 279.636728 -255.25349)
		(mid 280.187908 -254.70231)
		(end 279.636728 -254.15113)
		(stroke
			(width 0.2)
			(type default)
		)
		(layer "In6.Cu")
	)
	(gr_line
		(start 279.636728 -254.15113)
		(end 278.236934 -254.15113)
		(stroke
			(width 0.2)
			(type default)
		)
		(layer "In6.Cu")
	)
	(gr_arc
		(start 279.636728 -251.653548)
		(mid 280.187908 -251.102368)
		(end 279.636728 -250.551188)
		(stroke
			(width 0.2)
			(type default)
		)
		(layer "In6.Cu")
	)
	(gr_line
		(start 279.636728 -250.551188)
		(end 278.236934 -250.551188)
		(stroke
			(width 0.2)
			(type default)
		)
		(layer "In6.Cu")
	)
	(gr_line
		(start 279.748488 -187.6044)
		(end 279.8318 -187.6044)
		(stroke
			(width 0.381)
			(type default)
		)
		(layer "In6.Cu")
	)
	(gr_line
		(start 279.8318 -187.6044)
		(end 280.3652 -188.1378)
		(stroke
			(width 0.381)
			(type default)
		)
		(layer "In6.Cu")
	)
	(gr_line
		(start 280.0604 -84.455)
		(end 279.3238 -85.1916)
		(stroke
			(width 0.381)
			(type default)
		)
		(layer "In6.Cu")
	)
	(gr_line
		(start 280.162 -6.223)
		(end 283.8196 -6.223)
		(stroke
			(width 0.381)
			(type default)
		)
		(layer "In6.Cu")
	)
	(gr_line
		(start 280.17851 -102.539038)
		(end 279.182068 -101.542596)
		(stroke
			(width 0.381)
			(type default)
		)
		(layer "In6.Cu")
	)
	(gr_line
		(start 280.3652 -188.1378)
		(end 280.88971 -187.61329)
		(stroke
			(width 0.381)
			(type default)
		)
		(layer "In6.Cu")
	)
	(gr_line
		(start 280.3906 -190.0682)
		(end 280.3906 -187.6044)
		(stroke
			(width 0.381)
			(type default)
		)
		(layer "In6.Cu")
	)
	(gr_line
		(start 280.422858 -10.545826)
		(end 278.433784 -11.54049)
		(stroke
			(width 0.2)
			(type default)
		)
		(layer "In6.Cu")
	)
	(gr_line
		(start 280.423874 -176.847754)
		(end 278.424132 -177.847752)
		(stroke
			(width 0.2)
			(type default)
		)
		(layer "In6.Cu")
	)
	(gr_line
		(start 280.423874 -172.847762)
		(end 278.424132 -173.84776)
		(stroke
			(width 0.2)
			(type default)
		)
		(layer "In6.Cu")
	)
	(gr_line
		(start 280.423874 -168.84777)
		(end 278.424132 -169.847768)
		(stroke
			(width 0.2)
			(type default)
		)
		(layer "In6.Cu")
	)
	(gr_line
		(start 280.423874 -164.847778)
		(end 278.424132 -165.847776)
		(stroke
			(width 0.2)
			(type default)
		)
		(layer "In6.Cu")
	)
	(gr_line
		(start 280.423874 -136.847834)
		(end 278.424132 -137.847832)
		(stroke
			(width 0.2)
			(type default)
		)
		(layer "In6.Cu")
	)
	(gr_line
		(start 280.423874 -80.547972)
		(end 278.424132 -81.54797)
		(stroke
			(width 0.2)
			(type default)
		)
		(layer "In6.Cu")
	)
	(gr_line
		(start 280.423874 -76.54798)
		(end 278.424132 -77.547978)
		(stroke
			(width 0.2)
			(type default)
		)
		(layer "In6.Cu")
	)
	(gr_line
		(start 280.423874 -72.547988)
		(end 278.424132 -73.547986)
		(stroke
			(width 0.2)
			(type default)
		)
		(layer "In6.Cu")
	)
	(gr_line
		(start 280.423874 -68.547996)
		(end 278.424132 -69.547994)
		(stroke
			(width 0.2)
			(type default)
		)
		(layer "In6.Cu")
	)
	(gr_line
		(start 280.423874 -64.548004)
		(end 278.424132 -65.548002)
		(stroke
			(width 0.2)
			(type default)
		)
		(layer "In6.Cu")
	)
	(gr_line
		(start 280.423874 -60.548012)
		(end 278.424132 -61.54801)
		(stroke
			(width 0.2)
			(type default)
		)
		(layer "In6.Cu")
	)
	(gr_line
		(start 280.423874 -56.54802)
		(end 278.424132 -57.548018)
		(stroke
			(width 0.2)
			(type default)
		)
		(layer "In6.Cu")
	)
	(gr_line
		(start 280.423874 -52.548028)
		(end 278.424132 -53.548026)
		(stroke
			(width 0.2)
			(type default)
		)
		(layer "In6.Cu")
	)
	(gr_line
		(start 280.423874 -48.548036)
		(end 278.424132 -49.548034)
		(stroke
			(width 0.2)
			(type default)
		)
		(layer "In6.Cu")
	)
	(gr_line
		(start 280.423874 -44.548044)
		(end 278.424132 -45.548042)
		(stroke
			(width 0.2)
			(type default)
		)
		(layer "In6.Cu")
	)
	(gr_line
		(start 280.423874 -40.548052)
		(end 278.424132 -41.54805)
		(stroke
			(width 0.2)
			(type default)
		)
		(layer "In6.Cu")
	)
	(gr_line
		(start 280.423874 -36.54806)
		(end 278.424132 -37.548058)
		(stroke
			(width 0.2)
			(type default)
		)
		(layer "In6.Cu")
	)
	(gr_line
		(start 280.423874 -16.5481)
		(end 278.424132 -17.548098)
		(stroke
			(width 0.2)
			(type default)
		)
		(layer "In6.Cu")
	)
	(gr_line
		(start 280.425144 -176.85004)
		(end 280.423874 -176.847754)
		(stroke
			(width 0.2)
			(type default)
		)
		(layer "In6.Cu")
	)
	(gr_line
		(start 280.425144 -172.850048)
		(end 280.423874 -172.847762)
		(stroke
			(width 0.2)
			(type default)
		)
		(layer "In6.Cu")
	)
	(gr_line
		(start 280.425144 -168.850056)
		(end 280.423874 -168.84777)
		(stroke
			(width 0.2)
			(type default)
		)
		(layer "In6.Cu")
	)
	(gr_line
		(start 280.425144 -164.850064)
		(end 280.423874 -164.847778)
		(stroke
			(width 0.2)
			(type default)
		)
		(layer "In6.Cu")
	)
	(gr_line
		(start 280.425144 -136.85012)
		(end 280.423874 -136.847834)
		(stroke
			(width 0.2)
			(type default)
		)
		(layer "In6.Cu")
	)
	(gr_line
		(start 280.425144 -80.550258)
		(end 280.423874 -80.547972)
		(stroke
			(width 0.2)
			(type default)
		)
		(layer "In6.Cu")
	)
	(gr_line
		(start 280.425144 -76.550266)
		(end 280.423874 -76.54798)
		(stroke
			(width 0.2)
			(type default)
		)
		(layer "In6.Cu")
	)
	(gr_line
		(start 280.425144 -72.550274)
		(end 280.423874 -72.547988)
		(stroke
			(width 0.2)
			(type default)
		)
		(layer "In6.Cu")
	)
	(gr_line
		(start 280.425144 -68.550282)
		(end 280.423874 -68.547996)
		(stroke
			(width 0.2)
			(type default)
		)
		(layer "In6.Cu")
	)
	(gr_line
		(start 280.425144 -64.55029)
		(end 280.423874 -64.548004)
		(stroke
			(width 0.2)
			(type default)
		)
		(layer "In6.Cu")
	)
	(gr_line
		(start 280.425144 -60.550298)
		(end 280.423874 -60.548012)
		(stroke
			(width 0.2)
			(type default)
		)
		(layer "In6.Cu")
	)
	(gr_line
		(start 280.425144 -56.550306)
		(end 280.423874 -56.54802)
		(stroke
			(width 0.2)
			(type default)
		)
		(layer "In6.Cu")
	)
	(gr_line
		(start 280.425144 -52.550314)
		(end 280.423874 -52.548028)
		(stroke
			(width 0.2)
			(type default)
		)
		(layer "In6.Cu")
	)
	(gr_line
		(start 280.425144 -48.550322)
		(end 280.423874 -48.548036)
		(stroke
			(width 0.2)
			(type default)
		)
		(layer "In6.Cu")
	)
	(gr_line
		(start 280.425144 -44.55033)
		(end 280.423874 -44.548044)
		(stroke
			(width 0.2)
			(type default)
		)
		(layer "In6.Cu")
	)
	(gr_line
		(start 280.425144 -40.550338)
		(end 280.423874 -40.548052)
		(stroke
			(width 0.2)
			(type default)
		)
		(layer "In6.Cu")
	)
	(gr_line
		(start 280.425144 -36.550346)
		(end 280.423874 -36.54806)
		(stroke
			(width 0.2)
			(type default)
		)
		(layer "In6.Cu")
	)
	(gr_line
		(start 280.425144 -16.550386)
		(end 280.423874 -16.5481)
		(stroke
			(width 0.2)
			(type default)
		)
		(layer "In6.Cu")
	)
	(gr_line
		(start 280.42616 -160.852358)
		(end 278.426418 -161.852102)
		(stroke
			(width 0.2)
			(type default)
		)
		(layer "In6.Cu")
	)
	(gr_line
		(start 280.42616 -156.852366)
		(end 278.426418 -157.85211)
		(stroke
			(width 0.2)
			(type default)
		)
		(layer "In6.Cu")
	)
	(gr_line
		(start 280.42616 -152.852374)
		(end 278.426418 -153.852118)
		(stroke
			(width 0.2)
			(type default)
		)
		(layer "In6.Cu")
	)
	(gr_line
		(start 280.42616 -148.852382)
		(end 278.426418 -149.852126)
		(stroke
			(width 0.2)
			(type default)
		)
		(layer "In6.Cu")
	)
	(gr_line
		(start 280.42616 -128.852422)
		(end 278.426418 -129.852166)
		(stroke
			(width 0.2)
			(type default)
		)
		(layer "In6.Cu")
	)
	(gr_line
		(start 280.42616 -124.85243)
		(end 278.426418 -125.852174)
		(stroke
			(width 0.2)
			(type default)
		)
		(layer "In6.Cu")
	)
	(gr_line
		(start 280.42616 -120.852438)
		(end 278.426418 -121.852182)
		(stroke
			(width 0.2)
			(type default)
		)
		(layer "In6.Cu")
	)
	(gr_line
		(start 280.42616 -116.852446)
		(end 278.426418 -117.85219)
		(stroke
			(width 0.2)
			(type default)
		)
		(layer "In6.Cu")
	)
	(gr_line
		(start 280.436574 -112.872774)
		(end 278.44496 -113.868708)
		(stroke
			(width 0.2)
			(type default)
		)
		(layer "In6.Cu")
	)
	(gr_arc
		(start 280.636726 -358.253792)
		(mid 281.185366 -357.705152)
		(end 280.636726 -357.156512)
		(stroke
			(width 0.2)
			(type default)
		)
		(layer "In6.Cu")
	)
	(gr_line
		(start 280.636726 -357.156512)
		(end 279.236932 -357.156512)
		(stroke
			(width 0.2)
			(type default)
		)
		(layer "In6.Cu")
	)
	(gr_arc
		(start 280.636726 -354.65385)
		(mid 281.185366 -354.10521)
		(end 280.636726 -353.55657)
		(stroke
			(width 0.2)
			(type default)
		)
		(layer "In6.Cu")
	)
	(gr_line
		(start 280.636726 -353.55657)
		(end 279.236932 -353.55657)
		(stroke
			(width 0.2)
			(type default)
		)
		(layer "In6.Cu")
	)
	(gr_arc
		(start 280.636726 -351.053908)
		(mid 281.185366 -350.505268)
		(end 280.636726 -349.956628)
		(stroke
			(width 0.2)
			(type default)
		)
		(layer "In6.Cu")
	)
	(gr_line
		(start 280.636726 -349.956628)
		(end 279.236932 -349.956628)
		(stroke
			(width 0.2)
			(type default)
		)
		(layer "In6.Cu")
	)
	(gr_arc
		(start 280.636726 -347.453712)
		(mid 281.185366 -346.905072)
		(end 280.636726 -346.356432)
		(stroke
			(width 0.2)
			(type default)
		)
		(layer "In6.Cu")
	)
	(gr_line
		(start 280.636726 -346.356432)
		(end 279.236932 -346.356432)
		(stroke
			(width 0.2)
			(type default)
		)
		(layer "In6.Cu")
	)
	(gr_arc
		(start 280.636726 -343.85377)
		(mid 281.185366 -343.30513)
		(end 280.636726 -342.75649)
		(stroke
			(width 0.2)
			(type default)
		)
		(layer "In6.Cu")
	)
	(gr_line
		(start 280.636726 -342.75649)
		(end 279.236932 -342.75649)
		(stroke
			(width 0.2)
			(type default)
		)
		(layer "In6.Cu")
	)
	(gr_arc
		(start 280.636726 -340.253828)
		(mid 281.185366 -339.705188)
		(end 280.636726 -339.156548)
		(stroke
			(width 0.2)
			(type default)
		)
		(layer "In6.Cu")
	)
	(gr_line
		(start 280.636726 -339.156548)
		(end 279.236932 -339.156548)
		(stroke
			(width 0.2)
			(type default)
		)
		(layer "In6.Cu")
	)
	(gr_arc
		(start 280.636726 -336.653886)
		(mid 281.185366 -336.105246)
		(end 280.636726 -335.556606)
		(stroke
			(width 0.2)
			(type default)
		)
		(layer "In6.Cu")
	)
	(gr_line
		(start 280.636726 -335.556606)
		(end 279.236932 -335.556606)
		(stroke
			(width 0.2)
			(type default)
		)
		(layer "In6.Cu")
	)
	(gr_arc
		(start 280.636726 -333.05369)
		(mid 281.185366 -332.50505)
		(end 280.636726 -331.95641)
		(stroke
			(width 0.2)
			(type default)
		)
		(layer "In6.Cu")
	)
	(gr_line
		(start 280.636726 -331.95641)
		(end 279.236932 -331.95641)
		(stroke
			(width 0.2)
			(type default)
		)
		(layer "In6.Cu")
	)
	(gr_arc
		(start 280.636726 -329.453748)
		(mid 281.185366 -328.905108)
		(end 280.636726 -328.356468)
		(stroke
			(width 0.2)
			(type default)
		)
		(layer "In6.Cu")
	)
	(gr_line
		(start 280.636726 -328.356468)
		(end 279.236932 -328.356468)
		(stroke
			(width 0.2)
			(type default)
		)
		(layer "In6.Cu")
	)
	(gr_arc
		(start 280.636726 -325.853806)
		(mid 281.185366 -325.305166)
		(end 280.636726 -324.756526)
		(stroke
			(width 0.2)
			(type default)
		)
		(layer "In6.Cu")
	)
	(gr_line
		(start 280.636726 -324.756526)
		(end 279.236932 -324.756526)
		(stroke
			(width 0.2)
			(type default)
		)
		(layer "In6.Cu")
	)
	(gr_arc
		(start 280.636726 -322.253864)
		(mid 281.185366 -321.705224)
		(end 280.636726 -321.156584)
		(stroke
			(width 0.2)
			(type default)
		)
		(layer "In6.Cu")
	)
	(gr_line
		(start 280.636726 -321.156584)
		(end 279.236932 -321.156584)
		(stroke
			(width 0.2)
			(type default)
		)
		(layer "In6.Cu")
	)
	(gr_arc
		(start 280.636726 -318.653668)
		(mid 281.185366 -318.105028)
		(end 280.636726 -317.556388)
		(stroke
			(width 0.2)
			(type default)
		)
		(layer "In6.Cu")
	)
	(gr_line
		(start 280.636726 -317.556388)
		(end 279.236932 -317.556388)
		(stroke
			(width 0.2)
			(type default)
		)
		(layer "In6.Cu")
	)
	(gr_arc
		(start 280.636726 -315.053726)
		(mid 281.185366 -314.505086)
		(end 280.636726 -313.956446)
		(stroke
			(width 0.2)
			(type default)
		)
		(layer "In6.Cu")
	)
	(gr_line
		(start 280.636726 -313.956446)
		(end 279.236932 -313.956446)
		(stroke
			(width 0.2)
			(type default)
		)
		(layer "In6.Cu")
	)
	(gr_arc
		(start 280.636726 -311.453784)
		(mid 281.185366 -310.905144)
		(end 280.636726 -310.356504)
		(stroke
			(width 0.2)
			(type default)
		)
		(layer "In6.Cu")
	)
	(gr_line
		(start 280.636726 -310.356504)
		(end 279.236932 -310.356504)
		(stroke
			(width 0.2)
			(type default)
		)
		(layer "In6.Cu")
	)
	(gr_arc
		(start 280.636726 -307.853842)
		(mid 281.185366 -307.305202)
		(end 280.636726 -306.756562)
		(stroke
			(width 0.2)
			(type default)
		)
		(layer "In6.Cu")
	)
	(gr_line
		(start 280.636726 -306.756562)
		(end 279.236932 -306.756562)
		(stroke
			(width 0.2)
			(type default)
		)
		(layer "In6.Cu")
	)
	(gr_arc
		(start 280.636726 -304.2539)
		(mid 281.185366 -303.70526)
		(end 280.636726 -303.15662)
		(stroke
			(width 0.2)
			(type default)
		)
		(layer "In6.Cu")
	)
	(gr_line
		(start 280.636726 -303.15662)
		(end 279.236932 -303.15662)
		(stroke
			(width 0.2)
			(type default)
		)
		(layer "In6.Cu")
	)
	(gr_arc
		(start 280.636726 -300.653704)
		(mid 281.185366 -300.105064)
		(end 280.636726 -299.556424)
		(stroke
			(width 0.2)
			(type default)
		)
		(layer "In6.Cu")
	)
	(gr_line
		(start 280.636726 -299.556424)
		(end 279.236932 -299.556424)
		(stroke
			(width 0.2)
			(type default)
		)
		(layer "In6.Cu")
	)
	(gr_arc
		(start 280.636726 -297.053762)
		(mid 281.185366 -296.505122)
		(end 280.636726 -295.956482)
		(stroke
			(width 0.2)
			(type default)
		)
		(layer "In6.Cu")
	)
	(gr_line
		(start 280.636726 -295.956482)
		(end 279.236932 -295.956482)
		(stroke
			(width 0.2)
			(type default)
		)
		(layer "In6.Cu")
	)
	(gr_arc
		(start 280.636726 -264.253472)
		(mid 281.187906 -263.702292)
		(end 280.636726 -263.151112)
		(stroke
			(width 0.2)
			(type default)
		)
		(layer "In6.Cu")
	)
	(gr_line
		(start 280.636726 -263.151112)
		(end 279.236932 -263.151112)
		(stroke
			(width 0.2)
			(type default)
		)
		(layer "In6.Cu")
	)
	(gr_arc
		(start 280.636726 -260.65353)
		(mid 281.187906 -260.10235)
		(end 280.636726 -259.55117)
		(stroke
			(width 0.2)
			(type default)
		)
		(layer "In6.Cu")
	)
	(gr_line
		(start 280.636726 -259.55117)
		(end 279.236932 -259.55117)
		(stroke
			(width 0.2)
			(type default)
		)
		(layer "In6.Cu")
	)
	(gr_arc
		(start 280.636726 -257.053588)
		(mid 281.187906 -256.502408)
		(end 280.636726 -255.951228)
		(stroke
			(width 0.2)
			(type default)
		)
		(layer "In6.Cu")
	)
	(gr_line
		(start 280.636726 -255.951228)
		(end 279.236932 -255.951228)
		(stroke
			(width 0.2)
			(type default)
		)
		(layer "In6.Cu")
	)
	(gr_arc
		(start 280.636726 -253.453392)
		(mid 281.187906 -252.902212)
		(end 280.636726 -252.351032)
		(stroke
			(width 0.2)
			(type default)
		)
		(layer "In6.Cu")
	)
	(gr_line
		(start 280.636726 -252.351032)
		(end 279.236932 -252.351032)
		(stroke
			(width 0.2)
			(type default)
		)
		(layer "In6.Cu")
	)
	(gr_line
		(start 280.88971 -187.61329)
		(end 280.88971 -187.6044)
		(stroke
			(width 0.381)
			(type default)
		)
		(layer "In6.Cu")
	)
	(gr_arc
		(start 281.063446 -114.127026)
		(mid 281.377136 -113.186464)
		(end 280.436574 -112.872774)
		(stroke
			(width 0.2)
			(type default)
		)
		(layer "In6.Cu")
	)
	(gr_arc
		(start 281.07386 -162.14725)
		(mid 281.397456 -161.175954)
		(end 280.42616 -160.852358)
		(stroke
			(width 0.2)
			(type default)
		)
		(layer "In6.Cu")
	)
	(gr_arc
		(start 281.07386 -158.147258)
		(mid 281.397456 -157.175962)
		(end 280.42616 -156.852366)
		(stroke
			(width 0.2)
			(type default)
		)
		(layer "In6.Cu")
	)
	(gr_arc
		(start 281.07386 -154.147266)
		(mid 281.397456 -153.17597)
		(end 280.42616 -152.852374)
		(stroke
			(width 0.2)
			(type default)
		)
		(layer "In6.Cu")
	)
	(gr_arc
		(start 281.07386 -150.147274)
		(mid 281.397456 -149.175978)
		(end 280.42616 -148.852382)
		(stroke
			(width 0.2)
			(type default)
		)
		(layer "In6.Cu")
	)
	(gr_arc
		(start 281.07386 -130.147314)
		(mid 281.397456 -129.176018)
		(end 280.42616 -128.852422)
		(stroke
			(width 0.2)
			(type default)
		)
		(layer "In6.Cu")
	)
	(gr_arc
		(start 281.07386 -126.147322)
		(mid 281.397456 -125.176026)
		(end 280.42616 -124.85243)
		(stroke
			(width 0.2)
			(type default)
		)
		(layer "In6.Cu")
	)
	(gr_arc
		(start 281.07386 -122.14733)
		(mid 281.397456 -121.176034)
		(end 280.42616 -120.852438)
		(stroke
			(width 0.2)
			(type default)
		)
		(layer "In6.Cu")
	)
	(gr_arc
		(start 281.07386 -118.147338)
		(mid 281.397456 -117.176042)
		(end 280.42616 -116.852446)
		(stroke
			(width 0.2)
			(type default)
		)
		(layer "In6.Cu")
	)
	(gr_arc
		(start 281.074876 -178.149504)
		(mid 281.399742 -177.174906)
		(end 280.425144 -176.85004)
		(stroke
			(width 0.2)
			(type default)
		)
		(layer "In6.Cu")
	)
	(gr_arc
		(start 281.074876 -174.149512)
		(mid 281.399742 -173.174914)
		(end 280.425144 -172.850048)
		(stroke
			(width 0.2)
			(type default)
		)
		(layer "In6.Cu")
	)
	(gr_arc
		(start 281.074876 -170.14952)
		(mid 281.399742 -169.174922)
		(end 280.425144 -168.850056)
		(stroke
			(width 0.2)
			(type default)
		)
		(layer "In6.Cu")
	)
	(gr_arc
		(start 281.074876 -166.149528)
		(mid 281.399742 -165.17493)
		(end 280.425144 -164.850064)
		(stroke
			(width 0.2)
			(type default)
		)
		(layer "In6.Cu")
	)
	(gr_arc
		(start 281.074876 -138.149584)
		(mid 281.399742 -137.174986)
		(end 280.425144 -136.85012)
		(stroke
			(width 0.2)
			(type default)
		)
		(layer "In6.Cu")
	)
	(gr_arc
		(start 281.074876 -81.849722)
		(mid 281.399742 -80.875124)
		(end 280.425144 -80.550258)
		(stroke
			(width 0.2)
			(type default)
		)
		(layer "In6.Cu")
	)
	(gr_arc
		(start 281.074876 -77.84973)
		(mid 281.399742 -76.875132)
		(end 280.425144 -76.550266)
		(stroke
			(width 0.2)
			(type default)
		)
		(layer "In6.Cu")
	)
	(gr_arc
		(start 281.074876 -73.849738)
		(mid 281.399742 -72.87514)
		(end 280.425144 -72.550274)
		(stroke
			(width 0.2)
			(type default)
		)
		(layer "In6.Cu")
	)
	(gr_arc
		(start 281.074876 -69.849746)
		(mid 281.399742 -68.875148)
		(end 280.425144 -68.550282)
		(stroke
			(width 0.2)
			(type default)
		)
		(layer "In6.Cu")
	)
	(gr_arc
		(start 281.074876 -65.849754)
		(mid 281.399742 -64.875156)
		(end 280.425144 -64.55029)
		(stroke
			(width 0.2)
			(type default)
		)
		(layer "In6.Cu")
	)
	(gr_arc
		(start 281.074876 -61.849762)
		(mid 281.399742 -60.875164)
		(end 280.425144 -60.550298)
		(stroke
			(width 0.2)
			(type default)
		)
		(layer "In6.Cu")
	)
	(gr_arc
		(start 281.074876 -57.84977)
		(mid 281.399742 -56.875172)
		(end 280.425144 -56.550306)
		(stroke
			(width 0.2)
			(type default)
		)
		(layer "In6.Cu")
	)
	(gr_arc
		(start 281.074876 -53.849778)
		(mid 281.399742 -52.87518)
		(end 280.425144 -52.550314)
		(stroke
			(width 0.2)
			(type default)
		)
		(layer "In6.Cu")
	)
	(gr_arc
		(start 281.074876 -49.849786)
		(mid 281.399742 -48.875188)
		(end 280.425144 -48.550322)
		(stroke
			(width 0.2)
			(type default)
		)
		(layer "In6.Cu")
	)
	(gr_arc
		(start 281.074876 -45.849794)
		(mid 281.399742 -44.875196)
		(end 280.425144 -44.55033)
		(stroke
			(width 0.2)
			(type default)
		)
		(layer "In6.Cu")
	)
	(gr_arc
		(start 281.074876 -41.849802)
		(mid 281.399742 -40.875204)
		(end 280.425144 -40.550338)
		(stroke
			(width 0.2)
			(type default)
		)
		(layer "In6.Cu")
	)
	(gr_arc
		(start 281.074876 -37.84981)
		(mid 281.399742 -36.875212)
		(end 280.425144 -36.550346)
		(stroke
			(width 0.2)
			(type default)
		)
		(layer "In6.Cu")
	)
	(gr_arc
		(start 281.074876 -17.84985)
		(mid 281.399742 -16.875252)
		(end 280.425144 -16.550386)
		(stroke
			(width 0.2)
			(type default)
		)
		(layer "In6.Cu")
	)
	(gr_line
		(start 281.076146 -178.15179)
		(end 281.074876 -178.149504)
		(stroke
			(width 0.2)
			(type default)
		)
		(layer "In6.Cu")
	)
	(gr_line
		(start 281.076146 -174.151798)
		(end 281.074876 -174.149512)
		(stroke
			(width 0.2)
			(type default)
		)
		(layer "In6.Cu")
	)
	(gr_line
		(start 281.076146 -170.151806)
		(end 281.074876 -170.14952)
		(stroke
			(width 0.2)
			(type default)
		)
		(layer "In6.Cu")
	)
	(gr_line
		(start 281.076146 -166.151814)
		(end 281.074876 -166.149528)
		(stroke
			(width 0.2)
			(type default)
		)
		(layer "In6.Cu")
	)
	(gr_line
		(start 281.076146 -138.15187)
		(end 281.074876 -138.149584)
		(stroke
			(width 0.2)
			(type default)
		)
		(layer "In6.Cu")
	)
	(gr_line
		(start 281.076146 -81.852008)
		(end 281.074876 -81.849722)
		(stroke
			(width 0.2)
			(type default)
		)
		(layer "In6.Cu")
	)
	(gr_line
		(start 281.076146 -77.852016)
		(end 281.074876 -77.84973)
		(stroke
			(width 0.2)
			(type default)
		)
		(layer "In6.Cu")
	)
	(gr_line
		(start 281.076146 -73.852024)
		(end 281.074876 -73.849738)
		(stroke
			(width 0.2)
			(type default)
		)
		(layer "In6.Cu")
	)
	(gr_line
		(start 281.076146 -69.852032)
		(end 281.074876 -69.849746)
		(stroke
			(width 0.2)
			(type default)
		)
		(layer "In6.Cu")
	)
	(gr_line
		(start 281.076146 -65.85204)
		(end 281.074876 -65.849754)
		(stroke
			(width 0.2)
			(type default)
		)
		(layer "In6.Cu")
	)
	(gr_line
		(start 281.076146 -61.852048)
		(end 281.074876 -61.849762)
		(stroke
			(width 0.2)
			(type default)
		)
		(layer "In6.Cu")
	)
	(gr_line
		(start 281.076146 -57.852056)
		(end 281.074876 -57.84977)
		(stroke
			(width 0.2)
			(type default)
		)
		(layer "In6.Cu")
	)
	(gr_line
		(start 281.076146 -53.852064)
		(end 281.074876 -53.849778)
		(stroke
			(width 0.2)
			(type default)
		)
		(layer "In6.Cu")
	)
	(gr_line
		(start 281.076146 -49.852072)
		(end 281.074876 -49.849786)
		(stroke
			(width 0.2)
			(type default)
		)
		(layer "In6.Cu")
	)
	(gr_line
		(start 281.076146 -45.85208)
		(end 281.074876 -45.849794)
		(stroke
			(width 0.2)
			(type default)
		)
		(layer "In6.Cu")
	)
	(gr_line
		(start 281.076146 -41.852088)
		(end 281.074876 -41.849802)
		(stroke
			(width 0.2)
			(type default)
		)
		(layer "In6.Cu")
	)
	(gr_line
		(start 281.076146 -37.852096)
		(end 281.074876 -37.84981)
		(stroke
			(width 0.2)
			(type default)
		)
		(layer "In6.Cu")
	)
	(gr_line
		(start 281.076146 -17.852136)
		(end 281.074876 -17.84985)
		(stroke
			(width 0.2)
			(type default)
		)
		(layer "In6.Cu")
	)
	(gr_arc
		(start 281.077162 -11.854434)
		(mid 281.404314 -10.872978)
		(end 280.422858 -10.545826)
		(stroke
			(width 0.2)
			(type default)
		)
		(layer "In6.Cu")
	)
	(gr_line
		(start 281.1018 -84.455)
		(end 280.0604 -84.455)
		(stroke
			(width 0.381)
			(type default)
		)
		(layer "In6.Cu")
	)
	(gr_line
		(start 282.83662 -264.250932)
		(end 284.236668 -264.250932)
		(stroke
			(width 0.2)
			(type default)
		)
		(layer "In6.Cu")
	)
	(gr_arc
		(start 282.83662 -263.153652)
		(mid 282.28798 -263.702292)
		(end 282.83662 -264.250932)
		(stroke
			(width 0.2)
			(type default)
		)
		(layer "In6.Cu")
	)
	(gr_line
		(start 282.8544 -187.6044)
		(end 287.67024 -182.78856)
		(stroke
			(width 0.381)
			(type default)
		)
		(layer "In6.Cu")
	)
	(gr_line
		(start 282.922726 -35.854386)
		(end 284.922468 -36.854384)
		(stroke
			(width 0.2)
			(type default)
		)
		(layer "In6.Cu")
	)
	(gr_line
		(start 282.923742 -136.151874)
		(end 284.923738 -137.151872)
		(stroke
			(width 0.2)
			(type default)
		)
		(layer "In6.Cu")
	)
	(gr_line
		(start 282.923742 -108.15193)
		(end 284.923738 -109.151928)
		(stroke
			(width 0.2)
			(type default)
		)
		(layer "In6.Cu")
	)
	(gr_line
		(start 282.925012 -136.149588)
		(end 282.923742 -136.151874)
		(stroke
			(width 0.2)
			(type default)
		)
		(layer "In6.Cu")
	)
	(gr_line
		(start 282.936442 -180.126894)
		(end 284.928056 -181.122574)
		(stroke
			(width 0.2)
			(type default)
		)
		(layer "In6.Cu")
	)
	(gr_line
		(start 282.936442 -176.126902)
		(end 284.928056 -177.122582)
		(stroke
			(width 0.2)
			(type default)
		)
		(layer "In6.Cu")
	)
	(gr_line
		(start 282.936442 -172.12691)
		(end 284.928056 -173.12259)
		(stroke
			(width 0.2)
			(type default)
		)
		(layer "In6.Cu")
	)
	(gr_line
		(start 282.936442 -168.126918)
		(end 284.928056 -169.122598)
		(stroke
			(width 0.2)
			(type default)
		)
		(layer "In6.Cu")
	)
	(gr_line
		(start 282.936442 -164.126926)
		(end 284.928056 -165.122606)
		(stroke
			(width 0.2)
			(type default)
		)
		(layer "In6.Cu")
	)
	(gr_line
		(start 282.936442 -160.126934)
		(end 284.936438 -161.126932)
		(stroke
			(width 0.2)
			(type default)
		)
		(layer "In6.Cu")
	)
	(gr_line
		(start 282.936442 -156.126942)
		(end 284.928056 -157.122622)
		(stroke
			(width 0.2)
			(type default)
		)
		(layer "In6.Cu")
	)
	(gr_line
		(start 282.936442 -152.12695)
		(end 284.928056 -153.12263)
		(stroke
			(width 0.2)
			(type default)
		)
		(layer "In6.Cu")
	)
	(gr_line
		(start 282.936442 -128.126998)
		(end 284.928056 -129.122678)
		(stroke
			(width 0.2)
			(type default)
		)
		(layer "In6.Cu")
	)
	(gr_line
		(start 282.936442 -124.127006)
		(end 284.928056 -125.122686)
		(stroke
			(width 0.2)
			(type default)
		)
		(layer "In6.Cu")
	)
	(gr_line
		(start 282.936442 -120.127014)
		(end 284.928056 -121.122694)
		(stroke
			(width 0.2)
			(type default)
		)
		(layer "In6.Cu")
	)
	(gr_line
		(start 282.936442 -116.127022)
		(end 284.928056 -117.122702)
		(stroke
			(width 0.2)
			(type default)
		)
		(layer "In6.Cu")
	)
	(gr_line
		(start 282.936442 -83.827112)
		(end 284.928056 -84.822792)
		(stroke
			(width 0.2)
			(type default)
		)
		(layer "In6.Cu")
	)
	(gr_line
		(start 282.936442 -79.82712)
		(end 284.928056 -80.8228)
		(stroke
			(width 0.2)
			(type default)
		)
		(layer "In6.Cu")
	)
	(gr_line
		(start 282.936442 -75.827128)
		(end 284.928056 -76.822808)
		(stroke
			(width 0.2)
			(type default)
		)
		(layer "In6.Cu")
	)
	(gr_line
		(start 282.936442 -71.827136)
		(end 284.928056 -72.822816)
		(stroke
			(width 0.2)
			(type default)
		)
		(layer "In6.Cu")
	)
	(gr_line
		(start 282.936442 -67.827144)
		(end 284.928056 -68.822824)
		(stroke
			(width 0.2)
			(type default)
		)
		(layer "In6.Cu")
	)
	(gr_line
		(start 282.936442 -63.827152)
		(end 284.928056 -64.822832)
		(stroke
			(width 0.2)
			(type default)
		)
		(layer "In6.Cu")
	)
	(gr_line
		(start 282.936442 -59.82716)
		(end 284.928056 -60.82284)
		(stroke
			(width 0.2)
			(type default)
		)
		(layer "In6.Cu")
	)
	(gr_line
		(start 282.936442 -55.827168)
		(end 284.928056 -56.822848)
		(stroke
			(width 0.2)
			(type default)
		)
		(layer "In6.Cu")
	)
	(gr_line
		(start 282.936442 -51.827176)
		(end 284.928056 -52.822856)
		(stroke
			(width 0.2)
			(type default)
		)
		(layer "In6.Cu")
	)
	(gr_line
		(start 282.936442 -47.827184)
		(end 284.928056 -48.822864)
		(stroke
			(width 0.2)
			(type default)
		)
		(layer "In6.Cu")
	)
	(gr_line
		(start 282.936442 -43.827192)
		(end 284.928056 -44.822872)
		(stroke
			(width 0.2)
			(type default)
		)
		(layer "In6.Cu")
	)
	(gr_line
		(start 282.936442 -39.8272)
		(end 284.928056 -40.82288)
		(stroke
			(width 0.2)
			(type default)
		)
		(layer "In6.Cu")
	)
	(gr_arc
		(start 283.563314 -178.872642)
		(mid 282.622752 -179.186332)
		(end 282.936442 -180.126894)
		(stroke
			(width 0.2)
			(type default)
		)
		(layer "In6.Cu")
	)
	(gr_arc
		(start 283.563314 -174.87265)
		(mid 282.622752 -175.18634)
		(end 282.936442 -176.126902)
		(stroke
			(width 0.2)
			(type default)
		)
		(layer "In6.Cu")
	)
	(gr_arc
		(start 283.563314 -170.872658)
		(mid 282.622752 -171.186348)
		(end 282.936442 -172.12691)
		(stroke
			(width 0.2)
			(type default)
		)
		(layer "In6.Cu")
	)
	(gr_arc
		(start 283.563314 -166.872666)
		(mid 282.622752 -167.186356)
		(end 282.936442 -168.126918)
		(stroke
			(width 0.2)
			(type default)
		)
		(layer "In6.Cu")
	)
	(gr_arc
		(start 283.563314 -162.872674)
		(mid 282.622752 -163.186364)
		(end 282.936442 -164.126926)
		(stroke
			(width 0.2)
			(type default)
		)
		(layer "In6.Cu")
	)
	(gr_arc
		(start 283.563314 -154.87269)
		(mid 282.622752 -155.18638)
		(end 282.936442 -156.126942)
		(stroke
			(width 0.2)
			(type default)
		)
		(layer "In6.Cu")
	)
	(gr_arc
		(start 283.563314 -150.872698)
		(mid 282.622752 -151.186388)
		(end 282.936442 -152.12695)
		(stroke
			(width 0.2)
			(type default)
		)
		(layer "In6.Cu")
	)
	(gr_arc
		(start 283.563314 -126.872746)
		(mid 282.622752 -127.186436)
		(end 282.936442 -128.126998)
		(stroke
			(width 0.2)
			(type default)
		)
		(layer "In6.Cu")
	)
	(gr_arc
		(start 283.563314 -122.872754)
		(mid 282.622752 -123.186444)
		(end 282.936442 -124.127006)
		(stroke
			(width 0.2)
			(type default)
		)
		(layer "In6.Cu")
	)
	(gr_arc
		(start 283.563314 -118.872762)
		(mid 282.622752 -119.186452)
		(end 282.936442 -120.127014)
		(stroke
			(width 0.2)
			(type default)
		)
		(layer "In6.Cu")
	)
	(gr_arc
		(start 283.563314 -114.87277)
		(mid 282.622752 -115.18646)
		(end 282.936442 -116.127022)
		(stroke
			(width 0.2)
			(type default)
		)
		(layer "In6.Cu")
	)
	(gr_arc
		(start 283.563314 -82.57286)
		(mid 282.622752 -82.88655)
		(end 282.936442 -83.827112)
		(stroke
			(width 0.2)
			(type default)
		)
		(layer "In6.Cu")
	)
	(gr_arc
		(start 283.563314 -78.572868)
		(mid 282.622752 -78.886558)
		(end 282.936442 -79.82712)
		(stroke
			(width 0.2)
			(type default)
		)
		(layer "In6.Cu")
	)
	(gr_arc
		(start 283.563314 -74.572876)
		(mid 282.622752 -74.886566)
		(end 282.936442 -75.827128)
		(stroke
			(width 0.2)
			(type default)
		)
		(layer "In6.Cu")
	)
	(gr_arc
		(start 283.563314 -70.572884)
		(mid 282.622752 -70.886574)
		(end 282.936442 -71.827136)
		(stroke
			(width 0.2)
			(type default)
		)
		(layer "In6.Cu")
	)
	(gr_arc
		(start 283.563314 -66.572892)
		(mid 282.622752 -66.886582)
		(end 282.936442 -67.827144)
		(stroke
			(width 0.2)
			(type default)
		)
		(layer "In6.Cu")
	)
	(gr_arc
		(start 283.563314 -62.5729)
		(mid 282.622752 -62.88659)
		(end 282.936442 -63.827152)
		(stroke
			(width 0.2)
			(type default)
		)
		(layer "In6.Cu")
	)
	(gr_arc
		(start 283.563314 -58.572908)
		(mid 282.622752 -58.886598)
		(end 282.936442 -59.82716)
		(stroke
			(width 0.2)
			(type default)
		)
		(layer "In6.Cu")
	)
	(gr_arc
		(start 283.563314 -54.572916)
		(mid 282.622752 -54.886606)
		(end 282.936442 -55.827168)
		(stroke
			(width 0.2)
			(type default)
		)
		(layer "In6.Cu")
	)
	(gr_arc
		(start 283.563314 -50.572924)
		(mid 282.622752 -50.886614)
		(end 282.936442 -51.827176)
		(stroke
			(width 0.2)
			(type default)
		)
		(layer "In6.Cu")
	)
	(gr_arc
		(start 283.563314 -46.572932)
		(mid 282.622752 -46.886622)
		(end 282.936442 -47.827184)
		(stroke
			(width 0.2)
			(type default)
		)
		(layer "In6.Cu")
	)
	(gr_arc
		(start 283.563314 -42.57294)
		(mid 282.622752 -42.88663)
		(end 282.936442 -43.827192)
		(stroke
			(width 0.2)
			(type default)
		)
		(layer "In6.Cu")
	)
	(gr_arc
		(start 283.563314 -38.572948)
		(mid 282.622752 -38.886638)
		(end 282.936442 -39.8272)
		(stroke
			(width 0.2)
			(type default)
		)
		(layer "In6.Cu")
	)
	(gr_arc
		(start 283.571696 -158.877)
		(mid 282.62492 -159.182185)
		(end 282.936442 -160.126934)
		(stroke
			(width 0.2)
			(type default)
		)
		(layer "In6.Cu")
	)
	(gr_arc
		(start 283.574744 -134.850124)
		(mid 282.600146 -135.17499)
		(end 282.925012 -136.149588)
		(stroke
			(width 0.2)
			(type default)
		)
		(layer "In6.Cu")
	)
	(gr_line
		(start 283.576014 -134.847838)
		(end 283.574744 -134.850124)
		(stroke
			(width 0.2)
			(type default)
		)
		(layer "In6.Cu")
	)
	(gr_arc
		(start 283.576014 -106.847894)
		(mid 282.59786 -107.173776)
		(end 282.923742 -108.15193)
		(stroke
			(width 0.2)
			(type default)
		)
		(layer "In6.Cu")
	)
	(gr_arc
		(start 283.57703 -34.545778)
		(mid 282.595574 -34.87293)
		(end 282.922726 -35.854386)
		(stroke
			(width 0.2)
			(type default)
		)
		(layer "In6.Cu")
	)
	(gr_line
		(start 283.814774 -102.539038)
		(end 280.17851 -102.539038)
		(stroke
			(width 0.381)
			(type default)
		)
		(layer "In6.Cu")
	)
	(gr_line
		(start 283.8196 -6.223)
		(end 284.8356 -5.207)
		(stroke
			(width 0.381)
			(type default)
		)
		(layer "In6.Cu")
	)
	(gr_line
		(start 283.972 -87.3252)
		(end 281.1018 -84.455)
		(stroke
			(width 0.381)
			(type default)
		)
		(layer "In6.Cu")
	)
	(gr_arc
		(start 284.236668 -264.250932)
		(mid 284.785308 -263.702292)
		(end 284.236668 -263.153652)
		(stroke
			(width 0.2)
			(type default)
		)
		(layer "In6.Cu")
	)
	(gr_line
		(start 284.236668 -263.153652)
		(end 282.83662 -263.153652)
		(stroke
			(width 0.2)
			(type default)
		)
		(layer "In6.Cu")
	)
	(gr_line
		(start 284.8356 -5.207)
		(end 286.258 -5.207)
		(stroke
			(width 0.381)
			(type default)
		)
		(layer "In6.Cu")
	)
	(gr_line
		(start 284.863032 -101.49078)
		(end 283.814774 -102.539038)
		(stroke
			(width 0.381)
			(type default)
		)
		(layer "In6.Cu")
	)
	(gr_arc
		(start 284.922468 -36.854384)
		(mid 285.904229 -36.527384)
		(end 285.577026 -35.545776)
		(stroke
			(width 0.2)
			(type default)
		)
		(layer "In6.Cu")
	)
	(gr_line
		(start 284.923738 -137.151872)
		(end 284.923992 -137.151618)
		(stroke
			(width 0.2)
			(type default)
		)
		(layer "In6.Cu")
	)
	(gr_arc
		(start 284.923738 -109.151928)
		(mid 285.901892 -108.826046)
		(end 285.57601 -107.847892)
		(stroke
			(width 0.2)
			(type default)
		)
		(layer "In6.Cu")
	)
	(gr_line
		(start 284.923992 -137.151618)
		(end 284.925008 -137.149586)
		(stroke
			(width 0.2)
			(type default)
		)
		(layer "In6.Cu")
	)
	(gr_arc
		(start 284.925008 -137.149586)
		(mid 285.899606 -136.82472)
		(end 285.57474 -135.850122)
		(stroke
			(width 0.2)
			(type default)
		)
		(layer "In6.Cu")
	)
	(gr_arc
		(start 284.928056 -181.122574)
		(mid 285.874832 -180.817389)
		(end 285.56331 -179.87264)
		(stroke
			(width 0.2)
			(type default)
		)
		(layer "In6.Cu")
	)
	(gr_arc
		(start 284.928056 -177.122582)
		(mid 285.874832 -176.817397)
		(end 285.56331 -175.872648)
		(stroke
			(width 0.2)
			(type default)
		)
		(layer "In6.Cu")
	)
	(gr_arc
		(start 284.928056 -173.12259)
		(mid 285.874832 -172.817405)
		(end 285.56331 -171.872656)
		(stroke
			(width 0.2)
			(type default)
		)
		(layer "In6.Cu")
	)
	(gr_arc
		(start 284.928056 -169.122598)
		(mid 285.874832 -168.817413)
		(end 285.56331 -167.872664)
		(stroke
			(width 0.2)
			(type default)
		)
		(layer "In6.Cu")
	)
	(gr_arc
		(start 284.928056 -165.122606)
		(mid 285.874832 -164.817421)
		(end 285.56331 -163.872672)
		(stroke
			(width 0.2)
			(type default)
		)
		(layer "In6.Cu")
	)
	(gr_arc
		(start 284.928056 -157.122622)
		(mid 285.874832 -156.817437)
		(end 285.56331 -155.872688)
		(stroke
			(width 0.2)
			(type default)
		)
		(layer "In6.Cu")
	)
	(gr_arc
		(start 284.928056 -153.12263)
		(mid 285.874832 -152.817445)
		(end 285.56331 -151.872696)
		(stroke
			(width 0.2)
			(type default)
		)
		(layer "In6.Cu")
	)
	(gr_arc
		(start 284.928056 -129.122678)
		(mid 285.874832 -128.817493)
		(end 285.56331 -127.872744)
		(stroke
			(width 0.2)
			(type default)
		)
		(layer "In6.Cu")
	)
	(gr_arc
		(start 284.928056 -125.122686)
		(mid 285.874832 -124.817501)
		(end 285.56331 -123.872752)
		(stroke
			(width 0.2)
			(type default)
		)
		(layer "In6.Cu")
	)
	(gr_arc
		(start 284.928056 -121.122694)
		(mid 285.874832 -120.817509)
		(end 285.56331 -119.87276)
		(stroke
			(width 0.2)
			(type default)
		)
		(layer "In6.Cu")
	)
	(gr_arc
		(start 284.928056 -117.122702)
		(mid 285.874832 -116.817517)
		(end 285.56331 -115.872768)
		(stroke
			(width 0.2)
			(type default)
		)
		(layer "In6.Cu")
	)
	(gr_arc
		(start 284.928056 -84.822792)
		(mid 285.874832 -84.517607)
		(end 285.56331 -83.572858)
		(stroke
			(width 0.2)
			(type default)
		)
		(layer "In6.Cu")
	)
	(gr_arc
		(start 284.928056 -80.8228)
		(mid 285.874832 -80.517615)
		(end 285.56331 -79.572866)
		(stroke
			(width 0.2)
			(type default)
		)
		(layer "In6.Cu")
	)
	(gr_arc
		(start 284.928056 -76.822808)
		(mid 285.874832 -76.517623)
		(end 285.56331 -75.572874)
		(stroke
			(width 0.2)
			(type default)
		)
		(layer "In6.Cu")
	)
	(gr_arc
		(start 284.928056 -72.822816)
		(mid 285.874832 -72.517631)
		(end 285.56331 -71.572882)
		(stroke
			(width 0.2)
			(type default)
		)
		(layer "In6.Cu")
	)
	(gr_arc
		(start 284.928056 -68.822824)
		(mid 285.874832 -68.517639)
		(end 285.56331 -67.57289)
		(stroke
			(width 0.2)
			(type default)
		)
		(layer "In6.Cu")
	)
	(gr_arc
		(start 284.928056 -64.822832)
		(mid 285.874832 -64.517647)
		(end 285.56331 -63.572898)
		(stroke
			(width 0.2)
			(type default)
		)
		(layer "In6.Cu")
	)
	(gr_arc
		(start 284.928056 -60.82284)
		(mid 285.874832 -60.517655)
		(end 285.56331 -59.572906)
		(stroke
			(width 0.2)
			(type default)
		)
		(layer "In6.Cu")
	)
	(gr_arc
		(start 284.928056 -56.822848)
		(mid 285.874832 -56.517663)
		(end 285.56331 -55.572914)
		(stroke
			(width 0.2)
			(type default)
		)
		(layer "In6.Cu")
	)
	(gr_arc
		(start 284.928056 -52.822856)
		(mid 285.874832 -52.517671)
		(end 285.56331 -51.572922)
		(stroke
			(width 0.2)
			(type default)
		)
		(layer "In6.Cu")
	)
	(gr_arc
		(start 284.928056 -48.822864)
		(mid 285.874832 -48.517679)
		(end 285.56331 -47.57293)
		(stroke
			(width 0.2)
			(type default)
		)
		(layer "In6.Cu")
	)
	(gr_arc
		(start 284.928056 -44.822872)
		(mid 285.874832 -44.517687)
		(end 285.56331 -43.572938)
		(stroke
			(width 0.2)
			(type default)
		)
		(layer "In6.Cu")
	)
	(gr_arc
		(start 284.928056 -40.82288)
		(mid 285.874832 -40.517695)
		(end 285.56331 -39.572946)
		(stroke
			(width 0.2)
			(type default)
		)
		(layer "In6.Cu")
	)
	(gr_arc
		(start 284.936438 -161.126932)
		(mid 285.877 -160.813242)
		(end 285.56331 -159.87268)
		(stroke
			(width 0.2)
			(type default)
		)
		(layer "In6.Cu")
	)
	(gr_line
		(start 285.436564 -356.456234)
		(end 286.836612 -356.456234)
		(stroke
			(width 0.2)
			(type default)
		)
		(layer "In6.Cu")
	)
	(gr_arc
		(start 285.436564 -355.353874)
		(mid 284.885384 -355.905054)
		(end 285.436564 -356.456234)
		(stroke
			(width 0.2)
			(type default)
		)
		(layer "In6.Cu")
	)
	(gr_line
		(start 285.436564 -352.856292)
		(end 286.836612 -352.856292)
		(stroke
			(width 0.2)
			(type default)
		)
		(layer "In6.Cu")
	)
	(gr_arc
		(start 285.436564 -351.753932)
		(mid 284.885384 -352.305112)
		(end 285.436564 -352.856292)
		(stroke
			(width 0.2)
			(type default)
		)
		(layer "In6.Cu")
	)
	(gr_line
		(start 285.436564 -349.25635)
		(end 286.836612 -349.25635)
		(stroke
			(width 0.2)
			(type default)
		)
		(layer "In6.Cu")
	)
	(gr_arc
		(start 285.436564 -348.15399)
		(mid 284.885384 -348.70517)
		(end 285.436564 -349.25635)
		(stroke
			(width 0.2)
			(type default)
		)
		(layer "In6.Cu")
	)
	(gr_line
		(start 285.436564 -345.653868)
		(end 286.836612 -345.653868)
		(stroke
			(width 0.2)
			(type default)
		)
		(layer "In6.Cu")
	)
	(gr_arc
		(start 285.436564 -344.556588)
		(mid 284.887924 -345.105228)
		(end 285.436564 -345.653868)
		(stroke
			(width 0.2)
			(type default)
		)
		(layer "In6.Cu")
	)
	(gr_line
		(start 285.436564 -342.053672)
		(end 286.836612 -342.053672)
		(stroke
			(width 0.2)
			(type default)
		)
		(layer "In6.Cu")
	)
	(gr_arc
		(start 285.436564 -340.956392)
		(mid 284.887924 -341.505032)
		(end 285.436564 -342.053672)
		(stroke
			(width 0.2)
			(type default)
		)
		(layer "In6.Cu")
	)
	(gr_line
		(start 285.436564 -338.45373)
		(end 286.836612 -338.45373)
		(stroke
			(width 0.2)
			(type default)
		)
		(layer "In6.Cu")
	)
	(gr_arc
		(start 285.436564 -337.35645)
		(mid 284.887924 -337.90509)
		(end 285.436564 -338.45373)
		(stroke
			(width 0.2)
			(type default)
		)
		(layer "In6.Cu")
	)
	(gr_line
		(start 285.436564 -334.856328)
		(end 286.836612 -334.856328)
		(stroke
			(width 0.2)
			(type default)
		)
		(layer "In6.Cu")
	)
	(gr_arc
		(start 285.436564 -333.753968)
		(mid 284.885384 -334.305148)
		(end 285.436564 -334.856328)
		(stroke
			(width 0.2)
			(type default)
		)
		(layer "In6.Cu")
	)
	(gr_line
		(start 285.436564 -331.256386)
		(end 286.836612 -331.256386)
		(stroke
			(width 0.2)
			(type default)
		)
		(layer "In6.Cu")
	)
	(gr_arc
		(start 285.436564 -330.154026)
		(mid 284.885384 -330.705206)
		(end 285.436564 -331.256386)
		(stroke
			(width 0.2)
			(type default)
		)
		(layer "In6.Cu")
	)
	(gr_line
		(start 285.436564 -327.656444)
		(end 286.836612 -327.656444)
		(stroke
			(width 0.2)
			(type default)
		)
		(layer "In6.Cu")
	)
	(gr_arc
		(start 285.436564 -326.554084)
		(mid 284.885384 -327.105264)
		(end 285.436564 -327.656444)
		(stroke
			(width 0.2)
			(type default)
		)
		(layer "In6.Cu")
	)
	(gr_line
		(start 285.436564 -324.053708)
		(end 286.836612 -324.053708)
		(stroke
			(width 0.2)
			(type default)
		)
		(layer "In6.Cu")
	)
	(gr_arc
		(start 285.436564 -322.956428)
		(mid 284.887924 -323.505068)
		(end 285.436564 -324.053708)
		(stroke
			(width 0.2)
			(type default)
		)
		(layer "In6.Cu")
	)
	(gr_line
		(start 285.436564 -320.453766)
		(end 286.836612 -320.453766)
		(stroke
			(width 0.2)
			(type default)
		)
		(layer "In6.Cu")
	)
	(gr_arc
		(start 285.436564 -319.356486)
		(mid 284.887924 -319.905126)
		(end 285.436564 -320.453766)
		(stroke
			(width 0.2)
			(type default)
		)
		(layer "In6.Cu")
	)
	(gr_line
		(start 285.436564 -316.853824)
		(end 286.836612 -316.853824)
		(stroke
			(width 0.2)
			(type default)
		)
		(layer "In6.Cu")
	)
	(gr_arc
		(start 285.436564 -315.756544)
		(mid 284.887924 -316.305184)
		(end 285.436564 -316.853824)
		(stroke
			(width 0.2)
			(type default)
		)
		(layer "In6.Cu")
	)
	(gr_line
		(start 285.436564 -313.256422)
		(end 286.836612 -313.256422)
		(stroke
			(width 0.2)
			(type default)
		)
		(layer "In6.Cu")
	)
	(gr_arc
		(start 285.436564 -312.154062)
		(mid 284.885384 -312.705242)
		(end 285.436564 -313.256422)
		(stroke
			(width 0.2)
			(type default)
		)
		(layer "In6.Cu")
	)
	(gr_line
		(start 285.436564 -309.656226)
		(end 286.836612 -309.656226)
		(stroke
			(width 0.2)
			(type default)
		)
		(layer "In6.Cu")
	)
	(gr_arc
		(start 285.436564 -308.553866)
		(mid 284.885384 -309.105046)
		(end 285.436564 -309.656226)
		(stroke
			(width 0.2)
			(type default)
		)
		(layer "In6.Cu")
	)
	(gr_line
		(start 285.436564 -306.056284)
		(end 286.836612 -306.056284)
		(stroke
			(width 0.2)
			(type default)
		)
		(layer "In6.Cu")
	)
	(gr_arc
		(start 285.436564 -304.953924)
		(mid 284.885384 -305.505104)
		(end 285.436564 -306.056284)
		(stroke
			(width 0.2)
			(type default)
		)
		(layer "In6.Cu")
	)
	(gr_line
		(start 285.436564 -302.453802)
		(end 286.836612 -302.453802)
		(stroke
			(width 0.2)
			(type default)
		)
		(layer "In6.Cu")
	)
	(gr_arc
		(start 285.436564 -301.356522)
		(mid 284.887924 -301.905162)
		(end 285.436564 -302.453802)
		(stroke
			(width 0.2)
			(type default)
		)
		(layer "In6.Cu")
	)
	(gr_line
		(start 285.436564 -298.85386)
		(end 286.836612 -298.85386)
		(stroke
			(width 0.2)
			(type default)
		)
		(layer "In6.Cu")
	)
	(gr_arc
		(start 285.436564 -297.75658)
		(mid 284.887924 -298.30522)
		(end 285.436564 -298.85386)
		(stroke
			(width 0.2)
			(type default)
		)
		(layer "In6.Cu")
	)
	(gr_line
		(start 285.436564 -295.256458)
		(end 286.836612 -295.256458)
		(stroke
			(width 0.2)
			(type default)
		)
		(layer "In6.Cu")
	)
	(gr_arc
		(start 285.436564 -294.154098)
		(mid 284.885384 -294.705278)
		(end 285.436564 -295.256458)
		(stroke
			(width 0.2)
			(type default)
		)
		(layer "In6.Cu")
	)
	(gr_line
		(start 285.436564 -262.453374)
		(end 286.836612 -262.453374)
		(stroke
			(width 0.2)
			(type default)
		)
		(layer "In6.Cu")
	)
	(gr_arc
		(start 285.436564 -261.351014)
		(mid 284.885384 -261.902194)
		(end 285.436564 -262.453374)
		(stroke
			(width 0.2)
			(type default)
		)
		(layer "In6.Cu")
	)
	(gr_line
		(start 285.436564 -258.853432)
		(end 286.836612 -258.853432)
		(stroke
			(width 0.2)
			(type default)
		)
		(layer "In6.Cu")
	)
	(gr_arc
		(start 285.436564 -257.751072)
		(mid 284.885384 -258.302252)
		(end 285.436564 -258.853432)
		(stroke
			(width 0.2)
			(type default)
		)
		(layer "In6.Cu")
	)
	(gr_line
		(start 285.436564 -255.25349)
		(end 286.836612 -255.25349)
		(stroke
			(width 0.2)
			(type default)
		)
		(layer "In6.Cu")
	)
	(gr_arc
		(start 285.436564 -254.15113)
		(mid 284.885384 -254.70231)
		(end 285.436564 -255.25349)
		(stroke
			(width 0.2)
			(type default)
		)
		(layer "In6.Cu")
	)
	(gr_line
		(start 285.436564 -251.653548)
		(end 286.836612 -251.653548)
		(stroke
			(width 0.2)
			(type default)
		)
		(layer "In6.Cu")
	)
	(gr_arc
		(start 285.436564 -250.551188)
		(mid 284.885384 -251.102368)
		(end 285.436564 -251.653548)
		(stroke
			(width 0.2)
			(type default)
		)
		(layer "In6.Cu")
	)
	(gr_line
		(start 285.436818 -355.353874)
		(end 285.436564 -355.353874)
		(stroke
			(width 0.2)
			(type default)
		)
		(layer "In6.Cu")
	)
	(gr_line
		(start 285.436818 -351.753932)
		(end 285.436564 -351.753932)
		(stroke
			(width 0.2)
			(type default)
		)
		(layer "In6.Cu")
	)
	(gr_line
		(start 285.436818 -348.15399)
		(end 285.436564 -348.15399)
		(stroke
			(width 0.2)
			(type default)
		)
		(layer "In6.Cu")
	)
	(gr_line
		(start 285.436818 -344.556588)
		(end 285.436564 -344.556588)
		(stroke
			(width 0.2)
			(type default)
		)
		(layer "In6.Cu")
	)
	(gr_line
		(start 285.436818 -340.956392)
		(end 285.436564 -340.956392)
		(stroke
			(width 0.2)
			(type default)
		)
		(layer "In6.Cu")
	)
	(gr_line
		(start 285.436818 -337.35645)
		(end 285.436564 -337.35645)
		(stroke
			(width 0.2)
			(type default)
		)
		(layer "In6.Cu")
	)
	(gr_line
		(start 285.436818 -333.753968)
		(end 285.436564 -333.753968)
		(stroke
			(width 0.2)
			(type default)
		)
		(layer "In6.Cu")
	)
	(gr_line
		(start 285.436818 -330.154026)
		(end 285.436564 -330.154026)
		(stroke
			(width 0.2)
			(type default)
		)
		(layer "In6.Cu")
	)
	(gr_line
		(start 285.436818 -326.554084)
		(end 285.436564 -326.554084)
		(stroke
			(width 0.2)
			(type default)
		)
		(layer "In6.Cu")
	)
	(gr_line
		(start 285.436818 -322.956428)
		(end 285.436564 -322.956428)
		(stroke
			(width 0.2)
			(type default)
		)
		(layer "In6.Cu")
	)
	(gr_line
		(start 285.436818 -319.356486)
		(end 285.436564 -319.356486)
		(stroke
			(width 0.2)
			(type default)
		)
		(layer "In6.Cu")
	)
	(gr_line
		(start 285.436818 -315.756544)
		(end 285.436564 -315.756544)
		(stroke
			(width 0.2)
			(type default)
		)
		(layer "In6.Cu")
	)
	(gr_line
		(start 285.436818 -312.154062)
		(end 285.436564 -312.154062)
		(stroke
			(width 0.2)
			(type default)
		)
		(layer "In6.Cu")
	)
	(gr_line
		(start 285.436818 -308.553866)
		(end 285.436564 -308.553866)
		(stroke
			(width 0.2)
			(type default)
		)
		(layer "In6.Cu")
	)
	(gr_line
		(start 285.436818 -304.953924)
		(end 285.436564 -304.953924)
		(stroke
			(width 0.2)
			(type default)
		)
		(layer "In6.Cu")
	)
	(gr_line
		(start 285.436818 -301.356522)
		(end 285.436564 -301.356522)
		(stroke
			(width 0.2)
			(type default)
		)
		(layer "In6.Cu")
	)
	(gr_line
		(start 285.436818 -297.75658)
		(end 285.436564 -297.75658)
		(stroke
			(width 0.2)
			(type default)
		)
		(layer "In6.Cu")
	)
	(gr_line
		(start 285.436818 -294.154098)
		(end 285.436564 -294.154098)
		(stroke
			(width 0.2)
			(type default)
		)
		(layer "In6.Cu")
	)
	(gr_line
		(start 285.436818 -261.351014)
		(end 285.436564 -261.351014)
		(stroke
			(width 0.2)
			(type default)
		)
		(layer "In6.Cu")
	)
	(gr_line
		(start 285.436818 -257.751072)
		(end 285.436564 -257.751072)
		(stroke
			(width 0.2)
			(type default)
		)
		(layer "In6.Cu")
	)
	(gr_line
		(start 285.436818 -254.15113)
		(end 285.436564 -254.15113)
		(stroke
			(width 0.2)
			(type default)
		)
		(layer "In6.Cu")
	)
	(gr_line
		(start 285.436818 -250.551188)
		(end 285.436564 -250.551188)
		(stroke
			(width 0.2)
			(type default)
		)
		(layer "In6.Cu")
	)
	(gr_line
		(start 285.56331 -179.87264)
		(end 283.563314 -178.872642)
		(stroke
			(width 0.2)
			(type default)
		)
		(layer "In6.Cu")
	)
	(gr_line
		(start 285.56331 -175.872648)
		(end 283.563314 -174.87265)
		(stroke
			(width 0.2)
			(type default)
		)
		(layer "In6.Cu")
	)
	(gr_line
		(start 285.56331 -171.872656)
		(end 283.563314 -170.872658)
		(stroke
			(width 0.2)
			(type default)
		)
		(layer "In6.Cu")
	)
	(gr_line
		(start 285.56331 -167.872664)
		(end 283.563314 -166.872666)
		(stroke
			(width 0.2)
			(type default)
		)
		(layer "In6.Cu")
	)
	(gr_line
		(start 285.56331 -163.872672)
		(end 283.563314 -162.872674)
		(stroke
			(width 0.2)
			(type default)
		)
		(layer "In6.Cu")
	)
	(gr_line
		(start 285.56331 -159.87268)
		(end 283.571696 -158.877)
		(stroke
			(width 0.2)
			(type default)
		)
		(layer "In6.Cu")
	)
	(gr_line
		(start 285.56331 -155.872688)
		(end 283.563314 -154.87269)
		(stroke
			(width 0.2)
			(type default)
		)
		(layer "In6.Cu")
	)
	(gr_line
		(start 285.56331 -151.872696)
		(end 283.563314 -150.872698)
		(stroke
			(width 0.2)
			(type default)
		)
		(layer "In6.Cu")
	)
	(gr_line
		(start 285.56331 -127.872744)
		(end 283.563314 -126.872746)
		(stroke
			(width 0.2)
			(type default)
		)
		(layer "In6.Cu")
	)
	(gr_line
		(start 285.56331 -123.872752)
		(end 283.563314 -122.872754)
		(stroke
			(width 0.2)
			(type default)
		)
		(layer "In6.Cu")
	)
	(gr_line
		(start 285.56331 -119.87276)
		(end 283.563314 -118.872762)
		(stroke
			(width 0.2)
			(type default)
		)
		(layer "In6.Cu")
	)
	(gr_line
		(start 285.56331 -115.872768)
		(end 283.563314 -114.87277)
		(stroke
			(width 0.2)
			(type default)
		)
		(layer "In6.Cu")
	)
	(gr_line
		(start 285.56331 -83.572858)
		(end 283.563314 -82.57286)
		(stroke
			(width 0.2)
			(type default)
		)
		(layer "In6.Cu")
	)
	(gr_line
		(start 285.56331 -79.572866)
		(end 283.563314 -78.572868)
		(stroke
			(width 0.2)
			(type default)
		)
		(layer "In6.Cu")
	)
	(gr_line
		(start 285.56331 -75.572874)
		(end 283.563314 -74.572876)
		(stroke
			(width 0.2)
			(type default)
		)
		(layer "In6.Cu")
	)
	(gr_line
		(start 285.56331 -71.572882)
		(end 283.563314 -70.572884)
		(stroke
			(width 0.2)
			(type default)
		)
		(layer "In6.Cu")
	)
	(gr_line
		(start 285.56331 -67.57289)
		(end 283.563314 -66.572892)
		(stroke
			(width 0.2)
			(type default)
		)
		(layer "In6.Cu")
	)
	(gr_line
		(start 285.56331 -63.572898)
		(end 283.563314 -62.5729)
		(stroke
			(width 0.2)
			(type default)
		)
		(layer "In6.Cu")
	)
	(gr_line
		(start 285.56331 -59.572906)
		(end 283.563314 -58.572908)
		(stroke
			(width 0.2)
			(type default)
		)
		(layer "In6.Cu")
	)
	(gr_line
		(start 285.56331 -55.572914)
		(end 283.563314 -54.572916)
		(stroke
			(width 0.2)
			(type default)
		)
		(layer "In6.Cu")
	)
	(gr_line
		(start 285.56331 -51.572922)
		(end 283.563314 -50.572924)
		(stroke
			(width 0.2)
			(type default)
		)
		(layer "In6.Cu")
	)
	(gr_line
		(start 285.56331 -47.57293)
		(end 283.563314 -46.572932)
		(stroke
			(width 0.2)
			(type default)
		)
		(layer "In6.Cu")
	)
	(gr_line
		(start 285.56331 -43.572938)
		(end 283.563314 -42.57294)
		(stroke
			(width 0.2)
			(type default)
		)
		(layer "In6.Cu")
	)
	(gr_line
		(start 285.56331 -39.572946)
		(end 283.563314 -38.572948)
		(stroke
			(width 0.2)
			(type default)
		)
		(layer "In6.Cu")
	)
	(gr_line
		(start 285.57474 -135.850122)
		(end 285.57601 -135.847836)
		(stroke
			(width 0.2)
			(type default)
		)
		(layer "In6.Cu")
	)
	(gr_line
		(start 285.57601 -135.847836)
		(end 283.576014 -134.847838)
		(stroke
			(width 0.2)
			(type default)
		)
		(layer "In6.Cu")
	)
	(gr_line
		(start 285.57601 -107.847892)
		(end 283.576014 -106.847894)
		(stroke
			(width 0.2)
			(type default)
		)
		(layer "In6.Cu")
	)
	(gr_line
		(start 285.577026 -35.545776)
		(end 283.57703 -34.545778)
		(stroke
			(width 0.2)
			(type default)
		)
		(layer "In6.Cu")
	)
	(gr_line
		(start 286.234378 -101.49078)
		(end 284.863032 -101.49078)
		(stroke
			(width 0.381)
			(type default)
		)
		(layer "In6.Cu")
	)
	(gr_line
		(start 286.258 -5.207)
		(end 287.67024 -6.61924)
		(stroke
			(width 0.381)
			(type default)
		)
		(layer "In6.Cu")
	)
	(gr_line
		(start 286.436562 -358.256332)
		(end 287.83661 -358.256332)
		(stroke
			(width 0.2)
			(type default)
		)
		(layer "In6.Cu")
	)
	(gr_arc
		(start 286.436562 -357.153972)
		(mid 285.885382 -357.705152)
		(end 286.436562 -358.256332)
		(stroke
			(width 0.2)
			(type default)
		)
		(layer "In6.Cu")
	)
	(gr_line
		(start 286.436562 -354.65639)
		(end 287.83661 -354.65639)
		(stroke
			(width 0.2)
			(type default)
		)
		(layer "In6.Cu")
	)
	(gr_arc
		(start 286.436562 -353.55403)
		(mid 285.885382 -354.10521)
		(end 286.436562 -354.65639)
		(stroke
			(width 0.2)
			(type default)
		)
		(layer "In6.Cu")
	)
	(gr_line
		(start 286.436562 -351.056448)
		(end 287.83661 -351.056448)
		(stroke
			(width 0.2)
			(type default)
		)
		(layer "In6.Cu")
	)
	(gr_arc
		(start 286.436562 -349.954088)
		(mid 285.885382 -350.505268)
		(end 286.436562 -351.056448)
		(stroke
			(width 0.2)
			(type default)
		)
		(layer "In6.Cu")
	)
	(gr_line
		(start 286.436562 -347.453712)
		(end 287.83661 -347.453712)
		(stroke
			(width 0.2)
			(type default)
		)
		(layer "In6.Cu")
	)
	(gr_arc
		(start 286.436562 -346.356432)
		(mid 285.887922 -346.905072)
		(end 286.436562 -347.453712)
		(stroke
			(width 0.2)
			(type default)
		)
		(layer "In6.Cu")
	)
	(gr_line
		(start 286.436562 -343.85377)
		(end 287.83661 -343.85377)
		(stroke
			(width 0.2)
			(type default)
		)
		(layer "In6.Cu")
	)
	(gr_arc
		(start 286.436562 -342.75649)
		(mid 285.887922 -343.30513)
		(end 286.436562 -343.85377)
		(stroke
			(width 0.2)
			(type default)
		)
		(layer "In6.Cu")
	)
	(gr_line
		(start 286.436562 -340.253828)
		(end 287.83661 -340.253828)
		(stroke
			(width 0.2)
			(type default)
		)
		(layer "In6.Cu")
	)
	(gr_arc
		(start 286.436562 -339.156548)
		(mid 285.887922 -339.705188)
		(end 286.436562 -340.253828)
		(stroke
			(width 0.2)
			(type default)
		)
		(layer "In6.Cu")
	)
	(gr_line
		(start 286.436562 -336.656426)
		(end 287.83661 -336.656426)
		(stroke
			(width 0.2)
			(type default)
		)
		(layer "In6.Cu")
	)
	(gr_arc
		(start 286.436562 -335.554066)
		(mid 285.885382 -336.105246)
		(end 286.436562 -336.656426)
		(stroke
			(width 0.2)
			(type default)
		)
		(layer "In6.Cu")
	)
	(gr_line
		(start 286.436562 -333.05623)
		(end 287.83661 -333.05623)
		(stroke
			(width 0.2)
			(type default)
		)
		(layer "In6.Cu")
	)
	(gr_arc
		(start 286.436562 -331.95387)
		(mid 285.885382 -332.50505)
		(end 286.436562 -333.05623)
		(stroke
			(width 0.2)
			(type default)
		)
		(layer "In6.Cu")
	)
	(gr_line
		(start 286.436562 -329.456288)
		(end 287.83661 -329.456288)
		(stroke
			(width 0.2)
			(type default)
		)
		(layer "In6.Cu")
	)
	(gr_arc
		(start 286.436562 -328.353928)
		(mid 285.885382 -328.905108)
		(end 286.436562 -329.456288)
		(stroke
			(width 0.2)
			(type default)
		)
		(layer "In6.Cu")
	)
	(gr_line
		(start 286.436562 -325.853806)
		(end 287.83661 -325.853806)
		(stroke
			(width 0.2)
			(type default)
		)
		(layer "In6.Cu")
	)
	(gr_arc
		(start 286.436562 -324.756526)
		(mid 285.887922 -325.305166)
		(end 286.436562 -325.853806)
		(stroke
			(width 0.2)
			(type default)
		)
		(layer "In6.Cu")
	)
	(gr_line
		(start 286.436562 -322.253864)
		(end 287.83661 -322.253864)
		(stroke
			(width 0.2)
			(type default)
		)
		(layer "In6.Cu")
	)
	(gr_arc
		(start 286.436562 -321.156584)
		(mid 285.887922 -321.705224)
		(end 286.436562 -322.253864)
		(stroke
			(width 0.2)
			(type default)
		)
		(layer "In6.Cu")
	)
	(gr_line
		(start 286.436562 -318.653668)
		(end 287.83661 -318.653668)
		(stroke
			(width 0.2)
			(type default)
		)
		(layer "In6.Cu")
	)
	(gr_arc
		(start 286.436562 -317.556388)
		(mid 285.887922 -318.105028)
		(end 286.436562 -318.653668)
		(stroke
			(width 0.2)
			(type default)
		)
		(layer "In6.Cu")
	)
	(gr_line
		(start 286.436562 -315.056266)
		(end 287.83661 -315.056266)
		(stroke
			(width 0.2)
			(type default)
		)
		(layer "In6.Cu")
	)
	(gr_arc
		(start 286.436562 -313.953906)
		(mid 285.885382 -314.505086)
		(end 286.436562 -315.056266)
		(stroke
			(width 0.2)
			(type default)
		)
		(layer "In6.Cu")
	)
	(gr_line
		(start 286.436562 -311.456324)
		(end 287.83661 -311.456324)
		(stroke
			(width 0.2)
			(type default)
		)
		(layer "In6.Cu")
	)
	(gr_arc
		(start 286.436562 -310.353964)
		(mid 285.885382 -310.905144)
		(end 286.436562 -311.456324)
		(stroke
			(width 0.2)
			(type default)
		)
		(layer "In6.Cu")
	)
	(gr_line
		(start 286.436562 -307.856382)
		(end 287.83661 -307.856382)
		(stroke
			(width 0.2)
			(type default)
		)
		(layer "In6.Cu")
	)
	(gr_arc
		(start 286.436562 -306.754022)
		(mid 285.885382 -307.305202)
		(end 286.436562 -307.856382)
		(stroke
			(width 0.2)
			(type default)
		)
		(layer "In6.Cu")
	)
	(gr_line
		(start 286.436562 -304.2539)
		(end 287.83661 -304.2539)
		(stroke
			(width 0.2)
			(type default)
		)
		(layer "In6.Cu")
	)
	(gr_arc
		(start 286.436562 -303.15662)
		(mid 285.887922 -303.70526)
		(end 286.436562 -304.2539)
		(stroke
			(width 0.2)
			(type default)
		)
		(layer "In6.Cu")
	)
	(gr_line
		(start 286.436562 -300.653704)
		(end 287.83661 -300.653704)
		(stroke
			(width 0.2)
			(type default)
		)
		(layer "In6.Cu")
	)
	(gr_arc
		(start 286.436562 -299.556424)
		(mid 285.887922 -300.105064)
		(end 286.436562 -300.653704)
		(stroke
			(width 0.2)
			(type default)
		)
		(layer "In6.Cu")
	)
	(gr_line
		(start 286.436562 -297.056302)
		(end 287.83661 -297.056302)
		(stroke
			(width 0.2)
			(type default)
		)
		(layer "In6.Cu")
	)
	(gr_arc
		(start 286.436562 -295.953942)
		(mid 285.885382 -296.505122)
		(end 286.436562 -297.056302)
		(stroke
			(width 0.2)
			(type default)
		)
		(layer "In6.Cu")
	)
	(gr_line
		(start 286.436562 -264.253472)
		(end 287.83661 -264.253472)
		(stroke
			(width 0.2)
			(type default)
		)
		(layer "In6.Cu")
	)
	(gr_arc
		(start 286.436562 -263.151112)
		(mid 285.885382 -263.702292)
		(end 286.436562 -264.253472)
		(stroke
			(width 0.2)
			(type default)
		)
		(layer "In6.Cu")
	)
	(gr_line
		(start 286.436562 -260.65353)
		(end 287.83661 -260.65353)
		(stroke
			(width 0.2)
			(type default)
		)
		(layer "In6.Cu")
	)
	(gr_arc
		(start 286.436562 -259.55117)
		(mid 285.885382 -260.10235)
		(end 286.436562 -260.65353)
		(stroke
			(width 0.2)
			(type default)
		)
		(layer "In6.Cu")
	)
	(gr_line
		(start 286.436562 -257.053588)
		(end 287.83661 -257.053588)
		(stroke
			(width 0.2)
			(type default)
		)
		(layer "In6.Cu")
	)
	(gr_arc
		(start 286.436562 -255.951228)
		(mid 285.885382 -256.502408)
		(end 286.436562 -257.053588)
		(stroke
			(width 0.2)
			(type default)
		)
		(layer "In6.Cu")
	)
	(gr_line
		(start 286.436562 -253.453392)
		(end 287.83661 -253.453392)
		(stroke
			(width 0.2)
			(type default)
		)
		(layer "In6.Cu")
	)
	(gr_arc
		(start 286.436562 -252.351032)
		(mid 285.885382 -252.902212)
		(end 286.436562 -253.453392)
		(stroke
			(width 0.2)
			(type default)
		)
		(layer "In6.Cu")
	)
	(gr_line
		(start 286.436816 -357.153972)
		(end 286.436562 -357.153972)
		(stroke
			(width 0.2)
			(type default)
		)
		(layer "In6.Cu")
	)
	(gr_line
		(start 286.436816 -353.55403)
		(end 286.436562 -353.55403)
		(stroke
			(width 0.2)
			(type default)
		)
		(layer "In6.Cu")
	)
	(gr_line
		(start 286.436816 -349.954088)
		(end 286.436562 -349.954088)
		(stroke
			(width 0.2)
			(type default)
		)
		(layer "In6.Cu")
	)
	(gr_line
		(start 286.436816 -346.356432)
		(end 286.436562 -346.356432)
		(stroke
			(width 0.2)
			(type default)
		)
		(layer "In6.Cu")
	)
	(gr_line
		(start 286.436816 -342.75649)
		(end 286.436562 -342.75649)
		(stroke
			(width 0.2)
			(type default)
		)
		(layer "In6.Cu")
	)
	(gr_line
		(start 286.436816 -339.156548)
		(end 286.436562 -339.156548)
		(stroke
			(width 0.2)
			(type default)
		)
		(layer "In6.Cu")
	)
	(gr_line
		(start 286.436816 -335.554066)
		(end 286.436562 -335.554066)
		(stroke
			(width 0.2)
			(type default)
		)
		(layer "In6.Cu")
	)
	(gr_line
		(start 286.436816 -331.95387)
		(end 286.436562 -331.95387)
		(stroke
			(width 0.2)
			(type default)
		)
		(layer "In6.Cu")
	)
	(gr_line
		(start 286.436816 -328.353928)
		(end 286.436562 -328.353928)
		(stroke
			(width 0.2)
			(type default)
		)
		(layer "In6.Cu")
	)
	(gr_line
		(start 286.436816 -324.756526)
		(end 286.436562 -324.756526)
		(stroke
			(width 0.2)
			(type default)
		)
		(layer "In6.Cu")
	)
	(gr_line
		(start 286.436816 -321.156584)
		(end 286.436562 -321.156584)
		(stroke
			(width 0.2)
			(type default)
		)
		(layer "In6.Cu")
	)
	(gr_line
		(start 286.436816 -317.556388)
		(end 286.436562 -317.556388)
		(stroke
			(width 0.2)
			(type default)
		)
		(layer "In6.Cu")
	)
	(gr_line
		(start 286.436816 -313.953906)
		(end 286.436562 -313.953906)
		(stroke
			(width 0.2)
			(type default)
		)
		(layer "In6.Cu")
	)
	(gr_line
		(start 286.436816 -310.353964)
		(end 286.436562 -310.353964)
		(stroke
			(width 0.2)
			(type default)
		)
		(layer "In6.Cu")
	)
	(gr_line
		(start 286.436816 -306.754022)
		(end 286.436562 -306.754022)
		(stroke
			(width 0.2)
			(type default)
		)
		(layer "In6.Cu")
	)
	(gr_line
		(start 286.436816 -303.15662)
		(end 286.436562 -303.15662)
		(stroke
			(width 0.2)
			(type default)
		)
		(layer "In6.Cu")
	)
	(gr_line
		(start 286.436816 -299.556424)
		(end 286.436562 -299.556424)
		(stroke
			(width 0.2)
			(type default)
		)
		(layer "In6.Cu")
	)
	(gr_line
		(start 286.436816 -295.953942)
		(end 286.436562 -295.953942)
		(stroke
			(width 0.2)
			(type default)
		)
		(layer "In6.Cu")
	)
	(gr_line
		(start 286.436816 -263.151112)
		(end 286.436562 -263.151112)
		(stroke
			(width 0.2)
			(type default)
		)
		(layer "In6.Cu")
	)
	(gr_line
		(start 286.436816 -259.55117)
		(end 286.436562 -259.55117)
		(stroke
			(width 0.2)
			(type default)
		)
		(layer "In6.Cu")
	)
	(gr_line
		(start 286.436816 -255.951228)
		(end 286.436562 -255.951228)
		(stroke
			(width 0.2)
			(type default)
		)
		(layer "In6.Cu")
	)
	(gr_line
		(start 286.436816 -252.351032)
		(end 286.436562 -252.351032)
		(stroke
			(width 0.2)
			(type default)
		)
		(layer "In6.Cu")
	)
	(gr_line
		(start 286.6898 -360.792776)
		(end 287.191958 -361.294934)
		(stroke
			(width 0.381)
			(type default)
		)
		(layer "In6.Cu")
	)
	(gr_line
		(start 286.72028 -87.3252)
		(end 283.972 -87.3252)
		(stroke
			(width 0.381)
			(type default)
		)
		(layer "In6.Cu")
	)
	(gr_arc
		(start 286.836612 -356.456234)
		(mid 287.387792 -355.905054)
		(end 286.836612 -355.353874)
		(stroke
			(width 0.2)
			(type default)
		)
		(layer "In6.Cu")
	)
	(gr_line
		(start 286.836612 -355.353874)
		(end 285.436818 -355.353874)
		(stroke
			(width 0.2)
			(type default)
		)
		(layer "In6.Cu")
	)
	(gr_arc
		(start 286.836612 -352.856292)
		(mid 287.387792 -352.305112)
		(end 286.836612 -351.753932)
		(stroke
			(width 0.2)
			(type default)
		)
		(layer "In6.Cu")
	)
	(gr_line
		(start 286.836612 -351.753932)
		(end 285.436818 -351.753932)
		(stroke
			(width 0.2)
			(type default)
		)
		(layer "In6.Cu")
	)
	(gr_arc
		(start 286.836612 -349.25635)
		(mid 287.387792 -348.70517)
		(end 286.836612 -348.15399)
		(stroke
			(width 0.2)
			(type default)
		)
		(layer "In6.Cu")
	)
	(gr_line
		(start 286.836612 -348.15399)
		(end 285.436818 -348.15399)
		(stroke
			(width 0.2)
			(type default)
		)
		(layer "In6.Cu")
	)
	(gr_arc
		(start 286.836612 -345.653868)
		(mid 287.385252 -345.105228)
		(end 286.836612 -344.556588)
		(stroke
			(width 0.2)
			(type default)
		)
		(layer "In6.Cu")
	)
	(gr_line
		(start 286.836612 -344.556588)
		(end 285.436818 -344.556588)
		(stroke
			(width 0.2)
			(type default)
		)
		(layer "In6.Cu")
	)
	(gr_arc
		(start 286.836612 -342.053672)
		(mid 287.385252 -341.505032)
		(end 286.836612 -340.956392)
		(stroke
			(width 0.2)
			(type default)
		)
		(layer "In6.Cu")
	)
	(gr_line
		(start 286.836612 -340.956392)
		(end 285.436818 -340.956392)
		(stroke
			(width 0.2)
			(type default)
		)
		(layer "In6.Cu")
	)
	(gr_arc
		(start 286.836612 -338.45373)
		(mid 287.385252 -337.90509)
		(end 286.836612 -337.35645)
		(stroke
			(width 0.2)
			(type default)
		)
		(layer "In6.Cu")
	)
	(gr_line
		(start 286.836612 -337.35645)
		(end 285.436818 -337.35645)
		(stroke
			(width 0.2)
			(type default)
		)
		(layer "In6.Cu")
	)
	(gr_arc
		(start 286.836612 -334.856328)
		(mid 287.387792 -334.305148)
		(end 286.836612 -333.753968)
		(stroke
			(width 0.2)
			(type default)
		)
		(layer "In6.Cu")
	)
	(gr_line
		(start 286.836612 -333.753968)
		(end 285.436818 -333.753968)
		(stroke
			(width 0.2)
			(type default)
		)
		(layer "In6.Cu")
	)
	(gr_arc
		(start 286.836612 -331.256386)
		(mid 287.387792 -330.705206)
		(end 286.836612 -330.154026)
		(stroke
			(width 0.2)
			(type default)
		)
		(layer "In6.Cu")
	)
	(gr_line
		(start 286.836612 -330.154026)
		(end 285.436818 -330.154026)
		(stroke
			(width 0.2)
			(type default)
		)
		(layer "In6.Cu")
	)
	(gr_arc
		(start 286.836612 -327.656444)
		(mid 287.387792 -327.105264)
		(end 286.836612 -326.554084)
		(stroke
			(width 0.2)
			(type default)
		)
		(layer "In6.Cu")
	)
	(gr_line
		(start 286.836612 -326.554084)
		(end 285.436818 -326.554084)
		(stroke
			(width 0.2)
			(type default)
		)
		(layer "In6.Cu")
	)
	(gr_arc
		(start 286.836612 -324.053708)
		(mid 287.385252 -323.505068)
		(end 286.836612 -322.956428)
		(stroke
			(width 0.2)
			(type default)
		)
		(layer "In6.Cu")
	)
	(gr_line
		(start 286.836612 -322.956428)
		(end 285.436818 -322.956428)
		(stroke
			(width 0.2)
			(type default)
		)
		(layer "In6.Cu")
	)
	(gr_arc
		(start 286.836612 -320.453766)
		(mid 287.385252 -319.905126)
		(end 286.836612 -319.356486)
		(stroke
			(width 0.2)
			(type default)
		)
		(layer "In6.Cu")
	)
	(gr_line
		(start 286.836612 -319.356486)
		(end 285.436818 -319.356486)
		(stroke
			(width 0.2)
			(type default)
		)
		(layer "In6.Cu")
	)
	(gr_arc
		(start 286.836612 -316.853824)
		(mid 287.385252 -316.305184)
		(end 286.836612 -315.756544)
		(stroke
			(width 0.2)
			(type default)
		)
		(layer "In6.Cu")
	)
	(gr_line
		(start 286.836612 -315.756544)
		(end 285.436818 -315.756544)
		(stroke
			(width 0.2)
			(type default)
		)
		(layer "In6.Cu")
	)
	(gr_arc
		(start 286.836612 -313.256422)
		(mid 287.387792 -312.705242)
		(end 286.836612 -312.154062)
		(stroke
			(width 0.2)
			(type default)
		)
		(layer "In6.Cu")
	)
	(gr_line
		(start 286.836612 -312.154062)
		(end 285.436818 -312.154062)
		(stroke
			(width 0.2)
			(type default)
		)
		(layer "In6.Cu")
	)
	(gr_arc
		(start 286.836612 -309.656226)
		(mid 287.387792 -309.105046)
		(end 286.836612 -308.553866)
		(stroke
			(width 0.2)
			(type default)
		)
		(layer "In6.Cu")
	)
	(gr_line
		(start 286.836612 -308.553866)
		(end 285.436818 -308.553866)
		(stroke
			(width 0.2)
			(type default)
		)
		(layer "In6.Cu")
	)
	(gr_arc
		(start 286.836612 -306.056284)
		(mid 287.387792 -305.505104)
		(end 286.836612 -304.953924)
		(stroke
			(width 0.2)
			(type default)
		)
		(layer "In6.Cu")
	)
	(gr_line
		(start 286.836612 -304.953924)
		(end 285.436818 -304.953924)
		(stroke
			(width 0.2)
			(type default)
		)
		(layer "In6.Cu")
	)
	(gr_arc
		(start 286.836612 -302.453802)
		(mid 287.385252 -301.905162)
		(end 286.836612 -301.356522)
		(stroke
			(width 0.2)
			(type default)
		)
		(layer "In6.Cu")
	)
	(gr_line
		(start 286.836612 -301.356522)
		(end 285.436818 -301.356522)
		(stroke
			(width 0.2)
			(type default)
		)
		(layer "In6.Cu")
	)
	(gr_arc
		(start 286.836612 -298.85386)
		(mid 287.385252 -298.30522)
		(end 286.836612 -297.75658)
		(stroke
			(width 0.2)
			(type default)
		)
		(layer "In6.Cu")
	)
	(gr_line
		(start 286.836612 -297.75658)
		(end 285.436818 -297.75658)
		(stroke
			(width 0.2)
			(type default)
		)
		(layer "In6.Cu")
	)
	(gr_arc
		(start 286.836612 -295.256458)
		(mid 287.387792 -294.705278)
		(end 286.836612 -294.154098)
		(stroke
			(width 0.2)
			(type default)
		)
		(layer "In6.Cu")
	)
	(gr_line
		(start 286.836612 -294.154098)
		(end 285.436818 -294.154098)
		(stroke
			(width 0.2)
			(type default)
		)
		(layer "In6.Cu")
	)
	(gr_arc
		(start 286.836612 -262.453374)
		(mid 287.387792 -261.902194)
		(end 286.836612 -261.351014)
		(stroke
			(width 0.2)
			(type default)
		)
		(layer "In6.Cu")
	)
	(gr_line
		(start 286.836612 -261.351014)
		(end 285.436818 -261.351014)
		(stroke
			(width 0.2)
			(type default)
		)
		(layer "In6.Cu")
	)
	(gr_arc
		(start 286.836612 -258.853432)
		(mid 287.387792 -258.302252)
		(end 286.836612 -257.751072)
		(stroke
			(width 0.2)
			(type default)
		)
		(layer "In6.Cu")
	)
	(gr_line
		(start 286.836612 -257.751072)
		(end 285.436818 -257.751072)
		(stroke
			(width 0.2)
			(type default)
		)
		(layer "In6.Cu")
	)
	(gr_arc
		(start 286.836612 -255.25349)
		(mid 287.387792 -254.70231)
		(end 286.836612 -254.15113)
		(stroke
			(width 0.2)
			(type default)
		)
		(layer "In6.Cu")
	)
	(gr_line
		(start 286.836612 -254.15113)
		(end 285.436818 -254.15113)
		(stroke
			(width 0.2)
			(type default)
		)
		(layer "In6.Cu")
	)
	(gr_arc
		(start 286.836612 -251.653548)
		(mid 287.387792 -251.102368)
		(end 286.836612 -250.551188)
		(stroke
			(width 0.2)
			(type default)
		)
		(layer "In6.Cu")
	)
	(gr_line
		(start 286.836612 -250.551188)
		(end 285.436818 -250.551188)
		(stroke
			(width 0.2)
			(type default)
		)
		(layer "In6.Cu")
	)
	(gr_line
		(start 287.191958 -394.646404)
		(end 287.191958 -360.792776)
		(stroke
			(width 0.381)
			(type default)
		)
		(layer "In6.Cu")
	)
	(gr_line
		(start 287.191958 -367.406174)
		(end 287.691322 -366.90681)
		(stroke
			(width 0.381)
			(type default)
		)
		(layer "In6.Cu")
	)
	(gr_line
		(start 287.191958 -361.294934)
		(end 287.694116 -360.792776)
		(stroke
			(width 0.381)
			(type default)
		)
		(layer "In6.Cu")
	)
	(gr_line
		(start 287.67024 -182.78856)
		(end 287.67024 -102.926642)
		(stroke
			(width 0.381)
			(type default)
		)
		(layer "In6.Cu")
	)
	(gr_line
		(start 287.67024 -102.926642)
		(end 286.234378 -101.49078)
		(stroke
			(width 0.381)
			(type default)
		)
		(layer "In6.Cu")
	)
	(gr_line
		(start 287.67024 -102.926642)
		(end 310.513984 -80.082898)
		(stroke
			(width 0.381)
			(type default)
		)
		(layer "In6.Cu")
	)
	(gr_line
		(start 287.67024 -86.37524)
		(end 286.72028 -87.3252)
		(stroke
			(width 0.381)
			(type default)
		)
		(layer "In6.Cu")
	)
	(gr_line
		(start 287.67024 -33.943798)
		(end 287.67024 -86.37524)
		(stroke
			(width 0.381)
			(type default)
		)
		(layer "In6.Cu")
	)
	(gr_line
		(start 287.67024 -6.61924)
		(end 287.67024 -33.943798)
		(stroke
			(width 0.381)
			(type default)
		)
		(layer "In6.Cu")
	)
	(gr_line
		(start 287.691322 -366.90681)
		(end 287.191958 -366.407446)
		(stroke
			(width 0.381)
			(type default)
		)
		(layer "In6.Cu")
	)
	(gr_line
		(start 287.694116 -360.792776)
		(end 271.182084 -360.792776)
		(stroke
			(width 0.381)
			(type default)
		)
		(layer "In6.Cu")
	)
	(gr_arc
		(start 287.83661 -358.256332)
		(mid 288.38779 -357.705152)
		(end 287.83661 -357.153972)
		(stroke
			(width 0.2)
			(type default)
		)
		(layer "In6.Cu")
	)
	(gr_line
		(start 287.83661 -357.153972)
		(end 286.436816 -357.153972)
		(stroke
			(width 0.2)
			(type default)
		)
		(layer "In6.Cu")
	)
	(gr_arc
		(start 287.83661 -354.65639)
		(mid 288.38779 -354.10521)
		(end 287.83661 -353.55403)
		(stroke
			(width 0.2)
			(type default)
		)
		(layer "In6.Cu")
	)
	(gr_line
		(start 287.83661 -353.55403)
		(end 286.436816 -353.55403)
		(stroke
			(width 0.2)
			(type default)
		)
		(layer "In6.Cu")
	)
	(gr_arc
		(start 287.83661 -351.056448)
		(mid 288.38779 -350.505268)
		(end 287.83661 -349.954088)
		(stroke
			(width 0.2)
			(type default)
		)
		(layer "In6.Cu")
	)
	(gr_line
		(start 287.83661 -349.954088)
		(end 286.436816 -349.954088)
		(stroke
			(width 0.2)
			(type default)
		)
		(layer "In6.Cu")
	)
	(gr_arc
		(start 287.83661 -347.453712)
		(mid 288.38525 -346.905072)
		(end 287.83661 -346.356432)
		(stroke
			(width 0.2)
			(type default)
		)
		(layer "In6.Cu")
	)
	(gr_line
		(start 287.83661 -346.356432)
		(end 286.436816 -346.356432)
		(stroke
			(width 0.2)
			(type default)
		)
		(layer "In6.Cu")
	)
	(gr_arc
		(start 287.83661 -343.85377)
		(mid 288.38525 -343.30513)
		(end 287.83661 -342.75649)
		(stroke
			(width 0.2)
			(type default)
		)
		(layer "In6.Cu")
	)
	(gr_line
		(start 287.83661 -342.75649)
		(end 286.436816 -342.75649)
		(stroke
			(width 0.2)
			(type default)
		)
		(layer "In6.Cu")
	)
	(gr_arc
		(start 287.83661 -340.253828)
		(mid 288.38525 -339.705188)
		(end 287.83661 -339.156548)
		(stroke
			(width 0.2)
			(type default)
		)
		(layer "In6.Cu")
	)
	(gr_line
		(start 287.83661 -339.156548)
		(end 286.436816 -339.156548)
		(stroke
			(width 0.2)
			(type default)
		)
		(layer "In6.Cu")
	)
	(gr_arc
		(start 287.83661 -336.656426)
		(mid 288.38779 -336.105246)
		(end 287.83661 -335.554066)
		(stroke
			(width 0.2)
			(type default)
		)
		(layer "In6.Cu")
	)
	(gr_line
		(start 287.83661 -335.554066)
		(end 286.436816 -335.554066)
		(stroke
			(width 0.2)
			(type default)
		)
		(layer "In6.Cu")
	)
	(gr_arc
		(start 287.83661 -333.05623)
		(mid 288.38779 -332.50505)
		(end 287.83661 -331.95387)
		(stroke
			(width 0.2)
			(type default)
		)
		(layer "In6.Cu")
	)
	(gr_line
		(start 287.83661 -331.95387)
		(end 286.436816 -331.95387)
		(stroke
			(width 0.2)
			(type default)
		)
		(layer "In6.Cu")
	)
	(gr_arc
		(start 287.83661 -329.456288)
		(mid 288.38779 -328.905108)
		(end 287.83661 -328.353928)
		(stroke
			(width 0.2)
			(type default)
		)
		(layer "In6.Cu")
	)
	(gr_line
		(start 287.83661 -328.353928)
		(end 286.436816 -328.353928)
		(stroke
			(width 0.2)
			(type default)
		)
		(layer "In6.Cu")
	)
	(gr_arc
		(start 287.83661 -325.853806)
		(mid 288.38525 -325.305166)
		(end 287.83661 -324.756526)
		(stroke
			(width 0.2)
			(type default)
		)
		(layer "In6.Cu")
	)
	(gr_line
		(start 287.83661 -324.756526)
		(end 286.436816 -324.756526)
		(stroke
			(width 0.2)
			(type default)
		)
		(layer "In6.Cu")
	)
	(gr_arc
		(start 287.83661 -322.253864)
		(mid 288.38525 -321.705224)
		(end 287.83661 -321.156584)
		(stroke
			(width 0.2)
			(type default)
		)
		(layer "In6.Cu")
	)
	(gr_line
		(start 287.83661 -321.156584)
		(end 286.436816 -321.156584)
		(stroke
			(width 0.2)
			(type default)
		)
		(layer "In6.Cu")
	)
	(gr_arc
		(start 287.83661 -318.653668)
		(mid 288.38525 -318.105028)
		(end 287.83661 -317.556388)
		(stroke
			(width 0.2)
			(type default)
		)
		(layer "In6.Cu")
	)
	(gr_line
		(start 287.83661 -317.556388)
		(end 286.436816 -317.556388)
		(stroke
			(width 0.2)
			(type default)
		)
		(layer "In6.Cu")
	)
	(gr_arc
		(start 287.83661 -315.056266)
		(mid 288.38779 -314.505086)
		(end 287.83661 -313.953906)
		(stroke
			(width 0.2)
			(type default)
		)
		(layer "In6.Cu")
	)
	(gr_line
		(start 287.83661 -313.953906)
		(end 286.436816 -313.953906)
		(stroke
			(width 0.2)
			(type default)
		)
		(layer "In6.Cu")
	)
	(gr_arc
		(start 287.83661 -311.456324)
		(mid 288.38779 -310.905144)
		(end 287.83661 -310.353964)
		(stroke
			(width 0.2)
			(type default)
		)
		(layer "In6.Cu")
	)
	(gr_line
		(start 287.83661 -310.353964)
		(end 286.436816 -310.353964)
		(stroke
			(width 0.2)
			(type default)
		)
		(layer "In6.Cu")
	)
	(gr_arc
		(start 287.83661 -307.856382)
		(mid 288.38779 -307.305202)
		(end 287.83661 -306.754022)
		(stroke
			(width 0.2)
			(type default)
		)
		(layer "In6.Cu")
	)
	(gr_line
		(start 287.83661 -306.754022)
		(end 286.436816 -306.754022)
		(stroke
			(width 0.2)
			(type default)
		)
		(layer "In6.Cu")
	)
	(gr_arc
		(start 287.83661 -304.2539)
		(mid 288.38525 -303.70526)
		(end 287.83661 -303.15662)
		(stroke
			(width 0.2)
			(type default)
		)
		(layer "In6.Cu")
	)
	(gr_line
		(start 287.83661 -303.15662)
		(end 286.436816 -303.15662)
		(stroke
			(width 0.2)
			(type default)
		)
		(layer "In6.Cu")
	)
	(gr_arc
		(start 287.83661 -300.653704)
		(mid 288.38525 -300.105064)
		(end 287.83661 -299.556424)
		(stroke
			(width 0.2)
			(type default)
		)
		(layer "In6.Cu")
	)
	(gr_line
		(start 287.83661 -299.556424)
		(end 286.436816 -299.556424)
		(stroke
			(width 0.2)
			(type default)
		)
		(layer "In6.Cu")
	)
	(gr_arc
		(start 287.83661 -297.056302)
		(mid 288.38779 -296.505122)
		(end 287.83661 -295.953942)
		(stroke
			(width 0.2)
			(type default)
		)
		(layer "In6.Cu")
	)
	(gr_line
		(start 287.83661 -295.953942)
		(end 286.436816 -295.953942)
		(stroke
			(width 0.2)
			(type default)
		)
		(layer "In6.Cu")
	)
	(gr_arc
		(start 287.83661 -264.253472)
		(mid 288.38779 -263.702292)
		(end 287.83661 -263.151112)
		(stroke
			(width 0.2)
			(type default)
		)
		(layer "In6.Cu")
	)
	(gr_line
		(start 287.83661 -263.151112)
		(end 286.436816 -263.151112)
		(stroke
			(width 0.2)
			(type default)
		)
		(layer "In6.Cu")
	)
	(gr_arc
		(start 287.83661 -260.65353)
		(mid 288.38779 -260.10235)
		(end 287.83661 -259.55117)
		(stroke
			(width 0.2)
			(type default)
		)
		(layer "In6.Cu")
	)
	(gr_line
		(start 287.83661 -259.55117)
		(end 286.436816 -259.55117)
		(stroke
			(width 0.2)
			(type default)
		)
		(layer "In6.Cu")
	)
	(gr_arc
		(start 287.83661 -257.053588)
		(mid 288.38779 -256.502408)
		(end 287.83661 -255.951228)
		(stroke
			(width 0.2)
			(type default)
		)
		(layer "In6.Cu")
	)
	(gr_line
		(start 287.83661 -255.951228)
		(end 286.436816 -255.951228)
		(stroke
			(width 0.2)
			(type default)
		)
		(layer "In6.Cu")
	)
	(gr_arc
		(start 287.83661 -253.453392)
		(mid 288.38779 -252.902212)
		(end 287.83661 -252.351032)
		(stroke
			(width 0.2)
			(type default)
		)
		(layer "In6.Cu")
	)
	(gr_line
		(start 287.83661 -252.351032)
		(end 286.436816 -252.351032)
		(stroke
			(width 0.2)
			(type default)
		)
		(layer "In6.Cu")
	)
	(gr_line
		(start 289.814 -358.672892)
		(end 287.694116 -360.792776)
		(stroke
			(width 0.381)
			(type default)
		)
		(layer "In6.Cu")
	)
	(gr_line
		(start 289.814 -302.006)
		(end 289.814 -358.672892)
		(stroke
			(width 0.381)
			(type default)
		)
		(layer "In6.Cu")
	)
	(gr_arc
		(start 295.699942 -373.000016)
		(mid 295.992835 -373.707121)
		(end 296.69994 -374.000014)
		(stroke
			(width 2.54)
			(type default)
		)
		(layer "In6.Cu")
	)
	(gr_line
		(start 295.699942 -366.903)
		(end 287.191958 -366.903)
		(stroke
			(width 0.381)
			(type default)
		)
		(layer "In6.Cu")
	)
	(gr_line
		(start 295.699942 -350.19996)
		(end 295.699942 -373.000016)
		(stroke
			(width 2.54)
			(type default)
		)
		(layer "In6.Cu")
	)
	(gr_line
		(start 296.69994 -374.000014)
		(end 308.99989 -374.000014)
		(stroke
			(width 2.54)
			(type default)
		)
		(layer "In6.Cu")
	)
	(gr_arc
		(start 296.69994 -349.199962)
		(mid 295.992835 -349.492855)
		(end 295.699942 -350.19996)
		(stroke
			(width 2.54)
			(type default)
		)
		(layer "In6.Cu")
	)
	(gr_line
		(start 297.34256 -348.188026)
		(end 296.712386 -348.8182)
		(stroke
			(width 0.381)
			(type default)
		)
		(layer "In6.Cu")
	)
	(gr_line
		(start 297.34256 -348.17939)
		(end 297.34256 -348.188026)
		(stroke
			(width 0.381)
			(type default)
		)
		(layer "In6.Cu")
	)
	(gr_line
		(start 297.34256 -348.178374)
		(end 297.34256 -348.17939)
		(stroke
			(width 0.381)
			(type default)
		)
		(layer "In6.Cu")
	)
	(gr_line
		(start 297.8912 -348.008702)
		(end 296.69994 -349.199962)
		(stroke
			(width 0.381)
			(type default)
		)
		(layer "In6.Cu")
	)
	(gr_line
		(start 297.8912 -321.4878)
		(end 297.8912 -348.008702)
		(stroke
			(width 0.381)
			(type default)
		)
		(layer "In6.Cu")
	)
	(gr_arc
		(start 299.999908 0.999998)
		(mid 300.292801 0.292893)
		(end 300.999906 0)
		(stroke
			(width 2.54)
			(type default)
		)
		(layer "In6.Cu")
	)
	(gr_arc
		(start 299.999908 37.800026)
		(mid 299.707007 38.507118)
		(end 298.99991 38.800024)
		(stroke
			(width 2.54)
			(type default)
		)
		(layer "In6.Cu")
	)
	(gr_line
		(start 299.999908 37.800026)
		(end 299.999908 0.999998)
		(stroke
			(width 2.54)
			(type default)
		)
		(layer "In6.Cu")
	)
	(gr_line
		(start 300.999906 0)
		(end 347.000068 0)
		(stroke
			(width 2.54)
			(type default)
		)
		(layer "In6.Cu")
	)
	(gr_line
		(start 304.530506 -234.982512)
		(end 307.397658 -237.849664)
		(stroke
			(width 0.381)
			(type default)
		)
		(layer "In6.Cu")
	)
	(gr_line
		(start 304.557176 -286.490918)
		(end 304.785776 -286.719518)
		(stroke
			(width 0.381)
			(type default)
		)
		(layer "In6.Cu")
	)
	(gr_line
		(start 304.785776 -287.034224)
		(end 289.814 -302.006)
		(stroke
			(width 0.381)
			(type default)
		)
		(layer "In6.Cu")
	)
	(gr_line
		(start 304.785776 -286.719518)
		(end 304.785776 -287.034224)
		(stroke
			(width 0.381)
			(type default)
		)
		(layer "In6.Cu")
	)
	(gr_line
		(start 304.976276 -265.839448)
		(end 272.114518 -265.839448)
		(stroke
			(width 0.381)
			(type default)
		)
		(layer "In6.Cu")
	)
	(gr_line
		(start 305.329082 -286.490918)
		(end 304.557176 -286.490918)
		(stroke
			(width 0.381)
			(type default)
		)
		(layer "In6.Cu")
	)
	(gr_line
		(start 305.329082 -286.490918)
		(end 304.785776 -287.034224)
		(stroke
			(width 0.381)
			(type default)
		)
		(layer "In6.Cu")
	)
	(gr_line
		(start 307.397658 -263.418066)
		(end 304.976276 -265.839448)
		(stroke
			(width 0.381)
			(type default)
		)
		(layer "In6.Cu")
	)
	(gr_line
		(start 307.397658 -237.849664)
		(end 307.397658 -263.418066)
		(stroke
			(width 0.381)
			(type default)
		)
		(layer "In6.Cu")
	)
	(gr_line
		(start 308.99989 -421.200072)
		(end 201.000106 -421.200072)
		(stroke
			(width 2.54)
			(type default)
		)
		(layer "In6.Cu")
	)
	(gr_arc
		(start 308.99989 -421.200072)
		(mid 309.706993 -420.907181)
		(end 309.999888 -420.200074)
		(stroke
			(width 2.54)
			(type default)
		)
		(layer "In6.Cu")
	)
	(gr_arc
		(start 309.999888 -375.000012)
		(mid 309.706999 -374.292902)
		(end 308.99989 -374.000014)
		(stroke
			(width 2.54)
			(type default)
		)
		(layer "In6.Cu")
	)
	(gr_line
		(start 309.999888 -375.000012)
		(end 309.999888 -420.200074)
		(stroke
			(width 2.54)
			(type default)
		)
		(layer "In6.Cu")
	)
	(gr_line
		(start 310.513984 -80.082898)
		(end 310.513984 -38.101016)
		(stroke
			(width 0.381)
			(type default)
		)
		(layer "In6.Cu")
	)
	(gr_line
		(start 310.513984 -38.101016)
		(end 314.671202 -33.943798)
		(stroke
			(width 0.381)
			(type default)
		)
		(layer "In6.Cu")
	)
	(gr_line
		(start 314.671202 -33.943798)
		(end 368.138202 -33.943798)
		(stroke
			(width 0.381)
			(type default)
		)
		(layer "In6.Cu")
	)
	(gr_line
		(start 318.262 -301.117)
		(end 297.8912 -321.4878)
		(stroke
			(width 0.381)
			(type default)
		)
		(layer "In6.Cu")
	)
	(gr_line
		(start 319.2145 -43.008042)
		(end 320.3575 -43.008042)
		(stroke
			(width 0.2)
			(type default)
		)
		(layer "In6.Cu")
	)
	(gr_arc
		(start 319.214754 -42.246042)
		(mid 318.8335 -42.626915)
		(end 319.2145 -43.008042)
		(stroke
			(width 0.2)
			(type default)
		)
		(layer "In6.Cu")
	)
	(gr_arc
		(start 319.56756 -274.511516)
		(mid 319.9892 -274.933156)
		(end 320.41084 -274.511516)
		(stroke
			(width 0.2)
			(type default)
		)
		(layer "In6.Cu")
	)
	(gr_line
		(start 319.56756 -273.368516)
		(end 319.56756 -274.511516)
		(stroke
			(width 0.2)
			(type default)
		)
		(layer "In6.Cu")
	)
	(gr_arc
		(start 319.6082 -159.511238)
		(mid 319.989073 -159.892492)
		(end 320.3702 -159.511492)
		(stroke
			(width 0.2)
			(type default)
		)
		(layer "In6.Cu")
	)
	(gr_line
		(start 319.6082 -158.368492)
		(end 319.6082 -159.511238)
		(stroke
			(width 0.2)
			(type default)
		)
		(layer "In6.Cu")
	)
	(gr_arc
		(start 320.3575 -43.008042)
		(mid 320.7385 -42.627042)
		(end 320.3575 -42.246042)
		(stroke
			(width 0.2)
			(type default)
		)
		(layer "In6.Cu")
	)
	(gr_line
		(start 320.3575 -42.246042)
		(end 319.214754 -42.246042)
		(stroke
			(width 0.2)
			(type default)
		)
		(layer "In6.Cu")
	)
	(gr_line
		(start 320.3702 -159.511492)
		(end 320.3702 -158.368492)
		(stroke
			(width 0.2)
			(type default)
		)
		(layer "In6.Cu")
	)
	(gr_arc
		(start 320.3702 -158.368492)
		(mid 319.9892 -157.987492)
		(end 319.6082 -158.368492)
		(stroke
			(width 0.2)
			(type default)
		)
		(layer "In6.Cu")
	)
	(gr_line
		(start 320.41084 -274.511516)
		(end 320.41084 -273.36877)
		(stroke
			(width 0.2)
			(type default)
		)
		(layer "In6.Cu")
	)
	(gr_arc
		(start 320.41084 -273.36877)
		(mid 319.989327 -272.946876)
		(end 319.56756 -273.368516)
		(stroke
			(width 0.2)
			(type default)
		)
		(layer "In6.Cu")
	)
	(gr_line
		(start 322.6816 -46.818042)
		(end 323.824346 -46.818042)
		(stroke
			(width 0.2)
			(type default)
		)
		(layer "In6.Cu")
	)
	(gr_arc
		(start 322.6816 -46.056042)
		(mid 322.3006 -46.437042)
		(end 322.6816 -46.818042)
		(stroke
			(width 0.2)
			(type default)
		)
		(layer "In6.Cu")
	)
	(gr_arc
		(start 323.824346 -46.818042)
		(mid 324.2056 -46.437169)
		(end 323.8246 -46.056042)
		(stroke
			(width 0.2)
			(type default)
		)
		(layer "In6.Cu")
	)
	(gr_line
		(start 323.8246 -46.056042)
		(end 322.6816 -46.056042)
		(stroke
			(width 0.2)
			(type default)
		)
		(layer "In6.Cu")
	)
	(gr_arc
		(start 324.358 -278.321516)
		(mid 324.739 -278.702516)
		(end 325.12 -278.321516)
		(stroke
			(width 0.2)
			(type default)
		)
		(layer "In6.Cu")
	)
	(gr_line
		(start 324.358 -277.178516)
		(end 324.358 -278.321516)
		(stroke
			(width 0.2)
			(type default)
		)
		(layer "In6.Cu")
	)
	(gr_arc
		(start 324.358 -163.321492)
		(mid 324.739 -163.702492)
		(end 325.12 -163.321492)
		(stroke
			(width 0.2)
			(type default)
		)
		(layer "In6.Cu")
	)
	(gr_line
		(start 324.358 -162.178492)
		(end 324.358 -163.321492)
		(stroke
			(width 0.2)
			(type default)
		)
		(layer "In6.Cu")
	)
	(gr_line
		(start 325.12 -278.321516)
		(end 325.12 -277.17877)
		(stroke
			(width 0.2)
			(type default)
		)
		(layer "In6.Cu")
	)
	(gr_arc
		(start 325.12 -277.17877)
		(mid 324.739127 -276.797516)
		(end 324.358 -277.178516)
		(stroke
			(width 0.2)
			(type default)
		)
		(layer "In6.Cu")
	)
	(gr_line
		(start 325.12 -163.321492)
		(end 325.12 -162.178746)
		(stroke
			(width 0.2)
			(type default)
		)
		(layer "In6.Cu")
	)
	(gr_arc
		(start 325.12 -162.178746)
		(mid 324.739127 -161.797492)
		(end 324.358 -162.178492)
		(stroke
			(width 0.2)
			(type default)
		)
		(layer "In6.Cu")
	)
	(gr_line
		(start 335.915 -272.3896)
		(end 338.116926 -274.591526)
		(stroke
			(width 0.381)
			(type default)
		)
		(layer "In6.Cu")
	)
	(gr_line
		(start 335.915 -267.0556)
		(end 335.915 -272.3896)
		(stroke
			(width 0.381)
			(type default)
		)
		(layer "In6.Cu")
	)
	(gr_line
		(start 337.52155 -286.490918)
		(end 337.52155 -286.488124)
		(stroke
			(width 0.381)
			(type default)
		)
		(layer "In6.Cu")
	)
	(gr_line
		(start 337.52155 -286.488124)
		(end 338.116926 -285.892748)
		(stroke
			(width 0.381)
			(type default)
		)
		(layer "In6.Cu")
	)
	(gr_line
		(start 337.947 -62.611)
		(end 342.877648 -67.541648)
		(stroke
			(width 0.381)
			(type default)
		)
		(layer "In6.Cu")
	)
	(gr_line
		(start 337.947 -51.054)
		(end 337.947 -62.611)
		(stroke
			(width 0.381)
			(type default)
		)
		(layer "In6.Cu")
	)
	(gr_line
		(start 338.116926 -286.490918)
		(end 305.329082 -286.490918)
		(stroke
			(width 0.381)
			(type default)
		)
		(layer "In6.Cu")
	)
	(gr_line
		(start 338.116926 -286.490918)
		(end 398.199864 -286.490918)
		(stroke
			(width 0.381)
			(type default)
		)
		(layer "In6.Cu")
	)
	(gr_line
		(start 338.116926 -285.892748)
		(end 338.675472 -286.451294)
		(stroke
			(width 0.381)
			(type default)
		)
		(layer "In6.Cu")
	)
	(gr_line
		(start 338.116926 -274.591526)
		(end 338.116926 -286.490918)
		(stroke
			(width 0.381)
			(type default)
		)
		(layer "In6.Cu")
	)
	(gr_line
		(start 338.116926 -264.853674)
		(end 335.915 -267.0556)
		(stroke
			(width 0.381)
			(type default)
		)
		(layer "In6.Cu")
	)
	(gr_line
		(start 338.116926 -159.47136)
		(end 338.116926 -264.853674)
		(stroke
			(width 0.381)
			(type default)
		)
		(layer "In6.Cu")
	)
	(gr_line
		(start 338.192364 -163.504372)
		(end 338.62391 -163.935918)
		(stroke
			(width 0.381)
			(type default)
		)
		(layer "In6.Cu")
	)
	(gr_line
		(start 338.62391 -163.935918)
		(end 338.192364 -164.367464)
		(stroke
			(width 0.381)
			(type default)
		)
		(layer "In6.Cu")
	)
	(gr_line
		(start 338.675472 -286.451294)
		(end 338.675472 -286.490918)
		(stroke
			(width 0.381)
			(type default)
		)
		(layer "In6.Cu")
	)
	(gr_line
		(start 338.8614 -50.1396)
		(end 337.947 -51.054)
		(stroke
			(width 0.381)
			(type default)
		)
		(layer "In6.Cu")
	)
	(gr_line
		(start 342.053672 -155.534614)
		(end 338.116926 -159.47136)
		(stroke
			(width 0.381)
			(type default)
		)
		(layer "In6.Cu")
	)
	(gr_line
		(start 342.877648 -142.753842)
		(end 345.126818 -145.003012)
		(stroke
			(width 0.381)
			(type default)
		)
		(layer "In6.Cu")
	)
	(gr_line
		(start 342.877648 -72.2122)
		(end 343.41308 -71.676768)
		(stroke
			(width 0.381)
			(type default)
		)
		(layer "In6.Cu")
	)
	(gr_line
		(start 342.877648 -67.541648)
		(end 342.877648 -142.753842)
		(stroke
			(width 0.381)
			(type default)
		)
		(layer "In6.Cu")
	)
	(gr_line
		(start 343.41308 -71.676768)
		(end 343.41308 -71.636382)
		(stroke
			(width 0.381)
			(type default)
		)
		(layer "In6.Cu")
	)
	(gr_line
		(start 343.41308 -71.636382)
		(end 342.877648 -71.10095)
		(stroke
			(width 0.381)
			(type default)
		)
		(layer "In6.Cu")
	)
	(gr_line
		(start 345.126818 -145.003012)
		(end 353.203764 -145.003012)
		(stroke
			(width 0.381)
			(type default)
		)
		(layer "In6.Cu")
	)
	(gr_arc
		(start 348.000066 -13.999972)
		(mid 348.292959 -14.707077)
		(end 349.000064 -14.99997)
		(stroke
			(width 2.54)
			(type default)
		)
		(layer "In6.Cu")
	)
	(gr_arc
		(start 348.000066 -0.999998)
		(mid 347.707171 -0.292905)
		(end 347.000068 0)
		(stroke
			(width 2.54)
			(type default)
		)
		(layer "In6.Cu")
	)
	(gr_line
		(start 348.000066 -0.999998)
		(end 348.000066 -13.999972)
		(stroke
			(width 2.54)
			(type default)
		)
		(layer "In6.Cu")
	)
	(gr_line
		(start 348.671642 -15.956026)
		(end 349.227394 -16.511778)
		(stroke
			(width 0.381)
			(type default)
		)
		(layer "In6.Cu")
	)
	(gr_line
		(start 349.000064 -14.99997)
		(end 394.999972 -14.99997)
		(stroke
			(width 2.54)
			(type default)
		)
		(layer "In6.Cu")
	)
	(gr_line
		(start 349.184214 -33.327848)
		(end 348.628716 -33.8836)
		(stroke
			(width 0.381)
			(type default)
		)
		(layer "In6.Cu")
	)
	(gr_line
		(start 349.205804 -33.943798)
		(end 349.205804 -15.174976)
		(stroke
			(width 0.381)
			(type default)
		)
		(layer "In6.Cu")
	)
	(gr_line
		(start 349.227394 -16.511778)
		(end 349.782892 -15.956026)
		(stroke
			(width 0.381)
			(type default)
		)
		(layer "In6.Cu")
	)
	(gr_line
		(start 349.739966 -33.8836)
		(end 349.184214 -33.327848)
		(stroke
			(width 0.381)
			(type default)
		)
		(layer "In6.Cu")
	)
	(gr_line
		(start 350.092518 -163.935918)
		(end 338.116926 -163.935918)
		(stroke
			(width 0.381)
			(type default)
		)
		(layer "In6.Cu")
	)
	(gr_line
		(start 350.380808 -13.999972)
		(end 353.000056 -13.999972)
		(stroke
			(width 0.381)
			(type default)
		)
		(layer "In6.Cu")
	)
	(gr_line
		(start 350.764602 -43.013122)
		(end 351.907602 -43.013122)
		(stroke
			(width 0.2)
			(type default)
		)
		(layer "In6.Cu")
	)
	(gr_arc
		(start 350.764856 -42.240962)
		(mid 350.378522 -42.626915)
		(end 350.764602 -43.013122)
		(stroke
			(width 0.2)
			(type default)
		)
		(layer "In6.Cu")
	)
	(gr_arc
		(start 351.158302 -274.511262)
		(mid 351.539175 -274.892516)
		(end 351.920302 -274.511516)
		(stroke
			(width 0.2)
			(type default)
		)
		(layer "In6.Cu")
	)
	(gr_line
		(start 351.158302 -273.368516)
		(end 351.158302 -274.511262)
		(stroke
			(width 0.2)
			(type default)
		)
		(layer "In6.Cu")
	)
	(gr_arc
		(start 351.158302 -159.511238)
		(mid 351.539175 -159.892492)
		(end 351.920302 -159.511492)
		(stroke
			(width 0.2)
			(type default)
		)
		(layer "In6.Cu")
	)
	(gr_line
		(start 351.158302 -158.368492)
		(end 351.158302 -159.511238)
		(stroke
			(width 0.2)
			(type default)
		)
		(layer "In6.Cu")
	)
	(gr_arc
		(start 351.907602 -43.013122)
		(mid 352.293682 -42.627042)
		(end 351.907602 -42.240962)
		(stroke
			(width 0.2)
			(type default)
		)
		(layer "In6.Cu")
	)
	(gr_line
		(start 351.907602 -42.240962)
		(end 350.764856 -42.240962)
		(stroke
			(width 0.2)
			(type default)
		)
		(layer "In6.Cu")
	)
	(gr_line
		(start 351.920302 -274.511516)
		(end 351.920302 -273.368516)
		(stroke
			(width 0.2)
			(type default)
		)
		(layer "In6.Cu")
	)
	(gr_arc
		(start 351.920302 -273.368516)
		(mid 351.539302 -272.987516)
		(end 351.158302 -273.368516)
		(stroke
			(width 0.2)
			(type default)
		)
		(layer "In6.Cu")
	)
	(gr_line
		(start 351.920302 -159.511492)
		(end 351.920302 -158.368492)
		(stroke
			(width 0.2)
			(type default)
		)
		(layer "In6.Cu")
	)
	(gr_arc
		(start 351.920302 -158.368492)
		(mid 351.539302 -157.987492)
		(end 351.158302 -158.368492)
		(stroke
			(width 0.2)
			(type default)
		)
		(layer "In6.Cu")
	)
	(gr_line
		(start 352.1202 -165.9636)
		(end 350.092518 -163.935918)
		(stroke
			(width 0.381)
			(type default)
		)
		(layer "In6.Cu")
	)
	(gr_line
		(start 352.867468 -155.534614)
		(end 342.053672 -155.534614)
		(stroke
			(width 0.381)
			(type default)
		)
		(layer "In6.Cu")
	)
	(gr_line
		(start 353.203764 -145.003012)
		(end 353.836224 -145.635472)
		(stroke
			(width 0.381)
			(type default)
		)
		(layer "In6.Cu")
	)
	(gr_line
		(start 353.836224 -154.565858)
		(end 352.867468 -155.534614)
		(stroke
			(width 0.381)
			(type default)
		)
		(layer "In6.Cu")
	)
	(gr_line
		(start 353.836224 -145.635472)
		(end 353.836224 -154.565858)
		(stroke
			(width 0.381)
			(type default)
		)
		(layer "In6.Cu")
	)
	(gr_arc
		(start 354.601272 -22.350222)
		(mid 355.149912 -22.898862)
		(end 355.698552 -22.350222)
		(stroke
			(width 0.2)
			(type default)
		)
		(layer "In6.Cu")
	)
	(gr_line
		(start 354.601272 -20.950174)
		(end 354.601272 -22.350222)
		(stroke
			(width 0.2)
			(type default)
		)
		(layer "In6.Cu")
	)
	(gr_arc
		(start 354.601272 -18.750026)
		(mid 355.149912 -19.298666)
		(end 355.698552 -18.750026)
		(stroke
			(width 0.2)
			(type default)
		)
		(layer "In6.Cu")
	)
	(gr_line
		(start 354.601272 -17.349978)
		(end 354.601272 -18.750026)
		(stroke
			(width 0.2)
			(type default)
		)
		(layer "In6.Cu")
	)
	(gr_line
		(start 355.698552 -22.350222)
		(end 355.698552 -20.950428)
		(stroke
			(width 0.2)
			(type default)
		)
		(layer "In6.Cu")
	)
	(gr_arc
		(start 355.698552 -20.950428)
		(mid 355.150039 -20.401534)
		(end 354.601272 -20.950174)
		(stroke
			(width 0.2)
			(type default)
		)
		(layer "In6.Cu")
	)
	(gr_line
		(start 355.698552 -18.750026)
		(end 355.698552 -17.350232)
		(stroke
			(width 0.2)
			(type default)
		)
		(layer "In6.Cu")
	)
	(gr_arc
		(start 355.698552 -17.350232)
		(mid 355.150039 -16.801338)
		(end 354.601272 -17.349978)
		(stroke
			(width 0.2)
			(type default)
		)
		(layer "In6.Cu")
	)
	(gr_arc
		(start 355.903022 -48.321468)
		(mid 356.289102 -48.707548)
		(end 356.675182 -48.321468)
		(stroke
			(width 0.2)
			(type default)
		)
		(layer "In6.Cu")
	)
	(gr_line
		(start 355.903022 -47.178468)
		(end 355.903022 -48.321468)
		(stroke
			(width 0.2)
			(type default)
		)
		(layer "In6.Cu")
	)
	(gr_arc
		(start 355.908102 -278.321516)
		(mid 356.289102 -278.702516)
		(end 356.670102 -278.321516)
		(stroke
			(width 0.2)
			(type default)
		)
		(layer "In6.Cu")
	)
	(gr_line
		(start 355.908102 -277.178516)
		(end 355.908102 -278.321516)
		(stroke
			(width 0.2)
			(type default)
		)
		(layer "In6.Cu")
	)
	(gr_arc
		(start 355.908102 -163.321492)
		(mid 356.289102 -163.702492)
		(end 356.670102 -163.321492)
		(stroke
			(width 0.2)
			(type default)
		)
		(layer "In6.Cu")
	)
	(gr_line
		(start 355.908102 -162.178492)
		(end 355.908102 -163.321492)
		(stroke
			(width 0.2)
			(type default)
		)
		(layer "In6.Cu")
	)
	(gr_arc
		(start 356.40137 -23.35022)
		(mid 356.95001 -23.89886)
		(end 357.49865 -23.35022)
		(stroke
			(width 0.2)
			(type default)
		)
		(layer "In6.Cu")
	)
	(gr_line
		(start 356.40137 -21.950172)
		(end 356.40137 -23.35022)
		(stroke
			(width 0.2)
			(type default)
		)
		(layer "In6.Cu")
	)
	(gr_arc
		(start 356.40137 -19.750024)
		(mid 356.95001 -20.298664)
		(end 357.49865 -19.750024)
		(stroke
			(width 0.2)
			(type default)
		)
		(layer "In6.Cu")
	)
	(gr_line
		(start 356.40137 -18.35023)
		(end 356.40137 -19.750024)
		(stroke
			(width 0.2)
			(type default)
		)
		(layer "In6.Cu")
	)
	(gr_line
		(start 356.670102 -278.321516)
		(end 356.670102 -277.17877)
		(stroke
			(width 0.2)
			(type default)
		)
		(layer "In6.Cu")
	)
	(gr_arc
		(start 356.670102 -277.17877)
		(mid 356.289229 -276.797516)
		(end 355.908102 -277.178516)
		(stroke
			(width 0.2)
			(type default)
		)
		(layer "In6.Cu")
	)
	(gr_line
		(start 356.670102 -163.321492)
		(end 356.670102 -162.178746)
		(stroke
			(width 0.2)
			(type default)
		)
		(layer "In6.Cu")
	)
	(gr_arc
		(start 356.670102 -162.178746)
		(mid 356.289229 -161.797492)
		(end 355.908102 -162.178492)
		(stroke
			(width 0.2)
			(type default)
		)
		(layer "In6.Cu")
	)
	(gr_line
		(start 356.675182 -48.321468)
		(end 356.675182 -47.178722)
		(stroke
			(width 0.2)
			(type default)
		)
		(layer "In6.Cu")
	)
	(gr_arc
		(start 356.675182 -47.178722)
		(mid 356.289229 -46.792388)
		(end 355.903022 -47.178468)
		(stroke
			(width 0.2)
			(type default)
		)
		(layer "In6.Cu")
	)
	(gr_line
		(start 357.49865 -23.35022)
		(end 357.49865 -21.950426)
		(stroke
			(width 0.2)
			(type default)
		)
		(layer "In6.Cu")
	)
	(gr_arc
		(start 357.49865 -21.950426)
		(mid 356.950137 -21.401532)
		(end 356.40137 -21.950172)
		(stroke
			(width 0.2)
			(type default)
		)
		(layer "In6.Cu")
	)
	(gr_line
		(start 357.49865 -19.750024)
		(end 357.49865 -18.350484)
		(stroke
			(width 0.2)
			(type default)
		)
		(layer "In6.Cu")
	)
	(gr_arc
		(start 357.49865 -18.350484)
		(mid 356.950137 -17.80159)
		(end 356.40137 -18.35023)
		(stroke
			(width 0.2)
			(type default)
		)
		(layer "In6.Cu")
	)
	(gr_arc
		(start 358.201468 -22.350222)
		(mid 358.750108 -22.898862)
		(end 359.298748 -22.350222)
		(stroke
			(width 0.2)
			(type default)
		)
		(layer "In6.Cu")
	)
	(gr_line
		(start 358.201468 -20.950174)
		(end 358.201468 -22.350222)
		(stroke
			(width 0.2)
			(type default)
		)
		(layer "In6.Cu")
	)
	(gr_arc
		(start 358.201468 -18.750026)
		(mid 358.750108 -19.298666)
		(end 359.298748 -18.750026)
		(stroke
			(width 0.2)
			(type default)
		)
		(layer "In6.Cu")
	)
	(gr_line
		(start 358.201468 -17.349978)
		(end 358.201468 -18.750026)
		(stroke
			(width 0.2)
			(type default)
		)
		(layer "In6.Cu")
	)
	(gr_line
		(start 359.298748 -22.350222)
		(end 359.298748 -20.950428)
		(stroke
			(width 0.2)
			(type default)
		)
		(layer "In6.Cu")
	)
	(gr_arc
		(start 359.298748 -20.950428)
		(mid 358.750235 -20.401534)
		(end 358.201468 -20.950174)
		(stroke
			(width 0.2)
			(type default)
		)
		(layer "In6.Cu")
	)
	(gr_line
		(start 359.298748 -18.750026)
		(end 359.298748 -17.350232)
		(stroke
			(width 0.2)
			(type default)
		)
		(layer "In6.Cu")
	)
	(gr_arc
		(start 359.298748 -17.350232)
		(mid 358.750235 -16.801338)
		(end 358.201468 -17.349978)
		(stroke
			(width 0.2)
			(type default)
		)
		(layer "In6.Cu")
	)
	(gr_arc
		(start 360.001312 -23.35022)
		(mid 360.549952 -23.89886)
		(end 361.098592 -23.35022)
		(stroke
			(width 0.2)
			(type default)
		)
		(layer "In6.Cu")
	)
	(gr_line
		(start 360.001312 -21.950172)
		(end 360.001312 -23.35022)
		(stroke
			(width 0.2)
			(type default)
		)
		(layer "In6.Cu")
	)
	(gr_arc
		(start 360.001312 -19.750024)
		(mid 360.549952 -20.298664)
		(end 361.098592 -19.750024)
		(stroke
			(width 0.2)
			(type default)
		)
		(layer "In6.Cu")
	)
	(gr_line
		(start 360.001312 -18.35023)
		(end 360.001312 -19.750024)
		(stroke
			(width 0.2)
			(type default)
		)
		(layer "In6.Cu")
	)
	(gr_line
		(start 361.098592 -23.35022)
		(end 361.098592 -21.950426)
		(stroke
			(width 0.2)
			(type default)
		)
		(layer "In6.Cu")
	)
	(gr_arc
		(start 361.098592 -21.950426)
		(mid 360.550079 -21.401532)
		(end 360.001312 -21.950172)
		(stroke
			(width 0.2)
			(type default)
		)
		(layer "In6.Cu")
	)
	(gr_line
		(start 361.098592 -19.750024)
		(end 361.098592 -18.350484)
		(stroke
			(width 0.2)
			(type default)
		)
		(layer "In6.Cu")
	)
	(gr_arc
		(start 361.098592 -18.350484)
		(mid 360.550079 -17.80159)
		(end 360.001312 -18.35023)
		(stroke
			(width 0.2)
			(type default)
		)
		(layer "In6.Cu")
	)
	(gr_arc
		(start 361.80141 -29.550106)
		(mid 362.35005 -30.098746)
		(end 362.89869 -29.550106)
		(stroke
			(width 0.2)
			(type default)
		)
		(layer "In6.Cu")
	)
	(gr_line
		(start 361.80141 -28.150058)
		(end 361.80141 -29.550106)
		(stroke
			(width 0.2)
			(type default)
		)
		(layer "In6.Cu")
	)
	(gr_arc
		(start 361.80141 -22.350222)
		(mid 362.35005 -22.898862)
		(end 362.89869 -22.350222)
		(stroke
			(width 0.2)
			(type default)
		)
		(layer "In6.Cu")
	)
	(gr_line
		(start 361.80141 -20.950174)
		(end 361.80141 -22.350222)
		(stroke
			(width 0.2)
			(type default)
		)
		(layer "In6.Cu")
	)
	(gr_arc
		(start 361.80141 -18.750026)
		(mid 362.35005 -19.298666)
		(end 362.89869 -18.750026)
		(stroke
			(width 0.2)
			(type default)
		)
		(layer "In6.Cu")
	)
	(gr_line
		(start 361.80141 -17.349978)
		(end 361.80141 -18.750026)
		(stroke
			(width 0.2)
			(type default)
		)
		(layer "In6.Cu")
	)
	(gr_line
		(start 362.89869 -29.550106)
		(end 362.89869 -28.150312)
		(stroke
			(width 0.2)
			(type default)
		)
		(layer "In6.Cu")
	)
	(gr_arc
		(start 362.89869 -28.150312)
		(mid 362.350177 -27.601418)
		(end 361.80141 -28.150058)
		(stroke
			(width 0.2)
			(type default)
		)
		(layer "In6.Cu")
	)
	(gr_line
		(start 362.89869 -22.350222)
		(end 362.89869 -20.950428)
		(stroke
			(width 0.2)
			(type default)
		)
		(layer "In6.Cu")
	)
	(gr_arc
		(start 362.89869 -20.950428)
		(mid 362.350177 -20.401534)
		(end 361.80141 -20.950174)
		(stroke
			(width 0.2)
			(type default)
		)
		(layer "In6.Cu")
	)
	(gr_line
		(start 362.89869 -18.750026)
		(end 362.89869 -17.350232)
		(stroke
			(width 0.2)
			(type default)
		)
		(layer "In6.Cu")
	)
	(gr_arc
		(start 362.89869 -17.350232)
		(mid 362.350177 -16.801338)
		(end 361.80141 -17.349978)
		(stroke
			(width 0.2)
			(type default)
		)
		(layer "In6.Cu")
	)
	(gr_arc
		(start 363.601254 -23.35022)
		(mid 364.149894 -23.89886)
		(end 364.698534 -23.35022)
		(stroke
			(width 0.2)
			(type default)
		)
		(layer "In6.Cu")
	)
	(gr_line
		(start 363.601254 -21.950172)
		(end 363.601254 -23.35022)
		(stroke
			(width 0.2)
			(type default)
		)
		(layer "In6.Cu")
	)
	(gr_arc
		(start 363.601254 -19.750024)
		(mid 364.149894 -20.298664)
		(end 364.698534 -19.750024)
		(stroke
			(width 0.2)
			(type default)
		)
		(layer "In6.Cu")
	)
	(gr_line
		(start 363.601254 -18.35023)
		(end 363.601254 -19.750024)
		(stroke
			(width 0.2)
			(type default)
		)
		(layer "In6.Cu")
	)
	(gr_line
		(start 364.698534 -23.35022)
		(end 364.698534 -21.950426)
		(stroke
			(width 0.2)
			(type default)
		)
		(layer "In6.Cu")
	)
	(gr_arc
		(start 364.698534 -21.950426)
		(mid 364.150021 -21.401532)
		(end 363.601254 -21.950172)
		(stroke
			(width 0.2)
			(type default)
		)
		(layer "In6.Cu")
	)
	(gr_line
		(start 364.698534 -19.750024)
		(end 364.698534 -18.350484)
		(stroke
			(width 0.2)
			(type default)
		)
		(layer "In6.Cu")
	)
	(gr_arc
		(start 364.698534 -18.350484)
		(mid 364.150021 -17.80159)
		(end 363.601254 -18.35023)
		(stroke
			(width 0.2)
			(type default)
		)
		(layer "In6.Cu")
	)
	(gr_arc
		(start 365.401352 -22.350222)
		(mid 365.949992 -22.898862)
		(end 366.498632 -22.350222)
		(stroke
			(width 0.2)
			(type default)
		)
		(layer "In6.Cu")
	)
	(gr_line
		(start 365.401352 -20.950174)
		(end 365.401352 -22.350222)
		(stroke
			(width 0.2)
			(type default)
		)
		(layer "In6.Cu")
	)
	(gr_arc
		(start 365.401352 -18.750026)
		(mid 365.949992 -19.298666)
		(end 366.498632 -18.750026)
		(stroke
			(width 0.2)
			(type default)
		)
		(layer "In6.Cu")
	)
	(gr_line
		(start 365.401352 -17.349978)
		(end 365.401352 -18.750026)
		(stroke
			(width 0.2)
			(type default)
		)
		(layer "In6.Cu")
	)
	(gr_line
		(start 366.498632 -22.350222)
		(end 366.498632 -20.950428)
		(stroke
			(width 0.2)
			(type default)
		)
		(layer "In6.Cu")
	)
	(gr_arc
		(start 366.498632 -20.950428)
		(mid 365.950119 -20.401534)
		(end 365.401352 -20.950174)
		(stroke
			(width 0.2)
			(type default)
		)
		(layer "In6.Cu")
	)
	(gr_line
		(start 366.498632 -18.750026)
		(end 366.498632 -17.350232)
		(stroke
			(width 0.2)
			(type default)
		)
		(layer "In6.Cu")
	)
	(gr_arc
		(start 366.498632 -17.350232)
		(mid 365.950119 -16.801338)
		(end 365.401352 -17.349978)
		(stroke
			(width 0.2)
			(type default)
		)
		(layer "In6.Cu")
	)
	(gr_arc
		(start 367.19891 -30.54985)
		(mid 367.749963 -31.101284)
		(end 368.30127 -30.550104)
		(stroke
			(width 0.2)
			(type default)
		)
		(layer "In6.Cu")
	)
	(gr_line
		(start 367.19891 -29.150056)
		(end 367.19891 -30.54985)
		(stroke
			(width 0.2)
			(type default)
		)
		(layer "In6.Cu")
	)
	(gr_arc
		(start 367.20145 -23.35022)
		(mid 367.75009 -23.89886)
		(end 368.29873 -23.35022)
		(stroke
			(width 0.2)
			(type default)
		)
		(layer "In6.Cu")
	)
	(gr_line
		(start 367.20145 -21.950172)
		(end 367.20145 -23.35022)
		(stroke
			(width 0.2)
			(type default)
		)
		(layer "In6.Cu")
	)
	(gr_arc
		(start 367.20145 -19.750024)
		(mid 367.75009 -20.298664)
		(end 368.29873 -19.750024)
		(stroke
			(width 0.2)
			(type default)
		)
		(layer "In6.Cu")
	)
	(gr_line
		(start 367.20145 -18.35023)
		(end 367.20145 -19.750024)
		(stroke
			(width 0.2)
			(type default)
		)
		(layer "In6.Cu")
	)
	(gr_line
		(start 368.138202 -33.943798)
		(end 369.47221 -32.60979)
		(stroke
			(width 0.381)
			(type default)
		)
		(layer "In6.Cu")
	)
	(gr_line
		(start 368.29873 -23.35022)
		(end 368.29873 -21.950426)
		(stroke
			(width 0.2)
			(type default)
		)
		(layer "In6.Cu")
	)
	(gr_arc
		(start 368.29873 -21.950426)
		(mid 367.750217 -21.401532)
		(end 367.20145 -21.950172)
		(stroke
			(width 0.2)
			(type default)
		)
		(layer "In6.Cu")
	)
	(gr_line
		(start 368.29873 -19.750024)
		(end 368.29873 -18.350484)
		(stroke
			(width 0.2)
			(type default)
		)
		(layer "In6.Cu")
	)
	(gr_arc
		(start 368.29873 -18.350484)
		(mid 367.750217 -17.80159)
		(end 367.20145 -18.35023)
		(stroke
			(width 0.2)
			(type default)
		)
		(layer "In6.Cu")
	)
	(gr_line
		(start 368.30127 -30.550104)
		(end 368.30127 -29.150056)
		(stroke
			(width 0.2)
			(type default)
		)
		(layer "In6.Cu")
	)
	(gr_arc
		(start 368.30127 -29.150056)
		(mid 367.75009 -28.598876)
		(end 367.19891 -29.150056)
		(stroke
			(width 0.2)
			(type default)
		)
		(layer "In6.Cu")
	)
	(gr_line
		(start 369.236244 -165.9636)
		(end 352.1202 -165.9636)
		(stroke
			(width 0.381)
			(type default)
		)
		(layer "In6.Cu")
	)
	(gr_line
		(start 369.47221 -32.60979)
		(end 369.47221 -25.886918)
		(stroke
			(width 0.381)
			(type default)
		)
		(layer "In6.Cu")
	)
	(gr_line
		(start 369.47221 -25.886918)
		(end 371.991128 -23.368)
		(stroke
			(width 0.381)
			(type default)
		)
		(layer "In6.Cu")
	)
	(gr_line
		(start 371.263926 -163.935918)
		(end 369.236244 -165.9636)
		(stroke
			(width 0.381)
			(type default)
		)
		(layer "In6.Cu")
	)
	(gr_line
		(start 371.991128 -23.368)
		(end 378.017532 -23.368)
		(stroke
			(width 0.381)
			(type default)
		)
		(layer "In6.Cu")
	)
	(gr_arc
		(start 376.201432 -22.350222)
		(mid 376.750072 -22.898862)
		(end 377.298712 -22.350222)
		(stroke
			(width 0.2)
			(type default)
		)
		(layer "In6.Cu")
	)
	(gr_line
		(start 376.201432 -20.950174)
		(end 376.201432 -22.350222)
		(stroke
			(width 0.2)
			(type default)
		)
		(layer "In6.Cu")
	)
	(gr_arc
		(start 376.201432 -18.750026)
		(mid 376.750072 -19.298666)
		(end 377.298712 -18.750026)
		(stroke
			(width 0.2)
			(type default)
		)
		(layer "In6.Cu")
	)
	(gr_line
		(start 376.201432 -17.349978)
		(end 376.201432 -18.750026)
		(stroke
			(width 0.2)
			(type default)
		)
		(layer "In6.Cu")
	)
	(gr_line
		(start 377.298712 -22.350222)
		(end 377.298712 -20.950428)
		(stroke
			(width 0.2)
			(type default)
		)
		(layer "In6.Cu")
	)
	(gr_arc
		(start 377.298712 -20.950428)
		(mid 376.750199 -20.401534)
		(end 376.201432 -20.950174)
		(stroke
			(width 0.2)
			(type default)
		)
		(layer "In6.Cu")
	)
	(gr_line
		(start 377.298712 -18.750026)
		(end 377.298712 -17.350232)
		(stroke
			(width 0.2)
			(type default)
		)
		(layer "In6.Cu")
	)
	(gr_arc
		(start 377.298712 -17.350232)
		(mid 376.750199 -16.801338)
		(end 376.201432 -17.349978)
		(stroke
			(width 0.2)
			(type default)
		)
		(layer "In6.Cu")
	)
	(gr_arc
		(start 378.001276 -23.35022)
		(mid 378.549916 -23.89886)
		(end 379.098556 -23.35022)
		(stroke
			(width 0.2)
			(type default)
		)
		(layer "In6.Cu")
	)
	(gr_line
		(start 378.001276 -21.950172)
		(end 378.001276 -23.35022)
		(stroke
			(width 0.2)
			(type default)
		)
		(layer "In6.Cu")
	)
	(gr_arc
		(start 378.001276 -19.750024)
		(mid 378.549916 -20.298664)
		(end 379.098556 -19.750024)
		(stroke
			(width 0.2)
			(type default)
		)
		(layer "In6.Cu")
	)
	(gr_line
		(start 378.001276 -18.35023)
		(end 378.001276 -19.750024)
		(stroke
			(width 0.2)
			(type default)
		)
		(layer "In6.Cu")
	)
	(gr_line
		(start 378.017532 -23.368)
		(end 380.365 -25.715468)
		(stroke
			(width 0.381)
			(type default)
		)
		(layer "In6.Cu")
	)
	(gr_line
		(start 379.098556 -23.35022)
		(end 379.098556 -21.950426)
		(stroke
			(width 0.2)
			(type default)
		)
		(layer "In6.Cu")
	)
	(gr_arc
		(start 379.098556 -21.950426)
		(mid 378.550043 -21.401532)
		(end 378.001276 -21.950172)
		(stroke
			(width 0.2)
			(type default)
		)
		(layer "In6.Cu")
	)
	(gr_line
		(start 379.098556 -19.750024)
		(end 379.098556 -18.350484)
		(stroke
			(width 0.2)
			(type default)
		)
		(layer "In6.Cu")
	)
	(gr_arc
		(start 379.098556 -18.350484)
		(mid 378.550043 -17.80159)
		(end 378.001276 -18.35023)
		(stroke
			(width 0.2)
			(type default)
		)
		(layer "In6.Cu")
	)
	(gr_line
		(start 379.603 -50.1396)
		(end 338.8614 -50.1396)
		(stroke
			(width 0.381)
			(type default)
		)
		(layer "In6.Cu")
	)
	(gr_line
		(start 379.603 -50.1396)
		(end 380.365 -50.1396)
		(stroke
			(width 0.381)
			(type default)
		)
		(layer "In6.Cu")
	)
	(gr_arc
		(start 379.801374 -22.350222)
		(mid 380.350014 -22.898862)
		(end 380.898654 -22.350222)
		(stroke
			(width 0.2)
			(type default)
		)
		(layer "In6.Cu")
	)
	(gr_line
		(start 379.801374 -20.950174)
		(end 379.801374 -22.350222)
		(stroke
			(width 0.2)
			(type default)
		)
		(layer "In6.Cu")
	)
	(gr_arc
		(start 379.801374 -18.750026)
		(mid 380.350014 -19.298666)
		(end 380.898654 -18.750026)
		(stroke
			(width 0.2)
			(type default)
		)
		(layer "In6.Cu")
	)
	(gr_line
		(start 379.801374 -17.349978)
		(end 379.801374 -18.750026)
		(stroke
			(width 0.2)
			(type default)
		)
		(layer "In6.Cu")
	)
	(gr_line
		(start 380.365 -50.1396)
		(end 396.367 -50.1396)
		(stroke
			(width 0.381)
			(type default)
		)
		(layer "In6.Cu")
	)
	(gr_line
		(start 380.365 -25.715468)
		(end 380.365 -50.1396)
		(stroke
			(width 0.381)
			(type default)
		)
		(layer "In6.Cu")
	)
	(gr_line
		(start 380.389638 -49.555908)
		(end 379.83414 -50.11166)
		(stroke
			(width 0.381)
			(type default)
		)
		(layer "In6.Cu")
	)
	(gr_line
		(start 380.898654 -22.350222)
		(end 380.898654 -20.950428)
		(stroke
			(width 0.2)
			(type default)
		)
		(layer "In6.Cu")
	)
	(gr_arc
		(start 380.898654 -20.950428)
		(mid 380.350141 -20.401534)
		(end 379.801374 -20.950174)
		(stroke
			(width 0.2)
			(type default)
		)
		(layer "In6.Cu")
	)
	(gr_line
		(start 380.898654 -18.750026)
		(end 380.898654 -17.350232)
		(stroke
			(width 0.2)
			(type default)
		)
		(layer "In6.Cu")
	)
	(gr_arc
		(start 380.898654 -17.350232)
		(mid 380.350141 -16.801338)
		(end 379.801374 -17.349978)
		(stroke
			(width 0.2)
			(type default)
		)
		(layer "In6.Cu")
	)
	(gr_line
		(start 380.94539 -50.11166)
		(end 380.389638 -49.555908)
		(stroke
			(width 0.381)
			(type default)
		)
		(layer "In6.Cu")
	)
	(gr_arc
		(start 381.598932 -30.550104)
		(mid 382.150112 -31.101284)
		(end 382.701292 -30.550104)
		(stroke
			(width 0.2)
			(type default)
		)
		(layer "In6.Cu")
	)
	(gr_line
		(start 381.598932 -29.150056)
		(end 381.598932 -30.550104)
		(stroke
			(width 0.2)
			(type default)
		)
		(layer "In6.Cu")
	)
	(gr_arc
		(start 381.601472 -23.35022)
		(mid 382.150112 -23.89886)
		(end 382.698752 -23.35022)
		(stroke
			(width 0.2)
			(type default)
		)
		(layer "In6.Cu")
	)
	(gr_line
		(start 381.601472 -21.950172)
		(end 381.601472 -23.35022)
		(stroke
			(width 0.2)
			(type default)
		)
		(layer "In6.Cu")
	)
	(gr_arc
		(start 381.601472 -19.750024)
		(mid 382.150112 -20.298664)
		(end 382.698752 -19.750024)
		(stroke
			(width 0.2)
			(type default)
		)
		(layer "In6.Cu")
	)
	(gr_line
		(start 381.601472 -18.35023)
		(end 381.601472 -19.750024)
		(stroke
			(width 0.2)
			(type default)
		)
		(layer "In6.Cu")
	)
	(gr_line
		(start 382.698752 -23.35022)
		(end 382.698752 -21.950426)
		(stroke
			(width 0.2)
			(type default)
		)
		(layer "In6.Cu")
	)
	(gr_arc
		(start 382.698752 -21.950426)
		(mid 382.150239 -21.401532)
		(end 381.601472 -21.950172)
		(stroke
			(width 0.2)
			(type default)
		)
		(layer "In6.Cu")
	)
	(gr_line
		(start 382.698752 -19.750024)
		(end 382.698752 -18.350484)
		(stroke
			(width 0.2)
			(type default)
		)
		(layer "In6.Cu")
	)
	(gr_arc
		(start 382.698752 -18.350484)
		(mid 382.150239 -17.80159)
		(end 381.601472 -18.35023)
		(stroke
			(width 0.2)
			(type default)
		)
		(layer "In6.Cu")
	)
	(gr_line
		(start 382.701292 -30.550104)
		(end 382.701292 -29.15031)
		(stroke
			(width 0.2)
			(type default)
		)
		(layer "In6.Cu")
	)
	(gr_arc
		(start 382.701292 -29.15031)
		(mid 382.150239 -28.598876)
		(end 381.598932 -29.150056)
		(stroke
			(width 0.2)
			(type default)
		)
		(layer "In6.Cu")
	)
	(gr_arc
		(start 382.70815 -274.511262)
		(mid 383.089023 -274.892516)
		(end 383.47015 -274.511516)
		(stroke
			(width 0.2)
			(type default)
		)
		(layer "In6.Cu")
	)
	(gr_line
		(start 382.70815 -273.368516)
		(end 382.70815 -274.511262)
		(stroke
			(width 0.2)
			(type default)
		)
		(layer "In6.Cu")
	)
	(gr_arc
		(start 382.70815 -159.511238)
		(mid 383.089023 -159.892492)
		(end 383.47015 -159.511492)
		(stroke
			(width 0.2)
			(type default)
		)
		(layer "In6.Cu")
	)
	(gr_line
		(start 382.70815 -158.368492)
		(end 382.70815 -159.511238)
		(stroke
			(width 0.2)
			(type default)
		)
		(layer "In6.Cu")
	)
	(gr_line
		(start 382.7653 -46.5328)
		(end 383.908046 -46.5328)
		(stroke
			(width 0.2)
			(type default)
		)
		(layer "In6.Cu")
	)
	(gr_arc
		(start 382.7653 -45.7708)
		(mid 382.3843 -46.1518)
		(end 382.7653 -46.5328)
		(stroke
			(width 0.2)
			(type default)
		)
		(layer "In6.Cu")
	)
	(gr_arc
		(start 383.401316 -22.350222)
		(mid 383.949956 -22.898862)
		(end 384.498596 -22.350222)
		(stroke
			(width 0.2)
			(type default)
		)
		(layer "In6.Cu")
	)
	(gr_line
		(start 383.401316 -20.950174)
		(end 383.401316 -22.350222)
		(stroke
			(width 0.2)
			(type default)
		)
		(layer "In6.Cu")
	)
	(gr_arc
		(start 383.401316 -18.750026)
		(mid 383.949956 -19.298666)
		(end 384.498596 -18.750026)
		(stroke
			(width 0.2)
			(type default)
		)
		(layer "In6.Cu")
	)
	(gr_line
		(start 383.401316 -17.349978)
		(end 383.401316 -18.750026)
		(stroke
			(width 0.2)
			(type default)
		)
		(layer "In6.Cu")
	)
	(gr_line
		(start 383.47015 -274.511516)
		(end 383.47015 -273.368516)
		(stroke
			(width 0.2)
			(type default)
		)
		(layer "In6.Cu")
	)
	(gr_arc
		(start 383.47015 -273.368516)
		(mid 383.08915 -272.987516)
		(end 382.70815 -273.368516)
		(stroke
			(width 0.2)
			(type default)
		)
		(layer "In6.Cu")
	)
	(gr_line
		(start 383.47015 -159.511492)
		(end 383.47015 -158.368492)
		(stroke
			(width 0.2)
			(type default)
		)
		(layer "In6.Cu")
	)
	(gr_arc
		(start 383.47015 -158.368492)
		(mid 383.08915 -157.987492)
		(end 382.70815 -158.368492)
		(stroke
			(width 0.2)
			(type default)
		)
		(layer "In6.Cu")
	)
	(gr_arc
		(start 383.908046 -46.5328)
		(mid 384.2893 -46.151927)
		(end 383.9083 -45.7708)
		(stroke
			(width 0.2)
			(type default)
		)
		(layer "In6.Cu")
	)
	(gr_line
		(start 383.9083 -45.7708)
		(end 382.7653 -45.7708)
		(stroke
			(width 0.2)
			(type default)
		)
		(layer "In6.Cu")
	)
	(gr_line
		(start 384.498596 -22.350222)
		(end 384.498596 -20.950428)
		(stroke
			(width 0.2)
			(type default)
		)
		(layer "In6.Cu")
	)
	(gr_arc
		(start 384.498596 -20.950428)
		(mid 383.950083 -20.401534)
		(end 383.401316 -20.950174)
		(stroke
			(width 0.2)
			(type default)
		)
		(layer "In6.Cu")
	)
	(gr_line
		(start 384.498596 -18.750026)
		(end 384.498596 -17.350232)
		(stroke
			(width 0.2)
			(type default)
		)
		(layer "In6.Cu")
	)
	(gr_arc
		(start 384.498596 -17.350232)
		(mid 383.950083 -16.801338)
		(end 383.401316 -17.349978)
		(stroke
			(width 0.2)
			(type default)
		)
		(layer "In6.Cu")
	)
	(gr_arc
		(start 385.201414 -23.35022)
		(mid 385.750054 -23.89886)
		(end 386.298694 -23.35022)
		(stroke
			(width 0.2)
			(type default)
		)
		(layer "In6.Cu")
	)
	(gr_line
		(start 385.201414 -21.950172)
		(end 385.201414 -23.35022)
		(stroke
			(width 0.2)
			(type default)
		)
		(layer "In6.Cu")
	)
	(gr_arc
		(start 385.201414 -19.750024)
		(mid 385.750054 -20.298664)
		(end 386.298694 -19.750024)
		(stroke
			(width 0.2)
			(type default)
		)
		(layer "In6.Cu")
	)
	(gr_line
		(start 385.201414 -18.35023)
		(end 385.201414 -19.750024)
		(stroke
			(width 0.2)
			(type default)
		)
		(layer "In6.Cu")
	)
	(gr_line
		(start 386.298694 -23.35022)
		(end 386.298694 -21.950426)
		(stroke
			(width 0.2)
			(type default)
		)
		(layer "In6.Cu")
	)
	(gr_arc
		(start 386.298694 -21.950426)
		(mid 385.750181 -21.401532)
		(end 385.201414 -21.950172)
		(stroke
			(width 0.2)
			(type default)
		)
		(layer "In6.Cu")
	)
	(gr_line
		(start 386.298694 -19.750024)
		(end 386.298694 -18.350484)
		(stroke
			(width 0.2)
			(type default)
		)
		(layer "In6.Cu")
	)
	(gr_arc
		(start 386.298694 -18.350484)
		(mid 385.750181 -17.80159)
		(end 385.201414 -18.35023)
		(stroke
			(width 0.2)
			(type default)
		)
		(layer "In6.Cu")
	)
	(gr_arc
		(start 387.001258 -22.350222)
		(mid 387.549898 -22.898862)
		(end 388.098538 -22.350222)
		(stroke
			(width 0.2)
			(type default)
		)
		(layer "In6.Cu")
	)
	(gr_line
		(start 387.001258 -20.950174)
		(end 387.001258 -22.350222)
		(stroke
			(width 0.2)
			(type default)
		)
		(layer "In6.Cu")
	)
	(gr_arc
		(start 387.001258 -18.750026)
		(mid 387.549898 -19.298666)
		(end 388.098538 -18.750026)
		(stroke
			(width 0.2)
			(type default)
		)
		(layer "In6.Cu")
	)
	(gr_line
		(start 387.001258 -17.349978)
		(end 387.001258 -18.750026)
		(stroke
			(width 0.2)
			(type default)
		)
		(layer "In6.Cu")
	)
	(gr_arc
		(start 387.45795 -278.321516)
		(mid 387.83895 -278.702516)
		(end 388.21995 -278.321516)
		(stroke
			(width 0.2)
			(type default)
		)
		(layer "In6.Cu")
	)
	(gr_line
		(start 387.45795 -277.178516)
		(end 387.45795 -278.321516)
		(stroke
			(width 0.2)
			(type default)
		)
		(layer "In6.Cu")
	)
	(gr_arc
		(start 387.45795 -163.321492)
		(mid 387.83895 -163.702492)
		(end 388.21995 -163.321492)
		(stroke
			(width 0.2)
			(type default)
		)
		(layer "In6.Cu")
	)
	(gr_line
		(start 387.45795 -162.178492)
		(end 387.45795 -163.321492)
		(stroke
			(width 0.2)
			(type default)
		)
		(layer "In6.Cu")
	)
	(gr_arc
		(start 387.45795 -48.321468)
		(mid 387.83895 -48.702468)
		(end 388.21995 -48.321468)
		(stroke
			(width 0.2)
			(type default)
		)
		(layer "In6.Cu")
	)
	(gr_line
		(start 387.45795 -47.178468)
		(end 387.45795 -48.321468)
		(stroke
			(width 0.2)
			(type default)
		)
		(layer "In6.Cu")
	)
	(gr_line
		(start 388.098538 -22.350222)
		(end 388.098538 -20.950428)
		(stroke
			(width 0.2)
			(type default)
		)
		(layer "In6.Cu")
	)
	(gr_arc
		(start 388.098538 -20.950428)
		(mid 387.550025 -20.401534)
		(end 387.001258 -20.950174)
		(stroke
			(width 0.2)
			(type default)
		)
		(layer "In6.Cu")
	)
	(gr_line
		(start 388.098538 -18.750026)
		(end 388.098538 -17.350232)
		(stroke
			(width 0.2)
			(type default)
		)
		(layer "In6.Cu")
	)
	(gr_arc
		(start 388.098538 -17.350232)
		(mid 387.550025 -16.801338)
		(end 387.001258 -17.349978)
		(stroke
			(width 0.2)
			(type default)
		)
		(layer "In6.Cu")
	)
	(gr_line
		(start 388.21995 -278.321516)
		(end 388.21995 -277.17877)
		(stroke
			(width 0.2)
			(type default)
		)
		(layer "In6.Cu")
	)
	(gr_arc
		(start 388.21995 -277.17877)
		(mid 387.839077 -276.797516)
		(end 387.45795 -277.178516)
		(stroke
			(width 0.2)
			(type default)
		)
		(layer "In6.Cu")
	)
	(gr_line
		(start 388.21995 -163.321492)
		(end 388.21995 -162.178746)
		(stroke
			(width 0.2)
			(type default)
		)
		(layer "In6.Cu")
	)
	(gr_arc
		(start 388.21995 -162.178746)
		(mid 387.839077 -161.797492)
		(end 387.45795 -162.178492)
		(stroke
			(width 0.2)
			(type default)
		)
		(layer "In6.Cu")
	)
	(gr_line
		(start 388.21995 -48.321468)
		(end 388.21995 -47.178722)
		(stroke
			(width 0.2)
			(type default)
		)
		(layer "In6.Cu")
	)
	(gr_arc
		(start 388.21995 -47.178722)
		(mid 387.839077 -46.797468)
		(end 387.45795 -47.178468)
		(stroke
			(width 0.2)
			(type default)
		)
		(layer "In6.Cu")
	)
	(gr_arc
		(start 388.801356 -30.550104)
		(mid 389.349996 -31.098744)
		(end 389.898636 -30.550104)
		(stroke
			(width 0.2)
			(type default)
		)
		(layer "In6.Cu")
	)
	(gr_line
		(start 388.801356 -29.150056)
		(end 388.801356 -30.550104)
		(stroke
			(width 0.2)
			(type default)
		)
		(layer "In6.Cu")
	)
	(gr_arc
		(start 388.801356 -23.35022)
		(mid 389.349996 -23.89886)
		(end 389.898636 -23.35022)
		(stroke
			(width 0.2)
			(type default)
		)
		(layer "In6.Cu")
	)
	(gr_line
		(start 388.801356 -21.950172)
		(end 388.801356 -23.35022)
		(stroke
			(width 0.2)
			(type default)
		)
		(layer "In6.Cu")
	)
	(gr_arc
		(start 388.801356 -19.750024)
		(mid 389.349996 -20.298664)
		(end 389.898636 -19.750024)
		(stroke
			(width 0.2)
			(type default)
		)
		(layer "In6.Cu")
	)
	(gr_line
		(start 388.801356 -18.35023)
		(end 388.801356 -19.750024)
		(stroke
			(width 0.2)
			(type default)
		)
		(layer "In6.Cu")
	)
	(gr_line
		(start 389.898636 -30.550104)
		(end 389.898636 -29.15031)
		(stroke
			(width 0.2)
			(type default)
		)
		(layer "In6.Cu")
	)
	(gr_arc
		(start 389.898636 -29.15031)
		(mid 389.350123 -28.601416)
		(end 388.801356 -29.150056)
		(stroke
			(width 0.2)
			(type default)
		)
		(layer "In6.Cu")
	)
	(gr_line
		(start 389.898636 -23.35022)
		(end 389.898636 -21.950426)
		(stroke
			(width 0.2)
			(type default)
		)
		(layer "In6.Cu")
	)
	(gr_arc
		(start 389.898636 -21.950426)
		(mid 389.350123 -21.401532)
		(end 388.801356 -21.950172)
		(stroke
			(width 0.2)
			(type default)
		)
		(layer "In6.Cu")
	)
	(gr_line
		(start 389.898636 -19.750024)
		(end 389.898636 -18.350484)
		(stroke
			(width 0.2)
			(type default)
		)
		(layer "In6.Cu")
	)
	(gr_arc
		(start 389.898636 -18.350484)
		(mid 389.350123 -17.80159)
		(end 388.801356 -18.35023)
		(stroke
			(width 0.2)
			(type default)
		)
		(layer "In6.Cu")
	)
	(gr_arc
		(start 394.999972 -14.99997)
		(mid 395.707077 -14.707077)
		(end 395.99997 -13.999972)
		(stroke
			(width 2.54)
			(type default)
		)
		(layer "In6.Cu")
	)
	(gr_line
		(start 395.99997 -13.999972)
		(end 395.99997 -0.999998)
		(stroke
			(width 2.54)
			(type default)
		)
		(layer "In6.Cu")
	)
	(gr_line
		(start 396.367 -50.1396)
		(end 406.141682 -40.364918)
		(stroke
			(width 0.381)
			(type default)
		)
		(layer "In6.Cu")
	)
	(gr_arc
		(start 396.999968 0)
		(mid 396.292883 -0.292904)
		(end 395.99997 -0.999998)
		(stroke
			(width 2.54)
			(type default)
		)
		(layer "In6.Cu")
	)
	(gr_line
		(start 396.999968 0)
		(end 490.450124 0)
		(stroke
			(width 2.54)
			(type default)
		)
		(layer "In6.Cu")
	)
	(gr_line
		(start 398.199864 -286.490918)
		(end 401.560284 -283.130498)
		(stroke
			(width 0.381)
			(type default)
		)
		(layer "In6.Cu")
	)
	(gr_line
		(start 401.560284 -283.130498)
		(end 413.743394 -283.130498)
		(stroke
			(width 0.381)
			(type default)
		)
		(layer "In6.Cu")
	)
	(gr_line
		(start 402.124926 -163.935918)
		(end 371.263926 -163.935918)
		(stroke
			(width 0.381)
			(type default)
		)
		(layer "In6.Cu")
	)
	(gr_line
		(start 403.267926 -235.871766)
		(end 403.267926 -165.078918)
		(stroke
			(width 0.381)
			(type default)
		)
		(layer "In6.Cu")
	)
	(gr_line
		(start 403.267926 -165.078918)
		(end 402.124926 -163.935918)
		(stroke
			(width 0.381)
			(type default)
		)
		(layer "In6.Cu")
	)
	(gr_line
		(start 403.638258 -71.660258)
		(end 342.877648 -71.660258)
		(stroke
			(width 0.381)
			(type default)
		)
		(layer "In6.Cu")
	)
	(gr_line
		(start 406.141682 -40.364918)
		(end 473.130118 -40.364918)
		(stroke
			(width 0.381)
			(type default)
		)
		(layer "In6.Cu")
	)
	(gr_line
		(start 408.379676 -129.68732)
		(end 408.379676 -76.401676)
		(stroke
			(width 0.381)
			(type default)
		)
		(layer "In6.Cu")
	)
	(gr_line
		(start 408.379676 -76.401676)
		(end 403.638258 -71.660258)
		(stroke
			(width 0.381)
			(type default)
		)
		(layer "In6.Cu")
	)
	(gr_line
		(start 408.97683 -130.284474)
		(end 408.379676 -129.68732)
		(stroke
			(width 0.381)
			(type default)
		)
		(layer "In6.Cu")
	)
	(gr_line
		(start 410.635958 -243.239798)
		(end 403.267926 -235.871766)
		(stroke
			(width 0.381)
			(type default)
		)
		(layer "In6.Cu")
	)
	(gr_line
		(start 413.743394 -283.130498)
		(end 417.103814 -286.490918)
		(stroke
			(width 0.381)
			(type default)
		)
		(layer "In6.Cu")
	)
	(gr_arc
		(start 414.258252 -274.511262)
		(mid 414.639125 -274.892516)
		(end 415.020252 -274.511516)
		(stroke
			(width 0.2)
			(type default)
		)
		(layer "In6.Cu")
	)
	(gr_line
		(start 414.258252 -273.368516)
		(end 414.258252 -274.511262)
		(stroke
			(width 0.2)
			(type default)
		)
		(layer "In6.Cu")
	)
	(gr_arc
		(start 414.258252 -159.511238)
		(mid 414.639125 -159.892492)
		(end 415.020252 -159.511492)
		(stroke
			(width 0.2)
			(type default)
		)
		(layer "In6.Cu")
	)
	(gr_line
		(start 414.258252 -158.368492)
		(end 414.258252 -159.511238)
		(stroke
			(width 0.2)
			(type default)
		)
		(layer "In6.Cu")
	)
	(gr_arc
		(start 414.258252 -44.511214)
		(mid 414.639125 -44.892468)
		(end 415.020252 -44.511468)
		(stroke
			(width 0.2)
			(type default)
		)
		(layer "In6.Cu")
	)
	(gr_line
		(start 414.258252 -43.368468)
		(end 414.258252 -44.511214)
		(stroke
			(width 0.2)
			(type default)
		)
		(layer "In6.Cu")
	)
	(gr_line
		(start 415.020252 -274.511516)
		(end 415.020252 -273.368516)
		(stroke
			(width 0.2)
			(type default)
		)
		(layer "In6.Cu")
	)
	(gr_arc
		(start 415.020252 -273.368516)
		(mid 414.639252 -272.987516)
		(end 414.258252 -273.368516)
		(stroke
			(width 0.2)
			(type default)
		)
		(layer "In6.Cu")
	)
	(gr_line
		(start 415.020252 -159.511492)
		(end 415.020252 -158.368492)
		(stroke
			(width 0.2)
			(type default)
		)
		(layer "In6.Cu")
	)
	(gr_arc
		(start 415.020252 -158.368492)
		(mid 414.639252 -157.987492)
		(end 414.258252 -158.368492)
		(stroke
			(width 0.2)
			(type default)
		)
		(layer "In6.Cu")
	)
	(gr_line
		(start 415.020252 -44.511468)
		(end 415.020252 -43.368468)
		(stroke
			(width 0.2)
			(type default)
		)
		(layer "In6.Cu")
	)
	(gr_arc
		(start 415.020252 -43.368468)
		(mid 414.639252 -42.987468)
		(end 414.258252 -43.368468)
		(stroke
			(width 0.2)
			(type default)
		)
		(layer "In6.Cu")
	)
	(gr_line
		(start 417.103814 -286.490918)
		(end 470.662 -286.490918)
		(stroke
			(width 0.381)
			(type default)
		)
		(layer "In6.Cu")
	)
	(gr_arc
		(start 419.008052 -278.321516)
		(mid 419.389052 -278.702516)
		(end 419.770052 -278.321516)
		(stroke
			(width 0.2)
			(type default)
		)
		(layer "In6.Cu")
	)
	(gr_line
		(start 419.008052 -277.178516)
		(end 419.008052 -278.321516)
		(stroke
			(width 0.2)
			(type default)
		)
		(layer "In6.Cu")
	)
	(gr_arc
		(start 419.008052 -163.321492)
		(mid 419.389052 -163.702492)
		(end 419.770052 -163.321492)
		(stroke
			(width 0.2)
			(type default)
		)
		(layer "In6.Cu")
	)
	(gr_line
		(start 419.008052 -162.178492)
		(end 419.008052 -163.321492)
		(stroke
			(width 0.2)
			(type default)
		)
		(layer "In6.Cu")
	)
	(gr_arc
		(start 419.008052 -48.321468)
		(mid 419.389052 -48.702468)
		(end 419.770052 -48.321468)
		(stroke
			(width 0.2)
			(type default)
		)
		(layer "In6.Cu")
	)
	(gr_line
		(start 419.008052 -47.178468)
		(end 419.008052 -48.321468)
		(stroke
			(width 0.2)
			(type default)
		)
		(layer "In6.Cu")
	)
	(gr_line
		(start 419.770052 -278.321516)
		(end 419.770052 -277.17877)
		(stroke
			(width 0.2)
			(type default)
		)
		(layer "In6.Cu")
	)
	(gr_arc
		(start 419.770052 -277.17877)
		(mid 419.389179 -276.797516)
		(end 419.008052 -277.178516)
		(stroke
			(width 0.2)
			(type default)
		)
		(layer "In6.Cu")
	)
	(gr_line
		(start 419.770052 -163.321492)
		(end 419.770052 -162.178746)
		(stroke
			(width 0.2)
			(type default)
		)
		(layer "In6.Cu")
	)
	(gr_arc
		(start 419.770052 -162.178746)
		(mid 419.389179 -161.797492)
		(end 419.008052 -162.178492)
		(stroke
			(width 0.2)
			(type default)
		)
		(layer "In6.Cu")
	)
	(gr_line
		(start 419.770052 -48.321468)
		(end 419.770052 -47.178722)
		(stroke
			(width 0.2)
			(type default)
		)
		(layer "In6.Cu")
	)
	(gr_arc
		(start 419.770052 -47.178722)
		(mid 419.389179 -46.797468)
		(end 419.008052 -47.178468)
		(stroke
			(width 0.2)
			(type default)
		)
		(layer "In6.Cu")
	)
	(gr_line
		(start 430.928526 -130.284474)
		(end 408.97683 -130.284474)
		(stroke
			(width 0.381)
			(type default)
		)
		(layer "In6.Cu")
	)
	(gr_line
		(start 432.350926 -188.790326)
		(end 432.350926 -131.706874)
		(stroke
			(width 0.381)
			(type default)
		)
		(layer "In6.Cu")
	)
	(gr_line
		(start 432.350926 -131.706874)
		(end 430.928526 -130.284474)
		(stroke
			(width 0.381)
			(type default)
		)
		(layer "In6.Cu")
	)
	(gr_line
		(start 434.467 -190.9064)
		(end 432.350926 -188.790326)
		(stroke
			(width 0.381)
			(type default)
		)
		(layer "In6.Cu")
	)
	(gr_arc
		(start 437.8579 -163.321492)
		(mid 438.2389 -163.702492)
		(end 438.6199 -163.321492)
		(stroke
			(width 0.2)
			(type default)
		)
		(layer "In6.Cu")
	)
	(gr_line
		(start 437.8579 -162.178492)
		(end 437.8579 -163.321492)
		(stroke
			(width 0.2)
			(type default)
		)
		(layer "In6.Cu")
	)
	(gr_line
		(start 438.6199 -163.321492)
		(end 438.6199 -162.178746)
		(stroke
			(width 0.2)
			(type default)
		)
		(layer "In6.Cu")
	)
	(gr_arc
		(start 438.6199 -162.178746)
		(mid 438.239027 -161.797492)
		(end 437.8579 -162.178492)
		(stroke
			(width 0.2)
			(type default)
		)
		(layer "In6.Cu")
	)
	(gr_arc
		(start 439.4581 -159.511238)
		(mid 439.838973 -159.892492)
		(end 440.2201 -159.511492)
		(stroke
			(width 0.2)
			(type default)
		)
		(layer "In6.Cu")
	)
	(gr_line
		(start 439.4581 -158.368492)
		(end 439.4581 -159.511238)
		(stroke
			(width 0.2)
			(type default)
		)
		(layer "In6.Cu")
	)
	(gr_line
		(start 440.2201 -159.511492)
		(end 440.2201 -158.368492)
		(stroke
			(width 0.2)
			(type default)
		)
		(layer "In6.Cu")
	)
	(gr_arc
		(start 440.2201 -158.368492)
		(mid 439.8391 -157.987492)
		(end 439.4581 -158.368492)
		(stroke
			(width 0.2)
			(type default)
		)
		(layer "In6.Cu")
	)
	(gr_arc
		(start 445.8081 -274.511262)
		(mid 446.188973 -274.892516)
		(end 446.5701 -274.511516)
		(stroke
			(width 0.2)
			(type default)
		)
		(layer "In6.Cu")
	)
	(gr_line
		(start 445.8081 -273.368516)
		(end 445.8081 -274.511262)
		(stroke
			(width 0.2)
			(type default)
		)
		(layer "In6.Cu")
	)
	(gr_arc
		(start 445.8081 -44.511214)
		(mid 446.188973 -44.892468)
		(end 446.5701 -44.511468)
		(stroke
			(width 0.2)
			(type default)
		)
		(layer "In6.Cu")
	)
	(gr_line
		(start 445.8081 -43.368468)
		(end 445.8081 -44.511214)
		(stroke
			(width 0.2)
			(type default)
		)
		(layer "In6.Cu")
	)
	(gr_line
		(start 446.5701 -274.511516)
		(end 446.5701 -273.368516)
		(stroke
			(width 0.2)
			(type default)
		)
		(layer "In6.Cu")
	)
	(gr_arc
		(start 446.5701 -273.368516)
		(mid 446.1891 -272.987516)
		(end 445.8081 -273.368516)
		(stroke
			(width 0.2)
			(type default)
		)
		(layer "In6.Cu")
	)
	(gr_line
		(start 446.5701 -44.511468)
		(end 446.5701 -43.368468)
		(stroke
			(width 0.2)
			(type default)
		)
		(layer "In6.Cu")
	)
	(gr_arc
		(start 446.5701 -43.368468)
		(mid 446.1891 -42.987468)
		(end 445.8081 -43.368468)
		(stroke
			(width 0.2)
			(type default)
		)
		(layer "In6.Cu")
	)
	(gr_line
		(start 448.6148 -190.9064)
		(end 434.467 -190.9064)
		(stroke
			(width 0.381)
			(type default)
		)
		(layer "In6.Cu")
	)
	(gr_arc
		(start 450.5579 -278.321516)
		(mid 450.9389 -278.702516)
		(end 451.3199 -278.321516)
		(stroke
			(width 0.2)
			(type default)
		)
		(layer "In6.Cu")
	)
	(gr_line
		(start 450.5579 -277.178516)
		(end 450.5579 -278.321516)
		(stroke
			(width 0.2)
			(type default)
		)
		(layer "In6.Cu")
	)
	(gr_arc
		(start 450.5579 -48.321468)
		(mid 450.9389 -48.702468)
		(end 451.3199 -48.321468)
		(stroke
			(width 0.2)
			(type default)
		)
		(layer "In6.Cu")
	)
	(gr_line
		(start 450.5579 -47.178468)
		(end 450.5579 -48.321468)
		(stroke
			(width 0.2)
			(type default)
		)
		(layer "In6.Cu")
	)
	(gr_line
		(start 451.3199 -278.321516)
		(end 451.3199 -277.17877)
		(stroke
			(width 0.2)
			(type default)
		)
		(layer "In6.Cu")
	)
	(gr_arc
		(start 451.3199 -277.17877)
		(mid 450.939027 -276.797516)
		(end 450.5579 -277.178516)
		(stroke
			(width 0.2)
			(type default)
		)
		(layer "In6.Cu")
	)
	(gr_line
		(start 451.3199 -48.321468)
		(end 451.3199 -47.178722)
		(stroke
			(width 0.2)
			(type default)
		)
		(layer "In6.Cu")
	)
	(gr_arc
		(start 451.3199 -47.178722)
		(mid 450.939027 -46.797468)
		(end 450.5579 -47.178468)
		(stroke
			(width 0.2)
			(type default)
		)
		(layer "In6.Cu")
	)
	(gr_line
		(start 463.3214 -213.9442)
		(end 463.3214 -205.613)
		(stroke
			(width 0.381)
			(type default)
		)
		(layer "In6.Cu")
	)
	(gr_line
		(start 463.3214 -205.613)
		(end 448.6148 -190.9064)
		(stroke
			(width 0.381)
			(type default)
		)
		(layer "In6.Cu")
	)
	(gr_line
		(start 465.33308 -215.95588)
		(end 463.3214 -213.9442)
		(stroke
			(width 0.381)
			(type default)
		)
		(layer "In6.Cu")
	)
	(gr_line
		(start 469.265 -301.117)
		(end 318.262 -301.117)
		(stroke
			(width 0.381)
			(type default)
		)
		(layer "In6.Cu")
	)
	(gr_line
		(start 469.939878 -286.492442)
		(end 470.074498 -286.492442)
		(stroke
			(width 0.381)
			(type default)
		)
		(layer "In6.Cu")
	)
	(gr_line
		(start 470.074498 -286.492442)
		(end 470.621868 -287.039812)
		(stroke
			(width 0.381)
			(type default)
		)
		(layer "In6.Cu")
	)
	(gr_line
		(start 470.662 -299.72)
		(end 469.265 -301.117)
		(stroke
			(width 0.381)
			(type default)
		)
		(layer "In6.Cu")
	)
	(gr_line
		(start 470.662 -287.172908)
		(end 470.662 -287.038288)
		(stroke
			(width 0.381)
			(type default)
		)
		(layer "In6.Cu")
	)
	(gr_line
		(start 470.662 -287.038288)
		(end 471.20937 -286.490918)
		(stroke
			(width 0.381)
			(type default)
		)
		(layer "In6.Cu")
	)
	(gr_line
		(start 470.662 -286.490918)
		(end 470.662 -299.72)
		(stroke
			(width 0.381)
			(type default)
		)
		(layer "In6.Cu")
	)
	(gr_line
		(start 470.662 -286.490918)
		(end 475.530926 -286.490918)
		(stroke
			(width 0.381)
			(type default)
		)
		(layer "In6.Cu")
	)
	(gr_line
		(start 473.130118 -40.364918)
		(end 476.1738 -43.4086)
		(stroke
			(width 0.381)
			(type default)
		)
		(layer "In6.Cu")
	)
	(gr_line
		(start 474.452188 -243.239798)
		(end 410.635958 -243.239798)
		(stroke
			(width 0.381)
			(type default)
		)
		(layer "In6.Cu")
	)
	(gr_line
		(start 475.530926 -286.490918)
		(end 480.229926 -281.791918)
		(stroke
			(width 0.381)
			(type default)
		)
		(layer "In6.Cu")
	)
	(gr_line
		(start 475.819216 -259.532628)
		(end 475.819216 -244.606826)
		(stroke
			(width 0.381)
			(type default)
		)
		(layer "In6.Cu")
	)
	(gr_line
		(start 475.819216 -244.606826)
		(end 474.452188 -243.239798)
		(stroke
			(width 0.381)
			(type default)
		)
		(layer "In6.Cu")
	)
	(gr_line
		(start 476.1738 -47.9552)
		(end 478.8916 -50.673)
		(stroke
			(width 0.381)
			(type default)
		)
		(layer "In6.Cu")
	)
	(gr_line
		(start 476.1738 -43.4086)
		(end 476.1738 -47.9552)
		(stroke
			(width 0.381)
			(type default)
		)
		(layer "In6.Cu")
	)
	(gr_arc
		(start 477.358202 -274.511262)
		(mid 477.739075 -274.892516)
		(end 478.120202 -274.511516)
		(stroke
			(width 0.2)
			(type default)
		)
		(layer "In6.Cu")
	)
	(gr_line
		(start 477.358202 -273.368516)
		(end 477.358202 -274.511262)
		(stroke
			(width 0.2)
			(type default)
		)
		(layer "In6.Cu")
	)
	(gr_arc
		(start 477.358202 -159.511238)
		(mid 477.739075 -159.892492)
		(end 478.120202 -159.511492)
		(stroke
			(width 0.2)
			(type default)
		)
		(layer "In6.Cu")
	)
	(gr_line
		(start 477.358202 -158.368492)
		(end 477.358202 -159.511238)
		(stroke
			(width 0.2)
			(type default)
		)
		(layer "In6.Cu")
	)
	(gr_arc
		(start 477.358202 -44.511214)
		(mid 477.739075 -44.892468)
		(end 478.120202 -44.511468)
		(stroke
			(width 0.2)
			(type default)
		)
		(layer "In6.Cu")
	)
	(gr_line
		(start 477.358202 -43.368468)
		(end 477.358202 -44.511214)
		(stroke
			(width 0.2)
			(type default)
		)
		(layer "In6.Cu")
	)
	(gr_line
		(start 478.120202 -274.511516)
		(end 478.120202 -273.368516)
		(stroke
			(width 0.2)
			(type default)
		)
		(layer "In6.Cu")
	)
	(gr_arc
		(start 478.120202 -273.368516)
		(mid 477.739202 -272.987516)
		(end 477.358202 -273.368516)
		(stroke
			(width 0.2)
			(type default)
		)
		(layer "In6.Cu")
	)
	(gr_line
		(start 478.120202 -159.511492)
		(end 478.120202 -158.368492)
		(stroke
			(width 0.2)
			(type default)
		)
		(layer "In6.Cu")
	)
	(gr_arc
		(start 478.120202 -158.368492)
		(mid 477.739202 -157.987492)
		(end 477.358202 -158.368492)
		(stroke
			(width 0.2)
			(type default)
		)
		(layer "In6.Cu")
	)
	(gr_line
		(start 478.120202 -44.511468)
		(end 478.120202 -43.368468)
		(stroke
			(width 0.2)
			(type default)
		)
		(layer "In6.Cu")
	)
	(gr_arc
		(start 478.120202 -43.368468)
		(mid 477.739202 -42.987468)
		(end 477.358202 -43.368468)
		(stroke
			(width 0.2)
			(type default)
		)
		(layer "In6.Cu")
	)
	(gr_line
		(start 478.8916 -109.9566)
		(end 485.817926 -116.882926)
		(stroke
			(width 0.381)
			(type default)
		)
		(layer "In6.Cu")
	)
	(gr_line
		(start 478.8916 -50.673)
		(end 478.8916 -109.9566)
		(stroke
			(width 0.381)
			(type default)
		)
		(layer "In6.Cu")
	)
	(gr_line
		(start 480.229926 -281.791918)
		(end 480.229926 -263.943338)
		(stroke
			(width 0.381)
			(type default)
		)
		(layer "In6.Cu")
	)
	(gr_line
		(start 480.229926 -263.943338)
		(end 475.819216 -259.532628)
		(stroke
			(width 0.381)
			(type default)
		)
		(layer "In6.Cu")
	)
	(gr_arc
		(start 482.108002 -278.321516)
		(mid 482.489002 -278.702516)
		(end 482.870002 -278.321516)
		(stroke
			(width 0.2)
			(type default)
		)
		(layer "In6.Cu")
	)
	(gr_line
		(start 482.108002 -277.178516)
		(end 482.108002 -278.321516)
		(stroke
			(width 0.2)
			(type default)
		)
		(layer "In6.Cu")
	)
	(gr_arc
		(start 482.108002 -163.321492)
		(mid 482.489002 -163.702492)
		(end 482.870002 -163.321492)
		(stroke
			(width 0.2)
			(type default)
		)
		(layer "In6.Cu")
	)
	(gr_line
		(start 482.108002 -162.178492)
		(end 482.108002 -163.321492)
		(stroke
			(width 0.2)
			(type default)
		)
		(layer "In6.Cu")
	)
	(gr_arc
		(start 482.108002 -48.321468)
		(mid 482.489002 -48.702468)
		(end 482.870002 -48.321468)
		(stroke
			(width 0.2)
			(type default)
		)
		(layer "In6.Cu")
	)
	(gr_line
		(start 482.108002 -47.178468)
		(end 482.108002 -48.321468)
		(stroke
			(width 0.2)
			(type default)
		)
		(layer "In6.Cu")
	)
	(gr_line
		(start 482.870002 -278.321516)
		(end 482.870002 -277.17877)
		(stroke
			(width 0.2)
			(type default)
		)
		(layer "In6.Cu")
	)
	(gr_arc
		(start 482.870002 -277.17877)
		(mid 482.489129 -276.797516)
		(end 482.108002 -277.178516)
		(stroke
			(width 0.2)
			(type default)
		)
		(layer "In6.Cu")
	)
	(gr_line
		(start 482.870002 -163.321492)
		(end 482.870002 -162.178746)
		(stroke
			(width 0.2)
			(type default)
		)
		(layer "In6.Cu")
	)
	(gr_arc
		(start 482.870002 -162.178746)
		(mid 482.489129 -161.797492)
		(end 482.108002 -162.178492)
		(stroke
			(width 0.2)
			(type default)
		)
		(layer "In6.Cu")
	)
	(gr_line
		(start 482.870002 -48.321468)
		(end 482.870002 -47.178722)
		(stroke
			(width 0.2)
			(type default)
		)
		(layer "In6.Cu")
	)
	(gr_arc
		(start 482.870002 -47.178722)
		(mid 482.489129 -46.797468)
		(end 482.108002 -47.178468)
		(stroke
			(width 0.2)
			(type default)
		)
		(layer "In6.Cu")
	)
	(gr_line
		(start 485.17302 -215.95588)
		(end 465.33308 -215.95588)
		(stroke
			(width 0.381)
			(type default)
		)
		(layer "In6.Cu")
	)
	(gr_circle
		(center 485.817672 -215.310974)
		(end 485.817926 -215.310974)
		(stroke
			(width 0.381)
			(type default)
		)
		(fill no)
		(layer "In6.Cu")
	)
	(gr_line
		(start 485.817926 -215.310974)
		(end 485.17302 -215.95588)
		(stroke
			(width 0.381)
			(type default)
		)
		(layer "In6.Cu")
	)
	(gr_line
		(start 485.817926 -179.07889)
		(end 485.817926 -215.310974)
		(stroke
			(width 0.381)
			(type default)
		)
		(layer "In6.Cu")
	)
	(gr_line
		(start 485.817926 -116.882926)
		(end 485.817926 -215.310974)
		(stroke
			(width 0.381)
			(type default)
		)
		(layer "In6.Cu")
	)
	(gr_line
		(start 490.450124 -349.199962)
		(end 296.69994 -349.199962)
		(stroke
			(width 2.54)
			(type default)
		)
		(layer "In6.Cu")
	)
	(gr_arc
		(start 490.450124 -349.199962)
		(mid 491.157201 -348.907059)
		(end 491.450122 -348.199964)
		(stroke
			(width 2.54)
			(type default)
		)
		(layer "In6.Cu")
	)
	(gr_arc
		(start 491.450122 -0.999998)
		(mid 491.15723 -0.292885)
		(end 490.450124 0)
		(stroke
			(width 2.54)
			(type default)
		)
		(layer "In6.Cu")
	)
	(gr_line
		(start 491.450122 -0.999998)
		(end 491.450122 -348.199964)
		(stroke
			(width 2.54)
			(type default)
		)
		(layer "In6.Cu")
	)
	(gr_line
		(start 32.508952 -278.016716)
		(end 32.508952 -278.321516)
		(stroke
			(width 0.0508)
			(type default)
		)
		(layer "In7.Cu")
	)
	(gr_arc
		(start 32.508952 -277.483316)
		(mid 32.53871 -277.555158)
		(end 32.610552 -277.584916)
		(stroke
			(width 0.0508)
			(type default)
		)
		(layer "In7.Cu")
	)
	(gr_line
		(start 32.508952 -277.178516)
		(end 32.508952 -277.483316)
		(stroke
			(width 0.0508)
			(type default)
		)
		(layer "In7.Cu")
	)
	(gr_line
		(start 32.508952 -163.016692)
		(end 32.508952 -163.321492)
		(stroke
			(width 0.0508)
			(type default)
		)
		(layer "In7.Cu")
	)
	(gr_arc
		(start 32.508952 -162.483292)
		(mid 32.53871 -162.555134)
		(end 32.610552 -162.584892)
		(stroke
			(width 0.0508)
			(type default)
		)
		(layer "In7.Cu")
	)
	(gr_line
		(start 32.508952 -162.178492)
		(end 32.508952 -162.483292)
		(stroke
			(width 0.0508)
			(type default)
		)
		(layer "In7.Cu")
	)
	(gr_line
		(start 32.508952 -48.016668)
		(end 32.508952 -48.321468)
		(stroke
			(width 0.0508)
			(type default)
		)
		(layer "In7.Cu")
	)
	(gr_arc
		(start 32.508952 -47.483268)
		(mid 32.538696 -47.555148)
		(end 32.610552 -47.584868)
		(stroke
			(width 0.0508)
			(type default)
		)
		(layer "In7.Cu")
	)
	(gr_line
		(start 32.508952 -47.178468)
		(end 32.508952 -47.483268)
		(stroke
			(width 0.0508)
			(type default)
		)
		(layer "In7.Cu")
	)
	(gr_arc
		(start 32.610552 -277.915116)
		(mid 32.53871 -277.944874)
		(end 32.508952 -278.016716)
		(stroke
			(width 0.0508)
			(type default)
		)
		(layer "In7.Cu")
	)
	(gr_arc
		(start 32.610552 -162.915092)
		(mid 32.53871 -162.94485)
		(end 32.508952 -163.016692)
		(stroke
			(width 0.0508)
			(type default)
		)
		(layer "In7.Cu")
	)
	(gr_arc
		(start 32.610552 -47.915068)
		(mid 32.53871 -47.944826)
		(end 32.508952 -48.016668)
		(stroke
			(width 0.0508)
			(type default)
		)
		(layer "In7.Cu")
	)
	(gr_line
		(start 33.334706 -47.584868)
		(end 33.346898 -47.588932)
		(stroke
			(width 0.0508)
			(type default)
		)
		(layer "In7.Cu")
	)
	(gr_line
		(start 33.544256 -277.657306)
		(end 33.561528 -277.661116)
		(stroke
			(width 0.0508)
			(type default)
		)
		(layer "In7.Cu")
	)
	(gr_line
		(start 33.561528 -277.661116)
		(end 33.576768 -277.670768)
		(stroke
			(width 0.0508)
			(type default)
		)
		(layer "In7.Cu")
	)
	(gr_line
		(start 33.745678 -162.584892)
		(end 33.786064 -162.607752)
		(stroke
			(width 0.0508)
			(type default)
		)
		(layer "In7.Cu")
	)
	(gr_line
		(start 35.952684 -279.183592)
		(end 35.980878 -279.201626)
		(stroke
			(width 0.0508)
			(type default)
		)
		(layer "In7.Cu")
	)
	(gr_line
		(start 35.980878 -279.201626)
		(end 35.998912 -279.22982)
		(stroke
			(width 0.0508)
			(type default)
		)
		(layer "In7.Cu")
	)
	(gr_line
		(start 36.488878 -164.137848)
		(end 36.524946 -164.158168)
		(stroke
			(width 0.0508)
			(type default)
		)
		(layer "In7.Cu")
	)
	(gr_line
		(start 36.524946 -164.158168)
		(end 36.547298 -164.193474)
		(stroke
			(width 0.0508)
			(type default)
		)
		(layer "In7.Cu")
	)
	(gr_line
		(start 39.27221 -284.982412)
		(end 39.290244 -285.010606)
		(stroke
			(width 0.0508)
			(type default)
		)
		(layer "In7.Cu")
	)
	(gr_line
		(start 39.290244 -285.010606)
		(end 39.318438 -285.02864)
		(stroke
			(width 0.0508)
			(type default)
		)
		(layer "In7.Cu")
	)
	(gr_line
		(start 43.869864 -287.92805)
		(end 43.884342 -287.937448)
		(stroke
			(width 0.0508)
			(type default)
		)
		(layer "In7.Cu")
	)
	(gr_line
		(start 43.884342 -287.937448)
		(end 43.90136 -287.941004)
		(stroke
			(width 0.0508)
			(type default)
		)
		(layer "In7.Cu")
	)
	(gr_line
		(start 62.889892 -206.158338)
		(end 62.907926 -206.186532)
		(stroke
			(width 0.0508)
			(type default)
		)
		(layer "In7.Cu")
	)
	(gr_line
		(start 62.907926 -206.186532)
		(end 62.935612 -206.204058)
		(stroke
			(width 0.0508)
			(type default)
		)
		(layer "In7.Cu")
	)
	(gr_line
		(start 64.0588 -278.016716)
		(end 64.0588 -278.321516)
		(stroke
			(width 0.0508)
			(type default)
		)
		(layer "In7.Cu")
	)
	(gr_arc
		(start 64.0588 -277.483316)
		(mid 64.088558 -277.555158)
		(end 64.1604 -277.584916)
		(stroke
			(width 0.0508)
			(type default)
		)
		(layer "In7.Cu")
	)
	(gr_line
		(start 64.0588 -277.178516)
		(end 64.0588 -277.483316)
		(stroke
			(width 0.0508)
			(type default)
		)
		(layer "In7.Cu")
	)
	(gr_line
		(start 64.0588 -163.016692)
		(end 64.0588 -163.321492)
		(stroke
			(width 0.0508)
			(type default)
		)
		(layer "In7.Cu")
	)
	(gr_arc
		(start 64.0588 -162.483292)
		(mid 64.088558 -162.555134)
		(end 64.1604 -162.584892)
		(stroke
			(width 0.0508)
			(type default)
		)
		(layer "In7.Cu")
	)
	(gr_line
		(start 64.0588 -162.178492)
		(end 64.0588 -162.483292)
		(stroke
			(width 0.0508)
			(type default)
		)
		(layer "In7.Cu")
	)
	(gr_line
		(start 64.0588 -48.016668)
		(end 64.0588 -48.321468)
		(stroke
			(width 0.0508)
			(type default)
		)
		(layer "In7.Cu")
	)
	(gr_arc
		(start 64.0588 -47.483268)
		(mid 64.088547 -47.555131)
		(end 64.1604 -47.584868)
		(stroke
			(width 0.0508)
			(type default)
		)
		(layer "In7.Cu")
	)
	(gr_line
		(start 64.0588 -47.178468)
		(end 64.0588 -47.483268)
		(stroke
			(width 0.0508)
			(type default)
		)
		(layer "In7.Cu")
	)
	(gr_arc
		(start 64.1604 -277.915116)
		(mid 64.088558 -277.944874)
		(end 64.0588 -278.016716)
		(stroke
			(width 0.0508)
			(type default)
		)
		(layer "In7.Cu")
	)
	(gr_arc
		(start 64.1604 -162.915092)
		(mid 64.088558 -162.94485)
		(end 64.0588 -163.016692)
		(stroke
			(width 0.0508)
			(type default)
		)
		(layer "In7.Cu")
	)
	(gr_arc
		(start 64.1604 -47.915068)
		(mid 64.088558 -47.944826)
		(end 64.0588 -48.016668)
		(stroke
			(width 0.0508)
			(type default)
		)
		(layer "In7.Cu")
	)
	(gr_line
		(start 65.088008 -162.584892)
		(end 65.135506 -162.615118)
		(stroke
			(width 0.0508)
			(type default)
		)
		(layer "In7.Cu")
	)
	(gr_line
		(start 65.14211 -47.584868)
		(end 65.170812 -47.598076)
		(stroke
			(width 0.0508)
			(type default)
		)
		(layer "In7.Cu")
	)
	(gr_line
		(start 66.237358 -163.31692)
		(end 66.265552 -163.334954)
		(stroke
			(width 0.0508)
			(type default)
		)
		(layer "In7.Cu")
	)
	(gr_line
		(start 66.265552 -163.334954)
		(end 66.283586 -163.363148)
		(stroke
			(width 0.0508)
			(type default)
		)
		(layer "In7.Cu")
	)
	(gr_line
		(start 68.943474 -167.536114)
		(end 68.95338 -167.551862)
		(stroke
			(width 0.0508)
			(type default)
		)
		(layer "In7.Cu")
	)
	(gr_line
		(start 68.95338 -167.551862)
		(end 68.95719 -167.569642)
		(stroke
			(width 0.0508)
			(type default)
		)
		(layer "In7.Cu")
	)
	(gr_line
		(start 73.963784 -279.45334)
		(end 73.983596 -279.457404)
		(stroke
			(width 0.0508)
			(type default)
		)
		(layer "In7.Cu")
	)
	(gr_line
		(start 73.983596 -279.457404)
		(end 74.001376 -279.468834)
		(stroke
			(width 0.0508)
			(type default)
		)
		(layer "In7.Cu")
	)
	(gr_line
		(start 74.151998 -61.198252)
		(end 74.154792 -61.199014)
		(stroke
			(width 0.0508)
			(type default)
		)
		(layer "In7.Cu")
	)
	(gr_line
		(start 74.154792 -61.199014)
		(end 74.156824 -61.200538)
		(stroke
			(width 0.0508)
			(type default)
		)
		(layer "In7.Cu")
	)
	(gr_line
		(start 76.111354 -200.756012)
		(end 76.115164 -200.773792)
		(stroke
			(width 0.0508)
			(type default)
		)
		(layer "In7.Cu")
	)
	(gr_line
		(start 76.115164 -200.773792)
		(end 76.124816 -200.788778)
		(stroke
			(width 0.0508)
			(type default)
		)
		(layer "In7.Cu")
	)
	(gr_line
		(start 88.702388 -220.533214)
		(end 88.720676 -220.56217)
		(stroke
			(width 0.0508)
			(type default)
		)
		(layer "In7.Cu")
	)
	(gr_line
		(start 88.720676 -220.56217)
		(end 88.75014 -220.580966)
		(stroke
			(width 0.0508)
			(type default)
		)
		(layer "In7.Cu")
	)
	(gr_line
		(start 92.489274 -225.052128)
		(end 92.506546 -225.063304)
		(stroke
			(width 0.0508)
			(type default)
		)
		(layer "In7.Cu")
	)
	(gr_line
		(start 92.506546 -225.063304)
		(end 92.526866 -225.067368)
		(stroke
			(width 0.0508)
			(type default)
		)
		(layer "In7.Cu")
	)
	(gr_line
		(start 93.285564 -223.474026)
		(end 93.302836 -223.485202)
		(stroke
			(width 0.0508)
			(type default)
		)
		(layer "In7.Cu")
	)
	(gr_line
		(start 93.302836 -223.485202)
		(end 93.323156 -223.489266)
		(stroke
			(width 0.0508)
			(type default)
		)
		(layer "In7.Cu")
	)
	(gr_line
		(start 95.608902 -278.016716)
		(end 95.608902 -278.321516)
		(stroke
			(width 0.0508)
			(type default)
		)
		(layer "In7.Cu")
	)
	(gr_arc
		(start 95.608902 -277.483316)
		(mid 95.63866 -277.555158)
		(end 95.710502 -277.584916)
		(stroke
			(width 0.0508)
			(type default)
		)
		(layer "In7.Cu")
	)
	(gr_line
		(start 95.608902 -277.178516)
		(end 95.608902 -277.483316)
		(stroke
			(width 0.0508)
			(type default)
		)
		(layer "In7.Cu")
	)
	(gr_line
		(start 95.608902 -163.016692)
		(end 95.608902 -163.321492)
		(stroke
			(width 0.0508)
			(type default)
		)
		(layer "In7.Cu")
	)
	(gr_arc
		(start 95.608902 -162.483292)
		(mid 95.638657 -162.555139)
		(end 95.710502 -162.584892)
		(stroke
			(width 0.0508)
			(type default)
		)
		(layer "In7.Cu")
	)
	(gr_line
		(start 95.608902 -162.178492)
		(end 95.608902 -162.483292)
		(stroke
			(width 0.0508)
			(type default)
		)
		(layer "In7.Cu")
	)
	(gr_line
		(start 95.608902 -48.016668)
		(end 95.608902 -48.321468)
		(stroke
			(width 0.0508)
			(type default)
		)
		(layer "In7.Cu")
	)
	(gr_arc
		(start 95.608902 -47.483268)
		(mid 95.638649 -47.55513)
		(end 95.710502 -47.584868)
		(stroke
			(width 0.0508)
			(type default)
		)
		(layer "In7.Cu")
	)
	(gr_line
		(start 95.608902 -47.178468)
		(end 95.608902 -47.483268)
		(stroke
			(width 0.0508)
			(type default)
		)
		(layer "In7.Cu")
	)
	(gr_arc
		(start 95.710502 -277.915116)
		(mid 95.638664 -277.944874)
		(end 95.608902 -278.016716)
		(stroke
			(width 0.0508)
			(type default)
		)
		(layer "In7.Cu")
	)
	(gr_arc
		(start 95.710502 -162.915092)
		(mid 95.63866 -162.94485)
		(end 95.608902 -163.016692)
		(stroke
			(width 0.0508)
			(type default)
		)
		(layer "In7.Cu")
	)
	(gr_arc
		(start 95.710502 -47.915068)
		(mid 95.63866 -47.944826)
		(end 95.608902 -48.016668)
		(stroke
			(width 0.0508)
			(type default)
		)
		(layer "In7.Cu")
	)
	(gr_line
		(start 96.64319 -47.584868)
		(end 96.683576 -47.607728)
		(stroke
			(width 0.0508)
			(type default)
		)
		(layer "In7.Cu")
	)
	(gr_line
		(start 97.340166 -162.743642)
		(end 97.357184 -162.747198)
		(stroke
			(width 0.0508)
			(type default)
		)
		(layer "In7.Cu")
	)
	(gr_line
		(start 97.357184 -162.747198)
		(end 97.371662 -162.756596)
		(stroke
			(width 0.0508)
			(type default)
		)
		(layer "In7.Cu")
	)
	(gr_line
		(start 97.67316 -48.168306)
		(end 97.707958 -48.187864)
		(stroke
			(width 0.0508)
			(type default)
		)
		(layer "In7.Cu")
	)
	(gr_line
		(start 97.707958 -48.187864)
		(end 97.729802 -48.221392)
		(stroke
			(width 0.0508)
			(type default)
		)
		(layer "In7.Cu")
	)
	(gr_line
		(start 98.09226 -163.21532)
		(end 98.121724 -163.234116)
		(stroke
			(width 0.0508)
			(type default)
		)
		(layer "In7.Cu")
	)
	(gr_line
		(start 98.121724 -163.234116)
		(end 98.140266 -163.263326)
		(stroke
			(width 0.0508)
			(type default)
		)
		(layer "In7.Cu")
	)
	(gr_line
		(start 101.216206 -168.106598)
		(end 101.22535 -168.121076)
		(stroke
			(width 0.0508)
			(type default)
		)
		(layer "In7.Cu")
	)
	(gr_line
		(start 101.22535 -168.121076)
		(end 101.22916 -168.13784)
		(stroke
			(width 0.0508)
			(type default)
		)
		(layer "In7.Cu")
	)
	(gr_line
		(start 105.070402 -300.039532)
		(end 105.086912 -300.050454)
		(stroke
			(width 0.0508)
			(type default)
		)
		(layer "In7.Cu")
	)
	(gr_line
		(start 105.086912 -300.050454)
		(end 105.10647 -300.054772)
		(stroke
			(width 0.0508)
			(type default)
		)
		(layer "In7.Cu")
	)
	(gr_line
		(start 111.799116 -217.484452)
		(end 111.814864 -217.555318)
		(stroke
			(width 0.0508)
			(type default)
		)
		(layer "In7.Cu")
	)
	(gr_line
		(start 111.814864 -217.555318)
		(end 111.869728 -217.601546)
		(stroke
			(width 0.0508)
			(type default)
		)
		(layer "In7.Cu")
	)
	(gr_line
		(start 117.929152 -79.929228)
		(end 117.941344 -79.948024)
		(stroke
			(width 0.0508)
			(type default)
		)
		(layer "In7.Cu")
	)
	(gr_line
		(start 117.941344 -79.948024)
		(end 117.959632 -79.961232)
		(stroke
			(width 0.0508)
			(type default)
		)
		(layer "In7.Cu")
	)
	(gr_line
		(start 118.085108 -279.477216)
		(end 118.102126 -279.480772)
		(stroke
			(width 0.0508)
			(type default)
		)
		(layer "In7.Cu")
	)
	(gr_line
		(start 118.102126 -279.480772)
		(end 118.116604 -279.49017)
		(stroke
			(width 0.0508)
			(type default)
		)
		(layer "In7.Cu")
	)
	(gr_line
		(start 121.750074 -30.129734)
		(end 121.750074 -30.550104)
		(stroke
			(width 0.0635)
			(type default)
		)
		(layer "In7.Cu")
	)
	(gr_line
		(start 121.750074 -30.129734)
		(end 121.817638 -30.06217)
		(stroke
			(width 0.0635)
			(type default)
		)
		(layer "In7.Cu")
	)
	(gr_line
		(start 121.750074 -29.59608)
		(end 121.817638 -29.663644)
		(stroke
			(width 0.0635)
			(type default)
		)
		(layer "In7.Cu")
	)
	(gr_line
		(start 121.750074 -29.150056)
		(end 121.750074 -29.59608)
		(stroke
			(width 0.0635)
			(type default)
		)
		(layer "In7.Cu")
	)
	(gr_line
		(start 123.068334 -227.040186)
		(end 123.101862 -227.06838)
		(stroke
			(width 0.0508)
			(type default)
		)
		(layer "In7.Cu")
	)
	(gr_line
		(start 123.101862 -227.06838)
		(end 123.143518 -227.077016)
		(stroke
			(width 0.0508)
			(type default)
		)
		(layer "In7.Cu")
	)
	(gr_line
		(start 123.307602 -31.231586)
		(end 123.318524 -31.248096)
		(stroke
			(width 0.0635)
			(type default)
		)
		(layer "In7.Cu")
	)
	(gr_line
		(start 123.318524 -31.248096)
		(end 123.335034 -31.259018)
		(stroke
			(width 0.0635)
			(type default)
		)
		(layer "In7.Cu")
	)
	(gr_line
		(start 127.15875 -278.016716)
		(end 127.15875 -278.321516)
		(stroke
			(width 0.0508)
			(type default)
		)
		(layer "In7.Cu")
	)
	(gr_arc
		(start 127.15875 -277.483316)
		(mid 127.188508 -277.555158)
		(end 127.26035 -277.584916)
		(stroke
			(width 0.0508)
			(type default)
		)
		(layer "In7.Cu")
	)
	(gr_line
		(start 127.15875 -277.178516)
		(end 127.15875 -277.483316)
		(stroke
			(width 0.0508)
			(type default)
		)
		(layer "In7.Cu")
	)
	(gr_line
		(start 127.15875 -163.016692)
		(end 127.15875 -163.321492)
		(stroke
			(width 0.0508)
			(type default)
		)
		(layer "In7.Cu")
	)
	(gr_arc
		(start 127.15875 -162.483292)
		(mid 127.188508 -162.555134)
		(end 127.26035 -162.584892)
		(stroke
			(width 0.0508)
			(type default)
		)
		(layer "In7.Cu")
	)
	(gr_line
		(start 127.15875 -162.178492)
		(end 127.15875 -162.483292)
		(stroke
			(width 0.0508)
			(type default)
		)
		(layer "In7.Cu")
	)
	(gr_line
		(start 127.15875 -48.016668)
		(end 127.15875 -48.321468)
		(stroke
			(width 0.0508)
			(type default)
		)
		(layer "In7.Cu")
	)
	(gr_arc
		(start 127.15875 -47.483268)
		(mid 127.188508 -47.55511)
		(end 127.26035 -47.584868)
		(stroke
			(width 0.0508)
			(type default)
		)
		(layer "In7.Cu")
	)
	(gr_line
		(start 127.15875 -47.178468)
		(end 127.15875 -47.483268)
		(stroke
			(width 0.0508)
			(type default)
		)
		(layer "In7.Cu")
	)
	(gr_arc
		(start 127.26035 -277.915116)
		(mid 127.188508 -277.944874)
		(end 127.15875 -278.016716)
		(stroke
			(width 0.0508)
			(type default)
		)
		(layer "In7.Cu")
	)
	(gr_arc
		(start 127.26035 -162.915092)
		(mid 127.188508 -162.94485)
		(end 127.15875 -163.016692)
		(stroke
			(width 0.0508)
			(type default)
		)
		(layer "In7.Cu")
	)
	(gr_arc
		(start 127.26035 -47.915068)
		(mid 127.188508 -47.944826)
		(end 127.15875 -48.016668)
		(stroke
			(width 0.0508)
			(type default)
		)
		(layer "In7.Cu")
	)
	(gr_line
		(start 127.948944 -47.584868)
		(end 127.993394 -47.611792)
		(stroke
			(width 0.0508)
			(type default)
		)
		(layer "In7.Cu")
	)
	(gr_line
		(start 128.490218 -47.914306)
		(end 128.524254 -47.935134)
		(stroke
			(width 0.0508)
			(type default)
		)
		(layer "In7.Cu")
	)
	(gr_line
		(start 128.524254 -47.935134)
		(end 128.54559 -47.969424)
		(stroke
			(width 0.0508)
			(type default)
		)
		(layer "In7.Cu")
	)
	(gr_line
		(start 128.528572 -162.666426)
		(end 128.546352 -162.67049)
		(stroke
			(width 0.0508)
			(type default)
		)
		(layer "In7.Cu")
	)
	(gr_line
		(start 128.546352 -162.67049)
		(end 128.561592 -162.680142)
		(stroke
			(width 0.0508)
			(type default)
		)
		(layer "In7.Cu")
	)
	(gr_line
		(start 129.098294 -35.075622)
		(end 129.111756 -35.084512)
		(stroke
			(width 0.0635)
			(type default)
		)
		(layer "In7.Cu")
	)
	(gr_line
		(start 129.111756 -35.084512)
		(end 129.12725 -35.087814)
		(stroke
			(width 0.0635)
			(type default)
		)
		(layer "In7.Cu")
	)
	(gr_line
		(start 129.378202 -163.200334)
		(end 129.406396 -163.218368)
		(stroke
			(width 0.0508)
			(type default)
		)
		(layer "In7.Cu")
	)
	(gr_line
		(start 129.406396 -163.218368)
		(end 129.42443 -163.246562)
		(stroke
			(width 0.0508)
			(type default)
		)
		(layer "In7.Cu")
	)
	(gr_line
		(start 135.298942 -278.65324)
		(end 135.31596 -278.656796)
		(stroke
			(width 0.0508)
			(type default)
		)
		(layer "In7.Cu")
	)
	(gr_line
		(start 135.31596 -278.656796)
		(end 135.330438 -278.666194)
		(stroke
			(width 0.0508)
			(type default)
		)
		(layer "In7.Cu")
	)
	(gr_line
		(start 135.36803 -172.57395)
		(end 135.377428 -172.588428)
		(stroke
			(width 0.0508)
			(type default)
		)
		(layer "In7.Cu")
	)
	(gr_line
		(start 135.377428 -172.588428)
		(end 135.380984 -172.605446)
		(stroke
			(width 0.0508)
			(type default)
		)
		(layer "In7.Cu")
	)
	(gr_line
		(start 136.105392 -60.82792)
		(end 136.123426 -60.85713)
		(stroke
			(width 0.0508)
			(type default)
		)
		(layer "In7.Cu")
	)
	(gr_line
		(start 136.123426 -60.85713)
		(end 136.152382 -60.875926)
		(stroke
			(width 0.0508)
			(type default)
		)
		(layer "In7.Cu")
	)
	(gr_line
		(start 142.023846 -37.828474)
		(end 142.04569 -37.833046)
		(stroke
			(width 0.0635)
			(type default)
		)
		(layer "In7.Cu")
	)
	(gr_line
		(start 142.04569 -37.833046)
		(end 142.067534 -37.828474)
		(stroke
			(width 0.0635)
			(type default)
		)
		(layer "In7.Cu")
	)
	(gr_line
		(start 142.158974 -204.69987)
		(end 142.16253 -204.716888)
		(stroke
			(width 0.0508)
			(type default)
		)
		(layer "In7.Cu")
	)
	(gr_line
		(start 142.16253 -204.716888)
		(end 142.171928 -204.731366)
		(stroke
			(width 0.0508)
			(type default)
		)
		(layer "In7.Cu")
	)
	(gr_line
		(start 143.62557 -234.957874)
		(end 143.638016 -234.960414)
		(stroke
			(width 0.0508)
			(type default)
		)
		(layer "In7.Cu")
	)
	(gr_line
		(start 143.638016 -234.960414)
		(end 143.648938 -234.96651)
		(stroke
			(width 0.0508)
			(type default)
		)
		(layer "In7.Cu")
	)
	(gr_line
		(start 144.41297 -233.37901)
		(end 144.425416 -233.38155)
		(stroke
			(width 0.0508)
			(type default)
		)
		(layer "In7.Cu")
	)
	(gr_line
		(start 144.425416 -233.38155)
		(end 144.436338 -233.387646)
		(stroke
			(width 0.0508)
			(type default)
		)
		(layer "In7.Cu")
	)
	(gr_line
		(start 145.7452 -231.513888)
		(end 145.760694 -231.51719)
		(stroke
			(width 0.0508)
			(type default)
		)
		(layer "In7.Cu")
	)
	(gr_line
		(start 145.760694 -231.51719)
		(end 145.77441 -231.525318)
		(stroke
			(width 0.0508)
			(type default)
		)
		(layer "In7.Cu")
	)
	(gr_line
		(start 149.772116 -36.190936)
		(end 149.78634 -36.187888)
		(stroke
			(width 0.0635)
			(type default)
		)
		(layer "In7.Cu")
	)
	(gr_line
		(start 149.78634 -36.187888)
		(end 149.798532 -36.180014)
		(stroke
			(width 0.0635)
			(type default)
		)
		(layer "In7.Cu")
	)
	(gr_line
		(start 156.153358 -73.471024)
		(end 156.171138 -73.482708)
		(stroke
			(width 0.0508)
			(type default)
		)
		(layer "In7.Cu")
	)
	(gr_line
		(start 156.171138 -73.482708)
		(end 156.183838 -73.499726)
		(stroke
			(width 0.0508)
			(type default)
		)
		(layer "In7.Cu")
	)
	(gr_line
		(start 158.708852 -278.016716)
		(end 158.708852 -278.321516)
		(stroke
			(width 0.0508)
			(type default)
		)
		(layer "In7.Cu")
	)
	(gr_arc
		(start 158.708852 -277.483316)
		(mid 158.73861 -277.555158)
		(end 158.810452 -277.584916)
		(stroke
			(width 0.0508)
			(type default)
		)
		(layer "In7.Cu")
	)
	(gr_line
		(start 158.708852 -277.178516)
		(end 158.708852 -277.483316)
		(stroke
			(width 0.0508)
			(type default)
		)
		(layer "In7.Cu")
	)
	(gr_line
		(start 158.708852 -163.016692)
		(end 158.708852 -163.321492)
		(stroke
			(width 0.0508)
			(type default)
		)
		(layer "In7.Cu")
	)
	(gr_arc
		(start 158.708852 -162.483292)
		(mid 158.732171 -162.547967)
		(end 158.791402 -162.58286)
		(stroke
			(width 0.0508)
			(type default)
		)
		(layer "In7.Cu")
	)
	(gr_line
		(start 158.708852 -162.178492)
		(end 158.708852 -162.483292)
		(stroke
			(width 0.0508)
			(type default)
		)
		(layer "In7.Cu")
	)
	(gr_line
		(start 158.708852 -48.016668)
		(end 158.708852 -48.321468)
		(stroke
			(width 0.0508)
			(type default)
		)
		(layer "In7.Cu")
	)
	(gr_arc
		(start 158.708852 -47.483268)
		(mid 158.738596 -47.555148)
		(end 158.810452 -47.584868)
		(stroke
			(width 0.0508)
			(type default)
		)
		(layer "In7.Cu")
	)
	(gr_line
		(start 158.708852 -47.178468)
		(end 158.708852 -47.483268)
		(stroke
			(width 0.0508)
			(type default)
		)
		(layer "In7.Cu")
	)
	(gr_arc
		(start 158.791402 -162.58286)
		(mid 158.800879 -162.584332)
		(end 158.810452 -162.584892)
		(stroke
			(width 0.0508)
			(type default)
		)
		(layer "In7.Cu")
	)
	(gr_arc
		(start 158.810452 -277.915116)
		(mid 158.738647 -277.944892)
		(end 158.708852 -278.016716)
		(stroke
			(width 0.0508)
			(type default)
		)
		(layer "In7.Cu")
	)
	(gr_arc
		(start 158.810452 -162.915092)
		(mid 158.73861 -162.94485)
		(end 158.708852 -163.016692)
		(stroke
			(width 0.0508)
			(type default)
		)
		(layer "In7.Cu")
	)
	(gr_arc
		(start 158.810452 -47.915068)
		(mid 158.73861 -47.944826)
		(end 158.708852 -48.016668)
		(stroke
			(width 0.0508)
			(type default)
		)
		(layer "In7.Cu")
	)
	(gr_line
		(start 159.962342 -47.584868)
		(end 160.002728 -47.607728)
		(stroke
			(width 0.0508)
			(type default)
		)
		(layer "In7.Cu")
	)
	(gr_line
		(start 160.057338 -277.731982)
		(end 160.074356 -277.735538)
		(stroke
			(width 0.0508)
			(type default)
		)
		(layer "In7.Cu")
	)
	(gr_line
		(start 160.074356 -277.735538)
		(end 160.088834 -277.744936)
		(stroke
			(width 0.0508)
			(type default)
		)
		(layer "In7.Cu")
	)
	(gr_line
		(start 160.342072 -162.757104)
		(end 160.359344 -162.760914)
		(stroke
			(width 0.0508)
			(type default)
		)
		(layer "In7.Cu")
	)
	(gr_line
		(start 160.359344 -162.760914)
		(end 160.374584 -162.770566)
		(stroke
			(width 0.0508)
			(type default)
		)
		(layer "In7.Cu")
	)
	(gr_line
		(start 161.050732 -48.201326)
		(end 161.07791 -48.216566)
		(stroke
			(width 0.0508)
			(type default)
		)
		(layer "In7.Cu")
	)
	(gr_line
		(start 161.07791 -48.216566)
		(end 161.095944 -48.241458)
		(stroke
			(width 0.0508)
			(type default)
		)
		(layer "In7.Cu")
	)
	(gr_line
		(start 161.960306 -163.779962)
		(end 161.98596 -163.796472)
		(stroke
			(width 0.0508)
			(type default)
		)
		(layer "In7.Cu")
	)
	(gr_line
		(start 161.98596 -163.796472)
		(end 162.002724 -163.822126)
		(stroke
			(width 0.0508)
			(type default)
		)
		(layer "In7.Cu")
	)
	(gr_line
		(start 162.179 -279.07615)
		(end 162.207194 -279.094184)
		(stroke
			(width 0.0508)
			(type default)
		)
		(layer "In7.Cu")
	)
	(gr_line
		(start 162.207194 -279.094184)
		(end 162.225228 -279.122378)
		(stroke
			(width 0.0508)
			(type default)
		)
		(layer "In7.Cu")
	)
	(gr_line
		(start 164.723826 -240.13287)
		(end 164.746178 -240.168176)
		(stroke
			(width 0.0508)
			(type default)
		)
		(layer "In7.Cu")
	)
	(gr_line
		(start 164.746178 -240.168176)
		(end 164.7825 -240.188496)
		(stroke
			(width 0.0508)
			(type default)
		)
		(layer "In7.Cu")
	)
	(gr_line
		(start 167.57523 -24.30272)
		(end 167.579548 -24.299926)
		(stroke
			(width 0.0635)
			(type default)
		)
		(layer "In7.Cu")
	)
	(gr_line
		(start 167.579548 -24.299926)
		(end 167.584882 -24.298402)
		(stroke
			(width 0.0635)
			(type default)
		)
		(layer "In7.Cu")
	)
	(gr_line
		(start 168.97985 -312.285634)
		(end 168.994328 -312.295032)
		(stroke
			(width 0.0508)
			(type default)
		)
		(layer "In7.Cu")
	)
	(gr_line
		(start 168.994328 -312.295032)
		(end 169.011346 -312.298588)
		(stroke
			(width 0.0508)
			(type default)
		)
		(layer "In7.Cu")
	)
	(gr_line
		(start 170.96232 -121.378726)
		(end 170.971972 -121.385838)
		(stroke
			(width 0.0508)
			(type default)
		)
		(layer "In7.Cu")
	)
	(gr_line
		(start 170.971972 -121.385838)
		(end 170.979338 -121.395998)
		(stroke
			(width 0.0508)
			(type default)
		)
		(layer "In7.Cu")
	)
	(gr_line
		(start 171.658788 -125.905768)
		(end 171.676822 -125.917706)
		(stroke
			(width 0.0508)
			(type default)
		)
		(layer "In7.Cu")
	)
	(gr_line
		(start 171.676822 -125.917706)
		(end 171.689522 -125.935232)
		(stroke
			(width 0.0508)
			(type default)
		)
		(layer "In7.Cu")
	)
	(gr_line
		(start 172.93971 -296.553636)
		(end 172.957744 -296.58183)
		(stroke
			(width 0.0508)
			(type default)
		)
		(layer "In7.Cu")
	)
	(gr_line
		(start 172.957744 -296.58183)
		(end 172.985938 -296.599864)
		(stroke
			(width 0.0508)
			(type default)
		)
		(layer "In7.Cu")
	)
	(gr_line
		(start 186.05881 -19.106896)
		(end 186.08929 -19.09826)
		(stroke
			(width 0.0635)
			(type default)
		)
		(layer "In7.Cu")
	)
	(gr_line
		(start 186.08929 -19.09826)
		(end 186.120786 -19.104864)
		(stroke
			(width 0.0635)
			(type default)
		)
		(layer "In7.Cu")
	)
	(gr_line
		(start 188.548264 -177.489104)
		(end 188.555376 -177.522124)
		(stroke
			(width 0.0508)
			(type default)
		)
		(layer "In7.Cu")
	)
	(gr_line
		(start 188.548264 -177.489104)
		(end 188.55563 -177.456084)
		(stroke
			(width 0.0508)
			(type default)
		)
		(layer "In7.Cu")
	)
	(gr_line
		(start 189.32144 -76.11491)
		(end 189.334648 -76.16698)
		(stroke
			(width 0.0508)
			(type default)
		)
		(layer "In7.Cu")
	)
	(gr_line
		(start 189.32144 -76.11491)
		(end 189.337442 -76.063602)
		(stroke
			(width 0.0508)
			(type default)
		)
		(layer "In7.Cu")
	)
	(gr_line
		(start 189.334648 -76.167488)
		(end 189.334648 -76.167742)
		(stroke
			(width 0.0508)
			(type default)
		)
		(layer "In7.Cu")
	)
	(gr_line
		(start 190.258954 -278.016716)
		(end 190.258954 -278.321516)
		(stroke
			(width 0.0508)
			(type default)
		)
		(layer "In7.Cu")
	)
	(gr_arc
		(start 190.258954 -277.483316)
		(mid 190.288715 -277.555164)
		(end 190.360554 -277.584916)
		(stroke
			(width 0.0508)
			(type default)
		)
		(layer "In7.Cu")
	)
	(gr_line
		(start 190.258954 -277.178516)
		(end 190.258954 -277.483316)
		(stroke
			(width 0.0508)
			(type default)
		)
		(layer "In7.Cu")
	)
	(gr_line
		(start 190.258954 -163.016692)
		(end 190.258954 -163.321492)
		(stroke
			(width 0.0508)
			(type default)
		)
		(layer "In7.Cu")
	)
	(gr_arc
		(start 190.258954 -162.483292)
		(mid 190.288712 -162.555134)
		(end 190.360554 -162.584892)
		(stroke
			(width 0.0508)
			(type default)
		)
		(layer "In7.Cu")
	)
	(gr_line
		(start 190.258954 -162.178492)
		(end 190.258954 -162.483292)
		(stroke
			(width 0.0508)
			(type default)
		)
		(layer "In7.Cu")
	)
	(gr_line
		(start 190.258954 -48.016668)
		(end 190.258954 -48.321468)
		(stroke
			(width 0.0508)
			(type default)
		)
		(layer "In7.Cu")
	)
	(gr_arc
		(start 190.258954 -47.483268)
		(mid 190.288698 -47.555147)
		(end 190.360554 -47.584868)
		(stroke
			(width 0.0508)
			(type default)
		)
		(layer "In7.Cu")
	)
	(gr_line
		(start 190.258954 -47.178468)
		(end 190.258954 -47.483268)
		(stroke
			(width 0.0508)
			(type default)
		)
		(layer "In7.Cu")
	)
	(gr_arc
		(start 190.360554 -277.915116)
		(mid 190.288712 -277.944874)
		(end 190.258954 -278.016716)
		(stroke
			(width 0.0508)
			(type default)
		)
		(layer "In7.Cu")
	)
	(gr_arc
		(start 190.360554 -162.915092)
		(mid 190.288712 -162.94485)
		(end 190.258954 -163.016692)
		(stroke
			(width 0.0508)
			(type default)
		)
		(layer "In7.Cu")
	)
	(gr_arc
		(start 190.360554 -47.915068)
		(mid 190.288712 -47.944826)
		(end 190.258954 -48.016668)
		(stroke
			(width 0.0508)
			(type default)
		)
		(layer "In7.Cu")
	)
	(gr_line
		(start 191.040258 -162.584892)
		(end 191.071246 -162.599878)
		(stroke
			(width 0.0508)
			(type default)
		)
		(layer "In7.Cu")
	)
	(gr_line
		(start 191.040512 -47.584868)
		(end 191.080898 -47.607728)
		(stroke
			(width 0.0508)
			(type default)
		)
		(layer "In7.Cu")
	)
	(gr_line
		(start 191.367664 -277.584916)
		(end 191.415162 -277.615396)
		(stroke
			(width 0.0508)
			(type default)
		)
		(layer "In7.Cu")
	)
	(gr_line
		(start 191.398906 -183.963564)
		(end 191.406018 -183.996584)
		(stroke
			(width 0.0508)
			(type default)
		)
		(layer "In7.Cu")
	)
	(gr_line
		(start 191.398906 -183.963564)
		(end 191.406272 -183.931306)
		(stroke
			(width 0.0508)
			(type default)
		)
		(layer "In7.Cu")
	)
	(gr_line
		(start 191.645794 -162.878008)
		(end 191.737488 -162.922458)
		(stroke
			(width 0.0508)
			(type default)
		)
		(layer "In7.Cu")
	)
	(gr_line
		(start 191.737488 -162.922458)
		(end 191.769492 -163.018978)
		(stroke
			(width 0.0508)
			(type default)
		)
		(layer "In7.Cu")
	)
	(gr_line
		(start 191.812164 -48.021748)
		(end 191.845946 -48.040798)
		(stroke
			(width 0.0508)
			(type default)
		)
		(layer "In7.Cu")
	)
	(gr_line
		(start 191.845946 -48.040798)
		(end 191.866774 -48.072548)
		(stroke
			(width 0.0508)
			(type default)
		)
		(layer "In7.Cu")
	)
	(gr_line
		(start 191.96304 -163.60267)
		(end 191.979296 -163.651438)
		(stroke
			(width 0.0508)
			(type default)
		)
		(layer "In7.Cu")
	)
	(gr_line
		(start 191.967866 -163.701984)
		(end 191.979296 -163.651438)
		(stroke
			(width 0.0508)
			(type default)
		)
		(layer "In7.Cu")
	)
	(gr_line
		(start 192.157604 -48.51019)
		(end 192.171828 -48.531272)
		(stroke
			(width 0.0508)
			(type default)
		)
		(layer "In7.Cu")
	)
	(gr_line
		(start 192.171828 -48.531272)
		(end 192.176908 -48.556418)
		(stroke
			(width 0.0508)
			(type default)
		)
		(layer "In7.Cu")
	)
	(gr_line
		(start 192.363852 -154.512518)
		(end 192.381632 -154.537156)
		(stroke
			(width 0.0508)
			(type default)
		)
		(layer "In7.Cu")
	)
	(gr_line
		(start 192.381632 -154.537156)
		(end 192.387982 -154.566874)
		(stroke
			(width 0.0508)
			(type default)
		)
		(layer "In7.Cu")
	)
	(gr_line
		(start 192.570354 -91.747086)
		(end 192.584324 -91.76639)
		(stroke
			(width 0.0508)
			(type default)
		)
		(layer "In7.Cu")
	)
	(gr_line
		(start 192.584324 -91.76639)
		(end 192.589912 -91.789504)
		(stroke
			(width 0.0508)
			(type default)
		)
		(layer "In7.Cu")
	)
	(gr_line
		(start 192.824354 -184.076848)
		(end 192.83172 -184.111138)
		(stroke
			(width 0.0508)
			(type default)
		)
		(layer "In7.Cu")
	)
	(gr_line
		(start 192.824354 -184.076848)
		(end 192.832228 -184.04332)
		(stroke
			(width 0.0508)
			(type default)
		)
		(layer "In7.Cu")
	)
	(gr_line
		(start 193.503042 -278.955754)
		(end 193.521838 -278.967692)
		(stroke
			(width 0.0508)
			(type default)
		)
		(layer "In7.Cu")
	)
	(gr_line
		(start 193.521838 -278.967692)
		(end 193.534792 -278.985726)
		(stroke
			(width 0.0508)
			(type default)
		)
		(layer "In7.Cu")
	)
	(gr_line
		(start 193.546476 -316.148466)
		(end 193.560954 -316.157864)
		(stroke
			(width 0.0508)
			(type default)
		)
		(layer "In7.Cu")
	)
	(gr_line
		(start 193.560954 -316.157864)
		(end 193.577972 -316.16142)
		(stroke
			(width 0.0508)
			(type default)
		)
		(layer "In7.Cu")
	)
	(gr_line
		(start 193.828924 -152.979374)
		(end 193.846704 -153.004012)
		(stroke
			(width 0.0508)
			(type default)
		)
		(layer "In7.Cu")
	)
	(gr_line
		(start 193.846704 -153.004012)
		(end 193.853054 -153.03373)
		(stroke
			(width 0.0508)
			(type default)
		)
		(layer "In7.Cu")
	)
	(gr_line
		(start 194.54495 -60.461144)
		(end 194.545204 -60.460128)
		(stroke
			(width 0.0508)
			(type default)
		)
		(layer "In7.Cu")
	)
	(gr_line
		(start 194.545204 -60.459874)
		(end 194.558666 -60.41644)
		(stroke
			(width 0.0508)
			(type default)
		)
		(layer "In7.Cu")
	)
	(gr_line
		(start 194.549776 -60.371736)
		(end 194.558666 -60.41644)
		(stroke
			(width 0.0508)
			(type default)
		)
		(layer "In7.Cu")
	)
	(gr_line
		(start 195.288662 -168.447212)
		(end 195.295774 -168.416224)
		(stroke
			(width 0.0508)
			(type default)
		)
		(layer "In7.Cu")
	)
	(gr_line
		(start 195.289424 -168.385998)
		(end 195.295774 -168.416224)
		(stroke
			(width 0.0508)
			(type default)
		)
		(layer "In7.Cu")
	)
	(gr_line
		(start 195.634102 -215.329008)
		(end 195.64477 -215.345518)
		(stroke
			(width 0.0508)
			(type default)
		)
		(layer "In7.Cu")
	)
	(gr_line
		(start 195.64477 -215.345518)
		(end 195.649088 -215.364822)
		(stroke
			(width 0.0508)
			(type default)
		)
		(layer "In7.Cu")
	)
	(gr_line
		(start 196.943726 -167.823642)
		(end 196.951346 -167.791384)
		(stroke
			(width 0.0508)
			(type default)
		)
		(layer "In7.Cu")
	)
	(gr_line
		(start 196.944488 -167.758618)
		(end 196.951346 -167.791384)
		(stroke
			(width 0.0508)
			(type default)
		)
		(layer "In7.Cu")
	)
	(gr_line
		(start 200.894188 -267.092938)
		(end 200.930764 -267.113258)
		(stroke
			(width 0.0508)
			(type default)
		)
		(layer "In7.Cu")
	)
	(gr_line
		(start 200.930764 -267.113258)
		(end 200.954132 -267.149072)
		(stroke
			(width 0.0508)
			(type default)
		)
		(layer "In7.Cu")
	)
	(gr_line
		(start 201.343768 -265.32459)
		(end 201.379328 -265.344402)
		(stroke
			(width 0.0508)
			(type default)
		)
		(layer "In7.Cu")
	)
	(gr_line
		(start 201.379328 -265.344402)
		(end 201.401426 -265.378438)
		(stroke
			(width 0.0508)
			(type default)
		)
		(layer "In7.Cu")
	)
	(gr_line
		(start 201.779632 -139.957556)
		(end 201.845164 -140.0048)
		(stroke
			(width 0.0508)
			(type default)
		)
		(layer "In7.Cu")
	)
	(gr_line
		(start 201.845164 -140.0048)
		(end 201.86523 -140.083032)
		(stroke
			(width 0.0508)
			(type default)
		)
		(layer "In7.Cu")
	)
	(gr_line
		(start 202.363578 -135.631936)
		(end 202.379834 -135.65378)
		(stroke
			(width 0.0508)
			(type default)
		)
		(layer "In7.Cu")
	)
	(gr_line
		(start 202.379834 -135.65378)
		(end 202.386438 -135.679942)
		(stroke
			(width 0.0508)
			(type default)
		)
		(layer "In7.Cu")
	)
	(gr_line
		(start 202.691492 -263.48817)
		(end 202.727052 -263.507982)
		(stroke
			(width 0.0508)
			(type default)
		)
		(layer "In7.Cu")
	)
	(gr_line
		(start 202.727052 -263.507982)
		(end 202.74915 -263.542018)
		(stroke
			(width 0.0508)
			(type default)
		)
		(layer "In7.Cu")
	)
	(gr_line
		(start 203.684886 -261.642098)
		(end 203.720446 -261.66191)
		(stroke
			(width 0.0508)
			(type default)
		)
		(layer "In7.Cu")
	)
	(gr_line
		(start 203.720446 -261.66191)
		(end 203.742544 -261.695946)
		(stroke
			(width 0.0508)
			(type default)
		)
		(layer "In7.Cu")
	)
	(gr_line
		(start 204.024738 -23.196296)
		(end 204.046582 -23.200868)
		(stroke
			(width 0.0635)
			(type default)
		)
		(layer "In7.Cu")
	)
	(gr_line
		(start 204.046582 -23.200868)
		(end 204.068426 -23.196296)
		(stroke
			(width 0.0635)
			(type default)
		)
		(layer "In7.Cu")
	)
	(gr_line
		(start 204.402944 -316.61481)
		(end 204.418184 -316.624462)
		(stroke
			(width 0.0508)
			(type default)
		)
		(layer "In7.Cu")
	)
	(gr_line
		(start 204.418184 -316.624462)
		(end 204.435202 -316.628018)
		(stroke
			(width 0.0508)
			(type default)
		)
		(layer "In7.Cu")
	)
	(gr_line
		(start 207.47355 -208.447386)
		(end 207.48244 -208.409286)
		(stroke
			(width 0.0508)
			(type default)
		)
		(layer "In7.Cu")
	)
	(gr_line
		(start 207.47355 -208.447386)
		(end 207.483456 -208.486756)
		(stroke
			(width 0.0508)
			(type default)
		)
		(layer "In7.Cu")
	)
	(gr_line
		(start 209.537808 -206.978758)
		(end 209.547714 -206.938372)
		(stroke
			(width 0.0508)
			(type default)
		)
		(layer "In7.Cu")
	)
	(gr_line
		(start 209.537808 -206.978758)
		(end 209.547968 -207.019652)
		(stroke
			(width 0.0508)
			(type default)
		)
		(layer "In7.Cu")
	)
	(gr_line
		(start 211.693506 -206.36865)
		(end 211.703412 -206.328264)
		(stroke
			(width 0.0508)
			(type default)
		)
		(layer "In7.Cu")
	)
	(gr_line
		(start 211.693506 -206.36865)
		(end 211.703666 -206.409544)
		(stroke
			(width 0.0508)
			(type default)
		)
		(layer "In7.Cu")
	)
	(gr_line
		(start 213.28761 -184.608724)
		(end 213.297262 -184.64657)
		(stroke
			(width 0.0508)
			(type default)
		)
		(layer "In7.Cu")
	)
	(gr_line
		(start 213.288372 -184.685178)
		(end 213.288372 -184.685432)
		(stroke
			(width 0.0508)
			(type default)
		)
		(layer "In7.Cu")
	)
	(gr_line
		(start 213.288372 -184.685178)
		(end 213.297262 -184.64657)
		(stroke
			(width 0.0508)
			(type default)
		)
		(layer "In7.Cu")
	)
	(gr_line
		(start 213.445344 -205.81747)
		(end 213.45525 -205.77683)
		(stroke
			(width 0.0508)
			(type default)
		)
		(layer "In7.Cu")
	)
	(gr_line
		(start 213.445344 -205.81747)
		(end 213.455504 -205.85811)
		(stroke
			(width 0.0508)
			(type default)
		)
		(layer "In7.Cu")
	)
	(gr_line
		(start 214.949532 -172.127164)
		(end 214.95512 -172.10024)
		(stroke
			(width 0.0635)
			(type default)
		)
		(layer "In7.Cu")
	)
	(gr_line
		(start 214.949532 -172.127164)
		(end 214.95639 -172.153834)
		(stroke
			(width 0.0635)
			(type default)
		)
		(layer "In7.Cu")
	)
	(gr_line
		(start 215.014556 -186.168538)
		(end 215.024716 -186.127644)
		(stroke
			(width 0.0508)
			(type default)
		)
		(layer "In7.Cu")
	)
	(gr_line
		(start 215.014556 -186.087004)
		(end 215.024716 -186.127644)
		(stroke
			(width 0.0508)
			(type default)
		)
		(layer "In7.Cu")
	)
	(gr_line
		(start 216.34958 -172.996098)
		(end 216.355168 -172.969428)
		(stroke
			(width 0.0635)
			(type default)
		)
		(layer "In7.Cu")
	)
	(gr_line
		(start 216.34958 -172.996098)
		(end 216.356438 -173.023276)
		(stroke
			(width 0.0635)
			(type default)
		)
		(layer "In7.Cu")
	)
	(gr_line
		(start 216.356438 -173.023022)
		(end 216.356438 -173.02353)
		(stroke
			(width 0.0635)
			(type default)
		)
		(layer "In7.Cu")
	)
	(gr_line
		(start 216.620852 -187.78474)
		(end 216.631012 -187.743846)
		(stroke
			(width 0.0508)
			(type default)
		)
		(layer "In7.Cu")
	)
	(gr_line
		(start 216.620852 -187.703206)
		(end 216.631012 -187.743846)
		(stroke
			(width 0.0508)
			(type default)
		)
		(layer "In7.Cu")
	)
	(gr_line
		(start 217.999818 -188.644276)
		(end 218.009978 -188.684916)
		(stroke
			(width 0.0508)
			(type default)
		)
		(layer "In7.Cu")
	)
	(gr_line
		(start 218.000072 -188.725302)
		(end 218.009978 -188.684916)
		(stroke
			(width 0.0508)
			(type default)
		)
		(layer "In7.Cu")
	)
	(gr_line
		(start 218.06789 -184.27827)
		(end 218.068906 -184.28208)
		(stroke
			(width 0.0635)
			(type default)
		)
		(layer "In7.Cu")
	)
	(gr_line
		(start 218.068906 -184.28208)
		(end 218.070938 -184.285128)
		(stroke
			(width 0.0635)
			(type default)
		)
		(layer "In7.Cu")
	)
	(gr_line
		(start 218.845384 -182.715662)
		(end 218.8464 -182.719472)
		(stroke
			(width 0.0635)
			(type default)
		)
		(layer "In7.Cu")
	)
	(gr_line
		(start 218.8464 -182.719472)
		(end 218.848432 -182.72252)
		(stroke
			(width 0.0635)
			(type default)
		)
		(layer "In7.Cu")
	)
	(gr_line
		(start 219.951554 -315.963554)
		(end 219.962476 -315.97854)
		(stroke
			(width 0.0508)
			(type default)
		)
		(layer "In7.Cu")
	)
	(gr_line
		(start 219.962476 -315.97854)
		(end 219.978224 -315.989208)
		(stroke
			(width 0.0508)
			(type default)
		)
		(layer "In7.Cu")
	)
	(gr_line
		(start 220.209872 -326.68464)
		(end 220.227906 -326.68845)
		(stroke
			(width 0.0508)
			(type default)
		)
		(layer "In7.Cu")
	)
	(gr_line
		(start 220.227906 -326.68845)
		(end 220.244162 -326.698864)
		(stroke
			(width 0.0508)
			(type default)
		)
		(layer "In7.Cu")
	)
	(gr_line
		(start 220.928692 -325.392796)
		(end 220.94571 -325.396352)
		(stroke
			(width 0.0508)
			(type default)
		)
		(layer "In7.Cu")
	)
	(gr_line
		(start 220.94571 -325.396352)
		(end 220.960188 -325.40575)
		(stroke
			(width 0.0508)
			(type default)
		)
		(layer "In7.Cu")
	)
	(gr_line
		(start 221.05493 -323.49948)
		(end 221.071948 -323.503036)
		(stroke
			(width 0.0508)
			(type default)
		)
		(layer "In7.Cu")
	)
	(gr_line
		(start 221.071948 -323.503036)
		(end 221.086426 -323.512434)
		(stroke
			(width 0.0508)
			(type default)
		)
		(layer "In7.Cu")
	)
	(gr_line
		(start 221.105984 -157.644084)
		(end 221.111572 -157.617414)
		(stroke
			(width 0.0635)
			(type default)
		)
		(layer "In7.Cu")
	)
	(gr_line
		(start 221.105984 -157.644084)
		(end 221.112842 -157.671262)
		(stroke
			(width 0.0635)
			(type default)
		)
		(layer "In7.Cu")
	)
	(gr_line
		(start 221.112842 -157.671008)
		(end 221.112842 -157.671516)
		(stroke
			(width 0.0635)
			(type default)
		)
		(layer "In7.Cu")
	)
	(gr_line
		(start 221.685866 -320.114676)
		(end 221.702884 -320.118232)
		(stroke
			(width 0.0508)
			(type default)
		)
		(layer "In7.Cu")
	)
	(gr_line
		(start 221.702884 -320.118232)
		(end 221.717362 -320.12763)
		(stroke
			(width 0.0508)
			(type default)
		)
		(layer "In7.Cu")
	)
	(gr_line
		(start 222.007938 -137.464038)
		(end 222.011494 -137.44702)
		(stroke
			(width 0.0635)
			(type default)
		)
		(layer "In7.Cu")
	)
	(gr_line
		(start 222.011494 -137.44702)
		(end 222.020892 -137.432542)
		(stroke
			(width 0.0635)
			(type default)
		)
		(layer "In7.Cu")
	)
	(gr_line
		(start 222.053658 -322.137024)
		(end 222.070676 -322.14058)
		(stroke
			(width 0.0508)
			(type default)
		)
		(layer "In7.Cu")
	)
	(gr_line
		(start 222.070676 -322.14058)
		(end 222.085154 -322.149978)
		(stroke
			(width 0.0508)
			(type default)
		)
		(layer "In7.Cu")
	)
	(gr_line
		(start 222.164402 -19.34972)
		(end 222.178626 -19.346672)
		(stroke
			(width 0.0635)
			(type default)
		)
		(layer "In7.Cu")
	)
	(gr_line
		(start 222.178626 -19.346672)
		(end 222.190818 -19.338798)
		(stroke
			(width 0.0635)
			(type default)
		)
		(layer "In7.Cu")
	)
	(gr_line
		(start 222.669354 -157.960822)
		(end 222.674942 -157.934152)
		(stroke
			(width 0.0635)
			(type default)
		)
		(layer "In7.Cu")
	)
	(gr_line
		(start 222.669354 -157.960822)
		(end 222.676212 -157.987492)
		(stroke
			(width 0.0635)
			(type default)
		)
		(layer "In7.Cu")
	)
	(gr_line
		(start 222.676212 -157.987746)
		(end 222.676212 -157.988254)
		(stroke
			(width 0.0635)
			(type default)
		)
		(layer "In7.Cu")
	)
	(gr_line
		(start 223.205548 -139.309602)
		(end 223.20885 -139.293346)
		(stroke
			(width 0.0635)
			(type default)
		)
		(layer "In7.Cu")
	)
	(gr_line
		(start 223.20885 -139.293346)
		(end 223.21774 -139.279884)
		(stroke
			(width 0.0635)
			(type default)
		)
		(layer "In7.Cu")
	)
	(gr_line
		(start 224.504758 -140.91031)
		(end 224.50806 -140.894054)
		(stroke
			(width 0.0635)
			(type default)
		)
		(layer "In7.Cu")
	)
	(gr_line
		(start 224.50806 -140.894054)
		(end 224.51695 -140.880592)
		(stroke
			(width 0.0635)
			(type default)
		)
		(layer "In7.Cu")
	)
	(gr_line
		(start 225.957384 -141.809724)
		(end 225.960686 -141.793468)
		(stroke
			(width 0.0635)
			(type default)
		)
		(layer "In7.Cu")
	)
	(gr_line
		(start 225.960686 -141.793468)
		(end 225.969576 -141.780006)
		(stroke
			(width 0.0635)
			(type default)
		)
		(layer "In7.Cu")
	)
	(gr_line
		(start 226.114356 -306.440078)
		(end 226.129088 -306.462684)
		(stroke
			(width 0.0508)
			(type default)
		)
		(layer "In7.Cu")
	)
	(gr_line
		(start 226.129088 -306.462684)
		(end 226.150932 -306.477162)
		(stroke
			(width 0.0508)
			(type default)
		)
		(layer "In7.Cu")
	)
	(gr_line
		(start 226.894644 -305.240182)
		(end 226.910138 -305.264058)
		(stroke
			(width 0.0508)
			(type default)
		)
		(layer "In7.Cu")
	)
	(gr_line
		(start 226.910138 -305.264058)
		(end 226.93376 -305.279806)
		(stroke
			(width 0.0508)
			(type default)
		)
		(layer "In7.Cu")
	)
	(gr_line
		(start 227.199444 -169.87012)
		(end 227.205032 -169.84345)
		(stroke
			(width 0.0635)
			(type default)
		)
		(layer "In7.Cu")
	)
	(gr_line
		(start 227.199444 -169.87012)
		(end 227.206302 -169.897298)
		(stroke
			(width 0.0635)
			(type default)
		)
		(layer "In7.Cu")
	)
	(gr_line
		(start 227.206302 -169.897044)
		(end 227.206302 -169.897552)
		(stroke
			(width 0.0635)
			(type default)
		)
		(layer "In7.Cu")
	)
	(gr_line
		(start 228.8159 -170.507152)
		(end 228.831394 -170.431206)
		(stroke
			(width 0.0635)
			(type default)
		)
		(layer "In7.Cu")
	)
	(gr_line
		(start 228.8159 -170.507152)
		(end 228.849936 -170.558714)
		(stroke
			(width 0.0635)
			(type default)
		)
		(layer "In7.Cu")
	)
	(gr_line
		(start 229.086918 -304.705004)
		(end 229.102412 -304.72888)
		(stroke
			(width 0.0508)
			(type default)
		)
		(layer "In7.Cu")
	)
	(gr_line
		(start 229.102412 -304.72888)
		(end 229.126034 -304.744628)
		(stroke
			(width 0.0508)
			(type default)
		)
		(layer "In7.Cu")
	)
	(gr_line
		(start 229.11435 -170.454574)
		(end 229.115874 -170.460162)
		(stroke
			(width 0.0635)
			(type default)
		)
		(layer "In7.Cu")
	)
	(gr_line
		(start 230.475282 -303.466246)
		(end 230.490776 -303.490122)
		(stroke
			(width 0.0508)
			(type default)
		)
		(layer "In7.Cu")
	)
	(gr_line
		(start 230.490776 -303.490122)
		(end 230.514398 -303.50587)
		(stroke
			(width 0.0508)
			(type default)
		)
		(layer "In7.Cu")
	)
	(gr_line
		(start 230.683308 -13.490448)
		(end 231.177338 -13.169646)
		(stroke
			(width 0.0635)
			(type default)
		)
		(layer "In7.Cu")
	)
	(gr_line
		(start 230.73741 -152.49017)
		(end 230.754428 -152.406604)
		(stroke
			(width 0.0635)
			(type default)
		)
		(layer "In7.Cu")
	)
	(gr_line
		(start 230.754428 -152.406604)
		(end 230.827326 -152.362154)
		(stroke
			(width 0.0635)
			(type default)
		)
		(layer "In7.Cu")
	)
	(gr_line
		(start 230.775002 -291.538406)
		(end 230.802942 -291.595302)
		(stroke
			(width 0.0508)
			(type default)
		)
		(layer "In7.Cu")
	)
	(gr_line
		(start 230.802942 -291.595302)
		(end 230.858568 -291.62629)
		(stroke
			(width 0.0508)
			(type default)
		)
		(layer "In7.Cu")
	)
	(gr_line
		(start 230.809292 -13.744956)
		(end 230.999284 -13.785088)
		(stroke
			(width 0.0635)
			(type default)
		)
		(layer "In7.Cu")
	)
	(gr_line
		(start 230.999284 -13.785088)
		(end 231.318816 -13.577824)
		(stroke
			(width 0.0635)
			(type default)
		)
		(layer "In7.Cu")
	)
	(gr_line
		(start 231.318816 -13.577824)
		(end 231.359202 -13.387832)
		(stroke
			(width 0.0635)
			(type default)
		)
		(layer "In7.Cu")
	)
	(gr_line
		(start 231.557576 -12.922758)
		(end 232.050844 -12.602464)
		(stroke
			(width 0.0635)
			(type default)
		)
		(layer "In7.Cu")
	)
	(gr_line
		(start 231.682798 -13.177774)
		(end 231.87279 -13.217906)
		(stroke
			(width 0.0635)
			(type default)
		)
		(layer "In7.Cu")
	)
	(gr_line
		(start 231.727248 -290.126166)
		(end 231.755188 -290.183316)
		(stroke
			(width 0.0508)
			(type default)
		)
		(layer "In7.Cu")
	)
	(gr_line
		(start 231.755188 -290.183316)
		(end 231.810814 -290.214304)
		(stroke
			(width 0.0508)
			(type default)
		)
		(layer "In7.Cu")
	)
	(gr_line
		(start 231.860344 -155.55595)
		(end 231.878378 -155.467812)
		(stroke
			(width 0.0635)
			(type default)
		)
		(layer "In7.Cu")
	)
	(gr_line
		(start 231.87279 -13.217906)
		(end 232.192322 -13.010642)
		(stroke
			(width 0.0635)
			(type default)
		)
		(layer "In7.Cu")
	)
	(gr_line
		(start 231.878378 -155.467812)
		(end 231.956356 -155.423362)
		(stroke
			(width 0.0635)
			(type default)
		)
		(layer "In7.Cu")
	)
	(gr_line
		(start 232.192322 -13.010642)
		(end 232.232708 -12.82065)
		(stroke
			(width 0.0635)
			(type default)
		)
		(layer "In7.Cu")
	)
	(gr_line
		(start 232.431082 -12.355576)
		(end 232.923588 -12.03579)
		(stroke
			(width 0.0635)
			(type default)
		)
		(layer "In7.Cu")
	)
	(gr_line
		(start 232.440226 -173.505368)
		(end 232.45572 -173.429422)
		(stroke
			(width 0.0635)
			(type default)
		)
		(layer "In7.Cu")
	)
	(gr_line
		(start 232.440226 -173.505368)
		(end 232.475278 -173.558454)
		(stroke
			(width 0.0635)
			(type default)
		)
		(layer "In7.Cu")
	)
	(gr_line
		(start 232.556304 -12.610592)
		(end 232.746296 -12.650978)
		(stroke
			(width 0.0635)
			(type default)
		)
		(layer "In7.Cu")
	)
	(gr_line
		(start 232.612946 -288.858706)
		(end 232.640886 -288.915856)
		(stroke
			(width 0.0508)
			(type default)
		)
		(layer "In7.Cu")
	)
	(gr_line
		(start 232.640886 -288.915856)
		(end 232.696512 -288.946844)
		(stroke
			(width 0.0508)
			(type default)
		)
		(layer "In7.Cu")
	)
	(gr_line
		(start 232.73893 -173.45152)
		(end 232.740962 -173.459394)
		(stroke
			(width 0.0635)
			(type default)
		)
		(layer "In7.Cu")
	)
	(gr_line
		(start 232.746296 -12.650978)
		(end 233.065828 -12.44346)
		(stroke
			(width 0.0635)
			(type default)
		)
		(layer "In7.Cu")
	)
	(gr_line
		(start 232.753916 -301.799244)
		(end 232.775252 -301.843186)
		(stroke
			(width 0.0508)
			(type default)
		)
		(layer "In7.Cu")
	)
	(gr_line
		(start 232.766362 -203.052426)
		(end 232.767378 -203.056236)
		(stroke
			(width 0.0635)
			(type default)
		)
		(layer "In7.Cu")
	)
	(gr_line
		(start 232.767378 -203.056236)
		(end 232.76941 -203.059284)
		(stroke
			(width 0.0635)
			(type default)
		)
		(layer "In7.Cu")
	)
	(gr_line
		(start 232.775252 -301.843186)
		(end 232.816146 -301.870364)
		(stroke
			(width 0.0508)
			(type default)
		)
		(layer "In7.Cu")
	)
	(gr_line
		(start 233.031792 -130.90398)
		(end 233.047286 -130.880358)
		(stroke
			(width 0.0635)
			(type default)
		)
		(layer "In7.Cu")
	)
	(gr_line
		(start 233.047286 -130.880358)
		(end 233.071416 -130.865626)
		(stroke
			(width 0.0635)
			(type default)
		)
		(layer "In7.Cu")
	)
	(gr_line
		(start 233.065828 -12.44346)
		(end 233.10596 -12.253468)
		(stroke
			(width 0.0635)
			(type default)
		)
		(layer "In7.Cu")
	)
	(gr_line
		(start 233.424984 -158.723584)
		(end 233.442256 -158.638748)
		(stroke
			(width 0.0635)
			(type default)
		)
		(layer "In7.Cu")
	)
	(gr_line
		(start 233.442256 -158.638748)
		(end 233.51617 -158.59379)
		(stroke
			(width 0.0635)
			(type default)
		)
		(layer "In7.Cu")
	)
	(gr_line
		(start 233.790744 -300.489366)
		(end 233.813096 -300.535086)
		(stroke
			(width 0.0508)
			(type default)
		)
		(layer "In7.Cu")
	)
	(gr_line
		(start 233.813096 -300.535086)
		(end 233.85526 -300.56328)
		(stroke
			(width 0.0508)
			(type default)
		)
		(layer "In7.Cu")
	)
	(gr_line
		(start 233.836718 -287.78327)
		(end 233.86542 -287.841944)
		(stroke
			(width 0.0508)
			(type default)
		)
		(layer "In7.Cu")
	)
	(gr_line
		(start 233.86542 -287.841944)
		(end 233.922062 -287.87344)
		(stroke
			(width 0.0508)
			(type default)
		)
		(layer "In7.Cu")
	)
	(gr_line
		(start 233.898186 -11.402822)
		(end 233.910378 -11.394948)
		(stroke
			(width 0.0635)
			(type default)
		)
		(layer "In7.Cu")
	)
	(gr_line
		(start 233.910378 -11.394948)
		(end 233.924602 -11.3919)
		(stroke
			(width 0.0635)
			(type default)
		)
		(layer "In7.Cu")
	)
	(gr_line
		(start 233.959654 -126.339346)
		(end 233.975148 -126.315724)
		(stroke
			(width 0.0635)
			(type default)
		)
		(layer "In7.Cu")
	)
	(gr_line
		(start 233.975148 -126.315724)
		(end 233.999278 -126.300992)
		(stroke
			(width 0.0635)
			(type default)
		)
		(layer "In7.Cu")
	)
	(gr_line
		(start 234.07878 -284.086554)
		(end 234.107482 -284.145228)
		(stroke
			(width 0.0508)
			(type default)
		)
		(layer "In7.Cu")
	)
	(gr_line
		(start 234.107482 -284.145228)
		(end 234.163362 -284.176216)
		(stroke
			(width 0.0508)
			(type default)
		)
		(layer "In7.Cu")
	)
	(gr_line
		(start 234.119674 -202.538076)
		(end 234.12069 -202.541886)
		(stroke
			(width 0.0635)
			(type default)
		)
		(layer "In7.Cu")
	)
	(gr_line
		(start 234.12069 -202.541886)
		(end 234.122722 -202.544934)
		(stroke
			(width 0.0635)
			(type default)
		)
		(layer "In7.Cu")
	)
	(gr_line
		(start 234.388152 -122.078242)
		(end 234.403646 -122.05462)
		(stroke
			(width 0.0635)
			(type default)
		)
		(layer "In7.Cu")
	)
	(gr_line
		(start 234.403646 -122.05462)
		(end 234.427776 -122.039888)
		(stroke
			(width 0.0635)
			(type default)
		)
		(layer "In7.Cu")
	)
	(gr_line
		(start 234.729274 -117.871748)
		(end 234.744768 -117.848126)
		(stroke
			(width 0.0635)
			(type default)
		)
		(layer "In7.Cu")
	)
	(gr_line
		(start 234.744768 -117.848126)
		(end 234.768898 -117.833394)
		(stroke
			(width 0.0635)
			(type default)
		)
		(layer "In7.Cu")
	)
	(gr_line
		(start 234.806744 -161.883852)
		(end 234.824016 -161.799016)
		(stroke
			(width 0.0635)
			(type default)
		)
		(layer "In7.Cu")
	)
	(gr_line
		(start 234.824016 -161.79927)
		(end 234.896914 -161.75482)
		(stroke
			(width 0.0635)
			(type default)
		)
		(layer "In7.Cu")
	)
	(gr_line
		(start 234.824016 -161.799016)
		(end 234.824016 -161.79927)
		(stroke
			(width 0.0635)
			(type default)
		)
		(layer "In7.Cu")
	)
	(gr_line
		(start 235.312204 -283.301948)
		(end 235.340906 -283.360622)
		(stroke
			(width 0.0508)
			(type default)
		)
		(layer "In7.Cu")
	)
	(gr_line
		(start 235.340906 -283.360622)
		(end 235.397548 -283.392118)
		(stroke
			(width 0.0508)
			(type default)
		)
		(layer "In7.Cu")
	)
	(gr_line
		(start 235.345224 -201.589386)
		(end 235.34624 -201.593196)
		(stroke
			(width 0.0635)
			(type default)
		)
		(layer "In7.Cu")
	)
	(gr_line
		(start 235.34624 -201.593196)
		(end 235.348272 -201.596244)
		(stroke
			(width 0.0635)
			(type default)
		)
		(layer "In7.Cu")
	)
	(gr_line
		(start 235.509054 -161.382202)
		(end 235.544106 -161.360866)
		(stroke
			(width 0.0635)
			(type default)
		)
		(layer "In7.Cu")
	)
	(gr_line
		(start 235.509562 -129.381504)
		(end 235.544614 -129.360168)
		(stroke
			(width 0.0635)
			(type default)
		)
		(layer "In7.Cu")
	)
	(gr_line
		(start 235.509816 -157.381448)
		(end 235.544868 -157.360112)
		(stroke
			(width 0.0635)
			(type default)
		)
		(layer "In7.Cu")
	)
	(gr_line
		(start 235.509816 -121.38152)
		(end 235.544868 -121.360184)
		(stroke
			(width 0.0635)
			(type default)
		)
		(layer "In7.Cu")
	)
	(gr_line
		(start 235.51007 -125.381512)
		(end 235.545122 -125.360176)
		(stroke
			(width 0.0635)
			(type default)
		)
		(layer "In7.Cu")
	)
	(gr_line
		(start 235.51134 -117.38102)
		(end 235.545376 -117.360192)
		(stroke
			(width 0.0635)
			(type default)
		)
		(layer "In7.Cu")
	)
	(gr_line
		(start 235.531152 -153.378408)
		(end 235.563156 -153.36012)
		(stroke
			(width 0.0635)
			(type default)
		)
		(layer "In7.Cu")
	)
	(gr_line
		(start 235.544106 -161.360612)
		(end 235.544106 -161.360866)
		(stroke
			(width 0.0635)
			(type default)
		)
		(layer "In7.Cu")
	)
	(gr_line
		(start 235.70946 -161.640012)
		(end 235.70946 -161.640266)
		(stroke
			(width 0.0635)
			(type default)
		)
		(layer "In7.Cu")
	)
	(gr_line
		(start 235.70946 -161.640012)
		(end 235.823506 -161.640012)
		(stroke
			(width 0.0635)
			(type default)
		)
		(layer "In7.Cu")
	)
	(gr_line
		(start 235.722668 -149.381464)
		(end 235.75772 -149.360128)
		(stroke
			(width 0.0635)
			(type default)
		)
		(layer "In7.Cu")
	)
	(gr_line
		(start 235.962698 -198.236586)
		(end 235.963714 -198.240396)
		(stroke
			(width 0.0635)
			(type default)
		)
		(layer "In7.Cu")
	)
	(gr_line
		(start 235.963714 -198.240396)
		(end 235.965746 -198.243444)
		(stroke
			(width 0.0635)
			(type default)
		)
		(layer "In7.Cu")
	)
	(gr_line
		(start 236.050074 -162.499802)
		(end 236.79404 -162.127184)
		(stroke
			(width 0.0635)
			(type default)
		)
		(layer "In7.Cu")
	)
	(gr_line
		(start 236.050074 -158.49981)
		(end 236.79404 -158.127192)
		(stroke
			(width 0.0635)
			(type default)
		)
		(layer "In7.Cu")
	)
	(gr_line
		(start 236.050074 -154.499818)
		(end 236.79404 -154.1272)
		(stroke
			(width 0.0635)
			(type default)
		)
		(layer "In7.Cu")
	)
	(gr_line
		(start 236.050074 -150.499826)
		(end 236.79404 -150.127208)
		(stroke
			(width 0.0635)
			(type default)
		)
		(layer "In7.Cu")
	)
	(gr_line
		(start 236.050074 -130.499866)
		(end 236.79404 -130.127248)
		(stroke
			(width 0.0635)
			(type default)
		)
		(layer "In7.Cu")
	)
	(gr_line
		(start 236.050074 -126.499874)
		(end 236.79404 -126.127256)
		(stroke
			(width 0.0635)
			(type default)
		)
		(layer "In7.Cu")
	)
	(gr_line
		(start 236.050074 -122.499882)
		(end 236.79404 -122.127264)
		(stroke
			(width 0.0635)
			(type default)
		)
		(layer "In7.Cu")
	)
	(gr_line
		(start 236.050074 -118.49989)
		(end 236.79404 -118.127272)
		(stroke
			(width 0.0635)
			(type default)
		)
		(layer "In7.Cu")
	)
	(gr_line
		(start 236.050074 -12.200128)
		(end 236.79404 -11.82751)
		(stroke
			(width 0.0635)
			(type default)
		)
		(layer "In7.Cu")
	)
	(gr_line
		(start 236.641386 -195.608956)
		(end 236.642402 -195.612766)
		(stroke
			(width 0.0635)
			(type default)
		)
		(layer "In7.Cu")
	)
	(gr_line
		(start 236.642402 -195.612766)
		(end 236.644434 -195.615814)
		(stroke
			(width 0.0635)
			(type default)
		)
		(layer "In7.Cu")
	)
	(gr_line
		(start 236.79404 -162.127184)
		(end 236.803946 -162.122104)
		(stroke
			(width 0.0635)
			(type default)
		)
		(layer "In7.Cu")
	)
	(gr_line
		(start 236.79404 -158.127192)
		(end 236.803946 -158.122112)
		(stroke
			(width 0.0635)
			(type default)
		)
		(layer "In7.Cu")
	)
	(gr_line
		(start 236.79404 -154.1272)
		(end 236.803946 -154.12212)
		(stroke
			(width 0.0635)
			(type default)
		)
		(layer "In7.Cu")
	)
	(gr_line
		(start 236.79404 -150.127208)
		(end 236.803946 -150.122128)
		(stroke
			(width 0.0635)
			(type default)
		)
		(layer "In7.Cu")
	)
	(gr_line
		(start 236.79404 -130.127248)
		(end 236.803946 -130.122168)
		(stroke
			(width 0.0635)
			(type default)
		)
		(layer "In7.Cu")
	)
	(gr_line
		(start 236.79404 -126.127256)
		(end 236.803946 -126.122176)
		(stroke
			(width 0.0635)
			(type default)
		)
		(layer "In7.Cu")
	)
	(gr_line
		(start 236.79404 -122.127264)
		(end 236.803946 -122.122184)
		(stroke
			(width 0.0635)
			(type default)
		)
		(layer "In7.Cu")
	)
	(gr_line
		(start 236.79404 -118.127272)
		(end 236.803946 -118.122192)
		(stroke
			(width 0.0635)
			(type default)
		)
		(layer "In7.Cu")
	)
	(gr_line
		(start 236.79404 -11.82751)
		(end 236.803946 -11.82243)
		(stroke
			(width 0.0635)
			(type default)
		)
		(layer "In7.Cu")
	)
	(gr_arc
		(start 236.803946 -162.122104)
		(mid 236.872347 -162.02895)
		(end 236.836966 -161.918904)
		(stroke
			(width 0.0635)
			(type default)
		)
		(layer "In7.Cu")
	)
	(gr_arc
		(start 236.803946 -158.122112)
		(mid 236.872353 -158.028956)
		(end 236.836966 -157.918912)
		(stroke
			(width 0.0635)
			(type default)
		)
		(layer "In7.Cu")
	)
	(gr_arc
		(start 236.803946 -154.12212)
		(mid 236.871789 -154.028845)
		(end 236.836966 -153.91892)
		(stroke
			(width 0.0635)
			(type default)
		)
		(layer "In7.Cu")
	)
	(gr_arc
		(start 236.803946 -150.122128)
		(mid 236.872366 -150.028967)
		(end 236.836966 -149.918928)
		(stroke
			(width 0.0635)
			(type default)
		)
		(layer "In7.Cu")
	)
	(gr_arc
		(start 236.803946 -130.122168)
		(mid 236.872398 -130.028996)
		(end 236.836966 -129.918968)
		(stroke
			(width 0.0635)
			(type default)
		)
		(layer "In7.Cu")
	)
	(gr_arc
		(start 236.803946 -126.122176)
		(mid 236.872404 -126.029001)
		(end 236.836966 -125.918976)
		(stroke
			(width 0.0635)
			(type default)
		)
		(layer "In7.Cu")
	)
	(gr_arc
		(start 236.803946 -122.122184)
		(mid 236.872331 -122.029036)
		(end 236.836966 -121.918984)
		(stroke
			(width 0.0635)
			(type default)
		)
		(layer "In7.Cu")
	)
	(gr_arc
		(start 236.803946 -118.122192)
		(mid 236.872338 -118.029041)
		(end 236.836966 -117.918992)
		(stroke
			(width 0.0635)
			(type default)
		)
		(layer "In7.Cu")
	)
	(gr_arc
		(start 236.803946 -11.82243)
		(mid 236.872368 -11.729268)
		(end 236.836966 -11.61923)
		(stroke
			(width 0.0635)
			(type default)
		)
		(layer "In7.Cu")
	)
	(gr_arc
		(start 237.148116 -161.83483)
		(mid 237.231528 -161.877491)
		(end 237.324138 -161.863278)
		(stroke
			(width 0.0635)
			(type default)
		)
		(layer "In7.Cu")
	)
	(gr_arc
		(start 237.148116 -157.834838)
		(mid 237.231528 -157.877499)
		(end 237.324138 -157.863286)
		(stroke
			(width 0.0635)
			(type default)
		)
		(layer "In7.Cu")
	)
	(gr_arc
		(start 237.148116 -153.834846)
		(mid 237.231528 -153.877507)
		(end 237.324138 -153.863294)
		(stroke
			(width 0.0635)
			(type default)
		)
		(layer "In7.Cu")
	)
	(gr_arc
		(start 237.148116 -149.834854)
		(mid 237.231528 -149.877515)
		(end 237.324138 -149.863302)
		(stroke
			(width 0.0635)
			(type default)
		)
		(layer "In7.Cu")
	)
	(gr_arc
		(start 237.148116 -129.834894)
		(mid 237.231528 -129.877555)
		(end 237.324138 -129.863342)
		(stroke
			(width 0.0635)
			(type default)
		)
		(layer "In7.Cu")
	)
	(gr_arc
		(start 237.148116 -125.834902)
		(mid 237.231528 -125.877563)
		(end 237.324138 -125.86335)
		(stroke
			(width 0.0635)
			(type default)
		)
		(layer "In7.Cu")
	)
	(gr_arc
		(start 237.148116 -121.83491)
		(mid 237.231528 -121.877571)
		(end 237.324138 -121.863358)
		(stroke
			(width 0.0635)
			(type default)
		)
		(layer "In7.Cu")
	)
	(gr_arc
		(start 237.148116 -117.834918)
		(mid 237.231528 -117.877579)
		(end 237.324138 -117.863366)
		(stroke
			(width 0.0635)
			(type default)
		)
		(layer "In7.Cu")
	)
	(gr_arc
		(start 237.148116 -11.535156)
		(mid 237.231528 -11.577817)
		(end 237.324138 -11.563604)
		(stroke
			(width 0.0635)
			(type default)
		)
		(layer "In7.Cu")
	)
	(gr_line
		(start 237.229142 -192.060322)
		(end 237.230158 -192.064132)
		(stroke
			(width 0.0635)
			(type default)
		)
		(layer "In7.Cu")
	)
	(gr_line
		(start 237.230158 -192.064132)
		(end 237.23219 -192.06718)
		(stroke
			(width 0.0635)
			(type default)
		)
		(layer "In7.Cu")
	)
	(gr_line
		(start 237.324138 -161.863278)
		(end 238.05007 -161.499804)
		(stroke
			(width 0.0635)
			(type default)
		)
		(layer "In7.Cu")
	)
	(gr_line
		(start 237.324138 -157.863286)
		(end 238.05007 -157.499812)
		(stroke
			(width 0.0635)
			(type default)
		)
		(layer "In7.Cu")
	)
	(gr_line
		(start 237.324138 -153.863294)
		(end 238.05007 -153.49982)
		(stroke
			(width 0.0635)
			(type default)
		)
		(layer "In7.Cu")
	)
	(gr_line
		(start 237.324138 -149.863302)
		(end 238.05007 -149.499828)
		(stroke
			(width 0.0635)
			(type default)
		)
		(layer "In7.Cu")
	)
	(gr_line
		(start 237.324138 -129.863342)
		(end 238.05007 -129.499868)
		(stroke
			(width 0.0635)
			(type default)
		)
		(layer "In7.Cu")
	)
	(gr_line
		(start 237.324138 -125.86335)
		(end 238.05007 -125.499876)
		(stroke
			(width 0.0635)
			(type default)
		)
		(layer "In7.Cu")
	)
	(gr_line
		(start 237.324138 -121.863358)
		(end 238.05007 -121.499884)
		(stroke
			(width 0.0635)
			(type default)
		)
		(layer "In7.Cu")
	)
	(gr_line
		(start 237.324138 -117.863366)
		(end 238.05007 -117.499892)
		(stroke
			(width 0.0635)
			(type default)
		)
		(layer "In7.Cu")
	)
	(gr_line
		(start 237.324138 -11.563604)
		(end 238.05007 -11.20013)
		(stroke
			(width 0.0635)
			(type default)
		)
		(layer "In7.Cu")
	)
	(gr_line
		(start 240.549938 -163.4998)
		(end 241.311176 -163.881054)
		(stroke
			(width 0.0635)
			(type default)
		)
		(layer "In7.Cu")
	)
	(gr_line
		(start 240.549938 -159.499808)
		(end 241.311176 -159.881062)
		(stroke
			(width 0.0635)
			(type default)
		)
		(layer "In7.Cu")
	)
	(gr_line
		(start 240.549938 -155.499816)
		(end 241.311176 -155.88107)
		(stroke
			(width 0.0635)
			(type default)
		)
		(layer "In7.Cu")
	)
	(gr_line
		(start 240.549938 -151.499824)
		(end 241.311176 -151.881078)
		(stroke
			(width 0.0635)
			(type default)
		)
		(layer "In7.Cu")
	)
	(gr_line
		(start 240.549938 -127.499872)
		(end 241.311176 -127.880872)
		(stroke
			(width 0.0635)
			(type default)
		)
		(layer "In7.Cu")
	)
	(gr_line
		(start 240.549938 -123.49988)
		(end 241.311176 -123.881134)
		(stroke
			(width 0.0635)
			(type default)
		)
		(layer "In7.Cu")
	)
	(gr_line
		(start 240.549938 -119.499888)
		(end 241.311176 -119.881142)
		(stroke
			(width 0.0635)
			(type default)
		)
		(layer "In7.Cu")
	)
	(gr_line
		(start 240.549938 -115.499896)
		(end 241.311176 -115.88115)
		(stroke
			(width 0.0635)
			(type default)
		)
		(layer "In7.Cu")
	)
	(gr_arc
		(start 241.367818 -164.051488)
		(mid 241.374795 -163.95454)
		(end 241.311176 -163.881054)
		(stroke
			(width 0.0635)
			(type default)
		)
		(layer "In7.Cu")
	)
	(gr_arc
		(start 241.367818 -160.051496)
		(mid 241.374795 -159.954548)
		(end 241.311176 -159.881062)
		(stroke
			(width 0.0635)
			(type default)
		)
		(layer "In7.Cu")
	)
	(gr_arc
		(start 241.367818 -156.051504)
		(mid 241.374795 -155.954556)
		(end 241.311176 -155.88107)
		(stroke
			(width 0.0635)
			(type default)
		)
		(layer "In7.Cu")
	)
	(gr_arc
		(start 241.367818 -152.051512)
		(mid 241.374795 -151.954564)
		(end 241.311176 -151.881078)
		(stroke
			(width 0.0635)
			(type default)
		)
		(layer "In7.Cu")
	)
	(gr_arc
		(start 241.367818 -128.051306)
		(mid 241.374795 -127.954358)
		(end 241.311176 -127.880872)
		(stroke
			(width 0.0635)
			(type default)
		)
		(layer "In7.Cu")
	)
	(gr_line
		(start 241.367818 -128.051306)
		(end 241.367818 -128.05156)
		(stroke
			(width 0.0635)
			(type default)
		)
		(layer "In7.Cu")
	)
	(gr_arc
		(start 241.367818 -124.051568)
		(mid 241.374795 -123.95462)
		(end 241.311176 -123.881134)
		(stroke
			(width 0.0635)
			(type default)
		)
		(layer "In7.Cu")
	)
	(gr_arc
		(start 241.367818 -120.051576)
		(mid 241.374795 -119.954628)
		(end 241.311176 -119.881142)
		(stroke
			(width 0.0635)
			(type default)
		)
		(layer "In7.Cu")
	)
	(gr_arc
		(start 241.367818 -116.051584)
		(mid 241.374795 -115.954636)
		(end 241.311176 -115.88115)
		(stroke
			(width 0.0635)
			(type default)
		)
		(layer "In7.Cu")
	)
	(gr_line
		(start 241.617754 -128.176782)
		(end 241.617754 -128.177036)
		(stroke
			(width 0.0635)
			(type default)
		)
		(layer "In7.Cu")
	)
	(gr_line
		(start 241.618262 -128.175512)
		(end 241.618262 -128.175766)
		(stroke
			(width 0.0635)
			(type default)
		)
		(layer "In7.Cu")
	)
	(gr_arc
		(start 241.788696 -128.11887)
		(mid 241.691749 -128.111892)
		(end 241.618262 -128.175512)
		(stroke
			(width 0.0635)
			(type default)
		)
		(layer "In7.Cu")
	)
	(gr_line
		(start 241.788696 -128.11887)
		(end 242.549934 -128.49987)
		(stroke
			(width 0.0635)
			(type default)
		)
		(layer "In7.Cu")
	)
	(gr_arc
		(start 241.800634 -164.12464)
		(mid 241.693443 -164.11705)
		(end 241.61242 -164.187632)
		(stroke
			(width 0.0635)
			(type default)
		)
		(layer "In7.Cu")
	)
	(gr_line
		(start 241.800634 -164.12464)
		(end 242.549934 -164.499798)
		(stroke
			(width 0.0635)
			(type default)
		)
		(layer "In7.Cu")
	)
	(gr_arc
		(start 241.800634 -160.124648)
		(mid 241.693444 -160.117057)
		(end 241.61242 -160.18764)
		(stroke
			(width 0.0635)
			(type default)
		)
		(layer "In7.Cu")
	)
	(gr_line
		(start 241.800634 -160.124648)
		(end 242.549934 -160.499806)
		(stroke
			(width 0.0635)
			(type default)
		)
		(layer "In7.Cu")
	)
	(gr_arc
		(start 241.800634 -156.124656)
		(mid 241.693444 -156.117064)
		(end 241.61242 -156.187648)
		(stroke
			(width 0.0635)
			(type default)
		)
		(layer "In7.Cu")
	)
	(gr_line
		(start 241.800634 -156.124656)
		(end 242.549934 -156.499814)
		(stroke
			(width 0.0635)
			(type default)
		)
		(layer "In7.Cu")
	)
	(gr_arc
		(start 241.800634 -152.124664)
		(mid 241.693445 -152.117072)
		(end 241.61242 -152.187656)
		(stroke
			(width 0.0635)
			(type default)
		)
		(layer "In7.Cu")
	)
	(gr_line
		(start 241.800634 -152.124664)
		(end 242.549934 -152.499822)
		(stroke
			(width 0.0635)
			(type default)
		)
		(layer "In7.Cu")
	)
	(gr_arc
		(start 241.800634 -124.12472)
		(mid 241.693449 -124.117123)
		(end 241.61242 -124.187712)
		(stroke
			(width 0.0635)
			(type default)
		)
		(layer "In7.Cu")
	)
	(gr_line
		(start 241.800634 -124.12472)
		(end 242.549934 -124.499878)
		(stroke
			(width 0.0635)
			(type default)
		)
		(layer "In7.Cu")
	)
	(gr_arc
		(start 241.800634 -120.124728)
		(mid 241.693449 -120.117131)
		(end 241.61242 -120.18772)
		(stroke
			(width 0.0635)
			(type default)
		)
		(layer "In7.Cu")
	)
	(gr_line
		(start 241.800634 -120.124728)
		(end 242.549934 -120.499886)
		(stroke
			(width 0.0635)
			(type default)
		)
		(layer "In7.Cu")
	)
	(gr_arc
		(start 241.800634 -116.124736)
		(mid 241.693443 -116.117146)
		(end 241.61242 -116.187728)
		(stroke
			(width 0.0635)
			(type default)
		)
		(layer "In7.Cu")
	)
	(gr_line
		(start 241.800634 -116.124736)
		(end 242.549934 -116.499894)
		(stroke
			(width 0.0635)
			(type default)
		)
		(layer "In7.Cu")
	)
	(gr_line
		(start 241.894106 -165.584124)
		(end 241.949478 -165.639496)
		(stroke
			(width 0.0635)
			(type default)
		)
		(layer "In7.Cu")
	)
	(gr_line
		(start 242.868958 -117.360192)
		(end 242.896644 -117.37467)
		(stroke
			(width 0.0635)
			(type default)
		)
		(layer "In7.Cu")
	)
	(gr_line
		(start 242.904772 -125.360176)
		(end 242.938554 -125.380242)
		(stroke
			(width 0.0635)
			(type default)
		)
		(layer "In7.Cu")
	)
	(gr_line
		(start 242.922298 -121.360184)
		(end 242.950492 -121.375424)
		(stroke
			(width 0.0635)
			(type default)
		)
		(layer "In7.Cu")
	)
	(gr_line
		(start 242.92306 -129.360168)
		(end 242.961922 -129.385822)
		(stroke
			(width 0.0635)
			(type default)
		)
		(layer "In7.Cu")
	)
	(gr_line
		(start 243.068602 -161.360104)
		(end 243.105686 -161.383726)
		(stroke
			(width 0.0635)
			(type default)
		)
		(layer "In7.Cu")
	)
	(gr_line
		(start 243.18341 -153.36012)
		(end 243.220494 -153.383742)
		(stroke
			(width 0.0635)
			(type default)
		)
		(layer "In7.Cu")
	)
	(gr_line
		(start 243.210334 -157.360112)
		(end 243.247926 -157.384242)
		(stroke
			(width 0.0635)
			(type default)
		)
		(layer "In7.Cu")
	)
	(gr_line
		(start 243.269008 -165.360096)
		(end 243.306092 -165.383718)
		(stroke
			(width 0.0635)
			(type default)
		)
		(layer "In7.Cu")
	)
	(gr_line
		(start 243.782596 -121.824242)
		(end 243.805202 -121.836434)
		(stroke
			(width 0.0635)
			(type default)
		)
		(layer "In7.Cu")
	)
	(gr_line
		(start 243.801138 -117.850666)
		(end 243.824252 -117.862858)
		(stroke
			(width 0.0635)
			(type default)
		)
		(layer "In7.Cu")
	)
	(gr_line
		(start 243.805202 -121.836434)
		(end 243.820442 -121.857008)
		(stroke
			(width 0.0635)
			(type default)
		)
		(layer "In7.Cu")
	)
	(gr_line
		(start 243.824252 -117.862858)
		(end 243.839492 -117.88394)
		(stroke
			(width 0.0635)
			(type default)
		)
		(layer "In7.Cu")
	)
	(gr_line
		(start 243.8654 -125.93193)
		(end 243.88318 -125.942344)
		(stroke
			(width 0.0635)
			(type default)
		)
		(layer "In7.Cu")
	)
	(gr_line
		(start 243.88318 -125.942344)
		(end 243.895372 -125.959108)
		(stroke
			(width 0.0635)
			(type default)
		)
		(layer "In7.Cu")
	)
	(gr_line
		(start 244.154706 -130.174492)
		(end 244.166136 -130.182112)
		(stroke
			(width 0.0635)
			(type default)
		)
		(layer "In7.Cu")
	)
	(gr_line
		(start 244.166136 -130.182112)
		(end 244.17401 -130.193034)
		(stroke
			(width 0.0635)
			(type default)
		)
		(layer "In7.Cu")
	)
	(gr_line
		(start 246.698008 -228.506782)
		(end 247.003316 -229.008686)
		(stroke
			(width 0.0635)
			(type default)
		)
		(layer "In7.Cu")
	)
	(gr_line
		(start 246.921528 -228.331522)
		(end 247.109996 -228.377496)
		(stroke
			(width 0.0635)
			(type default)
		)
		(layer "In7.Cu")
	)
	(gr_line
		(start 247.109996 -228.377496)
		(end 247.308116 -228.703124)
		(stroke
			(width 0.0635)
			(type default)
		)
		(layer "In7.Cu")
	)
	(gr_line
		(start 247.23979 -229.39756)
		(end 247.544844 -229.89921)
		(stroke
			(width 0.0635)
			(type default)
		)
		(layer "In7.Cu")
	)
	(gr_line
		(start 247.262142 -228.891846)
		(end 247.308116 -228.703124)
		(stroke
			(width 0.0635)
			(type default)
		)
		(layer "In7.Cu")
	)
	(gr_line
		(start 247.462802 -229.221284)
		(end 247.65127 -229.267258)
		(stroke
			(width 0.0635)
			(type default)
		)
		(layer "In7.Cu")
	)
	(gr_line
		(start 247.65127 -229.267258)
		(end 247.84939 -229.592886)
		(stroke
			(width 0.0635)
			(type default)
		)
		(layer "In7.Cu")
	)
	(gr_line
		(start 247.781064 -230.287322)
		(end 248.08561 -230.787956)
		(stroke
			(width 0.0635)
			(type default)
		)
		(layer "In7.Cu")
	)
	(gr_line
		(start 247.803416 -229.781608)
		(end 247.84939 -229.592886)
		(stroke
			(width 0.0635)
			(type default)
		)
		(layer "In7.Cu")
	)
	(gr_line
		(start 248.003822 -230.111046)
		(end 248.192544 -230.15702)
		(stroke
			(width 0.0635)
			(type default)
		)
		(layer "In7.Cu")
	)
	(gr_line
		(start 248.192544 -230.15702)
		(end 248.39041 -230.482648)
		(stroke
			(width 0.0635)
			(type default)
		)
		(layer "In7.Cu")
	)
	(gr_line
		(start 248.322592 -231.177592)
		(end 248.627138 -231.677972)
		(stroke
			(width 0.0635)
			(type default)
		)
		(layer "In7.Cu")
	)
	(gr_line
		(start 248.344436 -230.671116)
		(end 248.39041 -230.482648)
		(stroke
			(width 0.0635)
			(type default)
		)
		(layer "In7.Cu")
	)
	(gr_line
		(start 248.545096 -231.000808)
		(end 248.733818 -231.046782)
		(stroke
			(width 0.0635)
			(type default)
		)
		(layer "In7.Cu")
	)
	(gr_line
		(start 248.733818 -231.046782)
		(end 248.931684 -231.37241)
		(stroke
			(width 0.0635)
			(type default)
		)
		(layer "In7.Cu")
	)
	(gr_line
		(start 248.88571 -231.560878)
		(end 248.931684 -231.37241)
		(stroke
			(width 0.0635)
			(type default)
		)
		(layer "In7.Cu")
	)
	(gr_line
		(start 251.970286 -234.63377)
		(end 252.276356 -235.136944)
		(stroke
			(width 0.0635)
			(type default)
		)
		(layer "In7.Cu")
	)
	(gr_line
		(start 252.193806 -234.458764)
		(end 252.382782 -234.504738)
		(stroke
			(width 0.0635)
			(type default)
		)
		(layer "In7.Cu")
	)
	(gr_line
		(start 252.382782 -234.504738)
		(end 252.580648 -234.830366)
		(stroke
			(width 0.0635)
			(type default)
		)
		(layer "In7.Cu")
	)
	(gr_line
		(start 252.480318 -141.485874)
		(end 252.494542 -141.504924)
		(stroke
			(width 0.0635)
			(type default)
		)
		(layer "In7.Cu")
	)
	(gr_line
		(start 252.494542 -141.504924)
		(end 252.499368 -141.528546)
		(stroke
			(width 0.0635)
			(type default)
		)
		(layer "In7.Cu")
	)
	(gr_line
		(start 252.511052 -235.523278)
		(end 252.818138 -236.027976)
		(stroke
			(width 0.0635)
			(type default)
		)
		(layer "In7.Cu")
	)
	(gr_line
		(start 252.534674 -235.019088)
		(end 252.580648 -234.830366)
		(stroke
			(width 0.0635)
			(type default)
		)
		(layer "In7.Cu")
	)
	(gr_line
		(start 252.73508 -235.348526)
		(end 252.923802 -235.3945)
		(stroke
			(width 0.0635)
			(type default)
		)
		(layer "In7.Cu")
	)
	(gr_line
		(start 252.83795 -233.31805)
		(end 253.14275 -233.818938)
		(stroke
			(width 0.0635)
			(type default)
		)
		(layer "In7.Cu")
	)
	(gr_line
		(start 252.923802 -235.3945)
		(end 253.121668 -235.720128)
		(stroke
			(width 0.0635)
			(type default)
		)
		(layer "In7.Cu")
	)
	(gr_line
		(start 253.052072 -236.412786)
		(end 253.359158 -236.917738)
		(stroke
			(width 0.0635)
			(type default)
		)
		(layer "In7.Cu")
	)
	(gr_line
		(start 253.060708 -233.141774)
		(end 253.249176 -233.187748)
		(stroke
			(width 0.0635)
			(type default)
		)
		(layer "In7.Cu")
	)
	(gr_line
		(start 253.075694 -235.90885)
		(end 253.121668 -235.720128)
		(stroke
			(width 0.0635)
			(type default)
		)
		(layer "In7.Cu")
	)
	(gr_line
		(start 253.249176 -233.187748)
		(end 253.447296 -233.513376)
		(stroke
			(width 0.0635)
			(type default)
		)
		(layer "In7.Cu")
	)
	(gr_line
		(start 253.2761 -236.238288)
		(end 253.464822 -236.284262)
		(stroke
			(width 0.0635)
			(type default)
		)
		(layer "In7.Cu")
	)
	(gr_line
		(start 253.324868 -234.118658)
		(end 253.362714 -234.180888)
		(stroke
			(width 0.0635)
			(type default)
		)
		(layer "In7.Cu")
	)
	(gr_line
		(start 253.379732 -234.208828)
		(end 253.683262 -234.707938)
		(stroke
			(width 0.0635)
			(type default)
		)
		(layer "In7.Cu")
	)
	(gr_line
		(start 253.401322 -233.701844)
		(end 253.447296 -233.513376)
		(stroke
			(width 0.0635)
			(type default)
		)
		(layer "In7.Cu")
	)
	(gr_line
		(start 253.464822 -236.284262)
		(end 253.662942 -236.60989)
		(stroke
			(width 0.0635)
			(type default)
		)
		(layer "In7.Cu")
	)
	(gr_line
		(start 253.563628 -233.973624)
		(end 253.598426 -234.030774)
		(stroke
			(width 0.0635)
			(type default)
		)
		(layer "In7.Cu")
	)
	(gr_line
		(start 253.575312 -139.11961)
		(end 253.590298 -139.139676)
		(stroke
			(width 0.0635)
			(type default)
		)
		(layer "In7.Cu")
	)
	(gr_line
		(start 253.590298 -139.139676)
		(end 253.595378 -139.164314)
		(stroke
			(width 0.0635)
			(type default)
		)
		(layer "In7.Cu")
	)
	(gr_line
		(start 253.601982 -234.031536)
		(end 253.79045 -234.07751)
		(stroke
			(width 0.0635)
			(type default)
		)
		(layer "In7.Cu")
	)
	(gr_line
		(start 253.616968 -236.798866)
		(end 253.662942 -236.60989)
		(stroke
			(width 0.0635)
			(type default)
		)
		(layer "In7.Cu")
	)
	(gr_line
		(start 253.79045 -234.07751)
		(end 253.988316 -234.403138)
		(stroke
			(width 0.0635)
			(type default)
		)
		(layer "In7.Cu")
	)
	(gr_line
		(start 253.79426 -240.172494)
		(end 254.09779 -240.67135)
		(stroke
			(width 0.0635)
			(type default)
		)
		(layer "In7.Cu")
	)
	(gr_line
		(start 253.920244 -235.097574)
		(end 254.225044 -235.598462)
		(stroke
			(width 0.0635)
			(type default)
		)
		(layer "In7.Cu")
	)
	(gr_line
		(start 253.935484 -243.253006)
		(end 253.976886 -243.321332)
		(stroke
			(width 0.0635)
			(type default)
		)
		(layer "In7.Cu")
	)
	(gr_line
		(start 253.942342 -234.591352)
		(end 253.988316 -234.403138)
		(stroke
			(width 0.0635)
			(type default)
		)
		(layer "In7.Cu")
	)
	(gr_line
		(start 253.976886 -243.321332)
		(end 254.24257 -243.757958)
		(stroke
			(width 0.0635)
			(type default)
		)
		(layer "In7.Cu")
	)
	(gr_line
		(start 254.01651 -239.995456)
		(end 254.204978 -240.04143)
		(stroke
			(width 0.0635)
			(type default)
		)
		(layer "In7.Cu")
	)
	(gr_line
		(start 254.143002 -234.921298)
		(end 254.33147 -234.967272)
		(stroke
			(width 0.0635)
			(type default)
		)
		(layer "In7.Cu")
	)
	(gr_line
		(start 254.15875 -243.077746)
		(end 254.347726 -243.12372)
		(stroke
			(width 0.0635)
			(type default)
		)
		(layer "In7.Cu")
	)
	(gr_line
		(start 254.204978 -240.04143)
		(end 254.403098 -240.366804)
		(stroke
			(width 0.0635)
			(type default)
		)
		(layer "In7.Cu")
	)
	(gr_line
		(start 254.33147 -234.967272)
		(end 254.52959 -235.2929)
		(stroke
			(width 0.0635)
			(type default)
		)
		(layer "In7.Cu")
	)
	(gr_line
		(start 254.335788 -241.062764)
		(end 254.638556 -241.560604)
		(stroke
			(width 0.0635)
			(type default)
		)
		(layer "In7.Cu")
	)
	(gr_line
		(start 254.347726 -243.12372)
		(end 254.545846 -243.449348)
		(stroke
			(width 0.0635)
			(type default)
		)
		(layer "In7.Cu")
	)
	(gr_line
		(start 254.357124 -240.555526)
		(end 254.403098 -240.366804)
		(stroke
			(width 0.0635)
			(type default)
		)
		(layer "In7.Cu")
	)
	(gr_line
		(start 254.429514 -232.97134)
		(end 254.734568 -233.472736)
		(stroke
			(width 0.0635)
			(type default)
		)
		(layer "In7.Cu")
	)
	(gr_line
		(start 254.47625 -244.142006)
		(end 254.782574 -244.645434)
		(stroke
			(width 0.0635)
			(type default)
		)
		(layer "In7.Cu")
	)
	(gr_line
		(start 254.483616 -235.481368)
		(end 254.52959 -235.2929)
		(stroke
			(width 0.0635)
			(type default)
		)
		(layer "In7.Cu")
	)
	(gr_line
		(start 254.499872 -243.638324)
		(end 254.545846 -243.449348)
		(stroke
			(width 0.0635)
			(type default)
		)
		(layer "In7.Cu")
	)
	(gr_line
		(start 254.557784 -240.885218)
		(end 254.746252 -240.931192)
		(stroke
			(width 0.0635)
			(type default)
		)
		(layer "In7.Cu")
	)
	(gr_line
		(start 254.652526 -232.795318)
		(end 254.841248 -232.841292)
		(stroke
			(width 0.0635)
			(type default)
		)
		(layer "In7.Cu")
	)
	(gr_line
		(start 254.69977 -243.967508)
		(end 254.888746 -244.013482)
		(stroke
			(width 0.0635)
			(type default)
		)
		(layer "In7.Cu")
	)
	(gr_line
		(start 254.746252 -240.931192)
		(end 254.944118 -241.256566)
		(stroke
			(width 0.0635)
			(type default)
		)
		(layer "In7.Cu")
	)
	(gr_line
		(start 254.841248 -232.841292)
		(end 255.039114 -233.16692)
		(stroke
			(width 0.0635)
			(type default)
		)
		(layer "In7.Cu")
	)
	(gr_line
		(start 254.8763 -241.95151)
		(end 255.180338 -242.451382)
		(stroke
			(width 0.0635)
			(type default)
		)
		(layer "In7.Cu")
	)
	(gr_line
		(start 254.888746 -244.013482)
		(end 255.086866 -244.33911)
		(stroke
			(width 0.0635)
			(type default)
		)
		(layer "In7.Cu")
	)
	(gr_line
		(start 254.898144 -241.445034)
		(end 254.944118 -241.256566)
		(stroke
			(width 0.0635)
			(type default)
		)
		(layer "In7.Cu")
	)
	(gr_line
		(start 254.905256 -136.928098)
		(end 254.91948 -136.947148)
		(stroke
			(width 0.0635)
			(type default)
		)
		(layer "In7.Cu")
	)
	(gr_line
		(start 254.91948 -136.947148)
		(end 254.924306 -136.97077)
		(stroke
			(width 0.0635)
			(type default)
		)
		(layer "In7.Cu")
	)
	(gr_line
		(start 254.970026 -233.860086)
		(end 255.27635 -234.363768)
		(stroke
			(width 0.0635)
			(type default)
		)
		(layer "In7.Cu")
	)
	(gr_line
		(start 254.99314 -233.355388)
		(end 255.039114 -233.16692)
		(stroke
			(width 0.0635)
			(type default)
		)
		(layer "In7.Cu")
	)
	(gr_line
		(start 255.018794 -245.033546)
		(end 255.322578 -245.533164)
		(stroke
			(width 0.0635)
			(type default)
		)
		(layer "In7.Cu")
	)
	(gr_line
		(start 255.040892 -244.528086)
		(end 255.086866 -244.33911)
		(stroke
			(width 0.0635)
			(type default)
		)
		(layer "In7.Cu")
	)
	(gr_line
		(start 255.098804 -241.77498)
		(end 255.287526 -241.820954)
		(stroke
			(width 0.0635)
			(type default)
		)
		(layer "In7.Cu")
	)
	(gr_line
		(start 255.1938 -233.68508)
		(end 255.382268 -233.731054)
		(stroke
			(width 0.0635)
			(type default)
		)
		(layer "In7.Cu")
	)
	(gr_line
		(start 255.241044 -244.85727)
		(end 255.43002 -244.903244)
		(stroke
			(width 0.0635)
			(type default)
		)
		(layer "In7.Cu")
	)
	(gr_line
		(start 255.287526 -241.820954)
		(end 255.485392 -242.146328)
		(stroke
			(width 0.0635)
			(type default)
		)
		(layer "In7.Cu")
	)
	(gr_line
		(start 255.382268 -233.731054)
		(end 255.580388 -234.056682)
		(stroke
			(width 0.0635)
			(type default)
		)
		(layer "In7.Cu")
	)
	(gr_line
		(start 255.417066 -242.84051)
		(end 255.721358 -243.340636)
		(stroke
			(width 0.0635)
			(type default)
		)
		(layer "In7.Cu")
	)
	(gr_line
		(start 255.43002 -244.903244)
		(end 255.627886 -245.228872)
		(stroke
			(width 0.0635)
			(type default)
		)
		(layer "In7.Cu")
	)
	(gr_line
		(start 255.439418 -242.33505)
		(end 255.485392 -242.146328)
		(stroke
			(width 0.0635)
			(type default)
		)
		(layer "In7.Cu")
	)
	(gr_line
		(start 255.511808 -234.750864)
		(end 255.816862 -235.25226)
		(stroke
			(width 0.0635)
			(type default)
		)
		(layer "In7.Cu")
	)
	(gr_line
		(start 255.534414 -234.245404)
		(end 255.580388 -234.056682)
		(stroke
			(width 0.0635)
			(type default)
		)
		(layer "In7.Cu")
	)
	(gr_line
		(start 255.581912 -245.417594)
		(end 255.627886 -245.228872)
		(stroke
			(width 0.0635)
			(type default)
		)
		(layer "In7.Cu")
	)
	(gr_line
		(start 255.639824 -242.664488)
		(end 255.828546 -242.710462)
		(stroke
			(width 0.0635)
			(type default)
		)
		(layer "In7.Cu")
	)
	(gr_line
		(start 255.731518 -158.796228)
		(end 255.73482 -158.812484)
		(stroke
			(width 0.0635)
			(type default)
		)
		(layer "In7.Cu")
	)
	(gr_line
		(start 255.73482 -234.574842)
		(end 255.923288 -234.620816)
		(stroke
			(width 0.0635)
			(type default)
		)
		(layer "In7.Cu")
	)
	(gr_line
		(start 255.73482 -158.812484)
		(end 255.74371 -158.825946)
		(stroke
			(width 0.0635)
			(type default)
		)
		(layer "In7.Cu")
	)
	(gr_line
		(start 255.828546 -242.710462)
		(end 256.026666 -243.03609)
		(stroke
			(width 0.0635)
			(type default)
		)
		(layer "In7.Cu")
	)
	(gr_line
		(start 255.923288 -234.620816)
		(end 256.121408 -234.946444)
		(stroke
			(width 0.0635)
			(type default)
		)
		(layer "In7.Cu")
	)
	(gr_line
		(start 255.980692 -243.224812)
		(end 256.026666 -243.03609)
		(stroke
			(width 0.0635)
			(type default)
		)
		(layer "In7.Cu")
	)
	(gr_line
		(start 256.035302 -241.318288)
		(end 256.341118 -241.820954)
		(stroke
			(width 0.0635)
			(type default)
		)
		(layer "In7.Cu")
	)
	(gr_line
		(start 256.056892 -161.561272)
		(end 256.077974 -161.574734)
		(stroke
			(width 0.0635)
			(type default)
		)
		(layer "In7.Cu")
	)
	(gr_line
		(start 256.075434 -235.134912)
		(end 256.121408 -234.946444)
		(stroke
			(width 0.0635)
			(type default)
		)
		(layer "In7.Cu")
	)
	(gr_line
		(start 256.077974 -161.574734)
		(end 256.091436 -161.595816)
		(stroke
			(width 0.0635)
			(type default)
		)
		(layer "In7.Cu")
	)
	(gr_line
		(start 256.228088 -134.72668)
		(end 256.242312 -134.74573)
		(stroke
			(width 0.0635)
			(type default)
		)
		(layer "In7.Cu")
	)
	(gr_line
		(start 256.242312 -134.74573)
		(end 256.247138 -134.769352)
		(stroke
			(width 0.0635)
			(type default)
		)
		(layer "In7.Cu")
	)
	(gr_line
		(start 256.258822 -241.143028)
		(end 256.447544 -241.189002)
		(stroke
			(width 0.0635)
			(type default)
		)
		(layer "In7.Cu")
	)
	(gr_line
		(start 256.447544 -241.189002)
		(end 256.645664 -241.51463)
		(stroke
			(width 0.0635)
			(type default)
		)
		(layer "In7.Cu")
	)
	(gr_line
		(start 256.576068 -242.207288)
		(end 256.882646 -242.711478)
		(stroke
			(width 0.0635)
			(type default)
		)
		(layer "In7.Cu")
	)
	(gr_line
		(start 256.599436 -241.703352)
		(end 256.645664 -241.51463)
		(stroke
			(width 0.0635)
			(type default)
		)
		(layer "In7.Cu")
	)
	(gr_line
		(start 256.799842 -242.03279)
		(end 256.988818 -242.078764)
		(stroke
			(width 0.0635)
			(type default)
		)
		(layer "In7.Cu")
	)
	(gr_line
		(start 256.988818 -242.078764)
		(end 257.186684 -242.404392)
		(stroke
			(width 0.0635)
			(type default)
		)
		(layer "In7.Cu")
	)
	(gr_line
		(start 257.118104 -243.098574)
		(end 257.423412 -243.600732)
		(stroke
			(width 0.0635)
			(type default)
		)
		(layer "In7.Cu")
	)
	(gr_line
		(start 257.14071 -242.593368)
		(end 257.186684 -242.404392)
		(stroke
			(width 0.0635)
			(type default)
		)
		(layer "In7.Cu")
	)
	(gr_line
		(start 257.236468 -229.47376)
		(end 257.541776 -229.975664)
		(stroke
			(width 0.0635)
			(type default)
		)
		(layer "In7.Cu")
	)
	(gr_line
		(start 257.256534 -158.428182)
		(end 257.259582 -158.442914)
		(stroke
			(width 0.0635)
			(type default)
		)
		(layer "In7.Cu")
	)
	(gr_line
		(start 257.259582 -158.442914)
		(end 257.267964 -158.455614)
		(stroke
			(width 0.0635)
			(type default)
		)
		(layer "In7.Cu")
	)
	(gr_line
		(start 257.340862 -242.922552)
		(end 257.529838 -242.968526)
		(stroke
			(width 0.0635)
			(type default)
		)
		(layer "In7.Cu")
	)
	(gr_line
		(start 257.404108 -166.402512)
		(end 257.42519 -166.415974)
		(stroke
			(width 0.0635)
			(type default)
		)
		(layer "In7.Cu")
	)
	(gr_line
		(start 257.42519 -166.415974)
		(end 257.438652 -166.437056)
		(stroke
			(width 0.0635)
			(type default)
		)
		(layer "In7.Cu")
	)
	(gr_line
		(start 257.459988 -229.298754)
		(end 257.648964 -229.344982)
		(stroke
			(width 0.0635)
			(type default)
		)
		(layer "In7.Cu")
	)
	(gr_line
		(start 257.529838 -242.968526)
		(end 257.727704 -243.294154)
		(stroke
			(width 0.0635)
			(type default)
		)
		(layer "In7.Cu")
	)
	(gr_line
		(start 257.648964 -229.344982)
		(end 257.84683 -229.670356)
		(stroke
			(width 0.0635)
			(type default)
		)
		(layer "In7.Cu")
	)
	(gr_line
		(start 257.65887 -243.988082)
		(end 257.964178 -244.49024)
		(stroke
			(width 0.0635)
			(type default)
		)
		(layer "In7.Cu")
	)
	(gr_line
		(start 257.68173 -243.482876)
		(end 257.727704 -243.294154)
		(stroke
			(width 0.0635)
			(type default)
		)
		(layer "In7.Cu")
	)
	(gr_line
		(start 257.776726 -230.362252)
		(end 258.08432 -230.867966)
		(stroke
			(width 0.0635)
			(type default)
		)
		(layer "In7.Cu")
	)
	(gr_line
		(start 257.800856 -229.859078)
		(end 257.84683 -229.670356)
		(stroke
			(width 0.0635)
			(type default)
		)
		(layer "In7.Cu")
	)
	(gr_line
		(start 257.881882 -243.812314)
		(end 258.070858 -243.858288)
		(stroke
			(width 0.0635)
			(type default)
		)
		(layer "In7.Cu")
	)
	(gr_line
		(start 258.001262 -230.188516)
		(end 258.189984 -230.234744)
		(stroke
			(width 0.0635)
			(type default)
		)
		(layer "In7.Cu")
	)
	(gr_line
		(start 258.00177 -249.938286)
		(end 258.306062 -250.438666)
		(stroke
			(width 0.0635)
			(type default)
		)
		(layer "In7.Cu")
	)
	(gr_line
		(start 258.070858 -243.858288)
		(end 258.268978 -244.183916)
		(stroke
			(width 0.0635)
			(type default)
		)
		(layer "In7.Cu")
	)
	(gr_line
		(start 258.189984 -230.234744)
		(end 258.388104 -230.560118)
		(stroke
			(width 0.0635)
			(type default)
		)
		(layer "In7.Cu")
	)
	(gr_line
		(start 258.22275 -244.372638)
		(end 258.268978 -244.183916)
		(stroke
			(width 0.0635)
			(type default)
		)
		(layer "In7.Cu")
	)
	(gr_line
		(start 258.22402 -249.761756)
		(end 258.412996 -249.80773)
		(stroke
			(width 0.0635)
			(type default)
		)
		(layer "In7.Cu")
	)
	(gr_line
		(start 258.317492 -231.25176)
		(end 258.625594 -231.75849)
		(stroke
			(width 0.0635)
			(type default)
		)
		(layer "In7.Cu")
	)
	(gr_line
		(start 258.34213 -230.749094)
		(end 258.388104 -230.560118)
		(stroke
			(width 0.0635)
			(type default)
		)
		(layer "In7.Cu")
	)
	(gr_line
		(start 258.404106 -171.130214)
		(end 258.425188 -171.143676)
		(stroke
			(width 0.0635)
			(type default)
		)
		(layer "In7.Cu")
	)
	(gr_line
		(start 258.412996 -249.80773)
		(end 258.610862 -250.133358)
		(stroke
			(width 0.0635)
			(type default)
		)
		(layer "In7.Cu")
	)
	(gr_line
		(start 258.425188 -171.143676)
		(end 258.43865 -171.164758)
		(stroke
			(width 0.0635)
			(type default)
		)
		(layer "In7.Cu")
	)
	(gr_line
		(start 258.542282 -231.078278)
		(end 258.731258 -231.124252)
		(stroke
			(width 0.0635)
			(type default)
		)
		(layer "In7.Cu")
	)
	(gr_line
		(start 258.543044 -250.828556)
		(end 258.847844 -251.329444)
		(stroke
			(width 0.0635)
			(type default)
		)
		(layer "In7.Cu")
	)
	(gr_line
		(start 258.564888 -250.32208)
		(end 258.610862 -250.133358)
		(stroke
			(width 0.0635)
			(type default)
		)
		(layer "In7.Cu")
	)
	(gr_line
		(start 258.731258 -231.124252)
		(end 258.929124 -231.44988)
		(stroke
			(width 0.0635)
			(type default)
		)
		(layer "In7.Cu")
	)
	(gr_line
		(start 258.765294 -250.651518)
		(end 258.954016 -250.697492)
		(stroke
			(width 0.0635)
			(type default)
		)
		(layer "In7.Cu")
	)
	(gr_line
		(start 258.88315 -231.638602)
		(end 258.929124 -231.44988)
		(stroke
			(width 0.0635)
			(type default)
		)
		(layer "In7.Cu")
	)
	(gr_line
		(start 258.942332 -248.635774)
		(end 259.245354 -249.134122)
		(stroke
			(width 0.0635)
			(type default)
		)
		(layer "In7.Cu")
	)
	(gr_line
		(start 258.954016 -250.697492)
		(end 259.152136 -251.02312)
		(stroke
			(width 0.0635)
			(type default)
		)
		(layer "In7.Cu")
	)
	(gr_line
		(start 259.083048 -251.71654)
		(end 259.38861 -252.218698)
		(stroke
			(width 0.0635)
			(type default)
		)
		(layer "In7.Cu")
	)
	(gr_line
		(start 259.09143 -158.840424)
		(end 259.094732 -158.85668)
		(stroke
			(width 0.0635)
			(type default)
		)
		(layer "In7.Cu")
	)
	(gr_line
		(start 259.094732 -158.85668)
		(end 259.103622 -158.870142)
		(stroke
			(width 0.0635)
			(type default)
		)
		(layer "In7.Cu")
	)
	(gr_line
		(start 259.104892 -175.448468)
		(end 259.125974 -175.46193)
		(stroke
			(width 0.0635)
			(type default)
		)
		(layer "In7.Cu")
	)
	(gr_line
		(start 259.106162 -251.211842)
		(end 259.152136 -251.02312)
		(stroke
			(width 0.0635)
			(type default)
		)
		(layer "In7.Cu")
	)
	(gr_line
		(start 259.125974 -175.46193)
		(end 259.139436 -175.483012)
		(stroke
			(width 0.0635)
			(type default)
		)
		(layer "In7.Cu")
	)
	(gr_line
		(start 259.164582 -248.458736)
		(end 259.35305 -248.50471)
		(stroke
			(width 0.0635)
			(type default)
		)
		(layer "In7.Cu")
	)
	(gr_line
		(start 259.306568 -251.54128)
		(end 259.49529 -251.587254)
		(stroke
			(width 0.0635)
			(type default)
		)
		(layer "In7.Cu")
	)
	(gr_line
		(start 259.35305 -248.50471)
		(end 259.550916 -248.830084)
		(stroke
			(width 0.0635)
			(type default)
		)
		(layer "In7.Cu")
	)
	(gr_line
		(start 259.373116 -236.730794)
		(end 259.678932 -237.23346)
		(stroke
			(width 0.0635)
			(type default)
		)
		(layer "In7.Cu")
	)
	(gr_line
		(start 259.48386 -249.526044)
		(end 259.786628 -250.023884)
		(stroke
			(width 0.0635)
			(type default)
		)
		(layer "In7.Cu")
	)
	(gr_line
		(start 259.49529 -251.587254)
		(end 259.693156 -251.912882)
		(stroke
			(width 0.0635)
			(type default)
		)
		(layer "In7.Cu")
	)
	(gr_line
		(start 259.504942 -249.018552)
		(end 259.550916 -248.830084)
		(stroke
			(width 0.0635)
			(type default)
		)
		(layer "In7.Cu")
	)
	(gr_line
		(start 259.59181 -228.831394)
		(end 259.89661 -229.332536)
		(stroke
			(width 0.0635)
			(type default)
		)
		(layer "In7.Cu")
	)
	(gr_line
		(start 259.596636 -236.555788)
		(end 259.785358 -236.601762)
		(stroke
			(width 0.0635)
			(type default)
		)
		(layer "In7.Cu")
	)
	(gr_line
		(start 259.62483 -252.607318)
		(end 259.930392 -253.10973)
		(stroke
			(width 0.0635)
			(type default)
		)
		(layer "In7.Cu")
	)
	(gr_line
		(start 259.647182 -252.101604)
		(end 259.693156 -251.912882)
		(stroke
			(width 0.0635)
			(type default)
		)
		(layer "In7.Cu")
	)
	(gr_line
		(start 259.705602 -249.348498)
		(end 259.894324 -249.394472)
		(stroke
			(width 0.0635)
			(type default)
		)
		(layer "In7.Cu")
	)
	(gr_line
		(start 259.785358 -236.601762)
		(end 259.983478 -236.92739)
		(stroke
			(width 0.0635)
			(type default)
		)
		(layer "In7.Cu")
	)
	(gr_line
		(start 259.814822 -228.655372)
		(end 260.003544 -228.701346)
		(stroke
			(width 0.0635)
			(type default)
		)
		(layer "In7.Cu")
	)
	(gr_line
		(start 259.847588 -252.431042)
		(end 260.03631 -252.477016)
		(stroke
			(width 0.0635)
			(type default)
		)
		(layer "In7.Cu")
	)
	(gr_line
		(start 259.894324 -249.394472)
		(end 260.09219 -249.719846)
		(stroke
			(width 0.0635)
			(type default)
		)
		(layer "In7.Cu")
	)
	(gr_line
		(start 259.913882 -237.620302)
		(end 260.220206 -238.124238)
		(stroke
			(width 0.0635)
			(type default)
		)
		(layer "In7.Cu")
	)
	(gr_line
		(start 259.937504 -237.116112)
		(end 259.983478 -236.92739)
		(stroke
			(width 0.0635)
			(type default)
		)
		(layer "In7.Cu")
	)
	(gr_line
		(start 260.003544 -228.701346)
		(end 260.20141 -229.026974)
		(stroke
			(width 0.0635)
			(type default)
		)
		(layer "In7.Cu")
	)
	(gr_line
		(start 260.02488 -250.415552)
		(end 260.32841 -250.914662)
		(stroke
			(width 0.0635)
			(type default)
		)
		(layer "In7.Cu")
	)
	(gr_line
		(start 260.03631 -252.477016)
		(end 260.23443 -252.802644)
		(stroke
			(width 0.0635)
			(type default)
		)
		(layer "In7.Cu")
	)
	(gr_line
		(start 260.046216 -249.908568)
		(end 260.09219 -249.719846)
		(stroke
			(width 0.0635)
			(type default)
		)
		(layer "In7.Cu")
	)
	(gr_line
		(start 260.084824 -229.641908)
		(end 260.116066 -229.693216)
		(stroke
			(width 0.0635)
			(type default)
		)
		(layer "In7.Cu")
	)
	(gr_line
		(start 260.087618 -245.23827)
		(end 260.391402 -245.737634)
		(stroke
			(width 0.0635)
			(type default)
		)
		(layer "In7.Cu")
	)
	(gr_line
		(start 260.133084 -229.72141)
		(end 260.437376 -230.221536)
		(stroke
			(width 0.0635)
			(type default)
		)
		(layer "In7.Cu")
	)
	(gr_line
		(start 260.13791 -237.44555)
		(end 260.326632 -237.491524)
		(stroke
			(width 0.0635)
			(type default)
		)
		(layer "In7.Cu")
	)
	(gr_line
		(start 260.155436 -229.215442)
		(end 260.20141 -229.026974)
		(stroke
			(width 0.0635)
			(type default)
		)
		(layer "In7.Cu")
	)
	(gr_line
		(start 260.16585 -253.49708)
		(end 260.17855 -253.517654)
		(stroke
			(width 0.0635)
			(type default)
		)
		(layer "In7.Cu")
	)
	(gr_line
		(start 260.17855 -253.517654)
		(end 260.197092 -253.5301)
		(stroke
			(width 0.0635)
			(type default)
		)
		(layer "In7.Cu")
	)
	(gr_line
		(start 260.188456 -252.991366)
		(end 260.23443 -252.802644)
		(stroke
			(width 0.0635)
			(type default)
		)
		(layer "In7.Cu")
	)
	(gr_line
		(start 260.246876 -250.23826)
		(end 260.435344 -250.284234)
		(stroke
			(width 0.0635)
			(type default)
		)
		(layer "In7.Cu")
	)
	(gr_line
		(start 260.310122 -245.06174)
		(end 260.49859 -245.107714)
		(stroke
			(width 0.0635)
			(type default)
		)
		(layer "In7.Cu")
	)
	(gr_line
		(start 260.323584 -229.49662)
		(end 260.35254 -229.544372)
		(stroke
			(width 0.0635)
			(type default)
		)
		(layer "In7.Cu")
	)
	(gr_line
		(start 260.326632 -237.491524)
		(end 260.524498 -237.817152)
		(stroke
			(width 0.0635)
			(type default)
		)
		(layer "In7.Cu")
	)
	(gr_line
		(start 260.356096 -229.545134)
		(end 260.544564 -229.591108)
		(stroke
			(width 0.0635)
			(type default)
		)
		(layer "In7.Cu")
	)
	(gr_line
		(start 260.435344 -250.284234)
		(end 260.633464 -250.609608)
		(stroke
			(width 0.0635)
			(type default)
		)
		(layer "In7.Cu")
	)
	(gr_line
		(start 260.454394 -238.509048)
		(end 260.761988 -239.014762)
		(stroke
			(width 0.0635)
			(type default)
		)
		(layer "In7.Cu")
	)
	(gr_line
		(start 260.478524 -238.005874)
		(end 260.524498 -237.817152)
		(stroke
			(width 0.0635)
			(type default)
		)
		(layer "In7.Cu")
	)
	(gr_line
		(start 260.49859 -245.107714)
		(end 260.69671 -245.433342)
		(stroke
			(width 0.0635)
			(type default)
		)
		(layer "In7.Cu")
	)
	(gr_line
		(start 260.544564 -229.591108)
		(end 260.74243 -229.916736)
		(stroke
			(width 0.0635)
			(type default)
		)
		(layer "In7.Cu")
	)
	(gr_line
		(start 260.568694 -246.02948)
		(end 260.613906 -246.103648)
		(stroke
			(width 0.0635)
			(type default)
		)
		(layer "In7.Cu")
	)
	(gr_line
		(start 260.58749 -250.79833)
		(end 260.633464 -250.609608)
		(stroke
			(width 0.0635)
			(type default)
		)
		(layer "In7.Cu")
	)
	(gr_line
		(start 260.628892 -246.12854)
		(end 260.93293 -246.628412)
		(stroke
			(width 0.0635)
			(type default)
		)
		(layer "In7.Cu")
	)
	(gr_line
		(start 260.650736 -245.62181)
		(end 260.69671 -245.433342)
		(stroke
			(width 0.0635)
			(type default)
		)
		(layer "In7.Cu")
	)
	(gr_line
		(start 260.674104 -230.610918)
		(end 260.979158 -231.112314)
		(stroke
			(width 0.0635)
			(type default)
		)
		(layer "In7.Cu")
	)
	(gr_line
		(start 260.67893 -238.335312)
		(end 260.867652 -238.38154)
		(stroke
			(width 0.0635)
			(type default)
		)
		(layer "In7.Cu")
	)
	(gr_line
		(start 260.696456 -230.10495)
		(end 260.74243 -229.916736)
		(stroke
			(width 0.0635)
			(type default)
		)
		(layer "In7.Cu")
	)
	(gr_line
		(start 260.761734 -158.334964)
		(end 260.765036 -158.35122)
		(stroke
			(width 0.0635)
			(type default)
		)
		(layer "In7.Cu")
	)
	(gr_line
		(start 260.765036 -158.35122)
		(end 260.773926 -158.364682)
		(stroke
			(width 0.0635)
			(type default)
		)
		(layer "In7.Cu")
	)
	(gr_line
		(start 260.801104 -245.874032)
		(end 260.84784 -245.95074)
		(stroke
			(width 0.0635)
			(type default)
		)
		(layer "In7.Cu")
	)
	(gr_line
		(start 260.851396 -245.951502)
		(end 261.039864 -245.997476)
		(stroke
			(width 0.0635)
			(type default)
		)
		(layer "In7.Cu")
	)
	(gr_line
		(start 260.867652 -238.38154)
		(end 261.065772 -238.706914)
		(stroke
			(width 0.0635)
			(type default)
		)
		(layer "In7.Cu")
	)
	(gr_line
		(start 260.897116 -230.434896)
		(end 261.085838 -230.48087)
		(stroke
			(width 0.0635)
			(type default)
		)
		(layer "In7.Cu")
	)
	(gr_line
		(start 260.95071 -246.657622)
		(end 261.015988 -246.76481)
		(stroke
			(width 0.0635)
			(type default)
		)
		(layer "In7.Cu")
	)
	(gr_line
		(start 260.996176 -239.399826)
		(end 261.3025 -239.903762)
		(stroke
			(width 0.0635)
			(type default)
		)
		(layer "In7.Cu")
	)
	(gr_line
		(start 261.019798 -238.895636)
		(end 261.065772 -238.706914)
		(stroke
			(width 0.0635)
			(type default)
		)
		(layer "In7.Cu")
	)
	(gr_line
		(start 261.039864 -245.997476)
		(end 261.23773 -246.323104)
		(stroke
			(width 0.0635)
			(type default)
		)
		(layer "In7.Cu")
	)
	(gr_line
		(start 261.085838 -230.48087)
		(end 261.283704 -230.806498)
		(stroke
			(width 0.0635)
			(type default)
		)
		(layer "In7.Cu")
	)
	(gr_line
		(start 261.169912 -247.017794)
		(end 261.474204 -247.518174)
		(stroke
			(width 0.0635)
			(type default)
		)
		(layer "In7.Cu")
	)
	(gr_line
		(start 261.186168 -252.32487)
		(end 261.19836 -252.344936)
		(stroke
			(width 0.0635)
			(type default)
		)
		(layer "In7.Cu")
	)
	(gr_line
		(start 261.191756 -246.511318)
		(end 261.23773 -246.323104)
		(stroke
			(width 0.0635)
			(type default)
		)
		(layer "In7.Cu")
	)
	(gr_line
		(start 261.19836 -252.344936)
		(end 261.217664 -252.358144)
		(stroke
			(width 0.0635)
			(type default)
		)
		(layer "In7.Cu")
	)
	(gr_line
		(start 261.220204 -239.225074)
		(end 261.408926 -239.271302)
		(stroke
			(width 0.0635)
			(type default)
		)
		(layer "In7.Cu")
	)
	(gr_line
		(start 261.23773 -230.994966)
		(end 261.283704 -230.806498)
		(stroke
			(width 0.0635)
			(type default)
		)
		(layer "In7.Cu")
	)
	(gr_line
		(start 261.392416 -246.841264)
		(end 261.580884 -246.887238)
		(stroke
			(width 0.0635)
			(type default)
		)
		(layer "In7.Cu")
	)
	(gr_line
		(start 261.408926 -239.271302)
		(end 261.606792 -239.596676)
		(stroke
			(width 0.0635)
			(type default)
		)
		(layer "In7.Cu")
	)
	(gr_line
		(start 261.560818 -239.785398)
		(end 261.606792 -239.596676)
		(stroke
			(width 0.0635)
			(type default)
		)
		(layer "In7.Cu")
	)
	(gr_line
		(start 261.580884 -246.887238)
		(end 261.779004 -247.212866)
		(stroke
			(width 0.0635)
			(type default)
		)
		(layer "In7.Cu")
	)
	(gr_line
		(start 261.663434 -247.829324)
		(end 261.693152 -247.878346)
		(stroke
			(width 0.0635)
			(type default)
		)
		(layer "In7.Cu")
	)
	(gr_line
		(start 261.711186 -247.908064)
		(end 262.015224 -248.407936)
		(stroke
			(width 0.0635)
			(type default)
		)
		(layer "In7.Cu")
	)
	(gr_line
		(start 261.73303 -247.401334)
		(end 261.779004 -247.212866)
		(stroke
			(width 0.0635)
			(type default)
		)
		(layer "In7.Cu")
	)
	(gr_line
		(start 261.765796 -245.034054)
		(end 262.070088 -245.53418)
		(stroke
			(width 0.0635)
			(type default)
		)
		(layer "In7.Cu")
	)
	(gr_line
		(start 261.773162 -250.753626)
		(end 261.785354 -250.773692)
		(stroke
			(width 0.0635)
			(type default)
		)
		(layer "In7.Cu")
	)
	(gr_line
		(start 261.785354 -250.773692)
		(end 261.804658 -250.7869)
		(stroke
			(width 0.0635)
			(type default)
		)
		(layer "In7.Cu")
	)
	(gr_line
		(start 261.920228 -247.714008)
		(end 261.930134 -247.730264)
		(stroke
			(width 0.0635)
			(type default)
		)
		(layer "In7.Cu")
	)
	(gr_line
		(start 261.93369 -247.731026)
		(end 262.122158 -247.777)
		(stroke
			(width 0.0635)
			(type default)
		)
		(layer "In7.Cu")
	)
	(gr_line
		(start 261.988554 -244.857778)
		(end 262.177022 -244.903752)
		(stroke
			(width 0.0635)
			(type default)
		)
		(layer "In7.Cu")
	)
	(gr_line
		(start 262.00608 -237.316518)
		(end 262.31469 -237.82401)
		(stroke
			(width 0.0635)
			(type default)
		)
		(layer "In7.Cu")
	)
	(gr_line
		(start 262.122158 -247.777)
		(end 262.320024 -248.102628)
		(stroke
			(width 0.0635)
			(type default)
		)
		(layer "In7.Cu")
	)
	(gr_line
		(start 262.177022 -244.903752)
		(end 262.375142 -245.229126)
		(stroke
			(width 0.0635)
			(type default)
		)
		(layer "In7.Cu")
	)
	(gr_line
		(start 262.229346 -245.796054)
		(end 262.290052 -245.89613)
		(stroke
			(width 0.0635)
			(type default)
		)
		(layer "In7.Cu")
	)
	(gr_line
		(start 262.23087 -237.143036)
		(end 262.419592 -237.18901)
		(stroke
			(width 0.0635)
			(type default)
		)
		(layer "In7.Cu")
	)
	(gr_line
		(start 262.27405 -248.291096)
		(end 262.320024 -248.102628)
		(stroke
			(width 0.0635)
			(type default)
		)
		(layer "In7.Cu")
	)
	(gr_line
		(start 262.307578 -245.924832)
		(end 262.611108 -246.423942)
		(stroke
			(width 0.0635)
			(type default)
		)
		(layer "In7.Cu")
	)
	(gr_line
		(start 262.329168 -245.417848)
		(end 262.375142 -245.229126)
		(stroke
			(width 0.0635)
			(type default)
		)
		(layer "In7.Cu")
	)
	(gr_line
		(start 262.419592 -237.18901)
		(end 262.617712 -237.514638)
		(stroke
			(width 0.0635)
			(type default)
		)
		(layer "In7.Cu")
	)
	(gr_line
		(start 262.468106 -245.65102)
		(end 262.526272 -245.746778)
		(stroke
			(width 0.0635)
			(type default)
		)
		(layer "In7.Cu")
	)
	(gr_line
		(start 262.529828 -245.74754)
		(end 262.718296 -245.793514)
		(stroke
			(width 0.0635)
			(type default)
		)
		(layer "In7.Cu")
	)
	(gr_line
		(start 262.547354 -238.206534)
		(end 262.855202 -238.712756)
		(stroke
			(width 0.0635)
			(type default)
		)
		(layer "In7.Cu")
	)
	(gr_line
		(start 262.571738 -237.70336)
		(end 262.617712 -237.514638)
		(stroke
			(width 0.0635)
			(type default)
		)
		(layer "In7.Cu")
	)
	(gr_line
		(start 262.718296 -245.793514)
		(end 262.916162 -246.118888)
		(stroke
			(width 0.0635)
			(type default)
		)
		(layer "In7.Cu")
	)
	(gr_line
		(start 262.772144 -238.032798)
		(end 262.960866 -238.078772)
		(stroke
			(width 0.0635)
			(type default)
		)
		(layer "In7.Cu")
	)
	(gr_line
		(start 262.793226 -249.68708)
		(end 262.805418 -249.707146)
		(stroke
			(width 0.0635)
			(type default)
		)
		(layer "In7.Cu")
	)
	(gr_line
		(start 262.805418 -249.707146)
		(end 262.824722 -249.720354)
		(stroke
			(width 0.0635)
			(type default)
		)
		(layer "In7.Cu")
	)
	(gr_line
		(start 262.84809 -246.813578)
		(end 263.15289 -247.314466)
		(stroke
			(width 0.0635)
			(type default)
		)
		(layer "In7.Cu")
	)
	(gr_line
		(start 262.870188 -246.307356)
		(end 262.916162 -246.118888)
		(stroke
			(width 0.0635)
			(type default)
		)
		(layer "In7.Cu")
	)
	(gr_line
		(start 262.960866 -238.078772)
		(end 263.158732 -238.4044)
		(stroke
			(width 0.0635)
			(type default)
		)
		(layer "In7.Cu")
	)
	(gr_line
		(start 263.070848 -246.637302)
		(end 263.259316 -246.683276)
		(stroke
			(width 0.0635)
			(type default)
		)
		(layer "In7.Cu")
	)
	(gr_line
		(start 263.087866 -239.09528)
		(end 263.396984 -239.603788)
		(stroke
			(width 0.0635)
			(type default)
		)
		(layer "In7.Cu")
	)
	(gr_line
		(start 263.112758 -238.592868)
		(end 263.158732 -238.4044)
		(stroke
			(width 0.0635)
			(type default)
		)
		(layer "In7.Cu")
	)
	(gr_line
		(start 263.259316 -246.683276)
		(end 263.457436 -247.00865)
		(stroke
			(width 0.0635)
			(type default)
		)
		(layer "In7.Cu")
	)
	(gr_line
		(start 263.313164 -238.92256)
		(end 263.501886 -238.968534)
		(stroke
			(width 0.0635)
			(type default)
		)
		(layer "In7.Cu")
	)
	(gr_line
		(start 263.390126 -247.70461)
		(end 263.693148 -248.202704)
		(stroke
			(width 0.0635)
			(type default)
		)
		(layer "In7.Cu")
	)
	(gr_line
		(start 263.411462 -247.197372)
		(end 263.457436 -247.00865)
		(stroke
			(width 0.0635)
			(type default)
		)
		(layer "In7.Cu")
	)
	(gr_line
		(start 263.501886 -238.968534)
		(end 263.700006 -239.294162)
		(stroke
			(width 0.0635)
			(type default)
		)
		(layer "In7.Cu")
	)
	(gr_line
		(start 263.588754 -247.49379)
		(end 263.608566 -247.526302)
		(stroke
			(width 0.0635)
			(type default)
		)
		(layer "In7.Cu")
	)
	(gr_line
		(start 263.612122 -247.527064)
		(end 263.80059 -247.573038)
		(stroke
			(width 0.0635)
			(type default)
		)
		(layer "In7.Cu")
	)
	(gr_line
		(start 263.630918 -239.987582)
		(end 263.936734 -240.490502)
		(stroke
			(width 0.0635)
			(type default)
		)
		(layer "In7.Cu")
	)
	(gr_line
		(start 263.654032 -239.482884)
		(end 263.700006 -239.294162)
		(stroke
			(width 0.0635)
			(type default)
		)
		(layer "In7.Cu")
	)
	(gr_line
		(start 263.80059 -247.573038)
		(end 263.998456 -247.898412)
		(stroke
			(width 0.0635)
			(type default)
		)
		(layer "In7.Cu")
	)
	(gr_line
		(start 263.854438 -239.812322)
		(end 264.04316 -239.858296)
		(stroke
			(width 0.0635)
			(type default)
		)
		(layer "In7.Cu")
	)
	(gr_line
		(start 263.87933 -252.190758)
		(end 264.38225 -252.531118)
		(stroke
			(width 0.0635)
			(type default)
		)
		(layer "In7.Cu")
	)
	(gr_line
		(start 263.926828 -354.401374)
		(end 264.053828 -354.675186)
		(stroke
			(width 0.0508)
			(type default)
		)
		(layer "In7.Cu")
	)
	(gr_line
		(start 263.952482 -248.08688)
		(end 263.998456 -247.898412)
		(stroke
			(width 0.0635)
			(type default)
		)
		(layer "In7.Cu")
	)
	(gr_line
		(start 263.97966 -244.305074)
		(end 264.285476 -244.807994)
		(stroke
			(width 0.0635)
			(type default)
		)
		(layer "In7.Cu")
	)
	(gr_line
		(start 264.00887 -251.938028)
		(end 264.213594 -251.898404)
		(stroke
			(width 0.0635)
			(type default)
		)
		(layer "In7.Cu")
	)
	(gr_line
		(start 264.02919 -331.792072)
		(end 264.088118 -332.088236)
		(stroke
			(width 0.0508)
			(type default)
		)
		(layer "In7.Cu")
	)
	(gr_line
		(start 264.04316 -239.858296)
		(end 264.241026 -240.183924)
		(stroke
			(width 0.0635)
			(type default)
		)
		(layer "In7.Cu")
	)
	(gr_line
		(start 264.053828 -354.675186)
		(end 264.340086 -354.779834)
		(stroke
			(width 0.0508)
			(type default)
		)
		(layer "In7.Cu")
	)
	(gr_line
		(start 264.077704 -354.102162)
		(end 264.69213 -354.326952)
		(stroke
			(width 0.0508)
			(type default)
		)
		(layer "In7.Cu")
	)
	(gr_line
		(start 264.088118 -332.088236)
		(end 264.341356 -332.2574)
		(stroke
			(width 0.0508)
			(type default)
		)
		(layer "In7.Cu")
	)
	(gr_line
		(start 264.119614 -248.904252)
		(end 264.131806 -248.924318)
		(stroke
			(width 0.0635)
			(type default)
		)
		(layer "In7.Cu")
	)
	(gr_line
		(start 264.131806 -248.924318)
		(end 264.15111 -248.937526)
		(stroke
			(width 0.0635)
			(type default)
		)
		(layer "In7.Cu")
	)
	(gr_line
		(start 264.195052 -240.372392)
		(end 264.241026 -240.183924)
		(stroke
			(width 0.0635)
			(type default)
		)
		(layer "In7.Cu")
	)
	(gr_line
		(start 264.20318 -244.129814)
		(end 264.391648 -244.175788)
		(stroke
			(width 0.0635)
			(type default)
		)
		(layer "In7.Cu")
	)
	(gr_line
		(start 264.213594 -251.898404)
		(end 264.529062 -252.112018)
		(stroke
			(width 0.0635)
			(type default)
		)
		(layer "In7.Cu")
	)
	(gr_line
		(start 264.244582 -331.535786)
		(end 264.791698 -331.901292)
		(stroke
			(width 0.0508)
			(type default)
		)
		(layer "In7.Cu")
	)
	(gr_line
		(start 264.340086 -354.779834)
		(end 264.613898 -354.65258)
		(stroke
			(width 0.0508)
			(type default)
		)
		(layer "In7.Cu")
	)
	(gr_line
		(start 264.341356 -332.2574)
		(end 264.63752 -332.198726)
		(stroke
			(width 0.0508)
			(type default)
		)
		(layer "In7.Cu")
	)
	(gr_line
		(start 264.391648 -244.175788)
		(end 264.589768 -244.501162)
		(stroke
			(width 0.0635)
			(type default)
		)
		(layer "In7.Cu")
	)
	(gr_line
		(start 264.40384 -330.321666)
		(end 264.462768 -330.61783)
		(stroke
			(width 0.0508)
			(type default)
		)
		(layer "In7.Cu")
	)
	(gr_line
		(start 264.462768 -330.61783)
		(end 264.71626 -330.787248)
		(stroke
			(width 0.0508)
			(type default)
		)
		(layer "In7.Cu")
	)
	(gr_line
		(start 264.521442 -245.195852)
		(end 264.825988 -245.69674)
		(stroke
			(width 0.0635)
			(type default)
		)
		(layer "In7.Cu")
	)
	(gr_line
		(start 264.529062 -252.112018)
		(end 264.568432 -252.316742)
		(stroke
			(width 0.0635)
			(type default)
		)
		(layer "In7.Cu")
	)
	(gr_line
		(start 264.543794 -244.689884)
		(end 264.589768 -244.501162)
		(stroke
			(width 0.0635)
			(type default)
		)
		(layer "In7.Cu")
	)
	(gr_line
		(start 264.619486 -330.065634)
		(end 265.166602 -330.43114)
		(stroke
			(width 0.0508)
			(type default)
		)
		(layer "In7.Cu")
	)
	(gr_line
		(start 264.71626 -330.787248)
		(end 265.012424 -330.728574)
		(stroke
			(width 0.0508)
			(type default)
		)
		(layer "In7.Cu")
	)
	(gr_line
		(start 264.744454 -245.019576)
		(end 264.932922 -245.06555)
		(stroke
			(width 0.0635)
			(type default)
		)
		(layer "In7.Cu")
	)
	(gr_line
		(start 264.75055 -237.31347)
		(end 265.055604 -237.814866)
		(stroke
			(width 0.0635)
			(type default)
		)
		(layer "In7.Cu")
	)
	(gr_line
		(start 264.758932 -252.786134)
		(end 265.261852 -253.126494)
		(stroke
			(width 0.0635)
			(type default)
		)
		(layer "In7.Cu")
	)
	(gr_line
		(start 264.888218 -252.532896)
		(end 265.092942 -252.493526)
		(stroke
			(width 0.0635)
			(type default)
		)
		(layer "In7.Cu")
	)
	(gr_line
		(start 264.895076 -332.370684)
		(end 264.95375 -332.666848)
		(stroke
			(width 0.0508)
			(type default)
		)
		(layer "In7.Cu")
	)
	(gr_line
		(start 264.904474 -354.758752)
		(end 265.031982 -355.032818)
		(stroke
			(width 0.0508)
			(type default)
		)
		(layer "In7.Cu")
	)
	(gr_line
		(start 264.932922 -245.06555)
		(end 265.130788 -245.390924)
		(stroke
			(width 0.0635)
			(type default)
		)
		(layer "In7.Cu")
	)
	(gr_line
		(start 264.95375 -332.666848)
		(end 265.207242 -332.836012)
		(stroke
			(width 0.0508)
			(type default)
		)
		(layer "In7.Cu")
	)
	(gr_line
		(start 264.973562 -237.137448)
		(end 265.16203 -237.183422)
		(stroke
			(width 0.0635)
			(type default)
		)
		(layer "In7.Cu")
	)
	(gr_line
		(start 265.031982 -355.032818)
		(end 265.31824 -355.137466)
		(stroke
			(width 0.0508)
			(type default)
		)
		(layer "In7.Cu")
	)
	(gr_line
		(start 265.053064 -354.458778)
		(end 265.672824 -354.685346)
		(stroke
			(width 0.0508)
			(type default)
		)
		(layer "In7.Cu")
	)
	(gr_line
		(start 265.061954 -246.084598)
		(end 265.367516 -246.586756)
		(stroke
			(width 0.0635)
			(type default)
		)
		(layer "In7.Cu")
	)
	(gr_line
		(start 265.062716 -352.862134)
		(end 265.18997 -353.135946)
		(stroke
			(width 0.0508)
			(type default)
		)
		(layer "In7.Cu")
	)
	(gr_line
		(start 265.084814 -245.579646)
		(end 265.130788 -245.390924)
		(stroke
			(width 0.0635)
			(type default)
		)
		(layer "In7.Cu")
	)
	(gr_line
		(start 265.092942 -252.493526)
		(end 265.40841 -252.70714)
		(stroke
			(width 0.0635)
			(type default)
		)
		(layer "In7.Cu")
	)
	(gr_line
		(start 265.110214 -332.114144)
		(end 265.658092 -332.480158)
		(stroke
			(width 0.0508)
			(type default)
		)
		(layer "In7.Cu")
	)
	(gr_line
		(start 265.16203 -237.183422)
		(end 265.36015 -237.50905)
		(stroke
			(width 0.0635)
			(type default)
		)
		(layer "In7.Cu")
	)
	(gr_line
		(start 265.18997 -353.135946)
		(end 265.476228 -353.240594)
		(stroke
			(width 0.0508)
			(type default)
		)
		(layer "In7.Cu")
	)
	(gr_line
		(start 265.207242 -332.836012)
		(end 265.503406 -332.777338)
		(stroke
			(width 0.0508)
			(type default)
		)
		(layer "In7.Cu")
	)
	(gr_line
		(start 265.210798 -352.561652)
		(end 265.831066 -352.788474)
		(stroke
			(width 0.0508)
			(type default)
		)
		(layer "In7.Cu")
	)
	(gr_line
		(start 265.224006 -238.091726)
		(end 265.276584 -238.178086)
		(stroke
			(width 0.0635)
			(type default)
		)
		(layer "In7.Cu")
	)
	(gr_line
		(start 265.24585 -249.677936)
		(end 265.728704 -250.004834)
		(stroke
			(width 0.0635)
			(type default)
		)
		(layer "In7.Cu")
	)
	(gr_line
		(start 265.269726 -330.900278)
		(end 265.328654 -331.196442)
		(stroke
			(width 0.0508)
			(type default)
		)
		(layer "In7.Cu")
	)
	(gr_line
		(start 265.285474 -245.909338)
		(end 265.473942 -245.955312)
		(stroke
			(width 0.0635)
			(type default)
		)
		(layer "In7.Cu")
	)
	(gr_line
		(start 265.29157 -238.203232)
		(end 265.596624 -238.704882)
		(stroke
			(width 0.0635)
			(type default)
		)
		(layer "In7.Cu")
	)
	(gr_line
		(start 265.314176 -237.697518)
		(end 265.36015 -237.50905)
		(stroke
			(width 0.0635)
			(type default)
		)
		(layer "In7.Cu")
	)
	(gr_line
		(start 265.31824 -355.137466)
		(end 265.592306 -355.010212)
		(stroke
			(width 0.0508)
			(type default)
		)
		(layer "In7.Cu")
	)
	(gr_line
		(start 265.328654 -331.196442)
		(end 265.582146 -331.36586)
		(stroke
			(width 0.0508)
			(type default)
		)
		(layer "In7.Cu")
	)
	(gr_line
		(start 265.373358 -249.423936)
		(end 265.563858 -249.387106)
		(stroke
			(width 0.0635)
			(type default)
		)
		(layer "In7.Cu")
	)
	(gr_line
		(start 265.40841 -252.70714)
		(end 265.44778 -252.911864)
		(stroke
			(width 0.0635)
			(type default)
		)
		(layer "In7.Cu")
	)
	(gr_line
		(start 265.470132 -329.03414)
		(end 265.52906 -329.330304)
		(stroke
			(width 0.0508)
			(type default)
		)
		(layer "In7.Cu")
	)
	(gr_line
		(start 265.471148 -237.960408)
		(end 265.51128 -238.026448)
		(stroke
			(width 0.0635)
			(type default)
		)
		(layer "In7.Cu")
	)
	(gr_line
		(start 265.473942 -245.955312)
		(end 265.672062 -246.280686)
		(stroke
			(width 0.0635)
			(type default)
		)
		(layer "In7.Cu")
	)
	(gr_line
		(start 265.476228 -353.240594)
		(end 265.750294 -353.113594)
		(stroke
			(width 0.0508)
			(type default)
		)
		(layer "In7.Cu")
	)
	(gr_line
		(start 265.485372 -330.644246)
		(end 266.032488 -331.009752)
		(stroke
			(width 0.0508)
			(type default)
		)
		(layer "In7.Cu")
	)
	(gr_line
		(start 265.510264 -251.537216)
		(end 265.996166 -251.865892)
		(stroke
			(width 0.0635)
			(type default)
		)
		(layer "In7.Cu")
	)
	(gr_line
		(start 265.514836 -238.02721)
		(end 265.703304 -238.073184)
		(stroke
			(width 0.0635)
			(type default)
		)
		(layer "In7.Cu")
	)
	(gr_line
		(start 265.52906 -329.330304)
		(end 265.782298 -329.499722)
		(stroke
			(width 0.0508)
			(type default)
		)
		(layer "In7.Cu")
	)
	(gr_line
		(start 265.563858 -249.387106)
		(end 265.879326 -249.60072)
		(stroke
			(width 0.0635)
			(type default)
		)
		(layer "In7.Cu")
	)
	(gr_line
		(start 265.582146 -331.36586)
		(end 265.87831 -331.307186)
		(stroke
			(width 0.0508)
			(type default)
		)
		(layer "In7.Cu")
	)
	(gr_line
		(start 265.603736 -246.975376)
		(end 265.908282 -247.476264)
		(stroke
			(width 0.0635)
			(type default)
		)
		(layer "In7.Cu")
	)
	(gr_line
		(start 265.612626 -238.730536)
		(end 265.81608 -239.065054)
		(stroke
			(width 0.0635)
			(type default)
		)
		(layer "In7.Cu")
	)
	(gr_line
		(start 265.626088 -246.469408)
		(end 265.672062 -246.280686)
		(stroke
			(width 0.0635)
			(type default)
		)
		(layer "In7.Cu")
	)
	(gr_line
		(start 265.63955 -253.381764)
		(end 266.139676 -253.720346)
		(stroke
			(width 0.0635)
			(type default)
		)
		(layer "In7.Cu")
	)
	(gr_line
		(start 265.640058 -251.284232)
		(end 265.830304 -251.247402)
		(stroke
			(width 0.0635)
			(type default)
		)
		(layer "In7.Cu")
	)
	(gr_line
		(start 265.685778 -328.778108)
		(end 266.232132 -329.143106)
		(stroke
			(width 0.0508)
			(type default)
		)
		(layer "In7.Cu")
	)
	(gr_line
		(start 265.703304 -238.073184)
		(end 265.90117 -238.398812)
		(stroke
			(width 0.0635)
			(type default)
		)
		(layer "In7.Cu")
	)
	(gr_line
		(start 265.760962 -332.949296)
		(end 265.819636 -333.24546)
		(stroke
			(width 0.0508)
			(type default)
		)
		(layer "In7.Cu")
	)
	(gr_line
		(start 265.767566 -253.128018)
		(end 265.97229 -253.088648)
		(stroke
			(width 0.0635)
			(type default)
		)
		(layer "In7.Cu")
	)
	(gr_line
		(start 265.782298 -329.499722)
		(end 266.078462 -329.440794)
		(stroke
			(width 0.0508)
			(type default)
		)
		(layer "In7.Cu")
	)
	(gr_line
		(start 265.819636 -333.24546)
		(end 266.073128 -333.414624)
		(stroke
			(width 0.0508)
			(type default)
		)
		(layer "In7.Cu")
	)
	(gr_line
		(start 265.821922 -327.102978)
		(end 265.880596 -327.398888)
		(stroke
			(width 0.0508)
			(type default)
		)
		(layer "In7.Cu")
	)
	(gr_line
		(start 265.826748 -246.7991)
		(end 266.015216 -246.845074)
		(stroke
			(width 0.0635)
			(type default)
		)
		(layer "In7.Cu")
	)
	(gr_line
		(start 265.830304 -251.247402)
		(end 266.146026 -251.461016)
		(stroke
			(width 0.0635)
			(type default)
		)
		(layer "In7.Cu")
	)
	(gr_line
		(start 265.831828 -239.09147)
		(end 266.138152 -239.595406)
		(stroke
			(width 0.0635)
			(type default)
		)
		(layer "In7.Cu")
	)
	(gr_line
		(start 265.855196 -238.587026)
		(end 265.90117 -238.398812)
		(stroke
			(width 0.0635)
			(type default)
		)
		(layer "In7.Cu")
	)
	(gr_line
		(start 265.879326 -249.60072)
		(end 265.916156 -249.791474)
		(stroke
			(width 0.0635)
			(type default)
		)
		(layer "In7.Cu")
	)
	(gr_line
		(start 265.880596 -327.398888)
		(end 266.134088 -327.568306)
		(stroke
			(width 0.0508)
			(type default)
		)
		(layer "In7.Cu")
	)
	(gr_line
		(start 265.882628 -355.116384)
		(end 266.009882 -355.39045)
		(stroke
			(width 0.0508)
			(type default)
		)
		(layer "In7.Cu")
	)
	(gr_line
		(start 265.97229 -253.088648)
		(end 266.287758 -253.302008)
		(stroke
			(width 0.0635)
			(type default)
		)
		(layer "In7.Cu")
	)
	(gr_line
		(start 265.975846 -332.692502)
		(end 266.524232 -333.059024)
		(stroke
			(width 0.0508)
			(type default)
		)
		(layer "In7.Cu")
	)
	(gr_line
		(start 265.99642 -311.170574)
		(end 266.079224 -311.460896)
		(stroke
			(width 0.0508)
			(type default)
		)
		(layer "In7.Cu")
	)
	(gr_line
		(start 266.009882 -355.39045)
		(end 266.29614 -355.495098)
		(stroke
			(width 0.0508)
			(type default)
		)
		(layer "In7.Cu")
	)
	(gr_line
		(start 266.012168 -257.465576)
		(end 266.501118 -257.796284)
		(stroke
			(width 0.0635)
			(type default)
		)
		(layer "In7.Cu")
	)
	(gr_line
		(start 266.015216 -246.845074)
		(end 266.213082 -247.170702)
		(stroke
			(width 0.0635)
			(type default)
		)
		(layer "In7.Cu")
	)
	(gr_line
		(start 266.02182 -251.883164)
		(end 266.321286 -252.085602)
		(stroke
			(width 0.0635)
			(type default)
		)
		(layer "In7.Cu")
	)
	(gr_line
		(start 266.03071 -354.816156)
		(end 266.558268 -355.009196)
		(stroke
			(width 0.0508)
			(type default)
		)
		(layer "In7.Cu")
	)
	(gr_line
		(start 266.039092 -326.847962)
		(end 266.582906 -327.21169)
		(stroke
			(width 0.0508)
			(type default)
		)
		(layer "In7.Cu")
	)
	(gr_line
		(start 266.040616 -353.219766)
		(end 266.168124 -353.493578)
		(stroke
			(width 0.0508)
			(type default)
		)
		(layer "In7.Cu")
	)
	(gr_line
		(start 266.055856 -238.916972)
		(end 266.244324 -238.962946)
		(stroke
			(width 0.0635)
			(type default)
		)
		(layer "In7.Cu")
	)
	(gr_line
		(start 266.073128 -333.414624)
		(end 266.369292 -333.35595)
		(stroke
			(width 0.0508)
			(type default)
		)
		(layer "In7.Cu")
	)
	(gr_line
		(start 266.079224 -311.460896)
		(end 266.345416 -311.608978)
		(stroke
			(width 0.0508)
			(type default)
		)
		(layer "In7.Cu")
	)
	(gr_line
		(start 266.092178 -351.48774)
		(end 266.219178 -351.761552)
		(stroke
			(width 0.0508)
			(type default)
		)
		(layer "In7.Cu")
	)
	(gr_line
		(start 266.108942 -250.261882)
		(end 266.590018 -250.58751)
		(stroke
			(width 0.0635)
			(type default)
		)
		(layer "In7.Cu")
	)
	(gr_line
		(start 266.134088 -327.568306)
		(end 266.430252 -327.509632)
		(stroke
			(width 0.0508)
			(type default)
		)
		(layer "In7.Cu")
	)
	(gr_line
		(start 266.135612 -331.47889)
		(end 266.19454 -331.775054)
		(stroke
			(width 0.0508)
			(type default)
		)
		(layer "In7.Cu")
	)
	(gr_line
		(start 266.142978 -257.213608)
		(end 266.333732 -257.176524)
		(stroke
			(width 0.0635)
			(type default)
		)
		(layer "In7.Cu")
	)
	(gr_line
		(start 266.146026 -251.461016)
		(end 266.182602 -251.651516)
		(stroke
			(width 0.0635)
			(type default)
		)
		(layer "In7.Cu")
	)
	(gr_line
		(start 266.167108 -247.35917)
		(end 266.213082 -247.170702)
		(stroke
			(width 0.0635)
			(type default)
		)
		(layer "In7.Cu")
	)
	(gr_line
		(start 266.168124 -353.493578)
		(end 266.454382 -353.59848)
		(stroke
			(width 0.0508)
			(type default)
		)
		(layer "In7.Cu")
	)
	(gr_line
		(start 266.183364 -251.655072)
		(end 266.498832 -251.868432)
		(stroke
			(width 0.0635)
			(type default)
		)
		(layer "In7.Cu")
	)
	(gr_line
		(start 266.188952 -352.919538)
		(end 266.80795 -353.145852)
		(stroke
			(width 0.0508)
			(type default)
		)
		(layer "In7.Cu")
	)
	(gr_line
		(start 266.190984 -310.898032)
		(end 266.766294 -311.217818)
		(stroke
			(width 0.0508)
			(type default)
		)
		(layer "In7.Cu")
	)
	(gr_line
		(start 266.19454 -331.775054)
		(end 266.448032 -331.944472)
		(stroke
			(width 0.0508)
			(type default)
		)
		(layer "In7.Cu")
	)
	(gr_line
		(start 266.199874 -239.696244)
		(end 266.359132 -239.958118)
		(stroke
			(width 0.0635)
			(type default)
		)
		(layer "In7.Cu")
	)
	(gr_line
		(start 266.219178 -351.761552)
		(end 266.505436 -351.8662)
		(stroke
			(width 0.0508)
			(type default)
		)
		(layer "In7.Cu")
	)
	(gr_line
		(start 266.235942 -250.007628)
		(end 266.426442 -249.970798)
		(stroke
			(width 0.0635)
			(type default)
		)
		(layer "In7.Cu")
	)
	(gr_line
		(start 266.241022 -351.187766)
		(end 266.858242 -351.413572)
		(stroke
			(width 0.0508)
			(type default)
		)
		(layer "In7.Cu")
	)
	(gr_line
		(start 266.244324 -238.962946)
		(end 266.442444 -239.288574)
		(stroke
			(width 0.0635)
			(type default)
		)
		(layer "In7.Cu")
	)
	(gr_line
		(start 266.287758 -253.302008)
		(end 266.327128 -253.506732)
		(stroke
			(width 0.0635)
			(type default)
		)
		(layer "In7.Cu")
	)
	(gr_line
		(start 266.29614 -355.495098)
		(end 266.569952 -355.368098)
		(stroke
			(width 0.0508)
			(type default)
		)
		(layer "In7.Cu")
	)
	(gr_line
		(start 266.333732 -257.176524)
		(end 266.649454 -257.390138)
		(stroke
			(width 0.0635)
			(type default)
		)
		(layer "In7.Cu")
	)
	(gr_line
		(start 266.336018 -329.612752)
		(end 266.394946 -329.908916)
		(stroke
			(width 0.0508)
			(type default)
		)
		(layer "In7.Cu")
	)
	(gr_line
		(start 266.338304 -252.097032)
		(end 266.346178 -252.102366)
		(stroke
			(width 0.0635)
			(type default)
		)
		(layer "In7.Cu")
	)
	(gr_line
		(start 266.345416 -311.608978)
		(end 266.635992 -311.526174)
		(stroke
			(width 0.0508)
			(type default)
		)
		(layer "In7.Cu")
	)
	(gr_line
		(start 266.351258 -331.222858)
		(end 266.898374 -331.588364)
		(stroke
			(width 0.0508)
			(type default)
		)
		(layer "In7.Cu")
	)
	(gr_line
		(start 266.371578 -252.120146)
		(end 266.860274 -252.4506)
		(stroke
			(width 0.0635)
			(type default)
		)
		(layer "In7.Cu")
	)
	(gr_line
		(start 266.374372 -239.98301)
		(end 266.678156 -240.482628)
		(stroke
			(width 0.0635)
			(type default)
		)
		(layer "In7.Cu")
	)
	(gr_line
		(start 266.394946 -329.908916)
		(end 266.648184 -330.078334)
		(stroke
			(width 0.0508)
			(type default)
		)
		(layer "In7.Cu")
	)
	(gr_line
		(start 266.39647 -239.477042)
		(end 266.442444 -239.288574)
		(stroke
			(width 0.0635)
			(type default)
		)
		(layer "In7.Cu")
	)
	(gr_line
		(start 266.426442 -249.970798)
		(end 266.74191 -250.184412)
		(stroke
			(width 0.0635)
			(type default)
		)
		(layer "In7.Cu")
	)
	(gr_line
		(start 266.448032 -331.944472)
		(end 266.744196 -331.885798)
		(stroke
			(width 0.0508)
			(type default)
		)
		(layer "In7.Cu")
	)
	(gr_line
		(start 266.454382 -353.59848)
		(end 266.728194 -353.471226)
		(stroke
			(width 0.0508)
			(type default)
		)
		(layer "In7.Cu")
	)
	(gr_line
		(start 266.502388 -251.86767)
		(end 266.692888 -251.831094)
		(stroke
			(width 0.0635)
			(type default)
		)
		(layer "In7.Cu")
	)
	(gr_line
		(start 266.505436 -351.8662)
		(end 266.779248 -351.738946)
		(stroke
			(width 0.0508)
			(type default)
		)
		(layer "In7.Cu")
	)
	(gr_line
		(start 266.545568 -239.726978)
		(end 266.593574 -239.805972)
		(stroke
			(width 0.0635)
			(type default)
		)
		(layer "In7.Cu")
	)
	(gr_line
		(start 266.552172 -329.356974)
		(end 267.098018 -329.721972)
		(stroke
			(width 0.0508)
			(type default)
		)
		(layer "In7.Cu")
	)
	(gr_line
		(start 266.558268 -355.00945)
		(end 266.648184 -355.04247)
		(stroke
			(width 0.0508)
			(type default)
		)
		(layer "In7.Cu")
	)
	(gr_line
		(start 266.558268 -355.009196)
		(end 266.558268 -355.00945)
		(stroke
			(width 0.0508)
			(type default)
		)
		(layer "In7.Cu")
	)
	(gr_line
		(start 266.59713 -239.806734)
		(end 266.785598 -239.852708)
		(stroke
			(width 0.0635)
			(type default)
		)
		(layer "In7.Cu")
	)
	(gr_line
		(start 266.613894 -244.892068)
		(end 266.91971 -245.394988)
		(stroke
			(width 0.0635)
			(type default)
		)
		(layer "In7.Cu")
	)
	(gr_line
		(start 266.648184 -330.078334)
		(end 266.944348 -330.019406)
		(stroke
			(width 0.0508)
			(type default)
		)
		(layer "In7.Cu")
	)
	(gr_line
		(start 266.649454 -257.390138)
		(end 266.686284 -257.581146)
		(stroke
			(width 0.0635)
			(type default)
		)
		(layer "In7.Cu")
	)
	(gr_line
		(start 266.687808 -327.68159)
		(end 266.746482 -327.9775)
		(stroke
			(width 0.0508)
			(type default)
		)
		(layer "In7.Cu")
	)
	(gr_line
		(start 266.692634 -309.620666)
		(end 266.775438 -309.911242)
		(stroke
			(width 0.0508)
			(type default)
		)
		(layer "In7.Cu")
	)
	(gr_line
		(start 266.692888 -251.831094)
		(end 267.00861 -252.044454)
		(stroke
			(width 0.0635)
			(type default)
		)
		(layer "In7.Cu")
	)
	(gr_line
		(start 266.74191 -250.184412)
		(end 266.778486 -250.374912)
		(stroke
			(width 0.0635)
			(type default)
		)
		(layer "In7.Cu")
	)
	(gr_line
		(start 266.746482 -327.9775)
		(end 266.999974 -328.146918)
		(stroke
			(width 0.0508)
			(type default)
		)
		(layer "In7.Cu")
	)
	(gr_line
		(start 266.775438 -309.911242)
		(end 267.041884 -310.059324)
		(stroke
			(width 0.0508)
			(type default)
		)
		(layer "In7.Cu")
	)
	(gr_line
		(start 266.785598 -239.852708)
		(end 266.983464 -240.178336)
		(stroke
			(width 0.0635)
			(type default)
		)
		(layer "In7.Cu")
	)
	(gr_line
		(start 266.814808 -248.966482)
		(end 266.827 -248.986548)
		(stroke
			(width 0.0635)
			(type default)
		)
		(layer "In7.Cu")
	)
	(gr_line
		(start 266.827 -248.986548)
		(end 266.846304 -248.999756)
		(stroke
			(width 0.0635)
			(type default)
		)
		(layer "In7.Cu")
	)
	(gr_line
		(start 266.827762 -350.132142)
		(end 266.95527 -350.405954)
		(stroke
			(width 0.0508)
			(type default)
		)
		(layer "In7.Cu")
	)
	(gr_line
		(start 266.83716 -244.716808)
		(end 267.026136 -244.762782)
		(stroke
			(width 0.0635)
			(type default)
		)
		(layer "In7.Cu")
	)
	(gr_line
		(start 266.848336 -324.612254)
		(end 266.848844 -324.612508)
		(stroke
			(width 0.0508)
			(type default)
		)
		(layer "In7.Cu")
	)
	(gr_line
		(start 266.87399 -258.04876)
		(end 267.36294 -258.379722)
		(stroke
			(width 0.0635)
			(type default)
		)
		(layer "In7.Cu")
	)
	(gr_line
		(start 266.883134 -252.465586)
		(end 267.168376 -252.658626)
		(stroke
			(width 0.0635)
			(type default)
		)
		(layer "In7.Cu")
	)
	(gr_line
		(start 266.886436 -309.34787)
		(end 267.461746 -309.66791)
		(stroke
			(width 0.0508)
			(type default)
		)
		(layer "In7.Cu")
	)
	(gr_line
		(start 266.905232 -327.426828)
		(end 267.4493 -327.790556)
		(stroke
			(width 0.0508)
			(type default)
		)
		(layer "In7.Cu")
	)
	(gr_line
		(start 266.906248 -311.676542)
		(end 266.989306 -311.967118)
		(stroke
			(width 0.0508)
			(type default)
		)
		(layer "In7.Cu")
	)
	(gr_line
		(start 266.93749 -240.36655)
		(end 266.983464 -240.178336)
		(stroke
			(width 0.0635)
			(type default)
		)
		(layer "In7.Cu")
	)
	(gr_line
		(start 266.95527 -350.405954)
		(end 267.241528 -350.510602)
		(stroke
			(width 0.0508)
			(type default)
		)
		(layer "In7.Cu")
	)
	(gr_line
		(start 266.969494 -250.844558)
		(end 267.453872 -251.172218)
		(stroke
			(width 0.0635)
			(type default)
		)
		(layer "In7.Cu")
	)
	(gr_line
		(start 266.976352 -349.831914)
		(end 267.595096 -350.058228)
		(stroke
			(width 0.0508)
			(type default)
		)
		(layer "In7.Cu")
	)
	(gr_line
		(start 266.989306 -311.967118)
		(end 267.255752 -312.1152)
		(stroke
			(width 0.0508)
			(type default)
		)
		(layer "In7.Cu")
	)
	(gr_line
		(start 266.999974 -328.146918)
		(end 267.296138 -328.088244)
		(stroke
			(width 0.0508)
			(type default)
		)
		(layer "In7.Cu")
	)
	(gr_line
		(start 267.005308 -257.797046)
		(end 267.196316 -257.760216)
		(stroke
			(width 0.0635)
			(type default)
		)
		(layer "In7.Cu")
	)
	(gr_line
		(start 267.00861 -252.044454)
		(end 267.045186 -252.234954)
		(stroke
			(width 0.0635)
			(type default)
		)
		(layer "In7.Cu")
	)
	(gr_line
		(start 267.01877 -353.577398)
		(end 267.146024 -353.851464)
		(stroke
			(width 0.0508)
			(type default)
		)
		(layer "In7.Cu")
	)
	(gr_line
		(start 267.026136 -244.762782)
		(end 267.224002 -245.08841)
		(stroke
			(width 0.0635)
			(type default)
		)
		(layer "In7.Cu")
	)
	(gr_line
		(start 267.041884 -310.059324)
		(end 267.33246 -309.976774)
		(stroke
			(width 0.0508)
			(type default)
		)
		(layer "In7.Cu")
	)
	(gr_line
		(start 267.070078 -351.845372)
		(end 267.197078 -352.119184)
		(stroke
			(width 0.0508)
			(type default)
		)
		(layer "In7.Cu")
	)
	(gr_line
		(start 267.098018 -250.591066)
		(end 267.288772 -250.55449)
		(stroke
			(width 0.0635)
			(type default)
		)
		(layer "In7.Cu")
	)
	(gr_line
		(start 267.100304 -311.403746)
		(end 267.67409 -311.723024)
		(stroke
			(width 0.0508)
			(type default)
		)
		(layer "In7.Cu")
	)
	(gr_line
		(start 267.103606 -308.089808)
		(end 267.18641 -308.38013)
		(stroke
			(width 0.0508)
			(type default)
		)
		(layer "In7.Cu")
	)
	(gr_line
		(start 267.117322 -306.343812)
		(end 267.200126 -306.634134)
		(stroke
			(width 0.0508)
			(type default)
		)
		(layer "In7.Cu")
	)
	(gr_line
		(start 267.146024 -353.851464)
		(end 267.432282 -353.956112)
		(stroke
			(width 0.0508)
			(type default)
		)
		(layer "In7.Cu")
	)
	(gr_line
		(start 267.15593 -245.782846)
		(end 267.46073 -246.284242)
		(stroke
			(width 0.0635)
			(type default)
		)
		(layer "In7.Cu")
	)
	(gr_line
		(start 267.165836 -353.276662)
		(end 267.788136 -353.504246)
		(stroke
			(width 0.0508)
			(type default)
		)
		(layer "In7.Cu")
	)
	(gr_line
		(start 267.178028 -245.277132)
		(end 267.224002 -245.08841)
		(stroke
			(width 0.0635)
			(type default)
		)
		(layer "In7.Cu")
	)
	(gr_line
		(start 267.18641 -308.38013)
		(end 267.452602 -308.528466)
		(stroke
			(width 0.0508)
			(type default)
		)
		(layer "In7.Cu")
	)
	(gr_line
		(start 267.196316 -257.760216)
		(end 267.511784 -257.97383)
		(stroke
			(width 0.0635)
			(type default)
		)
		(layer "In7.Cu")
	)
	(gr_line
		(start 267.197078 -352.119184)
		(end 267.483336 -352.224086)
		(stroke
			(width 0.0508)
			(type default)
		)
		(layer "In7.Cu")
	)
	(gr_line
		(start 267.200126 -306.634134)
		(end 267.466318 -306.78247)
		(stroke
			(width 0.0508)
			(type default)
		)
		(layer "In7.Cu")
	)
	(gr_line
		(start 267.201904 -330.191364)
		(end 267.260832 -330.487528)
		(stroke
			(width 0.0508)
			(type default)
		)
		(layer "In7.Cu")
	)
	(gr_line
		(start 267.204952 -324.745096)
		(end 267.331952 -325.018908)
		(stroke
			(width 0.0508)
			(type default)
		)
		(layer "In7.Cu")
	)
	(gr_line
		(start 267.220954 -351.546414)
		(end 267.834872 -351.77095)
		(stroke
			(width 0.0508)
			(type default)
		)
		(layer "In7.Cu")
	)
	(gr_line
		(start 267.233908 -252.70333)
		(end 267.722604 -253.034038)
		(stroke
			(width 0.0635)
			(type default)
		)
		(layer "In7.Cu")
	)
	(gr_line
		(start 267.237464 -346.841826)
		(end 267.364718 -347.115638)
		(stroke
			(width 0.0508)
			(type default)
		)
		(layer "In7.Cu")
	)
	(gr_line
		(start 267.241528 -350.510602)
		(end 267.51534 -350.383602)
		(stroke
			(width 0.0508)
			(type default)
		)
		(layer "In7.Cu")
	)
	(gr_line
		(start 267.255752 -312.1152)
		(end 267.546074 -312.032396)
		(stroke
			(width 0.0508)
			(type default)
		)
		(layer "In7.Cu")
	)
	(gr_line
		(start 267.260832 -330.487528)
		(end 267.51407 -330.656946)
		(stroke
			(width 0.0508)
			(type default)
		)
		(layer "In7.Cu")
	)
	(gr_line
		(start 267.288772 -250.55449)
		(end 267.60424 -250.768104)
		(stroke
			(width 0.0635)
			(type default)
		)
		(layer "In7.Cu")
	)
	(gr_line
		(start 267.299186 -307.818028)
		(end 267.871448 -308.13629)
		(stroke
			(width 0.0508)
			(type default)
		)
		(layer "In7.Cu")
	)
	(gr_line
		(start 267.312902 -306.072032)
		(end 267.884656 -306.390294)
		(stroke
			(width 0.0508)
			(type default)
		)
		(layer "In7.Cu")
	)
	(gr_line
		(start 267.331952 -325.018908)
		(end 267.61821 -325.12381)
		(stroke
			(width 0.0508)
			(type default)
		)
		(layer "In7.Cu")
	)
	(gr_line
		(start 267.356336 -324.446392)
		(end 267.969238 -324.670674)
		(stroke
			(width 0.0508)
			(type default)
		)
		(layer "In7.Cu")
	)
	(gr_line
		(start 267.364718 -347.115638)
		(end 267.650976 -347.220286)
		(stroke
			(width 0.0508)
			(type default)
		)
		(layer "In7.Cu")
	)
	(gr_line
		(start 267.364972 -252.451108)
		(end 267.555472 -252.414532)
		(stroke
			(width 0.0635)
			(type default)
		)
		(layer "In7.Cu")
	)
	(gr_line
		(start 267.378434 -245.60657)
		(end 267.567156 -245.652544)
		(stroke
			(width 0.0635)
			(type default)
		)
		(layer "In7.Cu")
	)
	(gr_line
		(start 267.387324 -346.54236)
		(end 268.00302 -346.767658)
		(stroke
			(width 0.0508)
			(type default)
		)
		(layer "In7.Cu")
	)
	(gr_line
		(start 267.41755 -329.935332)
		(end 267.963904 -330.30033)
		(stroke
			(width 0.0508)
			(type default)
		)
		(layer "In7.Cu")
	)
	(gr_line
		(start 267.432282 -353.956112)
		(end 267.706602 -353.828858)
		(stroke
			(width 0.0508)
			(type default)
		)
		(layer "In7.Cu")
	)
	(gr_line
		(start 267.452602 -308.528466)
		(end 267.742924 -308.445662)
		(stroke
			(width 0.0508)
			(type default)
		)
		(layer "In7.Cu")
	)
	(gr_line
		(start 267.466318 -306.78247)
		(end 267.75664 -306.699666)
		(stroke
			(width 0.0508)
			(type default)
		)
		(layer "In7.Cu")
	)
	(gr_line
		(start 267.483336 -352.224086)
		(end 267.757402 -352.096832)
		(stroke
			(width 0.0508)
			(type default)
		)
		(layer "In7.Cu")
	)
	(gr_line
		(start 267.511784 -257.97383)
		(end 267.548614 -258.164584)
		(stroke
			(width 0.0635)
			(type default)
		)
		(layer "In7.Cu")
	)
	(gr_line
		(start 267.51407 -330.656946)
		(end 267.810234 -330.598018)
		(stroke
			(width 0.0508)
			(type default)
		)
		(layer "In7.Cu")
	)
	(gr_line
		(start 267.553694 -328.260202)
		(end 267.612368 -328.556112)
		(stroke
			(width 0.0508)
			(type default)
		)
		(layer "In7.Cu")
	)
	(gr_line
		(start 267.555472 -252.414532)
		(end 267.871194 -252.627892)
		(stroke
			(width 0.0635)
			(type default)
		)
		(layer "In7.Cu")
	)
	(gr_line
		(start 267.567156 -245.652544)
		(end 267.765276 -245.978172)
		(stroke
			(width 0.0635)
			(type default)
		)
		(layer "In7.Cu")
	)
	(gr_line
		(start 267.58773 -249.501406)
		(end 268.089634 -249.841258)
		(stroke
			(width 0.0635)
			(type default)
		)
		(layer "In7.Cu")
	)
	(gr_line
		(start 267.602716 -310.126888)
		(end 267.68552 -310.417464)
		(stroke
			(width 0.0508)
			(type default)
		)
		(layer "In7.Cu")
	)
	(gr_line
		(start 267.60424 -250.768104)
		(end 267.64107 -250.958858)
		(stroke
			(width 0.0635)
			(type default)
		)
		(layer "In7.Cu")
	)
	(gr_line
		(start 267.612368 -328.556112)
		(end 267.86586 -328.72553)
		(stroke
			(width 0.0508)
			(type default)
		)
		(layer "In7.Cu")
	)
	(gr_line
		(start 267.61821 -325.12381)
		(end 267.892022 -324.996556)
		(stroke
			(width 0.0508)
			(type default)
		)
		(layer "In7.Cu")
	)
	(gr_line
		(start 267.650976 -347.220286)
		(end 267.924788 -347.093286)
		(stroke
			(width 0.0508)
			(type default)
		)
		(layer "In7.Cu")
	)
	(gr_line
		(start 267.654532 -323.064632)
		(end 267.781532 -323.338444)
		(stroke
			(width 0.0508)
			(type default)
		)
		(layer "In7.Cu")
	)
	(gr_line
		(start 267.68552 -310.417464)
		(end 267.951966 -310.565546)
		(stroke
			(width 0.0508)
			(type default)
		)
		(layer "In7.Cu")
	)
	(gr_line
		(start 267.697204 -246.672862)
		(end 268.001496 -247.173496)
		(stroke
			(width 0.0635)
			(type default)
		)
		(layer "In7.Cu")
	)
	(gr_line
		(start 267.716762 -249.248168)
		(end 267.921486 -249.209052)
		(stroke
			(width 0.0635)
			(type default)
		)
		(layer "In7.Cu")
	)
	(gr_line
		(start 267.719302 -246.166894)
		(end 267.765276 -245.978172)
		(stroke
			(width 0.0635)
			(type default)
		)
		(layer "In7.Cu")
	)
	(gr_line
		(start 267.736574 -258.632452)
		(end 268.226794 -258.964176)
		(stroke
			(width 0.0635)
			(type default)
		)
		(layer "In7.Cu")
	)
	(gr_line
		(start 267.771626 -328.005948)
		(end 268.315186 -328.368914)
		(stroke
			(width 0.0508)
			(type default)
		)
		(layer "In7.Cu")
	)
	(gr_line
		(start 267.781532 -323.338444)
		(end 268.06779 -323.443346)
		(stroke
			(width 0.0508)
			(type default)
		)
		(layer "In7.Cu")
	)
	(gr_line
		(start 267.797788 -309.855108)
		(end 268.37005 -310.17337)
		(stroke
			(width 0.0508)
			(type default)
		)
		(layer "In7.Cu")
	)
	(gr_line
		(start 267.805916 -322.765928)
		(end 268.419072 -322.99021)
		(stroke
			(width 0.0508)
			(type default)
		)
		(layer "In7.Cu")
	)
	(gr_line
		(start 267.80617 -350.489774)
		(end 267.93317 -350.763586)
		(stroke
			(width 0.0508)
			(type default)
		)
		(layer "In7.Cu")
	)
	(gr_line
		(start 267.816584 -312.182764)
		(end 267.899388 -312.473086)
		(stroke
			(width 0.0508)
			(type default)
		)
		(layer "In7.Cu")
	)
	(gr_line
		(start 267.831062 -251.427742)
		(end 268.316964 -251.756418)
		(stroke
			(width 0.0635)
			(type default)
		)
		(layer "In7.Cu")
	)
	(gr_line
		(start 267.860018 -253.126494)
		(end 268.073886 -253.271274)
		(stroke
			(width 0.0635)
			(type default)
		)
		(layer "In7.Cu")
	)
	(gr_line
		(start 267.86586 -328.72553)
		(end 268.162024 -328.666856)
		(stroke
			(width 0.0508)
			(type default)
		)
		(layer "In7.Cu")
	)
	(gr_line
		(start 267.867892 -258.380738)
		(end 268.058646 -258.343908)
		(stroke
			(width 0.0635)
			(type default)
		)
		(layer "In7.Cu")
	)
	(gr_line
		(start 267.871194 -252.627892)
		(end 267.90777 -252.818646)
		(stroke
			(width 0.0635)
			(type default)
		)
		(layer "In7.Cu")
	)
	(gr_line
		(start 267.899388 -312.473086)
		(end 268.165834 -312.621422)
		(stroke
			(width 0.0508)
			(type default)
		)
		(layer "In7.Cu")
	)
	(gr_line
		(start 267.919454 -246.496332)
		(end 268.10843 -246.542306)
		(stroke
			(width 0.0635)
			(type default)
		)
		(layer "In7.Cu")
	)
	(gr_line
		(start 267.921486 -249.209052)
		(end 268.237208 -249.422412)
		(stroke
			(width 0.0635)
			(type default)
		)
		(layer "In7.Cu")
	)
	(gr_line
		(start 267.93317 -350.763586)
		(end 268.219428 -350.868234)
		(stroke
			(width 0.0508)
			(type default)
		)
		(layer "In7.Cu")
	)
	(gr_line
		(start 267.951966 -310.565546)
		(end 268.242288 -310.482996)
		(stroke
			(width 0.0508)
			(type default)
		)
		(layer "In7.Cu")
	)
	(gr_line
		(start 267.954506 -350.189546)
		(end 268.572488 -350.41586)
		(stroke
			(width 0.0508)
			(type default)
		)
		(layer "In7.Cu")
	)
	(gr_line
		(start 267.960602 -251.175012)
		(end 268.151356 -251.138182)
		(stroke
			(width 0.0635)
			(type default)
		)
		(layer "In7.Cu")
	)
	(gr_line
		(start 268.011148 -311.910222)
		(end 268.585696 -312.229754)
		(stroke
			(width 0.0508)
			(type default)
		)
		(layer "In7.Cu")
	)
	(gr_line
		(start 268.013688 -308.59603)
		(end 268.096492 -308.886606)
		(stroke
			(width 0.0508)
			(type default)
		)
		(layer "In7.Cu")
	)
	(gr_line
		(start 268.027404 -306.850288)
		(end 268.109954 -307.14061)
		(stroke
			(width 0.0508)
			(type default)
		)
		(layer "In7.Cu")
	)
	(gr_line
		(start 268.048232 -352.203258)
		(end 268.175232 -352.47707)
		(stroke
			(width 0.0508)
			(type default)
		)
		(layer "In7.Cu")
	)
	(gr_line
		(start 268.058646 -258.343908)
		(end 268.374368 -258.557522)
		(stroke
			(width 0.0635)
			(type default)
		)
		(layer "In7.Cu")
	)
	(gr_line
		(start 268.06779 -323.443346)
		(end 268.341602 -323.316092)
		(stroke
			(width 0.0508)
			(type default)
		)
		(layer "In7.Cu")
	)
	(gr_line
		(start 268.096492 -308.886606)
		(end 268.362684 -309.034688)
		(stroke
			(width 0.0508)
			(type default)
		)
		(layer "In7.Cu")
	)
	(gr_line
		(start 268.097508 -253.28753)
		(end 268.585442 -253.617476)
		(stroke
			(width 0.0635)
			(type default)
		)
		(layer "In7.Cu")
	)
	(gr_line
		(start 268.102588 -252.953266)
		(end 268.224 -253.035562)
		(stroke
			(width 0.0635)
			(type default)
		)
		(layer "In7.Cu")
	)
	(gr_line
		(start 268.10843 -246.542306)
		(end 268.306296 -246.867934)
		(stroke
			(width 0.0635)
			(type default)
		)
		(layer "In7.Cu")
	)
	(gr_line
		(start 268.109954 -307.14061)
		(end 268.3764 -307.288692)
		(stroke
			(width 0.0508)
			(type default)
		)
		(layer "In7.Cu")
	)
	(gr_line
		(start 268.151356 -251.138182)
		(end 268.466824 -251.351796)
		(stroke
			(width 0.0635)
			(type default)
		)
		(layer "In7.Cu")
	)
	(gr_line
		(start 268.165834 -312.621422)
		(end 268.456156 -312.538618)
		(stroke
			(width 0.0508)
			(type default)
		)
		(layer "In7.Cu")
	)
	(gr_line
		(start 268.175232 -352.47707)
		(end 268.46149 -352.581718)
		(stroke
			(width 0.0508)
			(type default)
		)
		(layer "In7.Cu")
	)
	(gr_line
		(start 268.182598 -325.102728)
		(end 268.310106 -325.376794)
		(stroke
			(width 0.0508)
			(type default)
		)
		(layer "In7.Cu")
	)
	(gr_line
		(start 268.19987 -351.904554)
		(end 268.81328 -352.128836)
		(stroke
			(width 0.0508)
			(type default)
		)
		(layer "In7.Cu")
	)
	(gr_line
		(start 268.207998 -308.323488)
		(end 268.781276 -308.642512)
		(stroke
			(width 0.0508)
			(type default)
		)
		(layer "In7.Cu")
	)
	(gr_line
		(start 268.215618 -347.199458)
		(end 268.342618 -347.47327)
		(stroke
			(width 0.0508)
			(type default)
		)
		(layer "In7.Cu")
	)
	(gr_line
		(start 268.219428 -350.868234)
		(end 268.49324 -350.741234)
		(stroke
			(width 0.0508)
			(type default)
		)
		(layer "In7.Cu")
	)
	(gr_line
		(start 268.222222 -306.578)
		(end 268.793976 -306.896008)
		(stroke
			(width 0.0508)
			(type default)
		)
		(layer "In7.Cu")
	)
	(gr_line
		(start 268.227556 -253.0348)
		(end 268.418056 -252.99797)
		(stroke
			(width 0.0635)
			(type default)
		)
		(layer "In7.Cu")
	)
	(gr_line
		(start 268.237208 -249.422412)
		(end 268.276578 -249.627136)
		(stroke
			(width 0.0635)
			(type default)
		)
		(layer "In7.Cu")
	)
	(gr_line
		(start 268.23797 -247.56237)
		(end 268.543278 -248.064274)
		(stroke
			(width 0.0635)
			(type default)
		)
		(layer "In7.Cu")
	)
	(gr_line
		(start 268.260322 -247.056656)
		(end 268.306296 -246.867934)
		(stroke
			(width 0.0635)
			(type default)
		)
		(layer "In7.Cu")
	)
	(gr_line
		(start 268.310106 -325.376794)
		(end 268.59611 -325.481442)
		(stroke
			(width 0.0508)
			(type default)
		)
		(layer "In7.Cu")
	)
	(gr_line
		(start 268.331188 -324.802754)
		(end 268.949932 -325.029068)
		(stroke
			(width 0.0508)
			(type default)
		)
		(layer "In7.Cu")
	)
	(gr_line
		(start 268.342618 -347.47327)
		(end 268.628876 -347.578172)
		(stroke
			(width 0.0508)
			(type default)
		)
		(layer "In7.Cu")
	)
	(gr_line
		(start 268.362684 -309.034688)
		(end 268.653006 -308.951884)
		(stroke
			(width 0.0508)
			(type default)
		)
		(layer "In7.Cu")
	)
	(gr_line
		(start 268.365478 -346.899992)
		(end 268.981174 -347.12529)
		(stroke
			(width 0.0508)
			(type default)
		)
		(layer "In7.Cu")
	)
	(gr_line
		(start 268.374368 -258.557522)
		(end 268.411198 -258.748276)
		(stroke
			(width 0.0635)
			(type default)
		)
		(layer "In7.Cu")
	)
	(gr_line
		(start 268.3764 -307.288692)
		(end 268.666468 -307.205888)
		(stroke
			(width 0.0508)
			(type default)
		)
		(layer "In7.Cu")
	)
	(gr_line
		(start 268.418056 -252.99797)
		(end 268.733524 -253.211584)
		(stroke
			(width 0.0635)
			(type default)
		)
		(layer "In7.Cu")
	)
	(gr_line
		(start 268.426946 -344.883994)
		(end 268.554454 -345.157806)
		(stroke
			(width 0.0508)
			(type default)
		)
		(layer "In7.Cu")
	)
	(gr_line
		(start 268.460728 -247.386094)
		(end 268.64945 -247.432068)
		(stroke
			(width 0.0635)
			(type default)
		)
		(layer "In7.Cu")
	)
	(gr_line
		(start 268.46149 -352.581718)
		(end 268.735048 -352.454464)
		(stroke
			(width 0.0508)
			(type default)
		)
		(layer "In7.Cu")
	)
	(gr_line
		(start 268.465554 -250.095766)
		(end 268.969998 -250.437142)
		(stroke
			(width 0.0635)
			(type default)
		)
		(layer "In7.Cu")
	)
	(gr_line
		(start 268.466824 -251.351796)
		(end 268.503654 -251.542296)
		(stroke
			(width 0.0635)
			(type default)
		)
		(layer "In7.Cu")
	)
	(gr_line
		(start 268.512798 -310.633364)
		(end 268.595602 -310.923686)
		(stroke
			(width 0.0508)
			(type default)
		)
		(layer "In7.Cu")
	)
	(gr_line
		(start 268.554454 -345.157806)
		(end 268.840712 -345.262454)
		(stroke
			(width 0.0508)
			(type default)
		)
		(layer "In7.Cu")
	)
	(gr_line
		(start 268.576552 -344.584274)
		(end 269.193518 -344.809826)
		(stroke
			(width 0.0508)
			(type default)
		)
		(layer "In7.Cu")
	)
	(gr_line
		(start 268.595602 -310.923686)
		(end 268.862048 -311.071768)
		(stroke
			(width 0.0508)
			(type default)
		)
		(layer "In7.Cu")
	)
	(gr_line
		(start 268.59611 -325.481442)
		(end 268.870176 -325.354188)
		(stroke
			(width 0.0508)
			(type default)
		)
		(layer "In7.Cu")
	)
	(gr_line
		(start 268.59611 -249.84329)
		(end 268.800834 -249.80392)
		(stroke
			(width 0.0635)
			(type default)
		)
		(layer "In7.Cu")
	)
	(gr_line
		(start 268.59992 -259.216652)
		(end 269.089378 -259.547868)
		(stroke
			(width 0.0635)
			(type default)
		)
		(layer "In7.Cu")
	)
	(gr_line
		(start 268.628876 -347.578172)
		(end 268.902688 -347.450918)
		(stroke
			(width 0.0508)
			(type default)
		)
		(layer "In7.Cu")
	)
	(gr_line
		(start 268.632178 -323.422264)
		(end 268.759686 -323.69633)
		(stroke
			(width 0.0508)
			(type default)
		)
		(layer "In7.Cu")
	)
	(gr_line
		(start 268.64945 -247.432068)
		(end 268.84757 -247.757696)
		(stroke
			(width 0.0635)
			(type default)
		)
		(layer "In7.Cu")
	)
	(gr_line
		(start 268.670024 -307.204872)
		(end 268.679168 -307.209952)
		(stroke
			(width 0.0508)
			(type default)
		)
		(layer "In7.Cu")
	)
	(gr_line
		(start 268.708124 -310.36133)
		(end 269.280894 -310.679846)
		(stroke
			(width 0.0508)
			(type default)
		)
		(layer "In7.Cu")
	)
	(gr_line
		(start 268.730222 -258.96443)
		(end 268.92123 -258.9276)
		(stroke
			(width 0.0635)
			(type default)
		)
		(layer "In7.Cu")
	)
	(gr_line
		(start 268.733524 -253.211584)
		(end 268.770608 -253.402084)
		(stroke
			(width 0.0635)
			(type default)
		)
		(layer "In7.Cu")
	)
	(gr_line
		(start 268.759686 -323.69633)
		(end 269.045944 -323.800978)
		(stroke
			(width 0.0508)
			(type default)
		)
		(layer "In7.Cu")
	)
	(gr_line
		(start 268.781784 -323.122798)
		(end 269.39875 -323.34835)
		(stroke
			(width 0.0508)
			(type default)
		)
		(layer "In7.Cu")
	)
	(gr_line
		(start 268.784324 -350.84766)
		(end 268.911324 -351.121218)
		(stroke
			(width 0.0508)
			(type default)
		)
		(layer "In7.Cu")
	)
	(gr_line
		(start 268.800834 -249.80392)
		(end 269.116302 -250.017534)
		(stroke
			(width 0.0635)
			(type default)
		)
		(layer "In7.Cu")
	)
	(gr_line
		(start 268.801596 -247.946418)
		(end 268.84757 -247.757696)
		(stroke
			(width 0.0635)
			(type default)
		)
		(layer "In7.Cu")
	)
	(gr_line
		(start 268.829282 -306.915566)
		(end 268.987778 -307.003704)
		(stroke
			(width 0.0508)
			(type default)
		)
		(layer "In7.Cu")
	)
	(gr_line
		(start 268.840712 -345.262454)
		(end 269.114524 -345.135454)
		(stroke
			(width 0.0508)
			(type default)
		)
		(layer "In7.Cu")
	)
	(gr_line
		(start 268.862048 -311.071768)
		(end 269.15237 -310.989218)
		(stroke
			(width 0.0508)
			(type default)
		)
		(layer "In7.Cu")
	)
	(gr_line
		(start 268.911324 -351.121218)
		(end 269.197582 -351.22612)
		(stroke
			(width 0.0508)
			(type default)
		)
		(layer "In7.Cu")
	)
	(gr_line
		(start 268.92123 -258.9276)
		(end 269.236698 -259.14096)
		(stroke
			(width 0.0635)
			(type default)
		)
		(layer "In7.Cu")
	)
	(gr_line
		(start 268.92377 -309.102506)
		(end 269.006574 -309.392828)
		(stroke
			(width 0.0508)
			(type default)
		)
		(layer "In7.Cu")
	)
	(gr_line
		(start 268.933676 -350.547686)
		(end 269.550896 -350.773492)
		(stroke
			(width 0.0508)
			(type default)
		)
		(layer "In7.Cu")
	)
	(gr_line
		(start 268.937486 -307.35651)
		(end 269.020036 -307.646832)
		(stroke
			(width 0.0508)
			(type default)
		)
		(layer "In7.Cu")
	)
	(gr_line
		(start 269.006574 -309.392828)
		(end 269.272766 -309.54091)
		(stroke
			(width 0.0508)
			(type default)
		)
		(layer "In7.Cu")
	)
	(gr_line
		(start 269.020036 -307.646832)
		(end 269.286482 -307.794914)
		(stroke
			(width 0.0508)
			(type default)
		)
		(layer "In7.Cu")
	)
	(gr_line
		(start 269.045944 -323.800978)
		(end 269.319756 -323.673978)
		(stroke
			(width 0.0508)
			(type default)
		)
		(layer "In7.Cu")
	)
	(gr_line
		(start 269.116302 -250.017534)
		(end 269.155672 -250.222258)
		(stroke
			(width 0.0635)
			(type default)
		)
		(layer "In7.Cu")
	)
	(gr_line
		(start 269.11808 -308.82971)
		(end 269.69339 -309.14975)
		(stroke
			(width 0.0508)
			(type default)
		)
		(layer "In7.Cu")
	)
	(gr_line
		(start 269.133828 -307.085238)
		(end 269.70482 -307.402992)
		(stroke
			(width 0.0508)
			(type default)
		)
		(layer "In7.Cu")
	)
	(gr_line
		(start 269.161006 -325.460614)
		(end 269.288006 -325.734426)
		(stroke
			(width 0.0508)
			(type default)
		)
		(layer "In7.Cu")
	)
	(gr_line
		(start 269.193518 -347.557344)
		(end 269.320772 -347.831156)
		(stroke
			(width 0.0508)
			(type default)
		)
		(layer "In7.Cu")
	)
	(gr_line
		(start 269.197582 -351.22612)
		(end 269.47114 -351.098866)
		(stroke
			(width 0.0508)
			(type default)
		)
		(layer "In7.Cu")
	)
	(gr_line
		(start 269.236698 -259.14096)
		(end 269.273782 -259.331968)
		(stroke
			(width 0.0635)
			(type default)
		)
		(layer "In7.Cu")
	)
	(gr_line
		(start 269.272766 -309.54091)
		(end 269.563342 -309.45836)
		(stroke
			(width 0.0508)
			(type default)
		)
		(layer "In7.Cu")
	)
	(gr_line
		(start 269.286482 -307.794914)
		(end 269.576804 -307.712364)
		(stroke
			(width 0.0508)
			(type default)
		)
		(layer "In7.Cu")
	)
	(gr_line
		(start 269.288006 -325.734426)
		(end 269.574264 -325.839074)
		(stroke
			(width 0.0508)
			(type default)
		)
		(layer "In7.Cu")
	)
	(gr_line
		(start 269.309342 -325.160386)
		(end 269.929102 -325.386954)
		(stroke
			(width 0.0508)
			(type default)
		)
		(layer "In7.Cu")
	)
	(gr_line
		(start 269.320772 -347.831156)
		(end 269.60703 -347.935804)
		(stroke
			(width 0.0508)
			(type default)
		)
		(layer "In7.Cu")
	)
	(gr_line
		(start 269.343378 -347.257624)
		(end 269.960598 -347.48343)
		(stroke
			(width 0.0508)
			(type default)
		)
		(layer "In7.Cu")
	)
	(gr_line
		(start 269.345156 -250.690888)
		(end 269.848076 -251.030994)
		(stroke
			(width 0.0635)
			(type default)
		)
		(layer "In7.Cu")
	)
	(gr_line
		(start 269.357602 -244.888258)
		(end 269.66164 -245.38813)
		(stroke
			(width 0.0635)
			(type default)
		)
		(layer "In7.Cu")
	)
	(gr_line
		(start 269.405354 -345.241626)
		(end 269.532354 -345.515438)
		(stroke
			(width 0.0508)
			(type default)
		)
		(layer "In7.Cu")
	)
	(gr_line
		(start 269.475458 -250.438666)
		(end 269.680182 -250.399042)
		(stroke
			(width 0.0635)
			(type default)
		)
		(layer "In7.Cu")
	)
	(gr_line
		(start 269.532354 -345.515438)
		(end 269.818612 -345.62034)
		(stroke
			(width 0.0508)
			(type default)
		)
		(layer "In7.Cu")
	)
	(gr_line
		(start 269.554706 -344.941906)
		(end 270.17218 -345.167712)
		(stroke
			(width 0.0508)
			(type default)
		)
		(layer "In7.Cu")
	)
	(gr_line
		(start 269.574264 -325.839074)
		(end 269.848076 -325.712074)
		(stroke
			(width 0.0508)
			(type default)
		)
		(layer "In7.Cu")
	)
	(gr_line
		(start 269.580106 -244.71122)
		(end 269.768574 -244.757194)
		(stroke
			(width 0.0635)
			(type default)
		)
		(layer "In7.Cu")
	)
	(gr_line
		(start 269.60703 -347.935804)
		(end 269.880842 -347.808804)
		(stroke
			(width 0.0508)
			(type default)
		)
		(layer "In7.Cu")
	)
	(gr_line
		(start 269.610586 -323.78015)
		(end 269.737586 -324.053962)
		(stroke
			(width 0.0508)
			(type default)
		)
		(layer "In7.Cu")
	)
	(gr_line
		(start 269.680182 -250.399042)
		(end 269.99565 -250.612656)
		(stroke
			(width 0.0635)
			(type default)
		)
		(layer "In7.Cu")
	)
	(gr_line
		(start 269.710408 -303.956466)
		(end 269.792958 -304.246788)
		(stroke
			(width 0.0508)
			(type default)
		)
		(layer "In7.Cu")
	)
	(gr_line
		(start 269.737586 -324.053962)
		(end 270.023844 -324.15861)
		(stroke
			(width 0.0508)
			(type default)
		)
		(layer "In7.Cu")
	)
	(gr_line
		(start 269.759938 -323.48043)
		(end 270.376142 -323.705982)
		(stroke
			(width 0.0508)
			(type default)
		)
		(layer "In7.Cu")
	)
	(gr_line
		(start 269.768574 -244.757194)
		(end 269.96644 -245.082822)
		(stroke
			(width 0.0635)
			(type default)
		)
		(layer "In7.Cu")
	)
	(gr_line
		(start 269.778988 -245.58117)
		(end 269.882366 -245.751096)
		(stroke
			(width 0.0635)
			(type default)
		)
		(layer "In7.Cu")
	)
	(gr_line
		(start 269.792958 -304.246788)
		(end 270.059404 -304.39487)
		(stroke
			(width 0.0508)
			(type default)
		)
		(layer "In7.Cu")
	)
	(gr_line
		(start 269.818612 -345.62034)
		(end 270.09217 -345.493086)
		(stroke
			(width 0.0508)
			(type default)
		)
		(layer "In7.Cu")
	)
	(gr_line
		(start 269.899384 -245.778782)
		(end 270.202914 -246.277892)
		(stroke
			(width 0.0635)
			(type default)
		)
		(layer "In7.Cu")
	)
	(gr_line
		(start 269.904972 -303.683924)
		(end 270.479266 -304.003456)
		(stroke
			(width 0.0508)
			(type default)
		)
		(layer "In7.Cu")
	)
	(gr_line
		(start 269.920466 -245.27129)
		(end 269.96644 -245.082822)
		(stroke
			(width 0.0635)
			(type default)
		)
		(layer "In7.Cu")
	)
	(gr_line
		(start 269.99565 -250.612656)
		(end 270.03502 -250.81738)
		(stroke
			(width 0.0635)
			(type default)
		)
		(layer "In7.Cu")
	)
	(gr_line
		(start 270.016732 -245.434358)
		(end 270.11757 -245.60022)
		(stroke
			(width 0.0635)
			(type default)
		)
		(layer "In7.Cu")
	)
	(gr_line
		(start 270.023844 -324.15861)
		(end 270.297656 -324.03161)
		(stroke
			(width 0.0508)
			(type default)
		)
		(layer "In7.Cu")
	)
	(gr_line
		(start 270.059404 -304.39487)
		(end 270.349726 -304.31232)
		(stroke
			(width 0.0508)
			(type default)
		)
		(layer "In7.Cu")
	)
	(gr_line
		(start 270.121126 -245.600982)
		(end 270.309594 -245.646956)
		(stroke
			(width 0.0635)
			(type default)
		)
		(layer "In7.Cu")
	)
	(gr_line
		(start 270.309594 -245.646956)
		(end 270.507714 -245.972584)
		(stroke
			(width 0.0635)
			(type default)
		)
		(layer "In7.Cu")
	)
	(gr_line
		(start 270.383 -345.599512)
		(end 270.510508 -345.873324)
		(stroke
			(width 0.0508)
			(type default)
		)
		(layer "In7.Cu")
	)
	(gr_line
		(start 270.439896 -246.667782)
		(end 270.743934 -247.167654)
		(stroke
			(width 0.0635)
			(type default)
		)
		(layer "In7.Cu")
	)
	(gr_line
		(start 270.46174 -246.161052)
		(end 270.507714 -245.972584)
		(stroke
			(width 0.0635)
			(type default)
		)
		(layer "In7.Cu")
	)
	(gr_line
		(start 270.462756 -302.90262)
		(end 270.545306 -303.192942)
		(stroke
			(width 0.0508)
			(type default)
		)
		(layer "In7.Cu")
	)
	(gr_line
		(start 270.510508 -345.873324)
		(end 270.796766 -345.977972)
		(stroke
			(width 0.0508)
			(type default)
		)
		(layer "In7.Cu")
	)
	(gr_line
		(start 270.530066 -345.298522)
		(end 271.152112 -345.526106)
		(stroke
			(width 0.0508)
			(type default)
		)
		(layer "In7.Cu")
	)
	(gr_line
		(start 270.545306 -303.192942)
		(end 270.811752 -303.341024)
		(stroke
			(width 0.0508)
			(type default)
		)
		(layer "In7.Cu")
	)
	(gr_line
		(start 270.600678 -333.56423)
		(end 270.617442 -333.570326)
		(stroke
			(width 0.0508)
			(type default)
		)
		(layer "In7.Cu")
	)
	(gr_line
		(start 270.62049 -304.462942)
		(end 270.70304 -304.75301)
		(stroke
			(width 0.0508)
			(type default)
		)
		(layer "In7.Cu")
	)
	(gr_line
		(start 270.637 -313.74842)
		(end 270.676116 -313.770264)
		(stroke
			(width 0.0508)
			(type default)
		)
		(layer "In7.Cu")
	)
	(gr_line
		(start 270.657066 -302.629824)
		(end 271.232376 -302.949864)
		(stroke
			(width 0.0508)
			(type default)
		)
		(layer "In7.Cu")
	)
	(gr_line
		(start 270.6624 -246.490744)
		(end 270.850868 -246.536718)
		(stroke
			(width 0.0635)
			(type default)
		)
		(layer "In7.Cu")
	)
	(gr_line
		(start 270.70304 -304.75301)
		(end 270.969486 -304.901346)
		(stroke
			(width 0.0508)
			(type default)
		)
		(layer "In7.Cu")
	)
	(gr_line
		(start 270.725392 -308.34838)
		(end 270.764508 -308.370224)
		(stroke
			(width 0.0508)
			(type default)
		)
		(layer "In7.Cu")
	)
	(gr_line
		(start 270.750792 -351.564194)
		(end 270.767556 -351.57029)
		(stroke
			(width 0.0508)
			(type default)
		)
		(layer "In7.Cu")
	)
	(gr_line
		(start 270.795496 -331.764132)
		(end 270.81226 -331.770228)
		(stroke
			(width 0.0508)
			(type default)
		)
		(layer "In7.Cu")
	)
	(gr_line
		(start 270.796766 -345.977972)
		(end 271.070578 -345.850972)
		(stroke
			(width 0.0508)
			(type default)
		)
		(layer "In7.Cu")
	)
	(gr_line
		(start 270.809212 -310.148478)
		(end 270.848328 -310.170322)
		(stroke
			(width 0.0508)
			(type default)
		)
		(layer "In7.Cu")
	)
	(gr_line
		(start 270.811752 -303.341024)
		(end 271.102328 -303.258474)
		(stroke
			(width 0.0508)
			(type default)
		)
		(layer "In7.Cu")
	)
	(gr_line
		(start 270.816832 -304.191416)
		(end 271.38757 -304.508916)
		(stroke
			(width 0.0508)
			(type default)
		)
		(layer "In7.Cu")
	)
	(gr_line
		(start 270.850868 -246.536718)
		(end 271.048734 -246.862346)
		(stroke
			(width 0.0635)
			(type default)
		)
		(layer "In7.Cu")
	)
	(gr_line
		(start 270.870426 -247.375426)
		(end 270.964406 -247.530366)
		(stroke
			(width 0.0635)
			(type default)
		)
		(layer "In7.Cu")
	)
	(gr_line
		(start 270.876522 -335.364328)
		(end 270.893286 -335.370424)
		(stroke
			(width 0.0508)
			(type default)
		)
		(layer "In7.Cu")
	)
	(gr_line
		(start 270.882364 -311.948576)
		(end 270.92148 -311.97042)
		(stroke
			(width 0.0508)
			(type default)
		)
		(layer "In7.Cu")
	)
	(gr_line
		(start 270.941292 -356.964234)
		(end 270.958056 -356.97033)
		(stroke
			(width 0.0508)
			(type default)
		)
		(layer "In7.Cu")
	)
	(gr_line
		(start 270.969486 -304.901346)
		(end 271.259808 -304.818542)
		(stroke
			(width 0.0508)
			(type default)
		)
		(layer "In7.Cu")
	)
	(gr_line
		(start 270.981424 -247.558052)
		(end 271.285462 -248.05767)
		(stroke
			(width 0.0635)
			(type default)
		)
		(layer "In7.Cu")
	)
	(gr_line
		(start 270.983202 -249.956066)
		(end 271.484344 -250.29541)
		(stroke
			(width 0.0635)
			(type default)
		)
		(layer "In7.Cu")
	)
	(gr_line
		(start 271.00276 -247.050814)
		(end 271.048734 -246.862346)
		(stroke
			(width 0.0635)
			(type default)
		)
		(layer "In7.Cu")
	)
	(gr_line
		(start 271.091406 -247.201182)
		(end 271.199864 -247.379744)
		(stroke
			(width 0.0635)
			(type default)
		)
		(layer "In7.Cu")
	)
	(gr_line
		(start 271.11198 -249.702574)
		(end 271.31645 -249.663204)
		(stroke
			(width 0.0635)
			(type default)
		)
		(layer "In7.Cu")
	)
	(gr_line
		(start 271.201896 -329.964288)
		(end 271.21866 -329.970384)
		(stroke
			(width 0.0508)
			(type default)
		)
		(layer "In7.Cu")
	)
	(gr_line
		(start 271.20342 -247.380506)
		(end 271.391888 -247.42648)
		(stroke
			(width 0.0635)
			(type default)
		)
		(layer "In7.Cu")
	)
	(gr_line
		(start 271.229836 -353.364292)
		(end 271.2466 -353.370388)
		(stroke
			(width 0.0508)
			(type default)
		)
		(layer "In7.Cu")
	)
	(gr_line
		(start 271.31645 -249.663204)
		(end 271.631918 -249.876564)
		(stroke
			(width 0.0635)
			(type default)
		)
		(layer "In7.Cu")
	)
	(gr_line
		(start 271.364202 -355.164136)
		(end 271.380712 -355.170232)
		(stroke
			(width 0.0508)
			(type default)
		)
		(layer "In7.Cu")
	)
	(gr_line
		(start 271.372838 -303.408842)
		(end 271.455388 -303.699164)
		(stroke
			(width 0.0508)
			(type default)
		)
		(layer "In7.Cu")
	)
	(gr_line
		(start 271.391888 -247.42648)
		(end 271.590008 -247.752108)
		(stroke
			(width 0.0635)
			(type default)
		)
		(layer "In7.Cu")
	)
	(gr_line
		(start 271.455388 -303.699164)
		(end 271.721834 -303.847246)
		(stroke
			(width 0.0508)
			(type default)
		)
		(layer "In7.Cu")
	)
	(gr_line
		(start 271.511268 -250.313444)
		(end 271.83715 -250.533662)
		(stroke
			(width 0.0635)
			(type default)
		)
		(layer "In7.Cu")
	)
	(gr_line
		(start 271.521936 -248.446798)
		(end 271.534128 -248.466864)
		(stroke
			(width 0.0635)
			(type default)
		)
		(layer "In7.Cu")
	)
	(gr_line
		(start 271.530318 -304.96891)
		(end 271.613122 -305.259486)
		(stroke
			(width 0.0508)
			(type default)
		)
		(layer "In7.Cu")
	)
	(gr_line
		(start 271.533874 -248.466864)
		(end 271.534128 -248.466864)
		(stroke
			(width 0.0635)
			(type default)
		)
		(layer "In7.Cu")
	)
	(gr_line
		(start 271.533874 -248.466864)
		(end 271.554448 -248.480834)
		(stroke
			(width 0.0635)
			(type default)
		)
		(layer "In7.Cu")
	)
	(gr_line
		(start 271.544034 -247.940576)
		(end 271.590008 -247.752108)
		(stroke
			(width 0.0635)
			(type default)
		)
		(layer "In7.Cu")
	)
	(gr_line
		(start 271.567656 -303.136554)
		(end 272.141188 -303.455578)
		(stroke
			(width 0.0508)
			(type default)
		)
		(layer "In7.Cu")
	)
	(gr_line
		(start 271.613122 -305.259486)
		(end 271.879568 -305.407568)
		(stroke
			(width 0.0508)
			(type default)
		)
		(layer "In7.Cu")
	)
	(gr_line
		(start 271.631918 -249.876564)
		(end 271.671288 -250.081288)
		(stroke
			(width 0.0635)
			(type default)
		)
		(layer "In7.Cu")
	)
	(gr_line
		(start 271.67205 -250.084844)
		(end 271.722342 -250.11888)
		(stroke
			(width 0.0635)
			(type default)
		)
		(layer "In7.Cu")
	)
	(gr_line
		(start 271.721834 -303.847246)
		(end 272.012156 -303.764696)
		(stroke
			(width 0.0508)
			(type default)
		)
		(layer "In7.Cu")
	)
	(gr_line
		(start 271.724882 -304.696622)
		(end 272.298414 -305.015646)
		(stroke
			(width 0.0508)
			(type default)
		)
		(layer "In7.Cu")
	)
	(gr_line
		(start 271.861026 -250.550172)
		(end 272.363692 -250.890532)
		(stroke
			(width 0.0635)
			(type default)
		)
		(layer "In7.Cu")
	)
	(gr_line
		(start 271.879568 -305.407568)
		(end 272.16989 -305.325018)
		(stroke
			(width 0.0508)
			(type default)
		)
		(layer "In7.Cu")
	)
	(gr_line
		(start 271.99082 -250.297442)
		(end 272.195544 -250.258326)
		(stroke
			(width 0.0635)
			(type default)
		)
		(layer "In7.Cu")
	)
	(gr_line
		(start 272.195544 -250.258326)
		(end 272.511266 -250.471686)
		(stroke
			(width 0.0635)
			(type default)
		)
		(layer "In7.Cu")
	)
	(gr_line
		(start 272.28292 -303.915064)
		(end 272.36547 -304.205386)
		(stroke
			(width 0.0508)
			(type default)
		)
		(layer "In7.Cu")
	)
	(gr_line
		(start 272.36547 -304.205386)
		(end 272.631916 -304.353722)
		(stroke
			(width 0.0508)
			(type default)
		)
		(layer "In7.Cu")
	)
	(gr_line
		(start 272.386298 -250.905518)
		(end 272.70837 -251.12345)
		(stroke
			(width 0.0635)
			(type default)
		)
		(layer "In7.Cu")
	)
	(gr_line
		(start 272.4785 -303.643284)
		(end 273.050762 -303.961546)
		(stroke
			(width 0.0508)
			(type default)
		)
		(layer "In7.Cu")
	)
	(gr_line
		(start 272.511266 -250.471686)
		(end 272.550636 -250.67641)
		(stroke
			(width 0.0635)
			(type default)
		)
		(layer "In7.Cu")
	)
	(gr_line
		(start 272.631916 -304.353722)
		(end 272.922238 -304.270918)
		(stroke
			(width 0.0508)
			(type default)
		)
		(layer "In7.Cu")
	)
	(gr_line
		(start 272.740882 -251.145548)
		(end 273.24177 -251.484638)
		(stroke
			(width 0.0635)
			(type default)
		)
		(layer "In7.Cu")
	)
	(gr_line
		(start 272.870168 -250.892564)
		(end 273.074892 -250.853194)
		(stroke
			(width 0.0635)
			(type default)
		)
		(layer "In7.Cu")
	)
	(gr_line
		(start 272.964656 -249.434858)
		(end 273.464782 -249.77344)
		(stroke
			(width 0.0635)
			(type default)
		)
		(layer "In7.Cu")
	)
	(gr_line
		(start 273.074892 -250.853194)
		(end 273.39036 -251.066808)
		(stroke
			(width 0.0635)
			(type default)
		)
		(layer "In7.Cu")
	)
	(gr_line
		(start 273.092926 -249.181366)
		(end 273.29765 -249.141996)
		(stroke
			(width 0.0635)
			(type default)
		)
		(layer "In7.Cu")
	)
	(gr_line
		(start 273.119342 -258.443476)
		(end 273.602704 -258.770628)
		(stroke
			(width 0.0635)
			(type default)
		)
		(layer "In7.Cu")
	)
	(gr_line
		(start 273.247612 -258.189984)
		(end 273.438112 -258.153408)
		(stroke
			(width 0.0635)
			(type default)
		)
		(layer "In7.Cu")
	)
	(gr_line
		(start 273.263614 -251.499116)
		(end 274.739862 -252.498606)
		(stroke
			(width 0.0635)
			(type default)
		)
		(layer "In7.Cu")
	)
	(gr_line
		(start 273.29765 -249.141996)
		(end 273.613118 -249.355356)
		(stroke
			(width 0.0635)
			(type default)
		)
		(layer "In7.Cu")
	)
	(gr_line
		(start 273.39036 -251.066808)
		(end 273.42973 -251.271532)
		(stroke
			(width 0.0635)
			(type default)
		)
		(layer "In7.Cu")
	)
	(gr_line
		(start 273.421856 -256.88925)
		(end 273.9263 -257.230626)
		(stroke
			(width 0.0635)
			(type default)
		)
		(layer "In7.Cu")
	)
	(gr_line
		(start 273.425158 -255.213358)
		(end 273.926808 -255.552702)
		(stroke
			(width 0.0635)
			(type default)
		)
		(layer "In7.Cu")
	)
	(gr_line
		(start 273.430492 -251.275088)
		(end 274.949158 -252.302772)
		(stroke
			(width 0.0635)
			(type default)
		)
		(layer "In7.Cu")
	)
	(gr_line
		(start 273.438112 -258.153408)
		(end 273.753834 -258.366768)
		(stroke
			(width 0.0635)
			(type default)
		)
		(layer "In7.Cu")
	)
	(gr_line
		(start 273.55165 -256.63652)
		(end 273.756374 -256.59715)
		(stroke
			(width 0.0635)
			(type default)
		)
		(layer "In7.Cu")
	)
	(gr_line
		(start 273.554698 -254.960374)
		(end 273.759168 -254.921004)
		(stroke
			(width 0.0635)
			(type default)
		)
		(layer "In7.Cu")
	)
	(gr_line
		(start 273.613118 -249.355356)
		(end 273.652488 -249.560334)
		(stroke
			(width 0.0635)
			(type default)
		)
		(layer "In7.Cu")
	)
	(gr_line
		(start 273.702272 -253.639574)
		(end 274.188936 -253.969012)
		(stroke
			(width 0.0635)
			(type default)
		)
		(layer "In7.Cu")
	)
	(gr_line
		(start 273.738594 -262.693658)
		(end 274.241006 -263.033764)
		(stroke
			(width 0.0635)
			(type default)
		)
		(layer "In7.Cu")
	)
	(gr_line
		(start 273.753834 -258.366768)
		(end 273.79041 -258.557522)
		(stroke
			(width 0.0635)
			(type default)
		)
		(layer "In7.Cu")
	)
	(gr_line
		(start 273.756374 -256.59715)
		(end 274.072096 -256.81051)
		(stroke
			(width 0.0635)
			(type default)
		)
		(layer "In7.Cu")
	)
	(gr_line
		(start 273.759168 -254.921004)
		(end 274.074636 -255.134364)
		(stroke
			(width 0.0635)
			(type default)
		)
		(layer "In7.Cu")
	)
	(gr_line
		(start 273.7866 -304.748692)
		(end 273.824954 -304.770282)
		(stroke
			(width 0.0508)
			(type default)
		)
		(layer "In7.Cu")
	)
	(gr_line
		(start 273.831558 -253.38659)
		(end 274.022312 -253.350014)
		(stroke
			(width 0.0635)
			(type default)
		)
		(layer "In7.Cu")
	)
	(gr_line
		(start 273.841718 -250.02871)
		(end 274.344892 -250.369324)
		(stroke
			(width 0.0635)
			(type default)
		)
		(layer "In7.Cu")
	)
	(gr_line
		(start 273.868388 -262.441182)
		(end 274.073112 -262.401558)
		(stroke
			(width 0.0635)
			(type default)
		)
		(layer "In7.Cu")
	)
	(gr_line
		(start 273.953986 -255.571244)
		(end 273.961098 -255.57607)
		(stroke
			(width 0.0635)
			(type default)
		)
		(layer "In7.Cu")
	)
	(gr_line
		(start 273.97202 -249.776488)
		(end 274.176998 -249.737118)
		(stroke
			(width 0.0635)
			(type default)
		)
		(layer "In7.Cu")
	)
	(gr_line
		(start 273.98218 -259.027422)
		(end 274.465796 -259.354574)
		(stroke
			(width 0.0635)
			(type default)
		)
		(layer "In7.Cu")
	)
	(gr_line
		(start 274.022312 -253.350014)
		(end 274.33778 -253.563628)
		(stroke
			(width 0.0635)
			(type default)
		)
		(layer "In7.Cu")
	)
	(gr_line
		(start 274.072096 -256.81051)
		(end 274.11172 -257.015488)
		(stroke
			(width 0.0635)
			(type default)
		)
		(layer "In7.Cu")
	)
	(gr_line
		(start 274.073112 -262.401558)
		(end 274.38858 -262.614918)
		(stroke
			(width 0.0635)
			(type default)
		)
		(layer "In7.Cu")
	)
	(gr_line
		(start 274.074636 -255.134364)
		(end 274.114006 -255.339088)
		(stroke
			(width 0.0635)
			(type default)
		)
		(layer "In7.Cu")
	)
	(gr_line
		(start 274.080224 -261.060946)
		(end 274.583652 -261.401306)
		(stroke
			(width 0.0635)
			(type default)
		)
		(layer "In7.Cu")
	)
	(gr_line
		(start 274.110196 -258.773676)
		(end 274.300696 -258.736846)
		(stroke
			(width 0.0635)
			(type default)
		)
		(layer "In7.Cu")
	)
	(gr_line
		(start 274.114768 -255.342644)
		(end 274.142454 -255.361186)
		(stroke
			(width 0.0635)
			(type default)
		)
		(layer "In7.Cu")
	)
	(gr_line
		(start 274.176998 -249.737118)
		(end 274.492466 -249.950478)
		(stroke
			(width 0.0635)
			(type default)
		)
		(layer "In7.Cu")
	)
	(gr_line
		(start 274.21078 -260.808978)
		(end 274.415758 -260.769354)
		(stroke
			(width 0.0635)
			(type default)
		)
		(layer "In7.Cu")
	)
	(gr_line
		(start 274.300696 -258.736846)
		(end 274.616164 -258.95046)
		(stroke
			(width 0.0635)
			(type default)
		)
		(layer "In7.Cu")
	)
	(gr_line
		(start 274.30222 -257.484626)
		(end 274.803616 -257.823716)
		(stroke
			(width 0.0635)
			(type default)
		)
		(layer "In7.Cu")
	)
	(gr_line
		(start 274.30349 -255.807718)
		(end 274.807172 -256.148586)
		(stroke
			(width 0.0635)
			(type default)
		)
		(layer "In7.Cu")
	)
	(gr_line
		(start 274.33778 -253.563628)
		(end 274.374864 -253.754382)
		(stroke
			(width 0.0635)
			(type default)
		)
		(layer "In7.Cu")
	)
	(gr_line
		(start 274.375118 -306.54879)
		(end 274.413472 -306.57038)
		(stroke
			(width 0.0508)
			(type default)
		)
		(layer "In7.Cu")
	)
	(gr_line
		(start 274.38858 -262.614918)
		(end 274.42795 -262.819896)
		(stroke
			(width 0.0635)
			(type default)
		)
		(layer "In7.Cu")
	)
	(gr_line
		(start 274.415758 -260.769354)
		(end 274.731226 -260.982968)
		(stroke
			(width 0.0635)
			(type default)
		)
		(layer "In7.Cu")
	)
	(gr_line
		(start 274.430998 -257.231388)
		(end 274.635976 -257.192018)
		(stroke
			(width 0.0635)
			(type default)
		)
		(layer "In7.Cu")
	)
	(gr_line
		(start 274.433792 -255.555496)
		(end 274.638516 -255.515872)
		(stroke
			(width 0.0635)
			(type default)
		)
		(layer "In7.Cu")
	)
	(gr_line
		(start 274.492466 -249.950478)
		(end 274.531836 -250.155202)
		(stroke
			(width 0.0635)
			(type default)
		)
		(layer "In7.Cu")
	)
	(gr_line
		(start 274.564348 -254.223012)
		(end 275.050758 -254.552196)
		(stroke
			(width 0.0635)
			(type default)
		)
		(layer "In7.Cu")
	)
	(gr_line
		(start 274.616164 -258.95046)
		(end 274.652994 -259.141214)
		(stroke
			(width 0.0635)
			(type default)
		)
		(layer "In7.Cu")
	)
	(gr_line
		(start 274.617688 -263.288526)
		(end 275.12137 -263.629394)
		(stroke
			(width 0.0635)
			(type default)
		)
		(layer "In7.Cu")
	)
	(gr_line
		(start 274.635976 -257.192018)
		(end 274.951444 -257.405378)
		(stroke
			(width 0.0635)
			(type default)
		)
		(layer "In7.Cu")
	)
	(gr_line
		(start 274.638516 -255.515872)
		(end 274.953984 -255.729486)
		(stroke
			(width 0.0635)
			(type default)
		)
		(layer "In7.Cu")
	)
	(gr_line
		(start 274.694142 -253.970536)
		(end 274.884896 -253.933706)
		(stroke
			(width 0.0635)
			(type default)
		)
		(layer "In7.Cu")
	)
	(gr_line
		(start 274.721574 -250.624086)
		(end 275.224748 -250.964446)
		(stroke
			(width 0.0635)
			(type default)
		)
		(layer "In7.Cu")
	)
	(gr_line
		(start 274.731226 -260.982968)
		(end 274.770596 -261.187692)
		(stroke
			(width 0.0635)
			(type default)
		)
		(layer "In7.Cu")
	)
	(gr_line
		(start 274.747482 -263.03605)
		(end 274.95246 -262.996426)
		(stroke
			(width 0.0635)
			(type default)
		)
		(layer "In7.Cu")
	)
	(gr_line
		(start 274.844256 -259.61086)
		(end 275.327618 -259.938012)
		(stroke
			(width 0.0635)
			(type default)
		)
		(layer "In7.Cu")
	)
	(gr_line
		(start 274.851368 -250.371356)
		(end 275.056346 -250.331986)
		(stroke
			(width 0.0635)
			(type default)
		)
		(layer "In7.Cu")
	)
	(gr_line
		(start 274.884896 -253.933706)
		(end 275.200364 -254.14732)
		(stroke
			(width 0.0635)
			(type default)
		)
		(layer "In7.Cu")
	)
	(gr_line
		(start 274.951444 -257.405378)
		(end 274.990814 -257.610356)
		(stroke
			(width 0.0635)
			(type default)
		)
		(layer "In7.Cu")
	)
	(gr_line
		(start 274.95246 -262.996426)
		(end 275.267928 -263.21004)
		(stroke
			(width 0.0635)
			(type default)
		)
		(layer "In7.Cu")
	)
	(gr_line
		(start 274.953984 -255.729486)
		(end 274.993354 -255.93421)
		(stroke
			(width 0.0635)
			(type default)
		)
		(layer "In7.Cu")
	)
	(gr_line
		(start 274.960588 -261.656576)
		(end 275.463 -261.996682)
		(stroke
			(width 0.0635)
			(type default)
		)
		(layer "In7.Cu")
	)
	(gr_line
		(start 274.97278 -259.357368)
		(end 275.16328 -259.320538)
		(stroke
			(width 0.0635)
			(type default)
		)
		(layer "In7.Cu")
	)
	(gr_line
		(start 275.056346 -250.331986)
		(end 275.371814 -250.5456)
		(stroke
			(width 0.0635)
			(type default)
		)
		(layer "In7.Cu")
	)
	(gr_line
		(start 275.090382 -261.403846)
		(end 275.295106 -261.364476)
		(stroke
			(width 0.0635)
			(type default)
		)
		(layer "In7.Cu")
	)
	(gr_line
		(start 275.16328 -259.320538)
		(end 275.478748 -259.534152)
		(stroke
			(width 0.0635)
			(type default)
		)
		(layer "In7.Cu")
	)
	(gr_line
		(start 275.182076 -258.079748)
		(end 275.682456 -258.41833)
		(stroke
			(width 0.0635)
			(type default)
		)
		(layer "In7.Cu")
	)
	(gr_line
		(start 275.183854 -256.403602)
		(end 275.686774 -256.743962)
		(stroke
			(width 0.0635)
			(type default)
		)
		(layer "In7.Cu")
	)
	(gr_line
		(start 275.200364 -254.14732)
		(end 275.237194 -254.338074)
		(stroke
			(width 0.0635)
			(type default)
		)
		(layer "In7.Cu")
	)
	(gr_line
		(start 275.234908 -349.76435)
		(end 275.251672 -349.770446)
		(stroke
			(width 0.0508)
			(type default)
		)
		(layer "In7.Cu")
	)
	(gr_line
		(start 275.267928 -263.21004)
		(end 275.307552 -263.414764)
		(stroke
			(width 0.0635)
			(type default)
		)
		(layer "In7.Cu")
	)
	(gr_line
		(start 275.295106 -261.364476)
		(end 275.610574 -261.577836)
		(stroke
			(width 0.0635)
			(type default)
		)
		(layer "In7.Cu")
	)
	(gr_line
		(start 275.310346 -257.826256)
		(end 275.515324 -257.786886)
		(stroke
			(width 0.0635)
			(type default)
		)
		(layer "In7.Cu")
	)
	(gr_line
		(start 275.31314 -256.150364)
		(end 275.517864 -256.110994)
		(stroke
			(width 0.0635)
			(type default)
		)
		(layer "In7.Cu")
	)
	(gr_line
		(start 275.371814 -250.5456)
		(end 275.411438 -250.750324)
		(stroke
			(width 0.0635)
			(type default)
		)
		(layer "In7.Cu")
	)
	(gr_line
		(start 275.426932 -254.806704)
		(end 275.91258 -255.135634)
		(stroke
			(width 0.0635)
			(type default)
		)
		(layer "In7.Cu")
	)
	(gr_line
		(start 275.478748 -259.534152)
		(end 275.515324 -259.724652)
		(stroke
			(width 0.0635)
			(type default)
		)
		(layer "In7.Cu")
	)
	(gr_line
		(start 275.497036 -263.883648)
		(end 276.000464 -264.224262)
		(stroke
			(width 0.0635)
			(type default)
		)
		(layer "In7.Cu")
	)
	(gr_line
		(start 275.515324 -257.786886)
		(end 275.830792 -258.0005)
		(stroke
			(width 0.0635)
			(type default)
		)
		(layer "In7.Cu")
	)
	(gr_line
		(start 275.517864 -256.110994)
		(end 275.833332 -256.324608)
		(stroke
			(width 0.0635)
			(type default)
		)
		(layer "In7.Cu")
	)
	(gr_line
		(start 275.556472 -254.554228)
		(end 275.74748 -254.517398)
		(stroke
			(width 0.0635)
			(type default)
		)
		(layer "In7.Cu")
	)
	(gr_line
		(start 275.610574 -261.577836)
		(end 275.649944 -261.78256)
		(stroke
			(width 0.0635)
			(type default)
		)
		(layer "In7.Cu")
	)
	(gr_line
		(start 275.62683 -263.630918)
		(end 275.831808 -263.591548)
		(stroke
			(width 0.0635)
			(type default)
		)
		(layer "In7.Cu")
	)
	(gr_line
		(start 275.706586 -260.194298)
		(end 276.190456 -260.521958)
		(stroke
			(width 0.0635)
			(type default)
		)
		(layer "In7.Cu")
	)
	(gr_line
		(start 275.74748 -254.517398)
		(end 276.062948 -254.731012)
		(stroke
			(width 0.0635)
			(type default)
		)
		(layer "In7.Cu")
	)
	(gr_line
		(start 275.830792 -258.0005)
		(end 275.870162 -258.205224)
		(stroke
			(width 0.0635)
			(type default)
		)
		(layer "In7.Cu")
	)
	(gr_line
		(start 275.831808 -263.591548)
		(end 276.147276 -263.805162)
		(stroke
			(width 0.0635)
			(type default)
		)
		(layer "In7.Cu")
	)
	(gr_line
		(start 275.833332 -256.324608)
		(end 275.872702 -256.529332)
		(stroke
			(width 0.0635)
			(type default)
		)
		(layer "In7.Cu")
	)
	(gr_line
		(start 275.834856 -259.940806)
		(end 276.02561 -259.90423)
		(stroke
			(width 0.0635)
			(type default)
		)
		(layer "In7.Cu")
	)
	(gr_line
		(start 275.839428 -262.25119)
		(end 276.342856 -262.591804)
		(stroke
			(width 0.0635)
			(type default)
		)
		(layer "In7.Cu")
	)
	(gr_line
		(start 275.969476 -261.998968)
		(end 276.174454 -261.959344)
		(stroke
			(width 0.0635)
			(type default)
		)
		(layer "In7.Cu")
	)
	(gr_line
		(start 276.02561 -259.90423)
		(end 276.341078 -260.117844)
		(stroke
			(width 0.0635)
			(type default)
		)
		(layer "In7.Cu")
	)
	(gr_line
		(start 276.062948 -254.731012)
		(end 276.099524 -254.921766)
		(stroke
			(width 0.0635)
			(type default)
		)
		(layer "In7.Cu")
	)
	(gr_line
		(start 276.147276 -263.805162)
		(end 276.186646 -264.009886)
		(stroke
			(width 0.0635)
			(type default)
		)
		(layer "In7.Cu")
	)
	(gr_line
		(start 276.174454 -261.959344)
		(end 276.489922 -262.172958)
		(stroke
			(width 0.0635)
			(type default)
		)
		(layer "In7.Cu")
	)
	(gr_line
		(start 276.341078 -260.117844)
		(end 276.377908 -260.308344)
		(stroke
			(width 0.0635)
			(type default)
		)
		(layer "In7.Cu")
	)
	(gr_line
		(start 276.489922 -262.172958)
		(end 276.529292 -262.377682)
		(stroke
			(width 0.0635)
			(type default)
		)
		(layer "In7.Cu")
	)
	(gr_line
		(start 276.559772 -328.16419)
		(end 276.576536 -328.170286)
		(stroke
			(width 0.0508)
			(type default)
		)
		(layer "In7.Cu")
	)
	(gr_line
		(start 276.682454 -326.364346)
		(end 276.699218 -326.370442)
		(stroke
			(width 0.0508)
			(type default)
		)
		(layer "In7.Cu")
	)
	(gr_line
		(start 276.769576 -255.715262)
		(end 276.808946 -255.741932)
		(stroke
			(width 0.0635)
			(type default)
		)
		(layer "In7.Cu")
	)
	(gr_line
		(start 276.80539 -264.768838)
		(end 276.845522 -264.796016)
		(stroke
			(width 0.0635)
			(type default)
		)
		(layer "In7.Cu")
	)
	(gr_line
		(start 276.81936 -262.914384)
		(end 276.860508 -262.94207)
		(stroke
			(width 0.0635)
			(type default)
		)
		(layer "In7.Cu")
	)
	(gr_line
		(start 276.826218 -257.514852)
		(end 276.86635 -257.54203)
		(stroke
			(width 0.0635)
			(type default)
		)
		(layer "In7.Cu")
	)
	(gr_line
		(start 276.83206 -253.914656)
		(end 276.872192 -253.941834)
		(stroke
			(width 0.0635)
			(type default)
		)
		(layer "In7.Cu")
	)
	(gr_line
		(start 276.855428 -347.964252)
		(end 276.872192 -347.970348)
		(stroke
			(width 0.0508)
			(type default)
		)
		(layer "In7.Cu")
	)
	(gr_line
		(start 276.924516 -252.114812)
		(end 276.964648 -252.14199)
		(stroke
			(width 0.0635)
			(type default)
		)
		(layer "In7.Cu")
	)
	(gr_line
		(start 277.00732 -259.314696)
		(end 277.047452 -259.341874)
		(stroke
			(width 0.0635)
			(type default)
		)
		(layer "In7.Cu")
	)
	(gr_line
		(start 277.066502 -261.114794)
		(end 277.106634 -261.141972)
		(stroke
			(width 0.0635)
			(type default)
		)
		(layer "In7.Cu")
	)
	(gr_line
		(start 278.23668 -294.705278)
		(end 278.670004 -294.705278)
		(stroke
			(width 0.0508)
			(type default)
		)
		(layer "In7.Cu")
	)
	(gr_line
		(start 278.23668 -261.902194)
		(end 278.670004 -261.902194)
		(stroke
			(width 0.0635)
			(type default)
		)
		(layer "In7.Cu")
	)
	(gr_line
		(start 278.23668 -258.302252)
		(end 278.670004 -258.302252)
		(stroke
			(width 0.0635)
			(type default)
		)
		(layer "In7.Cu")
	)
	(gr_line
		(start 278.23668 -254.70231)
		(end 278.670004 -254.70231)
		(stroke
			(width 0.0635)
			(type default)
		)
		(layer "In7.Cu")
	)
	(gr_line
		(start 278.23668 -251.102368)
		(end 278.670004 -251.102368)
		(stroke
			(width 0.0635)
			(type default)
		)
		(layer "In7.Cu")
	)
	(gr_arc
		(start 278.670004 -294.705278)
		(mid 278.741846 -294.67552)
		(end 278.771604 -294.603678)
		(stroke
			(width 0.0508)
			(type default)
		)
		(layer "In7.Cu")
	)
	(gr_line
		(start 278.750014 -12.200128)
		(end 279.475946 -11.836654)
		(stroke
			(width 0.0635)
			(type default)
		)
		(layer "In7.Cu")
	)
	(gr_arc
		(start 278.797004 -262.029194)
		(mid 278.759805 -261.939394)
		(end 278.670004 -261.902194)
		(stroke
			(width 0.0635)
			(type default)
		)
		(layer "In7.Cu")
	)
	(gr_arc
		(start 278.797004 -258.429252)
		(mid 278.75979 -258.339479)
		(end 278.670004 -258.302252)
		(stroke
			(width 0.0635)
			(type default)
		)
		(layer "In7.Cu")
	)
	(gr_arc
		(start 278.797004 -254.82931)
		(mid 278.75981 -254.7395)
		(end 278.670004 -254.70231)
		(stroke
			(width 0.0635)
			(type default)
		)
		(layer "In7.Cu")
	)
	(gr_arc
		(start 278.797004 -251.229368)
		(mid 278.759795 -251.139585)
		(end 278.670004 -251.102368)
		(stroke
			(width 0.0635)
			(type default)
		)
		(layer "In7.Cu")
	)
	(gr_arc
		(start 279.101804 -294.603678)
		(mid 279.131554 -294.675533)
		(end 279.203404 -294.705278)
		(stroke
			(width 0.0508)
			(type default)
		)
		(layer "In7.Cu")
	)
	(gr_line
		(start 279.186894 -293.609776)
		(end 279.224994 -293.59733)
		(stroke
			(width 0.0508)
			(type default)
		)
		(layer "In7.Cu")
	)
	(gr_line
		(start 279.203404 -294.705278)
		(end 279.636728 -294.705278)
		(stroke
			(width 0.0508)
			(type default)
		)
		(layer "In7.Cu")
	)
	(gr_arc
		(start 279.203404 -261.902194)
		(mid 279.113601 -261.939391)
		(end 279.076404 -262.029194)
		(stroke
			(width 0.0635)
			(type default)
		)
		(layer "In7.Cu")
	)
	(gr_line
		(start 279.203404 -261.902194)
		(end 279.636728 -261.902194)
		(stroke
			(width 0.0635)
			(type default)
		)
		(layer "In7.Cu")
	)
	(gr_arc
		(start 279.203404 -258.302252)
		(mid 279.113601 -258.339449)
		(end 279.076404 -258.429252)
		(stroke
			(width 0.0635)
			(type default)
		)
		(layer "In7.Cu")
	)
	(gr_line
		(start 279.203404 -258.302252)
		(end 279.636728 -258.302252)
		(stroke
			(width 0.0635)
			(type default)
		)
		(layer "In7.Cu")
	)
	(gr_arc
		(start 279.203404 -254.70231)
		(mid 279.113601 -254.739507)
		(end 279.076404 -254.82931)
		(stroke
			(width 0.0635)
			(type default)
		)
		(layer "In7.Cu")
	)
	(gr_line
		(start 279.203404 -254.70231)
		(end 279.636728 -254.70231)
		(stroke
			(width 0.0635)
			(type default)
		)
		(layer "In7.Cu")
	)
	(gr_arc
		(start 279.203404 -251.102368)
		(mid 279.113601 -251.139565)
		(end 279.076404 -251.229368)
		(stroke
			(width 0.0635)
			(type default)
		)
		(layer "In7.Cu")
	)
	(gr_line
		(start 279.203404 -251.102368)
		(end 279.636728 -251.102368)
		(stroke
			(width 0.0635)
			(type default)
		)
		(layer "In7.Cu")
	)
	(gr_line
		(start 279.236678 -296.505122)
		(end 279.646888 -296.505122)
		(stroke
			(width 0.0508)
			(type default)
		)
		(layer "In7.Cu")
	)
	(gr_line
		(start 279.236678 -263.702292)
		(end 279.670002 -263.702292)
		(stroke
			(width 0.0635)
			(type default)
		)
		(layer "In7.Cu")
	)
	(gr_line
		(start 279.236678 -260.10235)
		(end 279.670002 -260.10235)
		(stroke
			(width 0.0635)
			(type default)
		)
		(layer "In7.Cu")
	)
	(gr_line
		(start 279.236678 -256.502408)
		(end 279.670002 -256.502408)
		(stroke
			(width 0.0635)
			(type default)
		)
		(layer "In7.Cu")
	)
	(gr_line
		(start 279.236678 -252.902212)
		(end 279.670002 -252.902212)
		(stroke
			(width 0.0635)
			(type default)
		)
		(layer "In7.Cu")
	)
	(gr_arc
		(start 279.646888 -296.505122)
		(mid 279.736706 -296.46793)
		(end 279.773888 -296.378122)
		(stroke
			(width 0.0508)
			(type default)
		)
		(layer "In7.Cu")
	)
	(gr_arc
		(start 279.651968 -11.865102)
		(mid 279.568556 -11.822441)
		(end 279.475946 -11.836654)
		(stroke
			(width 0.0635)
			(type default)
		)
		(layer "In7.Cu")
	)
	(gr_arc
		(start 279.797002 -263.829292)
		(mid 279.759802 -263.739494)
		(end 279.670002 -263.702292)
		(stroke
			(width 0.0635)
			(type default)
		)
		(layer "In7.Cu")
	)
	(gr_arc
		(start 279.797002 -260.22935)
		(mid 279.759822 -260.139514)
		(end 279.670002 -260.10235)
		(stroke
			(width 0.0635)
			(type default)
		)
		(layer "In7.Cu")
	)
	(gr_arc
		(start 279.797002 -256.629408)
		(mid 279.759808 -256.5396)
		(end 279.670002 -256.502408)
		(stroke
			(width 0.0635)
			(type default)
		)
		(layer "In7.Cu")
	)
	(gr_arc
		(start 279.797002 -253.029212)
		(mid 279.759809 -252.939401)
		(end 279.670002 -252.902212)
		(stroke
			(width 0.0635)
			(type default)
		)
		(layer "In7.Cu")
	)
	(gr_arc
		(start 279.996138 -11.577828)
		(mid 279.927692 -11.671002)
		(end 279.963118 -11.781028)
		(stroke
			(width 0.0635)
			(type default)
		)
		(layer "In7.Cu")
	)
	(gr_line
		(start 279.996138 -11.577828)
		(end 280.006044 -11.572748)
		(stroke
			(width 0.0635)
			(type default)
		)
		(layer "In7.Cu")
	)
	(gr_line
		(start 280.006044 -11.572748)
		(end 280.75001 -11.20013)
		(stroke
			(width 0.0635)
			(type default)
		)
		(layer "In7.Cu")
	)
	(gr_arc
		(start 280.104088 -296.378122)
		(mid 280.141285 -296.467925)
		(end 280.231088 -296.505122)
		(stroke
			(width 0.0508)
			(type default)
		)
		(layer "In7.Cu")
	)
	(gr_arc
		(start 280.203402 -263.702292)
		(mid 280.113599 -263.739489)
		(end 280.076402 -263.829292)
		(stroke
			(width 0.0635)
			(type default)
		)
		(layer "In7.Cu")
	)
	(gr_line
		(start 280.203402 -263.702292)
		(end 280.636726 -263.702292)
		(stroke
			(width 0.0635)
			(type default)
		)
		(layer "In7.Cu")
	)
	(gr_arc
		(start 280.203402 -260.10235)
		(mid 280.113599 -260.139547)
		(end 280.076402 -260.22935)
		(stroke
			(width 0.0635)
			(type default)
		)
		(layer "In7.Cu")
	)
	(gr_line
		(start 280.203402 -260.10235)
		(end 280.636726 -260.10235)
		(stroke
			(width 0.0635)
			(type default)
		)
		(layer "In7.Cu")
	)
	(gr_arc
		(start 280.203402 -256.502408)
		(mid 280.113599 -256.539605)
		(end 280.076402 -256.629408)
		(stroke
			(width 0.0635)
			(type default)
		)
		(layer "In7.Cu")
	)
	(gr_line
		(start 280.203402 -256.502408)
		(end 280.636726 -256.502408)
		(stroke
			(width 0.0635)
			(type default)
		)
		(layer "In7.Cu")
	)
	(gr_arc
		(start 280.203402 -252.902212)
		(mid 280.113599 -252.939409)
		(end 280.076402 -253.029212)
		(stroke
			(width 0.0635)
			(type default)
		)
		(layer "In7.Cu")
	)
	(gr_line
		(start 280.203402 -252.902212)
		(end 280.636726 -252.902212)
		(stroke
			(width 0.0635)
			(type default)
		)
		(layer "In7.Cu")
	)
	(gr_line
		(start 280.231088 -296.505122)
		(end 280.636726 -296.505122)
		(stroke
			(width 0.0508)
			(type default)
		)
		(layer "In7.Cu")
	)
	(gr_line
		(start 282.823666 -292.424104)
		(end 283.447998 -292.22065)
		(stroke
			(width 0.0508)
			(type default)
		)
		(layer "In7.Cu")
	)
	(gr_line
		(start 282.89123 -292.752018)
		(end 283.160724 -292.88867)
		(stroke
			(width 0.0508)
			(type default)
		)
		(layer "In7.Cu")
	)
	(gr_line
		(start 283.160724 -292.88867)
		(end 283.450538 -292.794182)
		(stroke
			(width 0.0508)
			(type default)
		)
		(layer "In7.Cu")
	)
	(gr_line
		(start 283.249878 -35.200082)
		(end 283.999178 -35.57524)
		(stroke
			(width 0.0635)
			(type default)
		)
		(layer "In7.Cu")
	)
	(gr_line
		(start 283.450538 -292.794182)
		(end 283.58719 -292.525196)
		(stroke
			(width 0.0508)
			(type default)
		)
		(layer "In7.Cu")
	)
	(gr_line
		(start 283.813504 -292.10127)
		(end 284.439106 -291.897308)
		(stroke
			(width 0.0508)
			(type default)
		)
		(layer "In7.Cu")
	)
	(gr_line
		(start 283.881322 -292.429184)
		(end 284.150816 -292.56609)
		(stroke
			(width 0.0508)
			(type default)
		)
		(layer "In7.Cu")
	)
	(gr_arc
		(start 283.999178 -35.57524)
		(mid 284.106361 -35.582824)
		(end 284.187392 -35.512248)
		(stroke
			(width 0.0635)
			(type default)
		)
		(layer "In7.Cu")
	)
	(gr_line
		(start 284.150816 -292.56609)
		(end 284.44063 -292.471602)
		(stroke
			(width 0.0508)
			(type default)
		)
		(layer "In7.Cu")
	)
	(gr_arc
		(start 284.431994 -35.648392)
		(mid 284.425017 -35.74534)
		(end 284.488636 -35.818826)
		(stroke
			(width 0.0635)
			(type default)
		)
		(layer "In7.Cu")
	)
	(gr_line
		(start 284.44063 -292.471602)
		(end 284.577282 -292.202362)
		(stroke
			(width 0.0508)
			(type default)
		)
		(layer "In7.Cu")
	)
	(gr_line
		(start 284.488636 -35.818826)
		(end 285.249874 -36.20008)
		(stroke
			(width 0.0635)
			(type default)
		)
		(layer "In7.Cu")
	)
	(gr_line
		(start 284.80258 -291.77869)
		(end 285.430468 -291.573966)
		(stroke
			(width 0.0508)
			(type default)
		)
		(layer "In7.Cu")
	)
	(gr_line
		(start 284.871668 -292.10635)
		(end 285.140908 -292.243256)
		(stroke
			(width 0.0508)
			(type default)
		)
		(layer "In7.Cu")
	)
	(gr_line
		(start 285.140908 -292.243256)
		(end 285.430722 -292.148768)
		(stroke
			(width 0.0508)
			(type default)
		)
		(layer "In7.Cu")
	)
	(gr_line
		(start 285.430722 -292.148768)
		(end 285.567628 -291.879274)
		(stroke
			(width 0.0508)
			(type default)
		)
		(layer "In7.Cu")
	)
	(gr_line
		(start 285.436564 -355.905054)
		(end 285.846774 -355.905054)
		(stroke
			(width 0.0508)
			(type default)
		)
		(layer "In7.Cu")
	)
	(gr_line
		(start 285.436564 -352.305112)
		(end 285.846774 -352.305112)
		(stroke
			(width 0.0508)
			(type default)
		)
		(layer "In7.Cu")
	)
	(gr_line
		(start 285.436564 -348.70517)
		(end 285.846774 -348.70517)
		(stroke
			(width 0.0508)
			(type default)
		)
		(layer "In7.Cu")
	)
	(gr_line
		(start 285.436564 -334.305148)
		(end 285.846774 -334.305148)
		(stroke
			(width 0.0508)
			(type default)
		)
		(layer "In7.Cu")
	)
	(gr_line
		(start 285.436564 -330.705206)
		(end 285.846774 -330.705206)
		(stroke
			(width 0.0508)
			(type default)
		)
		(layer "In7.Cu")
	)
	(gr_line
		(start 285.436564 -327.105264)
		(end 285.846774 -327.105264)
		(stroke
			(width 0.0508)
			(type default)
		)
		(layer "In7.Cu")
	)
	(gr_line
		(start 285.436564 -312.705242)
		(end 285.846774 -312.705242)
		(stroke
			(width 0.0508)
			(type default)
		)
		(layer "In7.Cu")
	)
	(gr_line
		(start 285.436564 -309.105046)
		(end 285.846774 -309.105046)
		(stroke
			(width 0.0508)
			(type default)
		)
		(layer "In7.Cu")
	)
	(gr_line
		(start 285.436564 -305.505104)
		(end 285.846774 -305.505104)
		(stroke
			(width 0.0508)
			(type default)
		)
		(layer "In7.Cu")
	)
	(gr_line
		(start 285.436564 -294.705278)
		(end 285.846774 -294.705278)
		(stroke
			(width 0.0508)
			(type default)
		)
		(layer "In7.Cu")
	)
	(gr_line
		(start 285.436564 -261.902194)
		(end 285.869888 -261.902194)
		(stroke
			(width 0.0635)
			(type default)
		)
		(layer "In7.Cu")
	)
	(gr_line
		(start 285.436564 -258.302252)
		(end 285.869888 -258.302252)
		(stroke
			(width 0.0635)
			(type default)
		)
		(layer "In7.Cu")
	)
	(gr_line
		(start 285.436564 -254.70231)
		(end 285.869888 -254.70231)
		(stroke
			(width 0.0635)
			(type default)
		)
		(layer "In7.Cu")
	)
	(gr_line
		(start 285.436564 -251.102368)
		(end 285.869888 -251.102368)
		(stroke
			(width 0.0635)
			(type default)
		)
		(layer "In7.Cu")
	)
	(gr_line
		(start 285.58871 -14.39545)
		(end 285.906718 -14.885162)
		(stroke
			(width 0.0635)
			(type default)
		)
		(layer "In7.Cu")
	)
	(gr_line
		(start 285.805626 -14.211808)
		(end 285.995364 -14.25194)
		(stroke
			(width 0.0635)
			(type default)
		)
		(layer "In7.Cu")
	)
	(gr_arc
		(start 285.846774 -355.905054)
		(mid 285.936577 -355.867857)
		(end 285.973774 -355.778054)
		(stroke
			(width 0.0508)
			(type default)
		)
		(layer "In7.Cu")
	)
	(gr_arc
		(start 285.846774 -352.305112)
		(mid 285.936577 -352.267915)
		(end 285.973774 -352.178112)
		(stroke
			(width 0.0508)
			(type default)
		)
		(layer "In7.Cu")
	)
	(gr_arc
		(start 285.846774 -348.70517)
		(mid 285.936577 -348.667973)
		(end 285.973774 -348.57817)
		(stroke
			(width 0.0508)
			(type default)
		)
		(layer "In7.Cu")
	)
	(gr_arc
		(start 285.846774 -334.305148)
		(mid 285.936577 -334.267951)
		(end 285.973774 -334.178148)
		(stroke
			(width 0.0508)
			(type default)
		)
		(layer "In7.Cu")
	)
	(gr_arc
		(start 285.846774 -330.705206)
		(mid 285.936577 -330.668009)
		(end 285.973774 -330.578206)
		(stroke
			(width 0.0508)
			(type default)
		)
		(layer "In7.Cu")
	)
	(gr_arc
		(start 285.846774 -327.105264)
		(mid 285.936577 -327.068067)
		(end 285.973774 -326.978264)
		(stroke
			(width 0.0508)
			(type default)
		)
		(layer "In7.Cu")
	)
	(gr_arc
		(start 285.846774 -312.705242)
		(mid 285.936577 -312.668045)
		(end 285.973774 -312.578242)
		(stroke
			(width 0.0508)
			(type default)
		)
		(layer "In7.Cu")
	)
	(gr_arc
		(start 285.846774 -309.105046)
		(mid 285.936577 -309.067849)
		(end 285.973774 -308.978046)
		(stroke
			(width 0.0508)
			(type default)
		)
		(layer "In7.Cu")
	)
	(gr_arc
		(start 285.846774 -305.505104)
		(mid 285.936577 -305.467907)
		(end 285.973774 -305.378104)
		(stroke
			(width 0.0508)
			(type default)
		)
		(layer "In7.Cu")
	)
	(gr_arc
		(start 285.846774 -294.705278)
		(mid 285.936577 -294.668081)
		(end 285.973774 -294.578278)
		(stroke
			(width 0.0508)
			(type default)
		)
		(layer "In7.Cu")
	)
	(gr_line
		(start 285.995364 -14.25194)
		(end 286.202882 -14.571472)
		(stroke
			(width 0.0635)
			(type default)
		)
		(layer "In7.Cu")
	)
	(gr_arc
		(start 285.996888 -262.029194)
		(mid 285.959688 -261.9394)
		(end 285.869888 -261.902194)
		(stroke
			(width 0.0635)
			(type default)
		)
		(layer "In7.Cu")
	)
	(gr_arc
		(start 285.996888 -258.429252)
		(mid 285.959673 -258.339485)
		(end 285.869888 -258.302252)
		(stroke
			(width 0.0635)
			(type default)
		)
		(layer "In7.Cu")
	)
	(gr_arc
		(start 285.996888 -254.82931)
		(mid 285.959693 -254.739505)
		(end 285.869888 -254.70231)
		(stroke
			(width 0.0635)
			(type default)
		)
		(layer "In7.Cu")
	)
	(gr_arc
		(start 285.996888 -251.229368)
		(mid 285.959679 -251.13959)
		(end 285.869888 -251.102368)
		(stroke
			(width 0.0635)
			(type default)
		)
		(layer "In7.Cu")
	)
	(gr_line
		(start 286.155892 -15.268702)
		(end 286.473646 -15.75816)
		(stroke
			(width 0.0635)
			(type default)
		)
		(layer "In7.Cu")
	)
	(gr_line
		(start 286.162496 -14.761464)
		(end 286.202882 -14.571472)
		(stroke
			(width 0.0635)
			(type default)
		)
		(layer "In7.Cu")
	)
	(gr_arc
		(start 286.303974 -355.778054)
		(mid 286.341171 -355.867857)
		(end 286.430974 -355.905054)
		(stroke
			(width 0.0508)
			(type default)
		)
		(layer "In7.Cu")
	)
	(gr_arc
		(start 286.303974 -352.178112)
		(mid 286.341171 -352.267915)
		(end 286.430974 -352.305112)
		(stroke
			(width 0.0508)
			(type default)
		)
		(layer "In7.Cu")
	)
	(gr_arc
		(start 286.303974 -348.57817)
		(mid 286.341159 -348.668001)
		(end 286.430974 -348.70517)
		(stroke
			(width 0.0508)
			(type default)
		)
		(layer "In7.Cu")
	)
	(gr_arc
		(start 286.303974 -334.178148)
		(mid 286.341171 -334.267951)
		(end 286.430974 -334.305148)
		(stroke
			(width 0.0508)
			(type default)
		)
		(layer "In7.Cu")
	)
	(gr_arc
		(start 286.303974 -330.578206)
		(mid 286.341171 -330.668009)
		(end 286.430974 -330.705206)
		(stroke
			(width 0.0508)
			(type default)
		)
		(layer "In7.Cu")
	)
	(gr_arc
		(start 286.303974 -326.978264)
		(mid 286.341171 -327.068067)
		(end 286.430974 -327.105264)
		(stroke
			(width 0.0508)
			(type default)
		)
		(layer "In7.Cu")
	)
	(gr_arc
		(start 286.303974 -312.578242)
		(mid 286.341185 -312.668027)
		(end 286.430974 -312.705242)
		(stroke
			(width 0.0508)
			(type default)
		)
		(layer "In7.Cu")
	)
	(gr_arc
		(start 286.303974 -308.978046)
		(mid 286.341171 -309.067849)
		(end 286.430974 -309.105046)
		(stroke
			(width 0.0508)
			(type default)
		)
		(layer "In7.Cu")
	)
	(gr_arc
		(start 286.303974 -305.378104)
		(mid 286.341171 -305.467913)
		(end 286.430974 -305.505104)
		(stroke
			(width 0.0508)
			(type default)
		)
		(layer "In7.Cu")
	)
	(gr_arc
		(start 286.303974 -294.578278)
		(mid 286.341162 -294.668104)
		(end 286.430974 -294.705278)
		(stroke
			(width 0.0508)
			(type default)
		)
		(layer "In7.Cu")
	)
	(gr_line
		(start 286.372554 -15.08506)
		(end 286.562546 -15.125446)
		(stroke
			(width 0.0635)
			(type default)
		)
		(layer "In7.Cu")
	)
	(gr_arc
		(start 286.403288 -261.902194)
		(mid 286.313485 -261.939391)
		(end 286.276288 -262.029194)
		(stroke
			(width 0.0635)
			(type default)
		)
		(layer "In7.Cu")
	)
	(gr_line
		(start 286.403288 -261.902194)
		(end 286.836612 -261.902194)
		(stroke
			(width 0.0635)
			(type default)
		)
		(layer "In7.Cu")
	)
	(gr_arc
		(start 286.403288 -258.302252)
		(mid 286.313485 -258.339449)
		(end 286.276288 -258.429252)
		(stroke
			(width 0.0635)
			(type default)
		)
		(layer "In7.Cu")
	)
	(gr_line
		(start 286.403288 -258.302252)
		(end 286.836612 -258.302252)
		(stroke
			(width 0.0635)
			(type default)
		)
		(layer "In7.Cu")
	)
	(gr_arc
		(start 286.403288 -254.70231)
		(mid 286.313485 -254.739507)
		(end 286.276288 -254.82931)
		(stroke
			(width 0.0635)
			(type default)
		)
		(layer "In7.Cu")
	)
	(gr_line
		(start 286.403288 -254.70231)
		(end 286.836612 -254.70231)
		(stroke
			(width 0.0635)
			(type default)
		)
		(layer "In7.Cu")
	)
	(gr_arc
		(start 286.403288 -251.102368)
		(mid 286.313485 -251.139565)
		(end 286.276288 -251.229368)
		(stroke
			(width 0.0635)
			(type default)
		)
		(layer "In7.Cu")
	)
	(gr_line
		(start 286.403288 -251.102368)
		(end 286.836612 -251.102368)
		(stroke
			(width 0.0635)
			(type default)
		)
		(layer "In7.Cu")
	)
	(gr_line
		(start 286.430974 -355.905054)
		(end 286.836612 -355.905054)
		(stroke
			(width 0.0508)
			(type default)
		)
		(layer "In7.Cu")
	)
	(gr_line
		(start 286.430974 -352.305112)
		(end 286.836612 -352.305112)
		(stroke
			(width 0.0508)
			(type default)
		)
		(layer "In7.Cu")
	)
	(gr_line
		(start 286.430974 -348.70517)
		(end 286.836612 -348.70517)
		(stroke
			(width 0.0508)
			(type default)
		)
		(layer "In7.Cu")
	)
	(gr_line
		(start 286.430974 -334.305148)
		(end 286.836612 -334.305148)
		(stroke
			(width 0.0508)
			(type default)
		)
		(layer "In7.Cu")
	)
	(gr_line
		(start 286.430974 -330.705206)
		(end 286.836612 -330.705206)
		(stroke
			(width 0.0508)
			(type default)
		)
		(layer "In7.Cu")
	)
	(gr_line
		(start 286.430974 -327.105264)
		(end 286.836612 -327.105264)
		(stroke
			(width 0.0508)
			(type default)
		)
		(layer "In7.Cu")
	)
	(gr_line
		(start 286.430974 -312.705242)
		(end 286.836612 -312.705242)
		(stroke
			(width 0.0508)
			(type default)
		)
		(layer "In7.Cu")
	)
	(gr_line
		(start 286.430974 -309.105046)
		(end 286.836612 -309.105046)
		(stroke
			(width 0.0508)
			(type default)
		)
		(layer "In7.Cu")
	)
	(gr_line
		(start 286.430974 -305.505104)
		(end 286.836612 -305.505104)
		(stroke
			(width 0.0508)
			(type default)
		)
		(layer "In7.Cu")
	)
	(gr_line
		(start 286.430974 -294.705278)
		(end 286.836612 -294.705278)
		(stroke
			(width 0.0508)
			(type default)
		)
		(layer "In7.Cu")
	)
	(gr_line
		(start 286.436562 -357.705152)
		(end 286.846772 -357.705152)
		(stroke
			(width 0.0508)
			(type default)
		)
		(layer "In7.Cu")
	)
	(gr_line
		(start 286.436562 -354.10521)
		(end 286.846772 -354.10521)
		(stroke
			(width 0.0508)
			(type default)
		)
		(layer "In7.Cu")
	)
	(gr_line
		(start 286.436562 -350.505268)
		(end 286.846772 -350.505268)
		(stroke
			(width 0.0508)
			(type default)
		)
		(layer "In7.Cu")
	)
	(gr_line
		(start 286.436562 -336.105246)
		(end 286.846772 -336.105246)
		(stroke
			(width 0.0508)
			(type default)
		)
		(layer "In7.Cu")
	)
	(gr_line
		(start 286.436562 -332.50505)
		(end 286.846772 -332.50505)
		(stroke
			(width 0.0508)
			(type default)
		)
		(layer "In7.Cu")
	)
	(gr_line
		(start 286.436562 -328.905108)
		(end 286.846772 -328.905108)
		(stroke
			(width 0.0508)
			(type default)
		)
		(layer "In7.Cu")
	)
	(gr_line
		(start 286.436562 -314.505086)
		(end 286.846772 -314.505086)
		(stroke
			(width 0.0508)
			(type default)
		)
		(layer "In7.Cu")
	)
	(gr_line
		(start 286.436562 -310.905144)
		(end 286.846772 -310.905144)
		(stroke
			(width 0.0508)
			(type default)
		)
		(layer "In7.Cu")
	)
	(gr_line
		(start 286.436562 -307.305202)
		(end 286.846772 -307.305202)
		(stroke
			(width 0.0508)
			(type default)
		)
		(layer "In7.Cu")
	)
	(gr_line
		(start 286.436562 -296.505122)
		(end 286.8422 -296.505122)
		(stroke
			(width 0.0508)
			(type default)
		)
		(layer "In7.Cu")
	)
	(gr_line
		(start 286.436562 -263.702292)
		(end 286.869886 -263.702292)
		(stroke
			(width 0.0635)
			(type default)
		)
		(layer "In7.Cu")
	)
	(gr_line
		(start 286.436562 -260.10235)
		(end 286.869886 -260.10235)
		(stroke
			(width 0.0635)
			(type default)
		)
		(layer "In7.Cu")
	)
	(gr_line
		(start 286.436562 -256.502408)
		(end 286.869886 -256.502408)
		(stroke
			(width 0.0635)
			(type default)
		)
		(layer "In7.Cu")
	)
	(gr_line
		(start 286.436562 -252.902212)
		(end 286.869886 -252.902212)
		(stroke
			(width 0.0635)
			(type default)
		)
		(layer "In7.Cu")
	)
	(gr_line
		(start 286.562546 -15.125446)
		(end 286.770064 -15.444978)
		(stroke
			(width 0.0635)
			(type default)
		)
		(layer "In7.Cu")
	)
	(gr_line
		(start 286.723074 -16.142208)
		(end 287.041082 -16.63192)
		(stroke
			(width 0.0635)
			(type default)
		)
		(layer "In7.Cu")
	)
	(gr_line
		(start 286.729678 -15.634716)
		(end 286.770064 -15.444978)
		(stroke
			(width 0.0635)
			(type default)
		)
		(layer "In7.Cu")
	)
	(gr_arc
		(start 286.846772 -354.10521)
		(mid 286.936596 -354.068023)
		(end 286.973772 -353.97821)
		(stroke
			(width 0.0508)
			(type default)
		)
		(layer "In7.Cu")
	)
	(gr_arc
		(start 286.846772 -350.505268)
		(mid 286.936581 -350.468079)
		(end 286.973772 -350.378268)
		(stroke
			(width 0.0508)
			(type default)
		)
		(layer "In7.Cu")
	)
	(gr_arc
		(start 286.846772 -336.105246)
		(mid 286.936575 -336.068049)
		(end 286.973772 -335.978246)
		(stroke
			(width 0.0508)
			(type default)
		)
		(layer "In7.Cu")
	)
	(gr_arc
		(start 286.846772 -332.50505)
		(mid 286.936575 -332.467853)
		(end 286.973772 -332.37805)
		(stroke
			(width 0.0508)
			(type default)
		)
		(layer "In7.Cu")
	)
	(gr_arc
		(start 286.846772 -328.905108)
		(mid 286.936575 -328.867911)
		(end 286.973772 -328.778108)
		(stroke
			(width 0.0508)
			(type default)
		)
		(layer "In7.Cu")
	)
	(gr_arc
		(start 286.846772 -314.505086)
		(mid 286.936575 -314.467889)
		(end 286.973772 -314.378086)
		(stroke
			(width 0.0508)
			(type default)
		)
		(layer "In7.Cu")
	)
	(gr_arc
		(start 286.846772 -310.905144)
		(mid 286.936575 -310.867947)
		(end 286.973772 -310.778144)
		(stroke
			(width 0.0508)
			(type default)
		)
		(layer "In7.Cu")
	)
	(gr_arc
		(start 286.846772 -307.305202)
		(mid 286.936575 -307.268005)
		(end 286.973772 -307.178202)
		(stroke
			(width 0.0508)
			(type default)
		)
		(layer "In7.Cu")
	)
	(gr_line
		(start 286.93999 -15.958566)
		(end 287.129728 -15.998698)
		(stroke
			(width 0.0635)
			(type default)
		)
		(layer "In7.Cu")
	)
	(gr_arc
		(start 286.9692 -296.632122)
		(mid 286.932003 -296.542319)
		(end 286.8422 -296.505122)
		(stroke
			(width 0.0508)
			(type default)
		)
		(layer "In7.Cu")
	)
	(gr_arc
		(start 286.996886 -263.829292)
		(mid 286.959685 -263.7395)
		(end 286.869886 -263.702292)
		(stroke
			(width 0.0635)
			(type default)
		)
		(layer "In7.Cu")
	)
	(gr_arc
		(start 286.996886 -260.22935)
		(mid 286.959705 -260.13952)
		(end 286.869886 -260.10235)
		(stroke
			(width 0.0635)
			(type default)
		)
		(layer "In7.Cu")
	)
	(gr_arc
		(start 286.996886 -256.629408)
		(mid 286.959691 -256.539605)
		(end 286.869886 -256.502408)
		(stroke
			(width 0.0635)
			(type default)
		)
		(layer "In7.Cu")
	)
	(gr_arc
		(start 286.996886 -253.029212)
		(mid 286.959692 -252.939407)
		(end 286.869886 -252.902212)
		(stroke
			(width 0.0635)
			(type default)
		)
		(layer "In7.Cu")
	)
	(gr_line
		(start 287.022794 -291.402516)
		(end 287.036002 -291.398198)
		(stroke
			(width 0.0508)
			(type default)
		)
		(layer "In7.Cu")
	)
	(gr_line
		(start 287.036002 -291.398198)
		(end 287.047178 -291.39007)
		(stroke
			(width 0.0508)
			(type default)
		)
		(layer "In7.Cu")
	)
	(gr_line
		(start 287.123378 -244.9703)
		(end 287.205928 -244.59819)
		(stroke
			(width 0.0635)
			(type default)
		)
		(layer "In7.Cu")
	)
	(gr_line
		(start 287.123378 -244.9703)
		(end 287.235392 -245.146068)
		(stroke
			(width 0.0635)
			(type default)
		)
		(layer "In7.Cu")
	)
	(gr_line
		(start 287.129728 -15.998698)
		(end 287.337246 -16.31823)
		(stroke
			(width 0.0635)
			(type default)
		)
		(layer "In7.Cu")
	)
	(gr_line
		(start 287.154874 -245.520972)
		(end 287.16097 -245.49354)
		(stroke
			(width 0.0635)
			(type default)
		)
		(layer "In7.Cu")
	)
	(gr_line
		(start 287.154874 -245.520972)
		(end 287.161732 -245.548658)
		(stroke
			(width 0.0635)
			(type default)
		)
		(layer "In7.Cu")
	)
	(gr_line
		(start 287.16859 -245.458742)
		(end 287.169606 -245.454678)
		(stroke
			(width 0.0635)
			(type default)
		)
		(layer "In7.Cu")
	)
	(gr_line
		(start 287.189926 -245.363492)
		(end 287.237424 -245.149116)
		(stroke
			(width 0.0635)
			(type default)
		)
		(layer "In7.Cu")
	)
	(gr_line
		(start 287.205928 -244.59819)
		(end 287.381696 -244.48643)
		(stroke
			(width 0.0635)
			(type default)
		)
		(layer "In7.Cu")
	)
	(gr_line
		(start 287.296606 -292.890194)
		(end 287.830006 -292.498018)
		(stroke
			(width 0.0508)
			(type default)
		)
		(layer "In7.Cu")
	)
	(gr_line
		(start 287.29686 -16.508222)
		(end 287.337246 -16.31823)
		(stroke
			(width 0.0635)
			(type default)
		)
		(layer "In7.Cu")
	)
	(gr_arc
		(start 287.303972 -357.578152)
		(mid 287.341169 -357.667955)
		(end 287.430972 -357.705152)
		(stroke
			(width 0.0508)
			(type default)
		)
		(layer "In7.Cu")
	)
	(gr_arc
		(start 287.303972 -353.97821)
		(mid 287.341169 -354.068013)
		(end 287.430972 -354.10521)
		(stroke
			(width 0.0508)
			(type default)
		)
		(layer "In7.Cu")
	)
	(gr_arc
		(start 287.303972 -350.378268)
		(mid 287.341169 -350.468071)
		(end 287.430972 -350.505268)
		(stroke
			(width 0.0508)
			(type default)
		)
		(layer "In7.Cu")
	)
	(gr_arc
		(start 287.303972 -335.978246)
		(mid 287.341169 -336.068049)
		(end 287.430972 -336.105246)
		(stroke
			(width 0.0508)
			(type default)
		)
		(layer "In7.Cu")
	)
	(gr_arc
		(start 287.303972 -332.37805)
		(mid 287.34115 -332.467895)
		(end 287.430972 -332.50505)
		(stroke
			(width 0.0508)
			(type default)
		)
		(layer "In7.Cu")
	)
	(gr_arc
		(start 287.303972 -328.778108)
		(mid 287.341169 -328.867911)
		(end 287.430972 -328.905108)
		(stroke
			(width 0.0508)
			(type default)
		)
		(layer "In7.Cu")
	)
	(gr_arc
		(start 287.303972 -314.378086)
		(mid 287.341163 -314.467908)
		(end 287.430972 -314.505086)
		(stroke
			(width 0.0508)
			(type default)
		)
		(layer "In7.Cu")
	)
	(gr_arc
		(start 287.303972 -310.778144)
		(mid 287.341183 -310.867928)
		(end 287.430972 -310.905144)
		(stroke
			(width 0.0508)
			(type default)
		)
		(layer "In7.Cu")
	)
	(gr_arc
		(start 287.303972 -307.178202)
		(mid 287.341168 -307.268013)
		(end 287.430972 -307.305202)
		(stroke
			(width 0.0508)
			(type default)
		)
		(layer "In7.Cu")
	)
	(gr_line
		(start 287.353248 -243.933726)
		(end 287.435798 -243.561616)
		(stroke
			(width 0.0635)
			(type default)
		)
		(layer "In7.Cu")
	)
	(gr_line
		(start 287.353248 -243.933726)
		(end 287.465262 -244.109748)
		(stroke
			(width 0.0635)
			(type default)
		)
		(layer "In7.Cu")
	)
	(gr_line
		(start 287.384744 -244.484398)
		(end 287.400492 -244.413278)
		(stroke
			(width 0.0635)
			(type default)
		)
		(layer "In7.Cu")
	)
	(gr_arc
		(start 287.403286 -263.702292)
		(mid 287.313483 -263.739489)
		(end 287.276286 -263.829292)
		(stroke
			(width 0.0635)
			(type default)
		)
		(layer "In7.Cu")
	)
	(gr_line
		(start 287.403286 -263.702292)
		(end 287.83661 -263.702292)
		(stroke
			(width 0.0635)
			(type default)
		)
		(layer "In7.Cu")
	)
	(gr_arc
		(start 287.403286 -260.10235)
		(mid 287.313483 -260.139547)
		(end 287.276286 -260.22935)
		(stroke
			(width 0.0635)
			(type default)
		)
		(layer "In7.Cu")
	)
	(gr_line
		(start 287.403286 -260.10235)
		(end 287.83661 -260.10235)
		(stroke
			(width 0.0635)
			(type default)
		)
		(layer "In7.Cu")
	)
	(gr_arc
		(start 287.403286 -256.502408)
		(mid 287.313483 -256.539605)
		(end 287.276286 -256.629408)
		(stroke
			(width 0.0635)
			(type default)
		)
		(layer "In7.Cu")
	)
	(gr_line
		(start 287.403286 -256.502408)
		(end 287.83661 -256.502408)
		(stroke
			(width 0.0635)
			(type default)
		)
		(layer "In7.Cu")
	)
	(gr_arc
		(start 287.403286 -252.902212)
		(mid 287.313483 -252.939409)
		(end 287.276286 -253.029212)
		(stroke
			(width 0.0635)
			(type default)
		)
		(layer "In7.Cu")
	)
	(gr_line
		(start 287.403286 -252.902212)
		(end 287.83661 -252.902212)
		(stroke
			(width 0.0635)
			(type default)
		)
		(layer "In7.Cu")
	)
	(gr_arc
		(start 287.4264 -296.505122)
		(mid 287.336605 -296.542321)
		(end 287.2994 -296.632122)
		(stroke
			(width 0.0508)
			(type default)
		)
		(layer "In7.Cu")
	)
	(gr_line
		(start 287.4264 -296.505122)
		(end 287.83661 -296.505122)
		(stroke
			(width 0.0508)
			(type default)
		)
		(layer "In7.Cu")
	)
	(gr_line
		(start 287.430972 -357.705152)
		(end 287.83661 -357.705152)
		(stroke
			(width 0.0508)
			(type default)
		)
		(layer "In7.Cu")
	)
	(gr_line
		(start 287.430972 -354.10521)
		(end 287.83661 -354.10521)
		(stroke
			(width 0.0508)
			(type default)
		)
		(layer "In7.Cu")
	)
	(gr_line
		(start 287.430972 -350.505268)
		(end 287.83661 -350.505268)
		(stroke
			(width 0.0508)
			(type default)
		)
		(layer "In7.Cu")
	)
	(gr_line
		(start 287.430972 -336.105246)
		(end 287.83661 -336.105246)
		(stroke
			(width 0.0508)
			(type default)
		)
		(layer "In7.Cu")
	)
	(gr_line
		(start 287.430972 -332.50505)
		(end 287.83661 -332.50505)
		(stroke
			(width 0.0508)
			(type default)
		)
		(layer "In7.Cu")
	)
	(gr_line
		(start 287.430972 -328.905108)
		(end 287.83661 -328.905108)
		(stroke
			(width 0.0508)
			(type default)
		)
		(layer "In7.Cu")
	)
	(gr_line
		(start 287.430972 -314.505086)
		(end 287.83661 -314.505086)
		(stroke
			(width 0.0508)
			(type default)
		)
		(layer "In7.Cu")
	)
	(gr_line
		(start 287.430972 -310.905144)
		(end 287.83661 -310.905144)
		(stroke
			(width 0.0508)
			(type default)
		)
		(layer "In7.Cu")
	)
	(gr_line
		(start 287.430972 -307.305202)
		(end 287.83661 -307.305202)
		(stroke
			(width 0.0508)
			(type default)
		)
		(layer "In7.Cu")
	)
	(gr_line
		(start 287.435798 -243.561616)
		(end 287.611566 -243.449602)
		(stroke
			(width 0.0635)
			(type default)
		)
		(layer "In7.Cu")
	)
	(gr_line
		(start 287.4645 -293.179754)
		(end 287.763204 -293.22522)
		(stroke
			(width 0.0508)
			(type default)
		)
		(layer "In7.Cu")
	)
	(gr_line
		(start 287.509458 -245.213378)
		(end 287.510982 -245.206012)
		(stroke
			(width 0.0635)
			(type default)
		)
		(layer "In7.Cu")
	)
	(gr_line
		(start 287.518348 -245.171722)
		(end 287.649158 -244.582442)
		(stroke
			(width 0.0635)
			(type default)
		)
		(layer "In7.Cu")
	)
	(gr_line
		(start 287.583118 -242.897152)
		(end 287.665414 -242.525296)
		(stroke
			(width 0.0635)
			(type default)
		)
		(layer "In7.Cu")
	)
	(gr_line
		(start 287.583118 -242.897152)
		(end 287.695132 -243.07292)
		(stroke
			(width 0.0635)
			(type default)
		)
		(layer "In7.Cu")
	)
	(gr_line
		(start 287.656778 -244.54866)
		(end 287.673288 -244.473476)
		(stroke
			(width 0.0635)
			(type default)
		)
		(layer "In7.Cu")
	)
	(gr_line
		(start 287.665414 -242.525296)
		(end 287.841182 -242.413028)
		(stroke
			(width 0.0635)
			(type default)
		)
		(layer "In7.Cu")
	)
	(gr_line
		(start 287.747964 -244.13718)
		(end 287.879282 -243.544598)
		(stroke
			(width 0.0635)
			(type default)
		)
		(layer "In7.Cu")
	)
	(gr_line
		(start 287.763204 -293.22522)
		(end 288.008822 -293.04488)
		(stroke
			(width 0.0508)
			(type default)
		)
		(layer "In7.Cu")
	)
	(gr_line
		(start 287.978088 -243.09832)
		(end 288.108644 -242.50904)
		(stroke
			(width 0.0635)
			(type default)
		)
		(layer "In7.Cu")
	)
	(gr_line
		(start 288.008822 -293.04488)
		(end 288.054542 -292.746176)
		(stroke
			(width 0.0508)
			(type default)
		)
		(layer "In7.Cu")
	)
	(gr_line
		(start 288.023046 -295.7703)
		(end 288.033968 -295.766744)
		(stroke
			(width 0.0508)
			(type default)
		)
		(layer "In7.Cu")
	)
	(gr_line
		(start 288.135314 -292.273736)
		(end 288.667698 -291.882576)
		(stroke
			(width 0.0508)
			(type default)
		)
		(layer "In7.Cu")
	)
	(gr_line
		(start 288.157158 -252.14199)
		(end 288.19856 -252.113542)
		(stroke
			(width 0.0635)
			(type default)
		)
		(layer "In7.Cu")
	)
	(gr_line
		(start 288.303716 -292.563042)
		(end 288.60242 -292.608762)
		(stroke
			(width 0.0508)
			(type default)
		)
		(layer "In7.Cu")
	)
	(gr_line
		(start 288.554668 -255.741932)
		(end 288.59607 -255.713484)
		(stroke
			(width 0.0635)
			(type default)
		)
		(layer "In7.Cu")
	)
	(gr_line
		(start 288.583878 -251.846842)
		(end 288.632392 -251.813568)
		(stroke
			(width 0.0635)
			(type default)
		)
		(layer "In7.Cu")
	)
	(gr_line
		(start 288.60242 -292.608762)
		(end 288.848038 -292.428168)
		(stroke
			(width 0.0508)
			(type default)
		)
		(layer "In7.Cu")
	)
	(gr_line
		(start 288.606738 -245.019576)
		(end 288.689288 -244.647466)
		(stroke
			(width 0.0635)
			(type default)
		)
		(layer "In7.Cu")
	)
	(gr_line
		(start 288.606738 -245.019576)
		(end 288.719006 -245.195598)
		(stroke
			(width 0.0635)
			(type default)
		)
		(layer "In7.Cu")
	)
	(gr_line
		(start 288.615628 -297.570144)
		(end 288.62655 -297.566588)
		(stroke
			(width 0.0508)
			(type default)
		)
		(layer "In7.Cu")
	)
	(gr_line
		(start 288.632392 -251.813568)
		(end 288.649664 -251.756672)
		(stroke
			(width 0.0635)
			(type default)
		)
		(layer "In7.Cu")
	)
	(gr_line
		(start 288.638234 -245.570248)
		(end 288.644584 -245.542054)
		(stroke
			(width 0.0635)
			(type default)
		)
		(layer "In7.Cu")
	)
	(gr_line
		(start 288.638234 -245.570248)
		(end 288.6456 -245.599458)
		(stroke
			(width 0.0635)
			(type default)
		)
		(layer "In7.Cu")
	)
	(gr_line
		(start 288.689288 -244.647466)
		(end 288.86531 -244.535452)
		(stroke
			(width 0.0635)
			(type default)
		)
		(layer "In7.Cu")
	)
	(gr_line
		(start 288.82467 -251.18695)
		(end 288.836608 -251.147834)
		(stroke
			(width 0.0635)
			(type default)
		)
		(layer "In7.Cu")
	)
	(gr_line
		(start 288.826702 -251.109226)
		(end 288.836354 -251.14758)
		(stroke
			(width 0.0635)
			(type default)
		)
		(layer "In7.Cu")
	)
	(gr_line
		(start 288.836354 -251.14758)
		(end 288.836608 -251.147834)
		(stroke
			(width 0.0635)
			(type default)
		)
		(layer "In7.Cu")
	)
	(gr_line
		(start 288.836608 -243.983002)
		(end 288.918904 -243.610892)
		(stroke
			(width 0.0635)
			(type default)
		)
		(layer "In7.Cu")
	)
	(gr_line
		(start 288.836608 -243.983002)
		(end 288.948622 -244.159024)
		(stroke
			(width 0.0635)
			(type default)
		)
		(layer "In7.Cu")
	)
	(gr_line
		(start 288.848038 -292.428168)
		(end 288.893758 -292.129464)
		(stroke
			(width 0.0508)
			(type default)
		)
		(layer "In7.Cu")
	)
	(gr_line
		(start 288.918904 -243.610892)
		(end 289.094926 -243.498878)
		(stroke
			(width 0.0635)
			(type default)
		)
		(layer "In7.Cu")
	)
	(gr_line
		(start 288.975038 -291.65677)
		(end 289.505644 -291.26688)
		(stroke
			(width 0.0508)
			(type default)
		)
		(layer "In7.Cu")
	)
	(gr_line
		(start 289.001708 -245.222776)
		(end 289.133026 -244.630194)
		(stroke
			(width 0.0635)
			(type default)
		)
		(layer "In7.Cu")
	)
	(gr_line
		(start 289.051746 -222.437198)
		(end 289.059112 -222.448882)
		(stroke
			(width 0.0635)
			(type default)
		)
		(layer "In7.Cu")
	)
	(gr_line
		(start 289.059112 -222.448882)
		(end 289.06216 -222.462344)
		(stroke
			(width 0.0635)
			(type default)
		)
		(layer "In7.Cu")
	)
	(gr_line
		(start 289.066224 -242.946428)
		(end 289.148774 -242.574318)
		(stroke
			(width 0.0635)
			(type default)
		)
		(layer "In7.Cu")
	)
	(gr_line
		(start 289.066224 -242.946428)
		(end 289.178492 -243.12245)
		(stroke
			(width 0.0635)
			(type default)
		)
		(layer "In7.Cu")
	)
	(gr_line
		(start 289.074098 -257.54203)
		(end 289.115246 -257.513582)
		(stroke
			(width 0.0635)
			(type default)
		)
		(layer "In7.Cu")
	)
	(gr_line
		(start 289.125152 -253.941834)
		(end 289.16503 -253.914148)
		(stroke
			(width 0.0635)
			(type default)
		)
		(layer "In7.Cu")
	)
	(gr_line
		(start 289.142932 -291.94633)
		(end 289.441636 -291.99205)
		(stroke
			(width 0.0508)
			(type default)
		)
		(layer "In7.Cu")
	)
	(gr_line
		(start 289.148774 -242.574318)
		(end 289.324796 -242.462304)
		(stroke
			(width 0.0635)
			(type default)
		)
		(layer "In7.Cu")
	)
	(gr_line
		(start 289.230308 -295.375838)
		(end 289.241738 -295.372028)
		(stroke
			(width 0.0508)
			(type default)
		)
		(layer "In7.Cu")
	)
	(gr_line
		(start 289.231324 -244.186964)
		(end 289.362896 -243.592858)
		(stroke
			(width 0.0635)
			(type default)
		)
		(layer "In7.Cu")
	)
	(gr_line
		(start 289.241738 -295.372028)
		(end 289.25139 -295.364916)
		(stroke
			(width 0.0508)
			(type default)
		)
		(layer "In7.Cu")
	)
	(gr_line
		(start 289.441636 -291.99205)
		(end 289.687254 -291.811456)
		(stroke
			(width 0.0508)
			(type default)
		)
		(layer "In7.Cu")
	)
	(gr_line
		(start 289.461194 -243.150136)
		(end 289.592512 -242.5573)
		(stroke
			(width 0.0635)
			(type default)
		)
		(layer "In7.Cu")
	)
	(gr_line
		(start 289.472878 -297.289982)
		(end 289.484308 -297.286172)
		(stroke
			(width 0.0508)
			(type default)
		)
		(layer "In7.Cu")
	)
	(gr_line
		(start 289.484308 -297.286172)
		(end 289.49396 -297.27906)
		(stroke
			(width 0.0508)
			(type default)
		)
		(layer "In7.Cu")
	)
	(gr_line
		(start 289.618928 -253.600966)
		(end 289.672268 -253.564136)
		(stroke
			(width 0.0635)
			(type default)
		)
		(layer "In7.Cu")
	)
	(gr_line
		(start 289.648392 -233.580178)
		(end 289.730942 -233.208322)
		(stroke
			(width 0.0635)
			(type default)
		)
		(layer "In7.Cu")
	)
	(gr_line
		(start 289.648392 -233.580178)
		(end 289.760406 -233.7562)
		(stroke
			(width 0.0635)
			(type default)
		)
		(layer "In7.Cu")
	)
	(gr_line
		(start 289.672268 -253.564136)
		(end 289.689032 -253.501906)
		(stroke
			(width 0.0635)
			(type default)
		)
		(layer "In7.Cu")
	)
	(gr_line
		(start 289.687254 -291.811456)
		(end 289.73272 -291.513006)
		(stroke
			(width 0.0508)
			(type default)
		)
		(layer "In7.Cu")
	)
	(gr_line
		(start 289.730942 -233.208322)
		(end 289.90671 -233.096308)
		(stroke
			(width 0.0635)
			(type default)
		)
		(layer "In7.Cu")
	)
	(gr_line
		(start 289.82797 -34.288984)
		(end 290.403026 -34.174938)
		(stroke
			(width 0.0635)
			(type default)
		)
		(layer "In7.Cu")
	)
	(gr_line
		(start 289.848798 -34.572448)
		(end 290.010088 -34.680398)
		(stroke
			(width 0.0635)
			(type default)
		)
		(layer "In7.Cu")
	)
	(gr_line
		(start 289.878262 -232.543604)
		(end 289.960558 -232.171748)
		(stroke
			(width 0.0635)
			(type default)
		)
		(layer "In7.Cu")
	)
	(gr_line
		(start 289.878262 -232.543604)
		(end 289.990276 -232.719626)
		(stroke
			(width 0.0635)
			(type default)
		)
		(layer "In7.Cu")
	)
	(gr_line
		(start 289.960558 -232.171748)
		(end 290.13658 -232.059734)
		(stroke
			(width 0.0635)
			(type default)
		)
		(layer "In7.Cu")
	)
	(gr_line
		(start 290.010088 -34.680398)
		(end 290.383722 -34.60623)
		(stroke
			(width 0.0635)
			(type default)
		)
		(layer "In7.Cu")
	)
	(gr_line
		(start 290.019486 -245.613682)
		(end 290.102036 -245.241572)
		(stroke
			(width 0.0635)
			(type default)
		)
		(layer "In7.Cu")
	)
	(gr_line
		(start 290.019486 -245.613682)
		(end 290.131754 -245.789704)
		(stroke
			(width 0.0635)
			(type default)
		)
		(layer "In7.Cu")
	)
	(gr_line
		(start 290.043108 -233.783124)
		(end 290.174172 -233.191812)
		(stroke
			(width 0.0635)
			(type default)
		)
		(layer "In7.Cu")
	)
	(gr_line
		(start 290.050982 -246.164354)
		(end 290.057332 -246.13616)
		(stroke
			(width 0.0635)
			(type default)
		)
		(layer "In7.Cu")
	)
	(gr_line
		(start 290.050982 -246.164354)
		(end 290.058348 -246.193564)
		(stroke
			(width 0.0635)
			(type default)
		)
		(layer "In7.Cu")
	)
	(gr_line
		(start 290.102036 -245.241572)
		(end 290.278058 -245.129558)
		(stroke
			(width 0.0635)
			(type default)
		)
		(layer "In7.Cu")
	)
	(gr_line
		(start 290.108132 -231.50703)
		(end 290.190428 -231.135174)
		(stroke
			(width 0.0635)
			(type default)
		)
		(layer "In7.Cu")
	)
	(gr_line
		(start 290.108132 -231.50703)
		(end 290.220146 -231.682798)
		(stroke
			(width 0.0635)
			(type default)
		)
		(layer "In7.Cu")
	)
	(gr_line
		(start 290.190428 -231.135174)
		(end 290.366196 -231.02316)
		(stroke
			(width 0.0635)
			(type default)
		)
		(layer "In7.Cu")
	)
	(gr_line
		(start 290.194746 -221.013782)
		(end 290.201604 -221.024704)
		(stroke
			(width 0.0635)
			(type default)
		)
		(layer "In7.Cu")
	)
	(gr_line
		(start 290.201604 -221.024704)
		(end 290.204398 -221.037404)
		(stroke
			(width 0.0635)
			(type default)
		)
		(layer "In7.Cu")
	)
	(gr_line
		(start 290.249356 -244.577108)
		(end 290.331906 -244.205252)
		(stroke
			(width 0.0635)
			(type default)
		)
		(layer "In7.Cu")
	)
	(gr_line
		(start 290.249356 -244.577108)
		(end 290.361624 -244.75313)
		(stroke
			(width 0.0635)
			(type default)
		)
		(layer "In7.Cu")
	)
	(gr_line
		(start 290.272978 -232.74655)
		(end 290.404042 -232.155238)
		(stroke
			(width 0.0635)
			(type default)
		)
		(layer "In7.Cu")
	)
	(gr_line
		(start 290.300156 -251.270262)
		(end 290.335462 -251.211334)
		(stroke
			(width 0.0635)
			(type default)
		)
		(layer "In7.Cu")
	)
	(gr_line
		(start 290.316412 -251.134626)
		(end 290.335462 -251.211334)
		(stroke
			(width 0.0635)
			(type default)
		)
		(layer "In7.Cu")
	)
	(gr_line
		(start 290.331906 -244.205252)
		(end 290.507928 -244.092984)
		(stroke
			(width 0.0635)
			(type default)
		)
		(layer "In7.Cu")
	)
	(gr_line
		(start 290.383722 -34.60623)
		(end 290.491672 -34.44494)
		(stroke
			(width 0.0635)
			(type default)
		)
		(layer "In7.Cu")
	)
	(gr_line
		(start 290.414456 -245.816882)
		(end 290.545774 -245.2243)
		(stroke
			(width 0.0635)
			(type default)
		)
		(layer "In7.Cu")
	)
	(gr_line
		(start 290.479226 -243.540534)
		(end 290.561776 -243.168678)
		(stroke
			(width 0.0635)
			(type default)
		)
		(layer "In7.Cu")
	)
	(gr_line
		(start 290.479226 -243.540534)
		(end 290.59124 -243.71681)
		(stroke
			(width 0.0635)
			(type default)
		)
		(layer "In7.Cu")
	)
	(gr_line
		(start 290.502848 -231.709976)
		(end 290.633912 -231.118664)
		(stroke
			(width 0.0635)
			(type default)
		)
		(layer "In7.Cu")
	)
	(gr_line
		(start 290.561776 -243.168678)
		(end 290.737798 -243.05641)
		(stroke
			(width 0.0635)
			(type default)
		)
		(layer "In7.Cu")
	)
	(gr_line
		(start 290.644326 -244.7798)
		(end 290.77539 -244.188488)
		(stroke
			(width 0.0635)
			(type default)
		)
		(layer "In7.Cu")
	)
	(gr_line
		(start 290.80206 -230.36022)
		(end 290.80206 -230.360474)
		(stroke
			(width 0.0635)
			(type default)
		)
		(layer "In7.Cu")
	)
	(gr_line
		(start 290.80206 -230.359966)
		(end 290.807394 -230.33609)
		(stroke
			(width 0.0635)
			(type default)
		)
		(layer "In7.Cu")
	)
	(gr_line
		(start 290.80206 -230.31196)
		(end 290.807394 -230.33609)
		(stroke
			(width 0.0635)
			(type default)
		)
		(layer "In7.Cu")
	)
	(gr_line
		(start 290.847526 -34.0868)
		(end 291.425122 -33.972246)
		(stroke
			(width 0.0635)
			(type default)
		)
		(layer "In7.Cu")
	)
	(gr_line
		(start 290.867084 -254.144526)
		(end 290.91763 -254.109474)
		(stroke
			(width 0.0635)
			(type default)
		)
		(layer "In7.Cu")
	)
	(gr_line
		(start 290.870132 -34.369756)
		(end 291.031422 -34.477706)
		(stroke
			(width 0.0635)
			(type default)
		)
		(layer "In7.Cu")
	)
	(gr_line
		(start 290.873942 -243.744242)
		(end 291.00526 -243.151914)
		(stroke
			(width 0.0635)
			(type default)
		)
		(layer "In7.Cu")
	)
	(gr_line
		(start 290.91763 -254.109474)
		(end 290.935664 -254.051054)
		(stroke
			(width 0.0635)
			(type default)
		)
		(layer "In7.Cu")
	)
	(gr_line
		(start 291.031422 -34.477706)
		(end 291.40531 -34.403538)
		(stroke
			(width 0.0635)
			(type default)
		)
		(layer "In7.Cu")
	)
	(gr_line
		(start 291.098732 -233.777282)
		(end 291.181028 -233.405426)
		(stroke
			(width 0.0635)
			(type default)
		)
		(layer "In7.Cu")
	)
	(gr_line
		(start 291.098732 -233.777282)
		(end 291.210746 -233.953304)
		(stroke
			(width 0.0635)
			(type default)
		)
		(layer "In7.Cu")
	)
	(gr_line
		(start 291.181028 -233.405426)
		(end 291.35705 -233.293158)
		(stroke
			(width 0.0635)
			(type default)
		)
		(layer "In7.Cu")
	)
	(gr_line
		(start 291.246052 -245.562374)
		(end 291.328602 -245.190264)
		(stroke
			(width 0.0635)
			(type default)
		)
		(layer "In7.Cu")
	)
	(gr_line
		(start 291.246052 -245.562374)
		(end 291.35832 -245.738396)
		(stroke
			(width 0.0635)
			(type default)
		)
		(layer "In7.Cu")
	)
	(gr_line
		(start 291.277548 -246.113046)
		(end 291.283898 -246.084852)
		(stroke
			(width 0.0635)
			(type default)
		)
		(layer "In7.Cu")
	)
	(gr_line
		(start 291.277548 -246.113046)
		(end 291.284914 -246.142256)
		(stroke
			(width 0.0635)
			(type default)
		)
		(layer "In7.Cu")
	)
	(gr_line
		(start 291.328348 -232.740708)
		(end 291.410898 -232.368852)
		(stroke
			(width 0.0635)
			(type default)
		)
		(layer "In7.Cu")
	)
	(gr_line
		(start 291.328348 -232.740708)
		(end 291.440362 -232.91673)
		(stroke
			(width 0.0635)
			(type default)
		)
		(layer "In7.Cu")
	)
	(gr_line
		(start 291.328602 -245.190264)
		(end 291.504624 -245.07825)
		(stroke
			(width 0.0635)
			(type default)
		)
		(layer "In7.Cu")
	)
	(gr_line
		(start 291.40531 -34.403538)
		(end 291.51326 -34.242248)
		(stroke
			(width 0.0635)
			(type default)
		)
		(layer "In7.Cu")
	)
	(gr_line
		(start 291.410898 -232.368852)
		(end 291.586666 -232.256584)
		(stroke
			(width 0.0635)
			(type default)
		)
		(layer "In7.Cu")
	)
	(gr_line
		(start 291.421566 -219.781882)
		(end 291.428932 -219.793566)
		(stroke
			(width 0.0635)
			(type default)
		)
		(layer "In7.Cu")
	)
	(gr_line
		(start 291.428932 -219.793566)
		(end 291.43198 -219.807028)
		(stroke
			(width 0.0635)
			(type default)
		)
		(layer "In7.Cu")
	)
	(gr_line
		(start 291.475922 -244.5258)
		(end 291.558472 -244.15369)
		(stroke
			(width 0.0635)
			(type default)
		)
		(layer "In7.Cu")
	)
	(gr_line
		(start 291.475922 -244.5258)
		(end 291.587936 -244.702076)
		(stroke
			(width 0.0635)
			(type default)
		)
		(layer "In7.Cu")
	)
	(gr_line
		(start 291.493448 -233.980736)
		(end 291.624766 -233.3879)
		(stroke
			(width 0.0635)
			(type default)
		)
		(layer "In7.Cu")
	)
	(gr_line
		(start 291.558218 -231.704134)
		(end 291.640514 -231.332278)
		(stroke
			(width 0.0635)
			(type default)
		)
		(layer "In7.Cu")
	)
	(gr_line
		(start 291.558218 -231.704134)
		(end 291.670232 -231.880156)
		(stroke
			(width 0.0635)
			(type default)
		)
		(layer "In7.Cu")
	)
	(gr_line
		(start 291.558472 -244.15369)
		(end 291.734494 -244.041676)
		(stroke
			(width 0.0635)
			(type default)
		)
		(layer "In7.Cu")
	)
	(gr_line
		(start 291.640514 -231.332278)
		(end 291.816536 -231.22001)
		(stroke
			(width 0.0635)
			(type default)
		)
		(layer "In7.Cu")
	)
	(gr_line
		(start 291.641022 -245.765828)
		(end 291.772594 -245.17223)
		(stroke
			(width 0.0635)
			(type default)
		)
		(layer "In7.Cu")
	)
	(gr_line
		(start 291.662612 -23.748492)
		(end 291.675312 -23.76805)
		(stroke
			(width 0.0635)
			(type default)
		)
		(layer "In7.Cu")
	)
	(gr_line
		(start 291.675312 -23.76805)
		(end 291.69487 -23.78075)
		(stroke
			(width 0.0635)
			(type default)
		)
		(layer "In7.Cu")
	)
	(gr_line
		(start 291.680646 -251.628148)
		(end 291.692838 -251.588524)
		(stroke
			(width 0.0635)
			(type default)
		)
		(layer "In7.Cu")
	)
	(gr_line
		(start 291.682932 -251.548646)
		(end 291.692838 -251.588524)
		(stroke
			(width 0.0635)
			(type default)
		)
		(layer "In7.Cu")
	)
	(gr_line
		(start 291.705792 -243.489226)
		(end 291.788342 -243.11737)
		(stroke
			(width 0.0635)
			(type default)
		)
		(layer "In7.Cu")
	)
	(gr_line
		(start 291.705792 -243.489226)
		(end 291.817806 -243.665248)
		(stroke
			(width 0.0635)
			(type default)
		)
		(layer "In7.Cu")
	)
	(gr_line
		(start 291.72281 -232.945178)
		(end 291.85489 -232.350056)
		(stroke
			(width 0.0635)
			(type default)
		)
		(layer "In7.Cu")
	)
	(gr_line
		(start 291.788342 -243.11737)
		(end 291.96411 -243.005102)
		(stroke
			(width 0.0635)
			(type default)
		)
		(layer "In7.Cu")
	)
	(gr_line
		(start 291.82314 -295.154858)
		(end 291.86886 -294.856662)
		(stroke
			(width 0.0508)
			(type default)
		)
		(layer "In7.Cu")
	)
	(gr_line
		(start 291.86886 -294.856662)
		(end 292.114478 -294.676068)
		(stroke
			(width 0.0508)
			(type default)
		)
		(layer "In7.Cu")
	)
	(gr_line
		(start 291.870384 -244.73154)
		(end 292.002464 -244.13591)
		(stroke
			(width 0.0635)
			(type default)
		)
		(layer "In7.Cu")
	)
	(gr_line
		(start 291.952934 -231.907842)
		(end 292.084506 -231.314244)
		(stroke
			(width 0.0635)
			(type default)
		)
		(layer "In7.Cu")
	)
	(gr_line
		(start 292.04539 -255.486916)
		(end 292.09492 -255.452626)
		(stroke
			(width 0.0635)
			(type default)
		)
		(layer "In7.Cu")
	)
	(gr_line
		(start 292.05174 -295.399714)
		(end 292.578028 -295.013126)
		(stroke
			(width 0.0508)
			(type default)
		)
		(layer "In7.Cu")
	)
	(gr_line
		(start 292.09492 -255.452626)
		(end 292.1127 -255.394968)
		(stroke
			(width 0.0635)
			(type default)
		)
		(layer "In7.Cu")
	)
	(gr_line
		(start 292.100508 -243.693442)
		(end 292.232334 -243.098574)
		(stroke
			(width 0.0635)
			(type default)
		)
		(layer "In7.Cu")
	)
	(gr_line
		(start 292.10381 -236.213904)
		(end 292.18636 -235.842048)
		(stroke
			(width 0.0635)
			(type default)
		)
		(layer "In7.Cu")
	)
	(gr_line
		(start 292.10381 -236.213904)
		(end 292.215824 -236.389926)
		(stroke
			(width 0.0635)
			(type default)
		)
		(layer "In7.Cu")
	)
	(gr_line
		(start 292.114478 -294.676068)
		(end 292.412674 -294.721788)
		(stroke
			(width 0.0508)
			(type default)
		)
		(layer "In7.Cu")
	)
	(gr_line
		(start 292.18636 -235.842048)
		(end 292.362128 -235.730288)
		(stroke
			(width 0.0635)
			(type default)
		)
		(layer "In7.Cu")
	)
	(gr_line
		(start 292.269926 -230.477314)
		(end 292.269926 -230.477822)
		(stroke
			(width 0.0635)
			(type default)
		)
		(layer "In7.Cu")
	)
	(gr_line
		(start 292.269926 -230.477314)
		(end 292.27526 -230.45293)
		(stroke
			(width 0.0635)
			(type default)
		)
		(layer "In7.Cu")
	)
	(gr_line
		(start 292.269926 -230.428546)
		(end 292.27526 -230.45293)
		(stroke
			(width 0.0635)
			(type default)
		)
		(layer "In7.Cu")
	)
	(gr_line
		(start 292.33368 -235.17733)
		(end 292.41623 -234.805474)
		(stroke
			(width 0.0635)
			(type default)
		)
		(layer "In7.Cu")
	)
	(gr_line
		(start 292.33368 -235.17733)
		(end 292.445694 -235.353352)
		(stroke
			(width 0.0635)
			(type default)
		)
		(layer "In7.Cu")
	)
	(gr_line
		(start 292.357556 -215.482424)
		(end 292.40099 -215.278208)
		(stroke
			(width 0.0635)
			(type default)
		)
		(layer "In7.Cu")
	)
	(gr_line
		(start 292.357556 -215.482424)
		(end 292.565074 -215.801956)
		(stroke
			(width 0.0635)
			(type default)
		)
		(layer "In7.Cu")
	)
	(gr_line
		(start 292.365176 -235.728256)
		(end 292.370764 -235.702602)
		(stroke
			(width 0.0635)
			(type default)
		)
		(layer "In7.Cu")
	)
	(gr_line
		(start 292.41623 -234.805474)
		(end 292.591998 -234.69346)
		(stroke
			(width 0.0635)
			(type default)
		)
		(layer "In7.Cu")
	)
	(gr_line
		(start 292.498526 -236.41812)
		(end 292.629844 -235.825538)
		(stroke
			(width 0.0635)
			(type default)
		)
		(layer "In7.Cu")
	)
	(gr_line
		(start 292.56355 -234.14101)
		(end 292.6461 -233.7689)
		(stroke
			(width 0.0635)
			(type default)
		)
		(layer "In7.Cu")
	)
	(gr_line
		(start 292.56355 -234.14101)
		(end 292.675564 -234.316778)
		(stroke
			(width 0.0635)
			(type default)
		)
		(layer "In7.Cu")
	)
	(gr_line
		(start 292.565074 -215.801956)
		(end 292.769544 -215.845644)
		(stroke
			(width 0.0635)
			(type default)
		)
		(layer "In7.Cu")
	)
	(gr_line
		(start 292.63594 -235.796836)
		(end 292.64356 -235.763054)
		(stroke
			(width 0.0635)
			(type default)
		)
		(layer "In7.Cu")
	)
	(gr_line
		(start 292.6461 -233.7689)
		(end 292.821868 -233.656886)
		(stroke
			(width 0.0635)
			(type default)
		)
		(layer "In7.Cu")
	)
	(gr_line
		(start 292.655752 -215.152732)
		(end 292.987984 -215.664542)
		(stroke
			(width 0.0635)
			(type default)
		)
		(layer "In7.Cu")
	)
	(gr_line
		(start 292.662356 -294.5384)
		(end 292.708076 -294.23995)
		(stroke
			(width 0.0508)
			(type default)
		)
		(layer "In7.Cu")
	)
	(gr_line
		(start 292.694868 -219.04833)
		(end 292.702234 -219.060014)
		(stroke
			(width 0.0635)
			(type default)
		)
		(layer "In7.Cu")
	)
	(gr_line
		(start 292.702234 -219.060014)
		(end 292.705282 -219.073476)
		(stroke
			(width 0.0635)
			(type default)
		)
		(layer "In7.Cu")
	)
	(gr_line
		(start 292.708076 -294.23995)
		(end 292.953694 -294.059356)
		(stroke
			(width 0.0508)
			(type default)
		)
		(layer "In7.Cu")
	)
	(gr_line
		(start 292.728396 -235.381292)
		(end 292.859968 -234.78744)
		(stroke
			(width 0.0635)
			(type default)
		)
		(layer "In7.Cu")
	)
	(gr_line
		(start 292.89121 -294.782748)
		(end 293.416736 -294.396668)
		(stroke
			(width 0.0508)
			(type default)
		)
		(layer "In7.Cu")
	)
	(gr_line
		(start 292.935914 -216.372948)
		(end 292.979348 -216.168478)
		(stroke
			(width 0.0635)
			(type default)
		)
		(layer "In7.Cu")
	)
	(gr_line
		(start 292.935914 -216.372948)
		(end 293.143432 -216.69248)
		(stroke
			(width 0.0635)
			(type default)
		)
		(layer "In7.Cu")
	)
	(gr_line
		(start 292.953694 -294.059356)
		(end 293.252144 -294.105076)
		(stroke
			(width 0.0508)
			(type default)
		)
		(layer "In7.Cu")
	)
	(gr_line
		(start 292.958266 -234.344464)
		(end 293.089838 -233.75112)
		(stroke
			(width 0.0635)
			(type default)
		)
		(layer "In7.Cu")
	)
	(gr_line
		(start 293.077138 -252.258322)
		(end 293.08933 -252.218698)
		(stroke
			(width 0.0635)
			(type default)
		)
		(layer "In7.Cu")
	)
	(gr_line
		(start 293.079424 -252.17882)
		(end 293.08933 -252.218698)
		(stroke
			(width 0.0635)
			(type default)
		)
		(layer "In7.Cu")
	)
	(gr_line
		(start 293.143432 -216.69248)
		(end 293.347648 -216.735914)
		(stroke
			(width 0.0635)
			(type default)
		)
		(layer "In7.Cu")
	)
	(gr_line
		(start 293.233094 -216.041732)
		(end 293.565834 -216.554304)
		(stroke
			(width 0.0635)
			(type default)
		)
		(layer "In7.Cu")
	)
	(gr_line
		(start 293.501572 -293.921688)
		(end 293.547292 -293.623238)
		(stroke
			(width 0.0508)
			(type default)
		)
		(layer "In7.Cu")
	)
	(gr_line
		(start 293.514018 -217.263472)
		(end 293.557452 -217.059002)
		(stroke
			(width 0.0635)
			(type default)
		)
		(layer "In7.Cu")
	)
	(gr_line
		(start 293.514018 -217.263472)
		(end 293.721536 -217.583004)
		(stroke
			(width 0.0635)
			(type default)
		)
		(layer "In7.Cu")
	)
	(gr_line
		(start 293.547292 -293.623238)
		(end 293.79291 -293.442898)
		(stroke
			(width 0.0508)
			(type default)
		)
		(layer "In7.Cu")
	)
	(gr_line
		(start 293.562278 -235.1151)
		(end 293.644828 -234.74299)
		(stroke
			(width 0.0635)
			(type default)
		)
		(layer "In7.Cu")
	)
	(gr_line
		(start 293.562278 -235.1151)
		(end 293.674292 -235.291122)
		(stroke
			(width 0.0635)
			(type default)
		)
		(layer "In7.Cu")
	)
	(gr_line
		(start 293.644828 -234.74299)
		(end 293.820596 -234.630976)
		(stroke
			(width 0.0635)
			(type default)
		)
		(layer "In7.Cu")
	)
	(gr_line
		(start 293.721536 -217.583004)
		(end 293.926006 -217.626184)
		(stroke
			(width 0.0635)
			(type default)
		)
		(layer "In7.Cu")
	)
	(gr_line
		(start 293.731188 -294.165782)
		(end 294.25646 -293.779956)
		(stroke
			(width 0.0508)
			(type default)
		)
		(layer "In7.Cu")
	)
	(gr_line
		(start 293.792148 -234.078526)
		(end 293.874698 -233.706416)
		(stroke
			(width 0.0635)
			(type default)
		)
		(layer "In7.Cu")
	)
	(gr_line
		(start 293.792148 -234.078526)
		(end 293.904162 -234.254548)
		(stroke
			(width 0.0635)
			(type default)
		)
		(layer "In7.Cu")
	)
	(gr_line
		(start 293.79291 -293.442898)
		(end 294.091106 -293.488618)
		(stroke
			(width 0.0508)
			(type default)
		)
		(layer "In7.Cu")
	)
	(gr_line
		(start 293.801038 -230.5431)
		(end 293.801038 -230.543354)
		(stroke
			(width 0.0635)
			(type default)
		)
		(layer "In7.Cu")
	)
	(gr_line
		(start 293.801038 -230.542846)
		(end 293.806372 -230.51897)
		(stroke
			(width 0.0635)
			(type default)
		)
		(layer "In7.Cu")
	)
	(gr_line
		(start 293.801038 -230.49484)
		(end 293.806372 -230.51897)
		(stroke
			(width 0.0635)
			(type default)
		)
		(layer "In7.Cu")
	)
	(gr_line
		(start 293.812468 -216.934034)
		(end 294.143938 -217.44432)
		(stroke
			(width 0.0635)
			(type default)
		)
		(layer "In7.Cu")
	)
	(gr_line
		(start 293.874698 -233.706416)
		(end 294.050466 -233.594402)
		(stroke
			(width 0.0635)
			(type default)
		)
		(layer "In7.Cu")
	)
	(gr_line
		(start 293.95674 -235.32084)
		(end 294.08882 -234.724956)
		(stroke
			(width 0.0635)
			(type default)
		)
		(layer "In7.Cu")
	)
	(gr_line
		(start 293.965376 -291.491924)
		(end 294.49395 -291.103558)
		(stroke
			(width 0.0508)
			(type default)
		)
		(layer "In7.Cu")
	)
	(gr_line
		(start 294.022018 -233.041952)
		(end 294.104314 -232.670096)
		(stroke
			(width 0.0635)
			(type default)
		)
		(layer "In7.Cu")
	)
	(gr_line
		(start 294.022018 -233.041952)
		(end 294.134032 -233.217974)
		(stroke
			(width 0.0635)
			(type default)
		)
		(layer "In7.Cu")
	)
	(gr_line
		(start 294.104314 -232.670096)
		(end 294.280336 -232.557828)
		(stroke
			(width 0.0635)
			(type default)
		)
		(layer "In7.Cu")
	)
	(gr_line
		(start 294.131746 -291.7825)
		(end 294.430196 -291.82822)
		(stroke
			(width 0.0508)
			(type default)
		)
		(layer "In7.Cu")
	)
	(gr_line
		(start 294.186864 -234.282742)
		(end 294.31869 -233.687874)
		(stroke
			(width 0.0635)
			(type default)
		)
		(layer "In7.Cu")
	)
	(gr_line
		(start 294.304212 -261.621016)
		(end 294.419528 -261.44728)
		(stroke
			(width 0.0635)
			(type default)
		)
		(layer "In7.Cu")
	)
	(gr_line
		(start 294.394128 -261.89051)
		(end 294.98798 -261.76986)
		(stroke
			(width 0.0635)
			(type default)
		)
		(layer "In7.Cu")
	)
	(gr_line
		(start 294.416734 -233.246168)
		(end 294.548306 -232.652062)
		(stroke
			(width 0.0635)
			(type default)
		)
		(layer "In7.Cu")
	)
	(gr_line
		(start 294.419528 -261.44728)
		(end 294.792908 -261.371334)
		(stroke
			(width 0.0635)
			(type default)
		)
		(layer "In7.Cu")
	)
	(gr_line
		(start 294.430196 -291.82822)
		(end 294.675814 -291.64788)
		(stroke
			(width 0.0508)
			(type default)
		)
		(layer "In7.Cu")
	)
	(gr_line
		(start 294.675814 -291.64788)
		(end 294.721534 -291.34943)
		(stroke
			(width 0.0508)
			(type default)
		)
		(layer "In7.Cu")
	)
	(gr_line
		(start 294.792908 -261.371334)
		(end 294.966898 -261.48665)
		(stroke
			(width 0.0635)
			(type default)
		)
		(layer "In7.Cu")
	)
	(gr_line
		(start 294.804084 -290.87572)
		(end 295.333166 -290.4871)
		(stroke
			(width 0.0508)
			(type default)
		)
		(layer "In7.Cu")
	)
	(gr_line
		(start 294.970962 -291.166042)
		(end 295.269412 -291.211762)
		(stroke
			(width 0.0508)
			(type default)
		)
		(layer "In7.Cu")
	)
	(gr_line
		(start 295.084754 -259.832856)
		(end 295.199816 -259.65912)
		(stroke
			(width 0.0635)
			(type default)
		)
		(layer "In7.Cu")
	)
	(gr_line
		(start 295.12641 -230.04399)
		(end 295.12641 -230.044244)
		(stroke
			(width 0.0635)
			(type default)
		)
		(layer "In7.Cu")
	)
	(gr_line
		(start 295.12641 -230.043736)
		(end 295.131744 -230.01986)
		(stroke
			(width 0.0635)
			(type default)
		)
		(layer "In7.Cu")
	)
	(gr_line
		(start 295.12641 -229.99573)
		(end 295.131744 -230.01986)
		(stroke
			(width 0.0635)
			(type default)
		)
		(layer "In7.Cu")
	)
	(gr_line
		(start 295.176448 -260.101842)
		(end 295.768014 -259.9817)
		(stroke
			(width 0.0635)
			(type default)
		)
		(layer "In7.Cu")
	)
	(gr_line
		(start 295.199816 -259.65912)
		(end 295.573196 -259.583428)
		(stroke
			(width 0.0635)
			(type default)
		)
		(layer "In7.Cu")
	)
	(gr_line
		(start 295.269412 -291.211762)
		(end 295.51503 -291.031168)
		(stroke
			(width 0.0508)
			(type default)
		)
		(layer "In7.Cu")
	)
	(gr_line
		(start 295.33342 -261.414768)
		(end 295.343072 -261.412736)
		(stroke
			(width 0.0635)
			(type default)
		)
		(layer "In7.Cu")
	)
	(gr_line
		(start 295.345104 -261.409688)
		(end 295.460166 -261.235952)
		(stroke
			(width 0.0635)
			(type default)
		)
		(layer "In7.Cu")
	)
	(gr_line
		(start 295.435274 -261.679182)
		(end 296.028364 -261.558786)
		(stroke
			(width 0.0635)
			(type default)
		)
		(layer "In7.Cu")
	)
	(gr_line
		(start 295.460166 -261.235952)
		(end 295.833546 -261.16026)
		(stroke
			(width 0.0635)
			(type default)
		)
		(layer "In7.Cu")
	)
	(gr_line
		(start 295.51503 -291.031168)
		(end 295.56075 -290.732718)
		(stroke
			(width 0.0508)
			(type default)
		)
		(layer "In7.Cu")
	)
	(gr_line
		(start 295.573196 -259.583428)
		(end 295.746932 -259.69849)
		(stroke
			(width 0.0635)
			(type default)
		)
		(layer "In7.Cu")
	)
	(gr_line
		(start 295.644316 -290.2585)
		(end 296.171874 -289.870896)
		(stroke
			(width 0.0508)
			(type default)
		)
		(layer "In7.Cu")
	)
	(gr_line
		(start 295.810432 -290.54933)
		(end 296.108628 -290.59505)
		(stroke
			(width 0.0508)
			(type default)
		)
		(layer "In7.Cu")
	)
	(gr_line
		(start 295.833546 -261.16026)
		(end 296.007028 -261.275322)
		(stroke
			(width 0.0635)
			(type default)
		)
		(layer "In7.Cu")
	)
	(gr_line
		(start 296.010076 -261.277354)
		(end 296.08145 -261.262876)
		(stroke
			(width 0.0635)
			(type default)
		)
		(layer "In7.Cu")
	)
	(gr_line
		(start 296.061892 -261.551928)
		(end 296.137076 -261.536688)
		(stroke
			(width 0.0635)
			(type default)
		)
		(layer "In7.Cu")
	)
	(gr_line
		(start 296.108628 -290.59505)
		(end 296.354246 -290.41471)
		(stroke
			(width 0.0508)
			(type default)
		)
		(layer "In7.Cu")
	)
	(gr_line
		(start 296.124884 -259.621782)
		(end 296.2402 -259.447792)
		(stroke
			(width 0.0635)
			(type default)
		)
		(layer "In7.Cu")
	)
	(gr_line
		(start 296.215562 -259.891022)
		(end 296.808398 -259.770626)
		(stroke
			(width 0.0635)
			(type default)
		)
		(layer "In7.Cu")
	)
	(gr_line
		(start 296.2402 -259.447792)
		(end 296.61358 -259.3721)
		(stroke
			(width 0.0635)
			(type default)
		)
		(layer "In7.Cu")
	)
	(gr_line
		(start 296.347388 -26.802842)
		(end 296.360342 -26.811224)
		(stroke
			(width 0.0635)
			(type default)
		)
		(layer "In7.Cu")
	)
	(gr_line
		(start 296.354246 -290.41471)
		(end 296.399966 -290.11626)
		(stroke
			(width 0.0508)
			(type default)
		)
		(layer "In7.Cu")
	)
	(gr_line
		(start 296.360342 -26.811224)
		(end 296.375074 -26.814526)
		(stroke
			(width 0.0635)
			(type default)
		)
		(layer "In7.Cu")
	)
	(gr_line
		(start 296.385234 -261.198614)
		(end 296.50055 -261.024624)
		(stroke
			(width 0.0635)
			(type default)
		)
		(layer "In7.Cu")
	)
	(gr_line
		(start 296.474896 -261.468108)
		(end 297.069256 -261.347458)
		(stroke
			(width 0.0635)
			(type default)
		)
		(layer "In7.Cu")
	)
	(gr_line
		(start 296.50055 -261.024624)
		(end 296.87393 -260.948932)
		(stroke
			(width 0.0635)
			(type default)
		)
		(layer "In7.Cu")
	)
	(gr_line
		(start 296.61358 -259.3721)
		(end 296.787316 -259.487162)
		(stroke
			(width 0.0635)
			(type default)
		)
		(layer "In7.Cu")
	)
	(gr_line
		(start 296.87393 -260.948932)
		(end 297.047666 -261.063994)
		(stroke
			(width 0.0635)
			(type default)
		)
		(layer "In7.Cu")
	)
	(gr_line
		(start 297.165522 -259.410454)
		(end 297.280838 -259.236718)
		(stroke
			(width 0.0635)
			(type default)
		)
		(layer "In7.Cu")
	)
	(gr_line
		(start 297.255438 -259.679948)
		(end 297.84929 -259.559298)
		(stroke
			(width 0.0635)
			(type default)
		)
		(layer "In7.Cu")
	)
	(gr_line
		(start 297.280838 -259.236718)
		(end 297.654218 -259.160772)
		(stroke
			(width 0.0635)
			(type default)
		)
		(layer "In7.Cu")
	)
	(gr_line
		(start 297.633898 -283.612336)
		(end 297.640248 -283.607764)
		(stroke
			(width 0.0508)
			(type default)
		)
		(layer "In7.Cu")
	)
	(gr_line
		(start 297.640248 -283.607764)
		(end 297.645582 -283.600906)
		(stroke
			(width 0.0508)
			(type default)
		)
		(layer "In7.Cu")
	)
	(gr_line
		(start 297.654218 -259.160772)
		(end 297.827954 -259.276088)
		(stroke
			(width 0.0635)
			(type default)
		)
		(layer "In7.Cu")
	)
	(gr_line
		(start 298.907962 -217.361516)
		(end 298.951142 -217.1573)
		(stroke
			(width 0.0635)
			(type default)
		)
		(layer "In7.Cu")
	)
	(gr_line
		(start 298.907962 -217.361516)
		(end 299.11548 -217.681048)
		(stroke
			(width 0.0635)
			(type default)
		)
		(layer "In7.Cu")
	)
	(gr_line
		(start 299.11548 -217.681048)
		(end 299.319696 -217.724482)
		(stroke
			(width 0.0635)
			(type default)
		)
		(layer "In7.Cu")
	)
	(gr_line
		(start 299.206158 -217.032332)
		(end 299.537628 -217.542618)
		(stroke
			(width 0.0635)
			(type default)
		)
		(layer "In7.Cu")
	)
	(gr_line
		(start 299.486066 -218.25204)
		(end 299.5295 -218.047824)
		(stroke
			(width 0.0635)
			(type default)
		)
		(layer "In7.Cu")
	)
	(gr_line
		(start 299.486066 -218.25204)
		(end 299.693584 -218.571572)
		(stroke
			(width 0.0635)
			(type default)
		)
		(layer "In7.Cu")
	)
	(gr_line
		(start 299.693584 -218.571572)
		(end 299.898054 -218.615006)
		(stroke
			(width 0.0635)
			(type default)
		)
		(layer "In7.Cu")
	)
	(gr_line
		(start 299.743368 -284.154118)
		(end 299.749718 -284.149546)
		(stroke
			(width 0.0508)
			(type default)
		)
		(layer "In7.Cu")
	)
	(gr_line
		(start 299.749718 -284.149546)
		(end 299.755052 -284.142688)
		(stroke
			(width 0.0508)
			(type default)
		)
		(layer "In7.Cu")
	)
	(gr_line
		(start 299.784516 -217.922602)
		(end 300.11624 -218.43365)
		(stroke
			(width 0.0635)
			(type default)
		)
		(layer "In7.Cu")
	)
	(gr_line
		(start 300.064424 -219.142564)
		(end 300.107858 -218.938348)
		(stroke
			(width 0.0635)
			(type default)
		)
		(layer "In7.Cu")
	)
	(gr_line
		(start 300.064424 -219.142564)
		(end 300.271942 -219.462096)
		(stroke
			(width 0.0635)
			(type default)
		)
		(layer "In7.Cu")
	)
	(gr_line
		(start 300.153324 -287.355534)
		(end 300.157642 -287.352486)
		(stroke
			(width 0.0508)
			(type default)
		)
		(layer "In7.Cu")
	)
	(gr_line
		(start 300.157642 -287.352486)
		(end 300.161452 -287.34766)
		(stroke
			(width 0.0508)
			(type default)
		)
		(layer "In7.Cu")
	)
	(gr_line
		(start 300.271942 -219.462096)
		(end 300.476158 -219.505276)
		(stroke
			(width 0.0635)
			(type default)
		)
		(layer "In7.Cu")
	)
	(gr_line
		(start 300.362366 -218.812364)
		(end 300.695106 -219.324682)
		(stroke
			(width 0.0635)
			(type default)
		)
		(layer "In7.Cu")
	)
	(gr_line
		(start 301.510954 -288.45002)
		(end 301.515272 -288.446972)
		(stroke
			(width 0.0508)
			(type default)
		)
		(layer "In7.Cu")
	)
	(gr_line
		(start 301.515272 -288.446972)
		(end 301.519082 -288.442146)
		(stroke
			(width 0.0508)
			(type default)
		)
		(layer "In7.Cu")
	)
	(gr_line
		(start 302.147224 -262.390382)
		(end 302.158146 -262.388096)
		(stroke
			(width 0.0635)
			(type default)
		)
		(layer "In7.Cu")
	)
	(gr_line
		(start 302.158146 -262.388096)
		(end 302.167544 -262.382508)
		(stroke
			(width 0.0635)
			(type default)
		)
		(layer "In7.Cu")
	)
	(gr_line
		(start 302.590454 -31.757874)
		(end 302.610266 -31.754064)
		(stroke
			(width 0.0635)
			(type default)
		)
		(layer "In7.Cu")
	)
	(gr_line
		(start 302.610266 -31.754064)
		(end 302.630078 -31.758128)
		(stroke
			(width 0.0635)
			(type default)
		)
		(layer "In7.Cu")
	)
	(gr_line
		(start 302.660558 -258.582668)
		(end 302.671734 -258.580382)
		(stroke
			(width 0.0635)
			(type default)
		)
		(layer "In7.Cu")
	)
	(gr_line
		(start 302.671734 -258.580382)
		(end 302.681132 -258.574794)
		(stroke
			(width 0.0635)
			(type default)
		)
		(layer "In7.Cu")
	)
	(gr_line
		(start 302.848518 -256.791206)
		(end 302.859694 -256.78892)
		(stroke
			(width 0.0635)
			(type default)
		)
		(layer "In7.Cu")
	)
	(gr_line
		(start 302.859694 -256.78892)
		(end 302.869092 -256.783332)
		(stroke
			(width 0.0635)
			(type default)
		)
		(layer "In7.Cu")
	)
	(gr_line
		(start 303.000918 -260.143244)
		(end 303.012094 -260.140958)
		(stroke
			(width 0.0635)
			(type default)
		)
		(layer "In7.Cu")
	)
	(gr_line
		(start 303.012094 -260.140958)
		(end 303.021492 -260.13537)
		(stroke
			(width 0.0635)
			(type default)
		)
		(layer "In7.Cu")
	)
	(gr_line
		(start 303.886616 -114.351308)
		(end 303.892712 -114.382042)
		(stroke
			(width 0.0508)
			(type default)
		)
		(layer "In7.Cu")
	)
	(gr_line
		(start 303.886616 -114.351308)
		(end 303.893474 -114.321082)
		(stroke
			(width 0.0508)
			(type default)
		)
		(layer "In7.Cu")
	)
	(gr_line
		(start 304.980848 -166.82974)
		(end 304.986436 -166.85768)
		(stroke
			(width 0.0508)
			(type default)
		)
		(layer "In7.Cu")
	)
	(gr_line
		(start 304.980848 -166.82974)
		(end 304.98669 -166.802308)
		(stroke
			(width 0.0508)
			(type default)
		)
		(layer "In7.Cu")
	)
	(gr_line
		(start 304.98669 -166.8018)
		(end 304.98669 -166.802054)
		(stroke
			(width 0.0508)
			(type default)
		)
		(layer "In7.Cu")
	)
	(gr_line
		(start 305.174142 -235.21797)
		(end 305.217576 -235.013754)
		(stroke
			(width 0.0635)
			(type default)
		)
		(layer "In7.Cu")
	)
	(gr_line
		(start 305.174142 -235.21797)
		(end 305.38166 -235.537502)
		(stroke
			(width 0.0635)
			(type default)
		)
		(layer "In7.Cu")
	)
	(gr_line
		(start 305.38166 -235.537502)
		(end 305.585876 -235.580936)
		(stroke
			(width 0.0635)
			(type default)
		)
		(layer "In7.Cu")
	)
	(gr_line
		(start 305.472084 -234.888278)
		(end 305.803808 -235.399072)
		(stroke
			(width 0.0635)
			(type default)
		)
		(layer "In7.Cu")
	)
	(gr_line
		(start 305.7525 -236.108494)
		(end 305.795934 -235.904278)
		(stroke
			(width 0.0635)
			(type default)
		)
		(layer "In7.Cu")
	)
	(gr_line
		(start 305.7525 -236.108494)
		(end 305.959764 -236.428026)
		(stroke
			(width 0.0635)
			(type default)
		)
		(layer "In7.Cu")
	)
	(gr_line
		(start 305.959764 -236.428026)
		(end 306.16398 -236.471206)
		(stroke
			(width 0.0635)
			(type default)
		)
		(layer "In7.Cu")
	)
	(gr_line
		(start 305.973734 -254.92329)
		(end 305.997356 -254.909066)
		(stroke
			(width 0.0635)
			(type default)
		)
		(layer "In7.Cu")
	)
	(gr_line
		(start 305.997356 -254.909066)
		(end 306.012342 -254.885952)
		(stroke
			(width 0.0635)
			(type default)
		)
		(layer "In7.Cu")
	)
	(gr_line
		(start 306.050442 -235.778548)
		(end 306.38242 -236.289596)
		(stroke
			(width 0.0635)
			(type default)
		)
		(layer "In7.Cu")
	)
	(gr_line
		(start 306.330604 -236.999018)
		(end 306.374038 -236.794802)
		(stroke
			(width 0.0635)
			(type default)
		)
		(layer "In7.Cu")
	)
	(gr_line
		(start 306.330604 -236.999018)
		(end 306.538122 -237.31855)
		(stroke
			(width 0.0635)
			(type default)
		)
		(layer "In7.Cu")
	)
	(gr_line
		(start 306.538122 -237.31855)
		(end 306.742338 -237.361984)
		(stroke
			(width 0.0635)
			(type default)
		)
		(layer "In7.Cu")
	)
	(gr_line
		(start 306.629308 -236.670342)
		(end 306.960524 -237.18012)
		(stroke
			(width 0.0635)
			(type default)
		)
		(layer "In7.Cu")
	)
	(gr_line
		(start 306.982114 -232.845102)
		(end 307.0225 -232.65511)
		(stroke
			(width 0.0635)
			(type default)
		)
		(layer "In7.Cu")
	)
	(gr_line
		(start 306.982114 -232.845102)
		(end 307.189632 -233.164634)
		(stroke
			(width 0.0635)
			(type default)
		)
		(layer "In7.Cu")
	)
	(gr_line
		(start 307.102764 -255.925066)
		(end 307.126386 -255.910842)
		(stroke
			(width 0.0635)
			(type default)
		)
		(layer "In7.Cu")
	)
	(gr_line
		(start 307.126386 -255.910842)
		(end 307.141372 -255.887728)
		(stroke
			(width 0.0635)
			(type default)
		)
		(layer "In7.Cu")
	)
	(gr_line
		(start 307.189632 -233.164634)
		(end 307.379878 -233.20502)
		(stroke
			(width 0.0635)
			(type default)
		)
		(layer "In7.Cu")
	)
	(gr_line
		(start 307.222906 -166.672768)
		(end 307.228494 -166.700454)
		(stroke
			(width 0.0508)
			(type default)
		)
		(layer "In7.Cu")
	)
	(gr_line
		(start 307.222906 -166.672768)
		(end 307.228748 -166.645082)
		(stroke
			(width 0.0508)
			(type default)
		)
		(layer "In7.Cu")
	)
	(gr_line
		(start 307.277516 -232.530142)
		(end 307.59781 -233.023156)
		(stroke
			(width 0.0635)
			(type default)
		)
		(layer "In7.Cu")
	)
	(gr_line
		(start 307.318664 -117.44833)
		(end 307.32476 -117.479064)
		(stroke
			(width 0.0508)
			(type default)
		)
		(layer "In7.Cu")
	)
	(gr_line
		(start 307.318664 -117.44833)
		(end 307.325522 -117.41785)
		(stroke
			(width 0.0508)
			(type default)
		)
		(layer "In7.Cu")
	)
	(gr_line
		(start 307.32476 -117.47881)
		(end 307.32476 -117.479064)
		(stroke
			(width 0.0508)
			(type default)
		)
		(layer "In7.Cu")
	)
	(gr_line
		(start 307.549296 -233.718608)
		(end 307.589682 -233.528362)
		(stroke
			(width 0.0635)
			(type default)
		)
		(layer "In7.Cu")
	)
	(gr_line
		(start 307.549296 -233.718608)
		(end 307.756814 -234.037886)
		(stroke
			(width 0.0635)
			(type default)
		)
		(layer "In7.Cu")
	)
	(gr_line
		(start 307.582824 -252.467364)
		(end 307.590698 -252.455172)
		(stroke
			(width 0.0635)
			(type default)
		)
		(layer "In7.Cu")
	)
	(gr_line
		(start 307.590698 -252.455172)
		(end 307.593746 -252.440948)
		(stroke
			(width 0.0635)
			(type default)
		)
		(layer "In7.Cu")
	)
	(gr_line
		(start 307.7083 -238.331502)
		(end 307.716682 -238.344456)
		(stroke
			(width 0.0635)
			(type default)
		)
		(layer "In7.Cu")
	)
	(gr_line
		(start 307.716682 -238.344456)
		(end 307.719984 -238.359188)
		(stroke
			(width 0.0635)
			(type default)
		)
		(layer "In7.Cu")
	)
	(gr_line
		(start 307.756814 -234.037886)
		(end 307.94706 -234.078272)
		(stroke
			(width 0.0635)
			(type default)
		)
		(layer "In7.Cu")
	)
	(gr_line
		(start 307.844444 -233.402886)
		(end 308.164992 -233.896408)
		(stroke
			(width 0.0635)
			(type default)
		)
		(layer "In7.Cu")
	)
	(gr_line
		(start 308.090824 -231.502204)
		(end 308.134258 -231.297734)
		(stroke
			(width 0.0635)
			(type default)
		)
		(layer "In7.Cu")
	)
	(gr_line
		(start 308.090824 -231.502204)
		(end 308.298342 -231.821736)
		(stroke
			(width 0.0635)
			(type default)
		)
		(layer "In7.Cu")
	)
	(gr_line
		(start 308.116478 -234.59186)
		(end 308.156864 -234.401614)
		(stroke
			(width 0.0635)
			(type default)
		)
		(layer "In7.Cu")
	)
	(gr_line
		(start 308.116478 -234.59186)
		(end 308.323996 -234.911392)
		(stroke
			(width 0.0635)
			(type default)
		)
		(layer "In7.Cu")
	)
	(gr_line
		(start 308.247288 -257.003804)
		(end 308.271926 -256.989072)
		(stroke
			(width 0.0635)
			(type default)
		)
		(layer "In7.Cu")
	)
	(gr_line
		(start 308.271926 -256.989072)
		(end 308.287674 -256.964942)
		(stroke
			(width 0.0635)
			(type default)
		)
		(layer "In7.Cu")
	)
	(gr_line
		(start 308.298342 -231.821736)
		(end 308.502558 -231.864916)
		(stroke
			(width 0.0635)
			(type default)
		)
		(layer "In7.Cu")
	)
	(gr_line
		(start 308.323996 -234.911392)
		(end 308.514496 -234.952032)
		(stroke
			(width 0.0635)
			(type default)
		)
		(layer "In7.Cu")
	)
	(gr_line
		(start 308.388258 -231.171242)
		(end 308.721252 -231.684068)
		(stroke
			(width 0.0635)
			(type default)
		)
		(layer "In7.Cu")
	)
	(gr_line
		(start 308.41188 -234.276392)
		(end 308.733444 -234.771438)
		(stroke
			(width 0.0635)
			(type default)
		)
		(layer "In7.Cu")
	)
	(gr_line
		(start 308.669182 -232.392728)
		(end 308.712362 -232.188258)
		(stroke
			(width 0.0635)
			(type default)
		)
		(layer "In7.Cu")
	)
	(gr_line
		(start 308.669182 -232.392728)
		(end 308.8767 -232.71226)
		(stroke
			(width 0.0635)
			(type default)
		)
		(layer "In7.Cu")
	)
	(gr_line
		(start 308.746398 -253.416562)
		(end 308.754272 -253.40437)
		(stroke
			(width 0.0635)
			(type default)
		)
		(layer "In7.Cu")
	)
	(gr_line
		(start 308.754272 -253.40437)
		(end 308.75732 -253.390146)
		(stroke
			(width 0.0635)
			(type default)
		)
		(layer "In7.Cu")
	)
	(gr_line
		(start 308.8132 -237.325662)
		(end 308.821582 -237.338616)
		(stroke
			(width 0.0635)
			(type default)
		)
		(layer "In7.Cu")
	)
	(gr_line
		(start 308.821582 -237.338616)
		(end 308.824884 -237.353348)
		(stroke
			(width 0.0635)
			(type default)
		)
		(layer "In7.Cu")
	)
	(gr_line
		(start 308.8767 -232.71226)
		(end 309.080916 -232.75544)
		(stroke
			(width 0.0635)
			(type default)
		)
		(layer "In7.Cu")
	)
	(gr_line
		(start 308.967124 -232.062782)
		(end 309.298848 -232.573576)
		(stroke
			(width 0.0635)
			(type default)
		)
		(layer "In7.Cu")
	)
	(gr_line
		(start 309.152798 -249.466608)
		(end 309.232046 -249.09399)
		(stroke
			(width 0.0635)
			(type default)
		)
		(layer "In7.Cu")
	)
	(gr_line
		(start 309.152798 -249.466608)
		(end 309.266336 -249.641614)
		(stroke
			(width 0.0635)
			(type default)
		)
		(layer "In7.Cu")
	)
	(gr_line
		(start 309.178452 -244.988842)
		(end 309.183532 -244.964966)
		(stroke
			(width 0.0635)
			(type default)
		)
		(layer "In7.Cu")
	)
	(gr_line
		(start 309.178452 -244.941852)
		(end 309.183532 -244.964966)
		(stroke
			(width 0.0635)
			(type default)
		)
		(layer "In7.Cu")
	)
	(gr_line
		(start 309.232046 -249.09399)
		(end 309.406798 -248.980452)
		(stroke
			(width 0.0635)
			(type default)
		)
		(layer "In7.Cu")
	)
	(gr_line
		(start 309.24754 -233.283252)
		(end 309.29072 -233.078782)
		(stroke
			(width 0.0635)
			(type default)
		)
		(layer "In7.Cu")
	)
	(gr_line
		(start 309.24754 -233.283252)
		(end 309.455058 -233.602784)
		(stroke
			(width 0.0635)
			(type default)
		)
		(layer "In7.Cu")
	)
	(gr_line
		(start 309.26024 -258.132072)
		(end 309.283862 -258.117848)
		(stroke
			(width 0.0635)
			(type default)
		)
		(layer "In7.Cu")
	)
	(gr_line
		(start 309.283862 -258.117848)
		(end 309.298848 -258.094734)
		(stroke
			(width 0.0635)
			(type default)
		)
		(layer "In7.Cu")
	)
	(gr_line
		(start 309.373524 -248.428256)
		(end 309.452772 -248.055384)
		(stroke
			(width 0.0635)
			(type default)
		)
		(layer "In7.Cu")
	)
	(gr_line
		(start 309.373524 -248.428256)
		(end 309.487062 -248.603008)
		(stroke
			(width 0.0635)
			(type default)
		)
		(layer "In7.Cu")
	)
	(gr_line
		(start 309.452772 -248.055384)
		(end 309.627778 -247.941846)
		(stroke
			(width 0.0635)
			(type default)
		)
		(layer "In7.Cu")
	)
	(gr_line
		(start 309.455058 -233.602784)
		(end 309.659274 -233.645964)
		(stroke
			(width 0.0635)
			(type default)
		)
		(layer "In7.Cu")
	)
	(gr_line
		(start 309.545482 -232.953052)
		(end 309.877968 -233.465116)
		(stroke
			(width 0.0635)
			(type default)
		)
		(layer "In7.Cu")
	)
	(gr_line
		(start 309.549038 -249.667776)
		(end 309.676038 -249.07113)
		(stroke
			(width 0.0635)
			(type default)
		)
		(layer "In7.Cu")
	)
	(gr_line
		(start 309.594504 -247.38965)
		(end 309.673752 -247.017032)
		(stroke
			(width 0.0635)
			(type default)
		)
		(layer "In7.Cu")
	)
	(gr_line
		(start 309.594504 -247.38965)
		(end 309.708042 -247.564656)
		(stroke
			(width 0.0635)
			(type default)
		)
		(layer "In7.Cu")
	)
	(gr_line
		(start 309.660544 -254.846582)
		(end 309.668418 -254.834644)
		(stroke
			(width 0.0635)
			(type default)
		)
		(layer "In7.Cu")
	)
	(gr_line
		(start 309.668418 -254.834644)
		(end 309.671466 -254.82042)
		(stroke
			(width 0.0635)
			(type default)
		)
		(layer "In7.Cu")
	)
	(gr_line
		(start 309.673752 -247.017032)
		(end 309.848504 -246.90324)
		(stroke
			(width 0.0635)
			(type default)
		)
		(layer "In7.Cu")
	)
	(gr_line
		(start 309.769764 -248.630694)
		(end 309.896764 -248.033286)
		(stroke
			(width 0.0635)
			(type default)
		)
		(layer "In7.Cu")
	)
	(gr_line
		(start 309.854346 -236.497368)
		(end 309.862728 -236.510322)
		(stroke
			(width 0.0635)
			(type default)
		)
		(layer "In7.Cu")
	)
	(gr_line
		(start 309.862728 -236.510322)
		(end 309.862982 -236.511084)
		(stroke
			(width 0.0635)
			(type default)
		)
		(layer "In7.Cu")
	)
	(gr_line
		(start 309.862982 -236.511084)
		(end 309.866284 -236.525816)
		(stroke
			(width 0.0635)
			(type default)
		)
		(layer "In7.Cu")
	)
	(gr_line
		(start 309.990998 -247.589802)
		(end 310.11749 -246.994426)
		(stroke
			(width 0.0635)
			(type default)
		)
		(layer "In7.Cu")
	)
	(gr_line
		(start 310.170068 -143.994886)
		(end 310.17591 -143.9672)
		(stroke
			(width 0.0508)
			(type default)
		)
		(layer "In7.Cu")
	)
	(gr_line
		(start 310.170322 -143.939514)
		(end 310.17591 -143.9672)
		(stroke
			(width 0.0508)
			(type default)
		)
		(layer "In7.Cu")
	)
	(gr_line
		(start 310.289956 -234.099608)
		(end 310.298338 -234.112562)
		(stroke
			(width 0.0635)
			(type default)
		)
		(layer "In7.Cu")
	)
	(gr_line
		(start 310.298338 -234.112308)
		(end 310.298338 -234.112562)
		(stroke
			(width 0.0635)
			(type default)
		)
		(layer "In7.Cu")
	)
	(gr_line
		(start 310.298338 -234.112308)
		(end 310.301894 -234.127802)
		(stroke
			(width 0.0635)
			(type default)
		)
		(layer "In7.Cu")
	)
	(gr_line
		(start 310.525668 -245.074694)
		(end 310.530748 -245.050818)
		(stroke
			(width 0.0635)
			(type default)
		)
		(layer "In7.Cu")
	)
	(gr_line
		(start 310.525668 -245.027704)
		(end 310.530748 -245.050818)
		(stroke
			(width 0.0635)
			(type default)
		)
		(layer "In7.Cu")
	)
	(gr_line
		(start 310.797448 -33.73374)
		(end 310.81726 -33.737804)
		(stroke
			(width 0.0635)
			(type default)
		)
		(layer "In7.Cu")
	)
	(gr_line
		(start 310.81726 -33.737804)
		(end 310.836818 -33.733994)
		(stroke
			(width 0.0635)
			(type default)
		)
		(layer "In7.Cu")
	)
	(gr_line
		(start 311.101232 -255.31953)
		(end 311.109106 -255.307338)
		(stroke
			(width 0.0635)
			(type default)
		)
		(layer "In7.Cu")
	)
	(gr_line
		(start 311.109106 -255.307338)
		(end 311.112154 -255.293114)
		(stroke
			(width 0.0635)
			(type default)
		)
		(layer "In7.Cu")
	)
	(gr_line
		(start 311.7469 -245.059708)
		(end 311.75198 -245.035832)
		(stroke
			(width 0.0635)
			(type default)
		)
		(layer "In7.Cu")
	)
	(gr_line
		(start 311.7469 -245.012972)
		(end 311.75198 -245.035832)
		(stroke
			(width 0.0635)
			(type default)
		)
		(layer "In7.Cu")
	)
	(gr_line
		(start 312.349896 -264.074656)
		(end 312.368438 -264.050018)
		(stroke
			(width 0.0508)
			(type default)
		)
		(layer "In7.Cu")
	)
	(gr_line
		(start 312.368438 -264.050018)
		(end 312.375296 -264.020046)
		(stroke
			(width 0.0508)
			(type default)
		)
		(layer "In7.Cu")
	)
	(gr_line
		(start 312.687462 -142.545816)
		(end 312.687462 -142.54607)
		(stroke
			(width 0.0508)
			(type default)
		)
		(layer "In7.Cu")
	)
	(gr_line
		(start 312.687462 -142.545562)
		(end 312.693304 -142.51813)
		(stroke
			(width 0.0508)
			(type default)
		)
		(layer "In7.Cu")
	)
	(gr_line
		(start 312.687716 -142.49019)
		(end 312.693304 -142.51813)
		(stroke
			(width 0.0508)
			(type default)
		)
		(layer "In7.Cu")
	)
	(gr_line
		(start 313.00674 -246.379746)
		(end 313.01182 -246.356378)
		(stroke
			(width 0.0635)
			(type default)
		)
		(layer "In7.Cu")
	)
	(gr_line
		(start 313.00674 -246.332756)
		(end 313.01182 -246.35587)
		(stroke
			(width 0.0635)
			(type default)
		)
		(layer "In7.Cu")
	)
	(gr_line
		(start 313.01182 -246.35587)
		(end 313.01182 -246.356378)
		(stroke
			(width 0.0635)
			(type default)
		)
		(layer "In7.Cu")
	)
	(gr_line
		(start 315.616082 -31.082742)
		(end 315.636656 -31.087314)
		(stroke
			(width 0.0635)
			(type default)
		)
		(layer "In7.Cu")
	)
	(gr_line
		(start 315.636656 -31.087314)
		(end 315.657484 -31.08325)
		(stroke
			(width 0.0635)
			(type default)
		)
		(layer "In7.Cu")
	)
	(gr_line
		(start 316.202314 -262.301736)
		(end 316.220856 -262.277098)
		(stroke
			(width 0.0508)
			(type default)
		)
		(layer "In7.Cu")
	)
	(gr_line
		(start 316.220856 -262.277098)
		(end 316.227714 -262.247126)
		(stroke
			(width 0.0508)
			(type default)
		)
		(layer "In7.Cu")
	)
	(gr_line
		(start 318.96304 -234.799886)
		(end 318.969898 -234.769406)
		(stroke
			(width 0.0508)
			(type default)
		)
		(layer "In7.Cu")
	)
	(gr_line
		(start 318.963802 -234.738672)
		(end 318.963802 -234.738926)
		(stroke
			(width 0.0508)
			(type default)
		)
		(layer "In7.Cu")
	)
	(gr_line
		(start 318.963802 -234.738672)
		(end 318.969898 -234.769406)
		(stroke
			(width 0.0508)
			(type default)
		)
		(layer "In7.Cu")
	)
	(gr_line
		(start 319.2145 -42.627042)
		(end 319.5193 -42.627042)
		(stroke
			(width 0.0508)
			(type default)
		)
		(layer "In7.Cu")
	)
	(gr_arc
		(start 319.6209 -42.728642)
		(mid 319.591142 -42.6568)
		(end 319.5193 -42.627042)
		(stroke
			(width 0.0508)
			(type default)
		)
		(layer "In7.Cu")
	)
	(gr_arc
		(start 320.0527 -42.627042)
		(mid 319.980873 -42.656802)
		(end 319.9511 -42.728642)
		(stroke
			(width 0.0508)
			(type default)
		)
		(layer "In7.Cu")
	)
	(gr_line
		(start 320.0527 -42.627042)
		(end 320.3575 -42.627042)
		(stroke
			(width 0.0508)
			(type default)
		)
		(layer "In7.Cu")
	)
	(gr_line
		(start 321.791076 -237.567978)
		(end 321.791076 -237.568232)
		(stroke
			(width 0.0508)
			(type default)
		)
		(layer "In7.Cu")
	)
	(gr_line
		(start 321.791076 -237.567724)
		(end 321.797934 -237.537498)
		(stroke
			(width 0.0508)
			(type default)
		)
		(layer "In7.Cu")
	)
	(gr_line
		(start 321.791838 -237.507018)
		(end 321.797934 -237.537498)
		(stroke
			(width 0.0508)
			(type default)
		)
		(layer "In7.Cu")
	)
	(gr_line
		(start 322.6816 -46.437042)
		(end 322.9864 -46.437042)
		(stroke
			(width 0.0508)
			(type default)
		)
		(layer "In7.Cu")
	)
	(gr_arc
		(start 323.088 -46.538642)
		(mid 323.058242 -46.4668)
		(end 322.9864 -46.437042)
		(stroke
			(width 0.0508)
			(type default)
		)
		(layer "In7.Cu")
	)
	(gr_arc
		(start 323.5198 -46.437042)
		(mid 323.447973 -46.466802)
		(end 323.4182 -46.538642)
		(stroke
			(width 0.0508)
			(type default)
		)
		(layer "In7.Cu")
	)
	(gr_line
		(start 323.5198 -46.437042)
		(end 323.8246 -46.437042)
		(stroke
			(width 0.0508)
			(type default)
		)
		(layer "In7.Cu")
	)
	(gr_line
		(start 332.275688 -27.526234)
		(end 332.2955 -27.522424)
		(stroke
			(width 0.0635)
			(type default)
		)
		(layer "In7.Cu")
	)
	(gr_line
		(start 332.2955 -27.522424)
		(end 332.315312 -27.526488)
		(stroke
			(width 0.0635)
			(type default)
		)
		(layer "In7.Cu")
	)
	(gr_line
		(start 332.798166 -29.09316)
		(end 332.817724 -29.08935)
		(stroke
			(width 0.0635)
			(type default)
		)
		(layer "In7.Cu")
	)
	(gr_line
		(start 332.817724 -29.08935)
		(end 332.837536 -29.093414)
		(stroke
			(width 0.0635)
			(type default)
		)
		(layer "In7.Cu")
	)
	(gr_line
		(start 333.104236 -132.851906)
		(end 333.108808 -132.827522)
		(stroke
			(width 0.0508)
			(type default)
		)
		(layer "In7.Cu")
	)
	(gr_line
		(start 333.104236 -132.851906)
		(end 333.109062 -132.876036)
		(stroke
			(width 0.0508)
			(type default)
		)
		(layer "In7.Cu")
	)
	(gr_line
		(start 333.864204 -240.132362)
		(end 333.873348 -240.118138)
		(stroke
			(width 0.0508)
			(type default)
		)
		(layer "In7.Cu")
	)
	(gr_line
		(start 333.873348 -240.118138)
		(end 333.877158 -240.101374)
		(stroke
			(width 0.0508)
			(type default)
		)
		(layer "In7.Cu")
	)
	(gr_line
		(start 334.813656 -132.935726)
		(end 334.818228 -132.958586)
		(stroke
			(width 0.0508)
			(type default)
		)
		(layer "In7.Cu")
	)
	(gr_line
		(start 334.813656 -132.935726)
		(end 334.818228 -132.91185)
		(stroke
			(width 0.0508)
			(type default)
		)
		(layer "In7.Cu")
	)
	(gr_line
		(start 335.513426 -240.772442)
		(end 335.523332 -240.756694)
		(stroke
			(width 0.0508)
			(type default)
		)
		(layer "In7.Cu")
	)
	(gr_line
		(start 335.523332 -240.756694)
		(end 335.527396 -240.73866)
		(stroke
			(width 0.0508)
			(type default)
		)
		(layer "In7.Cu")
	)
	(gr_line
		(start 345.029282 -190.584074)
		(end 345.03614 -190.553594)
		(stroke
			(width 0.0508)
			(type default)
		)
		(layer "In7.Cu")
	)
	(gr_line
		(start 345.030044 -190.523114)
		(end 345.03614 -190.553594)
		(stroke
			(width 0.0508)
			(type default)
		)
		(layer "In7.Cu")
	)
	(gr_line
		(start 345.030044 -190.522352)
		(end 345.030044 -190.52286)
		(stroke
			(width 0.0508)
			(type default)
		)
		(layer "In7.Cu")
	)
	(gr_line
		(start 346.77604 -190.844678)
		(end 346.783152 -190.813182)
		(stroke
			(width 0.0508)
			(type default)
		)
		(layer "In7.Cu")
	)
	(gr_line
		(start 346.776548 -190.780416)
		(end 346.783152 -190.813182)
		(stroke
			(width 0.0508)
			(type default)
		)
		(layer "In7.Cu")
	)
	(gr_line
		(start 346.776548 -190.779908)
		(end 346.776548 -190.780162)
		(stroke
			(width 0.0508)
			(type default)
		)
		(layer "In7.Cu")
	)
	(gr_line
		(start 350.764602 -42.627042)
		(end 351.069402 -42.627042)
		(stroke
			(width 0.0508)
			(type default)
		)
		(layer "In7.Cu")
	)
	(gr_arc
		(start 351.171002 -42.728642)
		(mid 351.141259 -42.656772)
		(end 351.069402 -42.627042)
		(stroke
			(width 0.0508)
			(type default)
		)
		(layer "In7.Cu")
	)
	(gr_line
		(start 351.49028 -44.904914)
		(end 351.501202 -44.879514)
		(stroke
			(width 0.0508)
			(type default)
		)
		(layer "In7.Cu")
	)
	(gr_arc
		(start 351.602802 -42.627042)
		(mid 351.53096 -42.6568)
		(end 351.501202 -42.728642)
		(stroke
			(width 0.0508)
			(type default)
		)
		(layer "In7.Cu")
	)
	(gr_line
		(start 351.602802 -42.627042)
		(end 351.907602 -42.627042)
		(stroke
			(width 0.0508)
			(type default)
		)
		(layer "In7.Cu")
	)
	(gr_line
		(start 353.992688 -48.425862)
		(end 354.010722 -48.397668)
		(stroke
			(width 0.0508)
			(type default)
		)
		(layer "In7.Cu")
	)
	(gr_line
		(start 354.010722 -48.397668)
		(end 354.038916 -48.379634)
		(stroke
			(width 0.0508)
			(type default)
		)
		(layer "In7.Cu")
	)
	(gr_line
		(start 355.086666 -47.711868)
		(end 355.101652 -47.702216)
		(stroke
			(width 0.0508)
			(type default)
		)
		(layer "In7.Cu")
	)
	(gr_line
		(start 355.101652 -47.702216)
		(end 355.11994 -47.698152)
		(stroke
			(width 0.0508)
			(type default)
		)
		(layer "In7.Cu")
	)
	(gr_arc
		(start 356.187502 -47.584868)
		(mid 356.259331 -47.555107)
		(end 356.289102 -47.483268)
		(stroke
			(width 0.0508)
			(type default)
		)
		(layer "In7.Cu")
	)
	(gr_arc
		(start 356.289102 -48.016668)
		(mid 356.259344 -47.944826)
		(end 356.187502 -47.915068)
		(stroke
			(width 0.0508)
			(type default)
		)
		(layer "In7.Cu")
	)
	(gr_line
		(start 356.289102 -48.016668)
		(end 356.289102 -48.321468)
		(stroke
			(width 0.0508)
			(type default)
		)
		(layer "In7.Cu")
	)
	(gr_line
		(start 356.289102 -47.178468)
		(end 356.289102 -47.483268)
		(stroke
			(width 0.0508)
			(type default)
		)
		(layer "In7.Cu")
	)
	(gr_line
		(start 359.928668 -33.507172)
		(end 359.950512 -33.511744)
		(stroke
			(width 0.0635)
			(type default)
		)
		(layer "In7.Cu")
	)
	(gr_line
		(start 359.950512 -33.511744)
		(end 359.972102 -33.506918)
		(stroke
			(width 0.0635)
			(type default)
		)
		(layer "In7.Cu")
	)
	(gr_line
		(start 363.89945 -35.805618)
		(end 363.92104 -35.81019)
		(stroke
			(width 0.0635)
			(type default)
		)
		(layer "In7.Cu")
	)
	(gr_line
		(start 363.92104 -35.81019)
		(end 363.94263 -35.805364)
		(stroke
			(width 0.0635)
			(type default)
		)
		(layer "In7.Cu")
	)
	(gr_line
		(start 365.314738 -32.3342)
		(end 365.329724 -32.330898)
		(stroke
			(width 0.0635)
			(type default)
		)
		(layer "In7.Cu")
	)
	(gr_line
		(start 365.329724 -32.330898)
		(end 365.342424 -32.322516)
		(stroke
			(width 0.0635)
			(type default)
		)
		(layer "In7.Cu")
	)
	(gr_line
		(start 366.67186 -31.44393)
		(end 366.687608 -31.433516)
		(stroke
			(width 0.0635)
			(type default)
		)
		(layer "In7.Cu")
	)
	(gr_line
		(start 366.687608 -31.433516)
		(end 366.69853 -31.417514)
		(stroke
			(width 0.0635)
			(type default)
		)
		(layer "In7.Cu")
	)
	(gr_line
		(start 366.961928 -31.030672)
		(end 366.989614 -30.990032)
		(stroke
			(width 0.0635)
			(type default)
		)
		(layer "In7.Cu")
	)
	(gr_arc
		(start 367.62309 -29.679138)
		(mid 367.712912 -29.641946)
		(end 367.75009 -29.552138)
		(stroke
			(width 0.0635)
			(type default)
		)
		(layer "In7.Cu")
	)
	(gr_arc
		(start 367.75009 -30.085538)
		(mid 367.712893 -29.995735)
		(end 367.62309 -29.958538)
		(stroke
			(width 0.0635)
			(type default)
		)
		(layer "In7.Cu")
	)
	(gr_line
		(start 367.75009 -30.085538)
		(end 367.75009 -30.550104)
		(stroke
			(width 0.0635)
			(type default)
		)
		(layer "In7.Cu")
	)
	(gr_line
		(start 367.75009 -29.150056)
		(end 367.75009 -29.552138)
		(stroke
			(width 0.0635)
			(type default)
		)
		(layer "In7.Cu")
	)
	(gr_line
		(start 380.246128 -32.215582)
		(end 380.25959 -32.212788)
		(stroke
			(width 0.0635)
			(type default)
		)
		(layer "In7.Cu")
	)
	(gr_line
		(start 380.25959 -32.212788)
		(end 380.271782 -32.204914)
		(stroke
			(width 0.0635)
			(type default)
		)
		(layer "In7.Cu")
	)
	(gr_line
		(start 380.8476 -31.830518)
		(end 380.863094 -31.820612)
		(stroke
			(width 0.0635)
			(type default)
		)
		(layer "In7.Cu")
	)
	(gr_line
		(start 380.863094 -31.820612)
		(end 380.873762 -31.805118)
		(stroke
			(width 0.0635)
			(type default)
		)
		(layer "In7.Cu")
	)
	(gr_line
		(start 381.362458 -31.08706)
		(end 381.389636 -31.046928)
		(stroke
			(width 0.0635)
			(type default)
		)
		(layer "In7.Cu")
	)
	(gr_arc
		(start 382.023112 -29.679138)
		(mid 382.11292 -29.641939)
		(end 382.150112 -29.552138)
		(stroke
			(width 0.0635)
			(type default)
		)
		(layer "In7.Cu")
	)
	(gr_arc
		(start 382.150112 -30.085538)
		(mid 382.112915 -29.995735)
		(end 382.023112 -29.958538)
		(stroke
			(width 0.0635)
			(type default)
		)
		(layer "In7.Cu")
	)
	(gr_line
		(start 382.150112 -30.085538)
		(end 382.150112 -30.550104)
		(stroke
			(width 0.0635)
			(type default)
		)
		(layer "In7.Cu")
	)
	(gr_line
		(start 382.150112 -29.150056)
		(end 382.150112 -29.552138)
		(stroke
			(width 0.0635)
			(type default)
		)
		(layer "In7.Cu")
	)
	(gr_line
		(start 0 -348.199964)
		(end 0 -0.999998)
		(stroke
			(width 1.524)
			(type default)
		)
		(layer "In8.Cu")
	)
	(gr_arc
		(start 0 -348.199964)
		(mid 0.292894 -348.907067)
		(end 0.999998 -349.199962)
		(stroke
			(width 1.524)
			(type default)
		)
		(layer "In8.Cu")
	)
	(gr_arc
		(start 0.999998 0)
		(mid 0.292893 -0.292893)
		(end 0 -0.999998)
		(stroke
			(width 1.524)
			(type default)
		)
		(layer "In8.Cu")
	)
	(gr_line
		(start 0.999998 0)
		(end 101.000052 0)
		(stroke
			(width 1.524)
			(type default)
		)
		(layer "In8.Cu")
	)
	(gr_arc
		(start 32.127952 -278.321516)
		(mid 32.508952 -278.702516)
		(end 32.889952 -278.321516)
		(stroke
			(width 0.2)
			(type default)
		)
		(layer "In8.Cu")
	)
	(gr_line
		(start 32.127952 -277.178516)
		(end 32.127952 -278.321516)
		(stroke
			(width 0.2)
			(type default)
		)
		(layer "In8.Cu")
	)
	(gr_arc
		(start 32.127952 -163.321492)
		(mid 32.508952 -163.702492)
		(end 32.889952 -163.321492)
		(stroke
			(width 0.2)
			(type default)
		)
		(layer "In8.Cu")
	)
	(gr_line
		(start 32.127952 -162.178492)
		(end 32.127952 -163.321492)
		(stroke
			(width 0.2)
			(type default)
		)
		(layer "In8.Cu")
	)
	(gr_arc
		(start 32.127952 -48.321468)
		(mid 32.508952 -48.702468)
		(end 32.889952 -48.321468)
		(stroke
			(width 0.2)
			(type default)
		)
		(layer "In8.Cu")
	)
	(gr_line
		(start 32.127952 -47.178468)
		(end 32.127952 -48.321468)
		(stroke
			(width 0.2)
			(type default)
		)
		(layer "In8.Cu")
	)
	(gr_line
		(start 32.889952 -278.321516)
		(end 32.889952 -277.17877)
		(stroke
			(width 0.2)
			(type default)
		)
		(layer "In8.Cu")
	)
	(gr_arc
		(start 32.889952 -277.17877)
		(mid 32.509079 -276.797516)
		(end 32.127952 -277.178516)
		(stroke
			(width 0.2)
			(type default)
		)
		(layer "In8.Cu")
	)
	(gr_line
		(start 32.889952 -163.321492)
		(end 32.889952 -162.178746)
		(stroke
			(width 0.2)
			(type default)
		)
		(layer "In8.Cu")
	)
	(gr_arc
		(start 32.889952 -162.178746)
		(mid 32.509079 -161.797492)
		(end 32.127952 -162.178492)
		(stroke
			(width 0.2)
			(type default)
		)
		(layer "In8.Cu")
	)
	(gr_line
		(start 32.889952 -48.321468)
		(end 32.889952 -47.178722)
		(stroke
			(width 0.2)
			(type default)
		)
		(layer "In8.Cu")
	)
	(gr_arc
		(start 32.889952 -47.178722)
		(mid 32.509079 -46.797468)
		(end 32.127952 -47.178468)
		(stroke
			(width 0.2)
			(type default)
		)
		(layer "In8.Cu")
	)
	(gr_arc
		(start 63.6778 -278.321516)
		(mid 64.0588 -278.702516)
		(end 64.4398 -278.321516)
		(stroke
			(width 0.2)
			(type default)
		)
		(layer "In8.Cu")
	)
	(gr_line
		(start 63.6778 -277.178516)
		(end 63.6778 -278.321516)
		(stroke
			(width 0.2)
			(type default)
		)
		(layer "In8.Cu")
	)
	(gr_arc
		(start 63.6778 -163.321492)
		(mid 64.0588 -163.702492)
		(end 64.4398 -163.321492)
		(stroke
			(width 0.2)
			(type default)
		)
		(layer "In8.Cu")
	)
	(gr_line
		(start 63.6778 -162.178492)
		(end 63.6778 -163.321492)
		(stroke
			(width 0.2)
			(type default)
		)
		(layer "In8.Cu")
	)
	(gr_arc
		(start 63.6778 -48.321468)
		(mid 64.0588 -48.702468)
		(end 64.4398 -48.321468)
		(stroke
			(width 0.2)
			(type default)
		)
		(layer "In8.Cu")
	)
	(gr_line
		(start 63.6778 -47.178468)
		(end 63.6778 -48.321468)
		(stroke
			(width 0.2)
			(type default)
		)
		(layer "In8.Cu")
	)
	(gr_line
		(start 64.4398 -278.321516)
		(end 64.4398 -277.17877)
		(stroke
			(width 0.2)
			(type default)
		)
		(layer "In8.Cu")
	)
	(gr_arc
		(start 64.4398 -277.17877)
		(mid 64.058927 -276.797516)
		(end 63.6778 -277.178516)
		(stroke
			(width 0.2)
			(type default)
		)
		(layer "In8.Cu")
	)
	(gr_line
		(start 64.4398 -163.321492)
		(end 64.4398 -162.178746)
		(stroke
			(width 0.2)
			(type default)
		)
		(layer "In8.Cu")
	)
	(gr_arc
		(start 64.4398 -162.178746)
		(mid 64.058927 -161.797492)
		(end 63.6778 -162.178492)
		(stroke
			(width 0.2)
			(type default)
		)
		(layer "In8.Cu")
	)
	(gr_line
		(start 64.4398 -48.321468)
		(end 64.4398 -47.178722)
		(stroke
			(width 0.2)
			(type default)
		)
		(layer "In8.Cu")
	)
	(gr_arc
		(start 64.4398 -47.178722)
		(mid 64.058927 -46.797468)
		(end 63.6778 -47.178468)
		(stroke
			(width 0.2)
			(type default)
		)
		(layer "In8.Cu")
	)
	(gr_arc
		(start 95.227902 -278.321516)
		(mid 95.608902 -278.702516)
		(end 95.989902 -278.321516)
		(stroke
			(width 0.2)
			(type default)
		)
		(layer "In8.Cu")
	)
	(gr_line
		(start 95.227902 -277.178516)
		(end 95.227902 -278.321516)
		(stroke
			(width 0.2)
			(type default)
		)
		(layer "In8.Cu")
	)
	(gr_arc
		(start 95.227902 -163.321492)
		(mid 95.608902 -163.702492)
		(end 95.989902 -163.321492)
		(stroke
			(width 0.2)
			(type default)
		)
		(layer "In8.Cu")
	)
	(gr_line
		(start 95.227902 -162.178492)
		(end 95.227902 -163.321492)
		(stroke
			(width 0.2)
			(type default)
		)
		(layer "In8.Cu")
	)
	(gr_arc
		(start 95.227902 -48.321468)
		(mid 95.608902 -48.702468)
		(end 95.989902 -48.321468)
		(stroke
			(width 0.2)
			(type default)
		)
		(layer "In8.Cu")
	)
	(gr_line
		(start 95.227902 -47.178468)
		(end 95.227902 -48.321468)
		(stroke
			(width 0.2)
			(type default)
		)
		(layer "In8.Cu")
	)
	(gr_line
		(start 95.989902 -278.321516)
		(end 95.989902 -277.17877)
		(stroke
			(width 0.2)
			(type default)
		)
		(layer "In8.Cu")
	)
	(gr_arc
		(start 95.989902 -277.17877)
		(mid 95.609029 -276.797516)
		(end 95.227902 -277.178516)
		(stroke
			(width 0.2)
			(type default)
		)
		(layer "In8.Cu")
	)
	(gr_line
		(start 95.989902 -163.321492)
		(end 95.989902 -162.178746)
		(stroke
			(width 0.2)
			(type default)
		)
		(layer "In8.Cu")
	)
	(gr_arc
		(start 95.989902 -162.178746)
		(mid 95.609029 -161.797492)
		(end 95.227902 -162.178492)
		(stroke
			(width 0.2)
			(type default)
		)
		(layer "In8.Cu")
	)
	(gr_line
		(start 95.989902 -48.321468)
		(end 95.989902 -47.178722)
		(stroke
			(width 0.2)
			(type default)
		)
		(layer "In8.Cu")
	)
	(gr_arc
		(start 95.989902 -47.178722)
		(mid 95.609029 -46.797468)
		(end 95.227902 -47.178468)
		(stroke
			(width 0.2)
			(type default)
		)
		(layer "In8.Cu")
	)
	(gr_arc
		(start 102.00005 -13.999972)
		(mid 102.292943 -14.707077)
		(end 103.000048 -14.99997)
		(stroke
			(width 1.524)
			(type default)
		)
		(layer "In8.Cu")
	)
	(gr_arc
		(start 102.00005 -0.999998)
		(mid 101.707154 -0.292911)
		(end 101.000052 0)
		(stroke
			(width 1.524)
			(type default)
		)
		(layer "In8.Cu")
	)
	(gr_line
		(start 102.00005 -0.999998)
		(end 102.00005 -13.999972)
		(stroke
			(width 1.524)
			(type default)
		)
		(layer "In8.Cu")
	)
	(gr_line
		(start 103.000048 -14.99997)
		(end 148.999956 -14.99997)
		(stroke
			(width 1.524)
			(type default)
		)
		(layer "In8.Cu")
	)
	(gr_arc
		(start 108.601256 -22.350222)
		(mid 109.149896 -22.898862)
		(end 109.698536 -22.350222)
		(stroke
			(width 0.2)
			(type default)
		)
		(layer "In8.Cu")
	)
	(gr_line
		(start 108.601256 -20.950174)
		(end 108.601256 -22.350222)
		(stroke
			(width 0.2)
			(type default)
		)
		(layer "In8.Cu")
	)
	(gr_arc
		(start 108.601256 -18.750026)
		(mid 109.149896 -19.298666)
		(end 109.698536 -18.750026)
		(stroke
			(width 0.2)
			(type default)
		)
		(layer "In8.Cu")
	)
	(gr_line
		(start 108.601256 -17.349978)
		(end 108.601256 -18.750026)
		(stroke
			(width 0.2)
			(type default)
		)
		(layer "In8.Cu")
	)
	(gr_line
		(start 109.698536 -22.350222)
		(end 109.698536 -20.950428)
		(stroke
			(width 0.2)
			(type default)
		)
		(layer "In8.Cu")
	)
	(gr_arc
		(start 109.698536 -20.950428)
		(mid 109.150023 -20.401534)
		(end 108.601256 -20.950174)
		(stroke
			(width 0.2)
			(type default)
		)
		(layer "In8.Cu")
	)
	(gr_line
		(start 109.698536 -18.750026)
		(end 109.698536 -17.350232)
		(stroke
			(width 0.2)
			(type default)
		)
		(layer "In8.Cu")
	)
	(gr_arc
		(start 109.698536 -17.350232)
		(mid 109.150023 -16.801338)
		(end 108.601256 -17.349978)
		(stroke
			(width 0.2)
			(type default)
		)
		(layer "In8.Cu")
	)
	(gr_arc
		(start 110.401354 -23.35022)
		(mid 110.949994 -23.89886)
		(end 111.498634 -23.35022)
		(stroke
			(width 0.2)
			(type default)
		)
		(layer "In8.Cu")
	)
	(gr_line
		(start 110.401354 -21.950172)
		(end 110.401354 -23.35022)
		(stroke
			(width 0.2)
			(type default)
		)
		(layer "In8.Cu")
	)
	(gr_arc
		(start 110.401354 -19.750024)
		(mid 110.949994 -20.298664)
		(end 111.498634 -19.750024)
		(stroke
			(width 0.2)
			(type default)
		)
		(layer "In8.Cu")
	)
	(gr_line
		(start 110.401354 -18.35023)
		(end 110.401354 -19.750024)
		(stroke
			(width 0.2)
			(type default)
		)
		(layer "In8.Cu")
	)
	(gr_line
		(start 111.498634 -23.35022)
		(end 111.498634 -21.950426)
		(stroke
			(width 0.2)
			(type default)
		)
		(layer "In8.Cu")
	)
	(gr_arc
		(start 111.498634 -21.950426)
		(mid 110.950121 -21.401532)
		(end 110.401354 -21.950172)
		(stroke
			(width 0.2)
			(type default)
		)
		(layer "In8.Cu")
	)
	(gr_line
		(start 111.498634 -19.750024)
		(end 111.498634 -18.350484)
		(stroke
			(width 0.2)
			(type default)
		)
		(layer "In8.Cu")
	)
	(gr_arc
		(start 111.498634 -18.350484)
		(mid 110.950121 -17.80159)
		(end 110.401354 -18.35023)
		(stroke
			(width 0.2)
			(type default)
		)
		(layer "In8.Cu")
	)
	(gr_arc
		(start 112.201452 -22.350222)
		(mid 112.750092 -22.898862)
		(end 113.298732 -22.350222)
		(stroke
			(width 0.2)
			(type default)
		)
		(layer "In8.Cu")
	)
	(gr_line
		(start 112.201452 -20.950174)
		(end 112.201452 -22.350222)
		(stroke
			(width 0.2)
			(type default)
		)
		(layer "In8.Cu")
	)
	(gr_arc
		(start 112.201452 -18.750026)
		(mid 112.750092 -19.298666)
		(end 113.298732 -18.750026)
		(stroke
			(width 0.2)
			(type default)
		)
		(layer "In8.Cu")
	)
	(gr_line
		(start 112.201452 -17.349978)
		(end 112.201452 -18.750026)
		(stroke
			(width 0.2)
			(type default)
		)
		(layer "In8.Cu")
	)
	(gr_line
		(start 113.298732 -22.350222)
		(end 113.298732 -20.950428)
		(stroke
			(width 0.2)
			(type default)
		)
		(layer "In8.Cu")
	)
	(gr_arc
		(start 113.298732 -20.950428)
		(mid 112.750219 -20.401534)
		(end 112.201452 -20.950174)
		(stroke
			(width 0.2)
			(type default)
		)
		(layer "In8.Cu")
	)
	(gr_line
		(start 113.298732 -18.750026)
		(end 113.298732 -17.350232)
		(stroke
			(width 0.2)
			(type default)
		)
		(layer "In8.Cu")
	)
	(gr_arc
		(start 113.298732 -17.350232)
		(mid 112.750219 -16.801338)
		(end 112.201452 -17.349978)
		(stroke
			(width 0.2)
			(type default)
		)
		(layer "In8.Cu")
	)
	(gr_arc
		(start 114.001296 -23.35022)
		(mid 114.549936 -23.89886)
		(end 115.098576 -23.35022)
		(stroke
			(width 0.2)
			(type default)
		)
		(layer "In8.Cu")
	)
	(gr_line
		(start 114.001296 -21.950172)
		(end 114.001296 -23.35022)
		(stroke
			(width 0.2)
			(type default)
		)
		(layer "In8.Cu")
	)
	(gr_arc
		(start 114.001296 -19.750024)
		(mid 114.549936 -20.298664)
		(end 115.098576 -19.750024)
		(stroke
			(width 0.2)
			(type default)
		)
		(layer "In8.Cu")
	)
	(gr_line
		(start 114.001296 -18.35023)
		(end 114.001296 -19.750024)
		(stroke
			(width 0.2)
			(type default)
		)
		(layer "In8.Cu")
	)
	(gr_line
		(start 115.098576 -23.35022)
		(end 115.098576 -21.950426)
		(stroke
			(width 0.2)
			(type default)
		)
		(layer "In8.Cu")
	)
	(gr_arc
		(start 115.098576 -21.950426)
		(mid 114.550063 -21.401532)
		(end 114.001296 -21.950172)
		(stroke
			(width 0.2)
			(type default)
		)
		(layer "In8.Cu")
	)
	(gr_line
		(start 115.098576 -19.750024)
		(end 115.098576 -18.350484)
		(stroke
			(width 0.2)
			(type default)
		)
		(layer "In8.Cu")
	)
	(gr_arc
		(start 115.098576 -18.350484)
		(mid 114.550063 -17.80159)
		(end 114.001296 -18.35023)
		(stroke
			(width 0.2)
			(type default)
		)
		(layer "In8.Cu")
	)
	(gr_arc
		(start 115.801394 -29.550106)
		(mid 116.350034 -30.098746)
		(end 116.898674 -29.550106)
		(stroke
			(width 0.2)
			(type default)
		)
		(layer "In8.Cu")
	)
	(gr_line
		(start 115.801394 -28.150058)
		(end 115.801394 -29.550106)
		(stroke
			(width 0.2)
			(type default)
		)
		(layer "In8.Cu")
	)
	(gr_arc
		(start 115.801394 -22.350222)
		(mid 116.350034 -22.898862)
		(end 116.898674 -22.350222)
		(stroke
			(width 0.2)
			(type default)
		)
		(layer "In8.Cu")
	)
	(gr_line
		(start 115.801394 -20.950174)
		(end 115.801394 -22.350222)
		(stroke
			(width 0.2)
			(type default)
		)
		(layer "In8.Cu")
	)
	(gr_arc
		(start 115.801394 -18.750026)
		(mid 116.350034 -19.298666)
		(end 116.898674 -18.750026)
		(stroke
			(width 0.2)
			(type default)
		)
		(layer "In8.Cu")
	)
	(gr_line
		(start 115.801394 -17.349978)
		(end 115.801394 -18.750026)
		(stroke
			(width 0.2)
			(type default)
		)
		(layer "In8.Cu")
	)
	(gr_line
		(start 116.898674 -29.550106)
		(end 116.898674 -28.150312)
		(stroke
			(width 0.2)
			(type default)
		)
		(layer "In8.Cu")
	)
	(gr_arc
		(start 116.898674 -28.150312)
		(mid 116.350161 -27.601418)
		(end 115.801394 -28.150058)
		(stroke
			(width 0.2)
			(type default)
		)
		(layer "In8.Cu")
	)
	(gr_line
		(start 116.898674 -22.350222)
		(end 116.898674 -20.950428)
		(stroke
			(width 0.2)
			(type default)
		)
		(layer "In8.Cu")
	)
	(gr_arc
		(start 116.898674 -20.950428)
		(mid 116.350161 -20.401534)
		(end 115.801394 -20.950174)
		(stroke
			(width 0.2)
			(type default)
		)
		(layer "In8.Cu")
	)
	(gr_line
		(start 116.898674 -18.750026)
		(end 116.898674 -17.350232)
		(stroke
			(width 0.2)
			(type default)
		)
		(layer "In8.Cu")
	)
	(gr_arc
		(start 116.898674 -17.350232)
		(mid 116.350161 -16.801338)
		(end 115.801394 -17.349978)
		(stroke
			(width 0.2)
			(type default)
		)
		(layer "In8.Cu")
	)
	(gr_arc
		(start 117.601238 -23.35022)
		(mid 118.149878 -23.89886)
		(end 118.698518 -23.35022)
		(stroke
			(width 0.2)
			(type default)
		)
		(layer "In8.Cu")
	)
	(gr_line
		(start 117.601238 -21.950172)
		(end 117.601238 -23.35022)
		(stroke
			(width 0.2)
			(type default)
		)
		(layer "In8.Cu")
	)
	(gr_arc
		(start 117.601238 -19.750024)
		(mid 118.149878 -20.298664)
		(end 118.698518 -19.750024)
		(stroke
			(width 0.2)
			(type default)
		)
		(layer "In8.Cu")
	)
	(gr_line
		(start 117.601238 -18.35023)
		(end 117.601238 -19.750024)
		(stroke
			(width 0.2)
			(type default)
		)
		(layer "In8.Cu")
	)
	(gr_line
		(start 118.698518 -23.35022)
		(end 118.698518 -21.950426)
		(stroke
			(width 0.2)
			(type default)
		)
		(layer "In8.Cu")
	)
	(gr_arc
		(start 118.698518 -21.950426)
		(mid 118.150005 -21.401532)
		(end 117.601238 -21.950172)
		(stroke
			(width 0.2)
			(type default)
		)
		(layer "In8.Cu")
	)
	(gr_line
		(start 118.698518 -19.750024)
		(end 118.698518 -18.350484)
		(stroke
			(width 0.2)
			(type default)
		)
		(layer "In8.Cu")
	)
	(gr_arc
		(start 118.698518 -18.350484)
		(mid 118.150005 -17.80159)
		(end 117.601238 -18.35023)
		(stroke
			(width 0.2)
			(type default)
		)
		(layer "In8.Cu")
	)
	(gr_arc
		(start 119.401336 -22.350222)
		(mid 119.949976 -22.898862)
		(end 120.498616 -22.350222)
		(stroke
			(width 0.2)
			(type default)
		)
		(layer "In8.Cu")
	)
	(gr_line
		(start 119.401336 -20.950174)
		(end 119.401336 -22.350222)
		(stroke
			(width 0.2)
			(type default)
		)
		(layer "In8.Cu")
	)
	(gr_arc
		(start 119.401336 -18.750026)
		(mid 119.949976 -19.298666)
		(end 120.498616 -18.750026)
		(stroke
			(width 0.2)
			(type default)
		)
		(layer "In8.Cu")
	)
	(gr_line
		(start 119.401336 -17.349978)
		(end 119.401336 -18.750026)
		(stroke
			(width 0.2)
			(type default)
		)
		(layer "In8.Cu")
	)
	(gr_line
		(start 120.498616 -22.350222)
		(end 120.498616 -20.950428)
		(stroke
			(width 0.2)
			(type default)
		)
		(layer "In8.Cu")
	)
	(gr_arc
		(start 120.498616 -20.950428)
		(mid 119.950103 -20.401534)
		(end 119.401336 -20.950174)
		(stroke
			(width 0.2)
			(type default)
		)
		(layer "In8.Cu")
	)
	(gr_line
		(start 120.498616 -18.750026)
		(end 120.498616 -17.350232)
		(stroke
			(width 0.2)
			(type default)
		)
		(layer "In8.Cu")
	)
	(gr_arc
		(start 120.498616 -17.350232)
		(mid 119.950103 -16.801338)
		(end 119.401336 -17.349978)
		(stroke
			(width 0.2)
			(type default)
		)
		(layer "In8.Cu")
	)
	(gr_arc
		(start 121.198894 -30.54985)
		(mid 121.749947 -31.101284)
		(end 122.301254 -30.550104)
		(stroke
			(width 0.2)
			(type default)
		)
		(layer "In8.Cu")
	)
	(gr_line
		(start 121.198894 -29.150056)
		(end 121.198894 -30.54985)
		(stroke
			(width 0.2)
			(type default)
		)
		(layer "In8.Cu")
	)
	(gr_arc
		(start 121.201434 -23.35022)
		(mid 121.750074 -23.89886)
		(end 122.298714 -23.35022)
		(stroke
			(width 0.2)
			(type default)
		)
		(layer "In8.Cu")
	)
	(gr_line
		(start 121.201434 -21.950172)
		(end 121.201434 -23.35022)
		(stroke
			(width 0.2)
			(type default)
		)
		(layer "In8.Cu")
	)
	(gr_arc
		(start 121.201434 -19.750024)
		(mid 121.750074 -20.298664)
		(end 122.298714 -19.750024)
		(stroke
			(width 0.2)
			(type default)
		)
		(layer "In8.Cu")
	)
	(gr_line
		(start 121.201434 -18.35023)
		(end 121.201434 -19.750024)
		(stroke
			(width 0.2)
			(type default)
		)
		(layer "In8.Cu")
	)
	(gr_line
		(start 122.298714 -23.35022)
		(end 122.298714 -21.950426)
		(stroke
			(width 0.2)
			(type default)
		)
		(layer "In8.Cu")
	)
	(gr_arc
		(start 122.298714 -21.950426)
		(mid 121.750201 -21.401532)
		(end 121.201434 -21.950172)
		(stroke
			(width 0.2)
			(type default)
		)
		(layer "In8.Cu")
	)
	(gr_line
		(start 122.298714 -19.750024)
		(end 122.298714 -18.350484)
		(stroke
			(width 0.2)
			(type default)
		)
		(layer "In8.Cu")
	)
	(gr_arc
		(start 122.298714 -18.350484)
		(mid 121.750201 -17.80159)
		(end 121.201434 -18.35023)
		(stroke
			(width 0.2)
			(type default)
		)
		(layer "In8.Cu")
	)
	(gr_line
		(start 122.301254 -30.550104)
		(end 122.301254 -29.150056)
		(stroke
			(width 0.2)
			(type default)
		)
		(layer "In8.Cu")
	)
	(gr_arc
		(start 122.301254 -29.150056)
		(mid 121.750074 -28.598876)
		(end 121.198894 -29.150056)
		(stroke
			(width 0.2)
			(type default)
		)
		(layer "In8.Cu")
	)
	(gr_arc
		(start 126.77775 -278.321516)
		(mid 127.15875 -278.702516)
		(end 127.53975 -278.321516)
		(stroke
			(width 0.2)
			(type default)
		)
		(layer "In8.Cu")
	)
	(gr_line
		(start 126.77775 -277.178516)
		(end 126.77775 -278.321516)
		(stroke
			(width 0.2)
			(type default)
		)
		(layer "In8.Cu")
	)
	(gr_arc
		(start 126.77775 -163.321492)
		(mid 127.15875 -163.702492)
		(end 127.53975 -163.321492)
		(stroke
			(width 0.2)
			(type default)
		)
		(layer "In8.Cu")
	)
	(gr_line
		(start 126.77775 -162.178492)
		(end 126.77775 -163.321492)
		(stroke
			(width 0.2)
			(type default)
		)
		(layer "In8.Cu")
	)
	(gr_arc
		(start 126.77775 -48.321468)
		(mid 127.15875 -48.702468)
		(end 127.53975 -48.321468)
		(stroke
			(width 0.2)
			(type default)
		)
		(layer "In8.Cu")
	)
	(gr_line
		(start 126.77775 -47.178468)
		(end 126.77775 -48.321468)
		(stroke
			(width 0.2)
			(type default)
		)
		(layer "In8.Cu")
	)
	(gr_line
		(start 127.53975 -278.321516)
		(end 127.53975 -277.17877)
		(stroke
			(width 0.2)
			(type default)
		)
		(layer "In8.Cu")
	)
	(gr_arc
		(start 127.53975 -277.17877)
		(mid 127.158877 -276.797516)
		(end 126.77775 -277.178516)
		(stroke
			(width 0.2)
			(type default)
		)
		(layer "In8.Cu")
	)
	(gr_line
		(start 127.53975 -163.321492)
		(end 127.53975 -162.178746)
		(stroke
			(width 0.2)
			(type default)
		)
		(layer "In8.Cu")
	)
	(gr_arc
		(start 127.53975 -162.178746)
		(mid 127.158877 -161.797492)
		(end 126.77775 -162.178492)
		(stroke
			(width 0.2)
			(type default)
		)
		(layer "In8.Cu")
	)
	(gr_line
		(start 127.53975 -48.321468)
		(end 127.53975 -47.178722)
		(stroke
			(width 0.2)
			(type default)
		)
		(layer "In8.Cu")
	)
	(gr_arc
		(start 127.53975 -47.178722)
		(mid 127.158877 -46.797468)
		(end 126.77775 -47.178468)
		(stroke
			(width 0.2)
			(type default)
		)
		(layer "In8.Cu")
	)
	(gr_arc
		(start 130.201416 -22.350222)
		(mid 130.750056 -22.898862)
		(end 131.298696 -22.350222)
		(stroke
			(width 0.2)
			(type default)
		)
		(layer "In8.Cu")
	)
	(gr_line
		(start 130.201416 -20.950174)
		(end 130.201416 -22.350222)
		(stroke
			(width 0.2)
			(type default)
		)
		(layer "In8.Cu")
	)
	(gr_arc
		(start 130.201416 -18.750026)
		(mid 130.750056 -19.298666)
		(end 131.298696 -18.750026)
		(stroke
			(width 0.2)
			(type default)
		)
		(layer "In8.Cu")
	)
	(gr_line
		(start 130.201416 -17.349978)
		(end 130.201416 -18.750026)
		(stroke
			(width 0.2)
			(type default)
		)
		(layer "In8.Cu")
	)
	(gr_line
		(start 131.298696 -22.350222)
		(end 131.298696 -20.950428)
		(stroke
			(width 0.2)
			(type default)
		)
		(layer "In8.Cu")
	)
	(gr_arc
		(start 131.298696 -20.950428)
		(mid 130.750183 -20.401534)
		(end 130.201416 -20.950174)
		(stroke
			(width 0.2)
			(type default)
		)
		(layer "In8.Cu")
	)
	(gr_line
		(start 131.298696 -18.750026)
		(end 131.298696 -17.350232)
		(stroke
			(width 0.2)
			(type default)
		)
		(layer "In8.Cu")
	)
	(gr_arc
		(start 131.298696 -17.350232)
		(mid 130.750183 -16.801338)
		(end 130.201416 -17.349978)
		(stroke
			(width 0.2)
			(type default)
		)
		(layer "In8.Cu")
	)
	(gr_arc
		(start 132.00126 -23.35022)
		(mid 132.5499 -23.89886)
		(end 133.09854 -23.35022)
		(stroke
			(width 0.2)
			(type default)
		)
		(layer "In8.Cu")
	)
	(gr_line
		(start 132.00126 -21.950172)
		(end 132.00126 -23.35022)
		(stroke
			(width 0.2)
			(type default)
		)
		(layer "In8.Cu")
	)
	(gr_arc
		(start 132.00126 -19.74977)
		(mid 132.549773 -20.298664)
		(end 133.09854 -19.750024)
		(stroke
			(width 0.2)
			(type default)
		)
		(layer "In8.Cu")
	)
	(gr_line
		(start 132.00126 -18.35023)
		(end 132.00126 -19.74977)
		(stroke
			(width 0.2)
			(type default)
		)
		(layer "In8.Cu")
	)
	(gr_line
		(start 133.09854 -23.35022)
		(end 133.09854 -21.950426)
		(stroke
			(width 0.2)
			(type default)
		)
		(layer "In8.Cu")
	)
	(gr_arc
		(start 133.09854 -21.950426)
		(mid 132.550027 -21.401532)
		(end 132.00126 -21.950172)
		(stroke
			(width 0.2)
			(type default)
		)
		(layer "In8.Cu")
	)
	(gr_line
		(start 133.09854 -19.750024)
		(end 133.09854 -18.35023)
		(stroke
			(width 0.2)
			(type default)
		)
		(layer "In8.Cu")
	)
	(gr_arc
		(start 133.09854 -18.35023)
		(mid 132.5499 -17.80159)
		(end 132.00126 -18.35023)
		(stroke
			(width 0.2)
			(type default)
		)
		(layer "In8.Cu")
	)
	(gr_arc
		(start 133.801358 -22.350222)
		(mid 134.349998 -22.898862)
		(end 134.898638 -22.350222)
		(stroke
			(width 0.2)
			(type default)
		)
		(layer "In8.Cu")
	)
	(gr_line
		(start 133.801358 -20.950174)
		(end 133.801358 -22.350222)
		(stroke
			(width 0.2)
			(type default)
		)
		(layer "In8.Cu")
	)
	(gr_arc
		(start 133.801358 -18.750026)
		(mid 134.349998 -19.298666)
		(end 134.898638 -18.750026)
		(stroke
			(width 0.2)
			(type default)
		)
		(layer "In8.Cu")
	)
	(gr_line
		(start 133.801358 -17.349978)
		(end 133.801358 -18.750026)
		(stroke
			(width 0.2)
			(type default)
		)
		(layer "In8.Cu")
	)
	(gr_line
		(start 134.898638 -22.350222)
		(end 134.898638 -20.950428)
		(stroke
			(width 0.2)
			(type default)
		)
		(layer "In8.Cu")
	)
	(gr_arc
		(start 134.898638 -20.950428)
		(mid 134.350125 -20.401534)
		(end 133.801358 -20.950174)
		(stroke
			(width 0.2)
			(type default)
		)
		(layer "In8.Cu")
	)
	(gr_line
		(start 134.898638 -18.750026)
		(end 134.898638 -17.350232)
		(stroke
			(width 0.2)
			(type default)
		)
		(layer "In8.Cu")
	)
	(gr_arc
		(start 134.898638 -17.350232)
		(mid 134.350125 -16.801338)
		(end 133.801358 -17.349978)
		(stroke
			(width 0.2)
			(type default)
		)
		(layer "In8.Cu")
	)
	(gr_arc
		(start 135.601456 -30.550104)
		(mid 136.150096 -31.098744)
		(end 136.698736 -30.550104)
		(stroke
			(width 0.2)
			(type default)
		)
		(layer "In8.Cu")
	)
	(gr_line
		(start 135.601456 -29.150056)
		(end 135.601456 -30.550104)
		(stroke
			(width 0.2)
			(type default)
		)
		(layer "In8.Cu")
	)
	(gr_arc
		(start 135.601456 -23.35022)
		(mid 136.150096 -23.89886)
		(end 136.698736 -23.35022)
		(stroke
			(width 0.2)
			(type default)
		)
		(layer "In8.Cu")
	)
	(gr_line
		(start 135.601456 -21.950172)
		(end 135.601456 -23.35022)
		(stroke
			(width 0.2)
			(type default)
		)
		(layer "In8.Cu")
	)
	(gr_arc
		(start 135.601456 -19.750024)
		(mid 136.150096 -20.298664)
		(end 136.698736 -19.750024)
		(stroke
			(width 0.2)
			(type default)
		)
		(layer "In8.Cu")
	)
	(gr_line
		(start 135.601456 -18.35023)
		(end 135.601456 -19.750024)
		(stroke
			(width 0.2)
			(type default)
		)
		(layer "In8.Cu")
	)
	(gr_line
		(start 136.698736 -30.550104)
		(end 136.698736 -29.15031)
		(stroke
			(width 0.2)
			(type default)
		)
		(layer "In8.Cu")
	)
	(gr_arc
		(start 136.698736 -29.15031)
		(mid 136.150223 -28.601416)
		(end 135.601456 -29.150056)
		(stroke
			(width 0.2)
			(type default)
		)
		(layer "In8.Cu")
	)
	(gr_line
		(start 136.698736 -23.35022)
		(end 136.698736 -21.950426)
		(stroke
			(width 0.2)
			(type default)
		)
		(layer "In8.Cu")
	)
	(gr_arc
		(start 136.698736 -21.950426)
		(mid 136.150223 -21.401532)
		(end 135.601456 -21.950172)
		(stroke
			(width 0.2)
			(type default)
		)
		(layer "In8.Cu")
	)
	(gr_line
		(start 136.698736 -19.750024)
		(end 136.698736 -18.350484)
		(stroke
			(width 0.2)
			(type default)
		)
		(layer "In8.Cu")
	)
	(gr_arc
		(start 136.698736 -18.350484)
		(mid 136.150223 -17.80159)
		(end 135.601456 -18.35023)
		(stroke
			(width 0.2)
			(type default)
		)
		(layer "In8.Cu")
	)
	(gr_arc
		(start 137.4013 -22.350222)
		(mid 137.94994 -22.898862)
		(end 138.49858 -22.350222)
		(stroke
			(width 0.2)
			(type default)
		)
		(layer "In8.Cu")
	)
	(gr_line
		(start 137.4013 -20.950174)
		(end 137.4013 -22.350222)
		(stroke
			(width 0.2)
			(type default)
		)
		(layer "In8.Cu")
	)
	(gr_arc
		(start 137.4013 -18.750026)
		(mid 137.94994 -19.298666)
		(end 138.49858 -18.750026)
		(stroke
			(width 0.2)
			(type default)
		)
		(layer "In8.Cu")
	)
	(gr_line
		(start 137.4013 -17.349978)
		(end 137.4013 -18.750026)
		(stroke
			(width 0.2)
			(type default)
		)
		(layer "In8.Cu")
	)
	(gr_line
		(start 138.49858 -22.350222)
		(end 138.49858 -20.950428)
		(stroke
			(width 0.2)
			(type default)
		)
		(layer "In8.Cu")
	)
	(gr_arc
		(start 138.49858 -20.950428)
		(mid 137.950067 -20.401534)
		(end 137.4013 -20.950174)
		(stroke
			(width 0.2)
			(type default)
		)
		(layer "In8.Cu")
	)
	(gr_line
		(start 138.49858 -18.750026)
		(end 138.49858 -17.350232)
		(stroke
			(width 0.2)
			(type default)
		)
		(layer "In8.Cu")
	)
	(gr_arc
		(start 138.49858 -17.350232)
		(mid 137.950067 -16.801338)
		(end 137.4013 -17.349978)
		(stroke
			(width 0.2)
			(type default)
		)
		(layer "In8.Cu")
	)
	(gr_arc
		(start 139.201398 -23.35022)
		(mid 139.750038 -23.89886)
		(end 140.298678 -23.35022)
		(stroke
			(width 0.2)
			(type default)
		)
		(layer "In8.Cu")
	)
	(gr_line
		(start 139.201398 -21.950172)
		(end 139.201398 -23.35022)
		(stroke
			(width 0.2)
			(type default)
		)
		(layer "In8.Cu")
	)
	(gr_arc
		(start 139.201398 -19.750024)
		(mid 139.750038 -20.298664)
		(end 140.298678 -19.750024)
		(stroke
			(width 0.2)
			(type default)
		)
		(layer "In8.Cu")
	)
	(gr_line
		(start 139.201398 -18.35023)
		(end 139.201398 -19.750024)
		(stroke
			(width 0.2)
			(type default)
		)
		(layer "In8.Cu")
	)
	(gr_line
		(start 140.298678 -23.35022)
		(end 140.298678 -21.950426)
		(stroke
			(width 0.2)
			(type default)
		)
		(layer "In8.Cu")
	)
	(gr_arc
		(start 140.298678 -21.950426)
		(mid 139.750165 -21.401532)
		(end 139.201398 -21.950172)
		(stroke
			(width 0.2)
			(type default)
		)
		(layer "In8.Cu")
	)
	(gr_line
		(start 140.298678 -19.750024)
		(end 140.298678 -18.350484)
		(stroke
			(width 0.2)
			(type default)
		)
		(layer "In8.Cu")
	)
	(gr_arc
		(start 140.298678 -18.350484)
		(mid 139.750165 -17.80159)
		(end 139.201398 -18.35023)
		(stroke
			(width 0.2)
			(type default)
		)
		(layer "In8.Cu")
	)
	(gr_arc
		(start 141.001242 -22.350222)
		(mid 141.549882 -22.898862)
		(end 142.098522 -22.350222)
		(stroke
			(width 0.2)
			(type default)
		)
		(layer "In8.Cu")
	)
	(gr_line
		(start 141.001242 -20.950174)
		(end 141.001242 -22.350222)
		(stroke
			(width 0.2)
			(type default)
		)
		(layer "In8.Cu")
	)
	(gr_arc
		(start 141.001242 -18.750026)
		(mid 141.549882 -19.298666)
		(end 142.098522 -18.750026)
		(stroke
			(width 0.2)
			(type default)
		)
		(layer "In8.Cu")
	)
	(gr_line
		(start 141.001242 -17.349978)
		(end 141.001242 -18.750026)
		(stroke
			(width 0.2)
			(type default)
		)
		(layer "In8.Cu")
	)
	(gr_line
		(start 142.098522 -22.350222)
		(end 142.098522 -20.950428)
		(stroke
			(width 0.2)
			(type default)
		)
		(layer "In8.Cu")
	)
	(gr_arc
		(start 142.098522 -20.950428)
		(mid 141.550009 -20.401534)
		(end 141.001242 -20.950174)
		(stroke
			(width 0.2)
			(type default)
		)
		(layer "In8.Cu")
	)
	(gr_line
		(start 142.098522 -18.750026)
		(end 142.098522 -17.350232)
		(stroke
			(width 0.2)
			(type default)
		)
		(layer "In8.Cu")
	)
	(gr_arc
		(start 142.098522 -17.350232)
		(mid 141.550009 -16.801338)
		(end 141.001242 -17.349978)
		(stroke
			(width 0.2)
			(type default)
		)
		(layer "In8.Cu")
	)
	(gr_arc
		(start 142.80134 -30.550104)
		(mid 143.34998 -31.098744)
		(end 143.89862 -30.550104)
		(stroke
			(width 0.2)
			(type default)
		)
		(layer "In8.Cu")
	)
	(gr_line
		(start 142.80134 -29.150056)
		(end 142.80134 -30.550104)
		(stroke
			(width 0.2)
			(type default)
		)
		(layer "In8.Cu")
	)
	(gr_arc
		(start 142.80134 -23.35022)
		(mid 143.34998 -23.89886)
		(end 143.89862 -23.35022)
		(stroke
			(width 0.2)
			(type default)
		)
		(layer "In8.Cu")
	)
	(gr_line
		(start 142.80134 -21.950172)
		(end 142.80134 -23.35022)
		(stroke
			(width 0.2)
			(type default)
		)
		(layer "In8.Cu")
	)
	(gr_arc
		(start 142.80134 -19.750024)
		(mid 143.34998 -20.298664)
		(end 143.89862 -19.750024)
		(stroke
			(width 0.2)
			(type default)
		)
		(layer "In8.Cu")
	)
	(gr_line
		(start 142.80134 -18.35023)
		(end 142.80134 -19.750024)
		(stroke
			(width 0.2)
			(type default)
		)
		(layer "In8.Cu")
	)
	(gr_line
		(start 143.89862 -30.550104)
		(end 143.89862 -29.15031)
		(stroke
			(width 0.2)
			(type default)
		)
		(layer "In8.Cu")
	)
	(gr_arc
		(start 143.89862 -29.15031)
		(mid 143.350107 -28.601416)
		(end 142.80134 -29.150056)
		(stroke
			(width 0.2)
			(type default)
		)
		(layer "In8.Cu")
	)
	(gr_line
		(start 143.89862 -23.35022)
		(end 143.89862 -21.950426)
		(stroke
			(width 0.2)
			(type default)
		)
		(layer "In8.Cu")
	)
	(gr_arc
		(start 143.89862 -21.950426)
		(mid 143.350107 -21.401532)
		(end 142.80134 -21.950172)
		(stroke
			(width 0.2)
			(type default)
		)
		(layer "In8.Cu")
	)
	(gr_line
		(start 143.89862 -19.750024)
		(end 143.89862 -18.350484)
		(stroke
			(width 0.2)
			(type default)
		)
		(layer "In8.Cu")
	)
	(gr_arc
		(start 143.89862 -18.350484)
		(mid 143.350107 -17.80159)
		(end 142.80134 -18.35023)
		(stroke
			(width 0.2)
			(type default)
		)
		(layer "In8.Cu")
	)
	(gr_arc
		(start 148.999956 -14.99997)
		(mid 149.707061 -14.707077)
		(end 149.999954 -13.999972)
		(stroke
			(width 1.524)
			(type default)
		)
		(layer "In8.Cu")
	)
	(gr_line
		(start 149.999954 -13.999972)
		(end 149.999954 -0.999998)
		(stroke
			(width 1.524)
			(type default)
		)
		(layer "In8.Cu")
	)
	(gr_arc
		(start 150.999952 0)
		(mid 150.292877 -0.292909)
		(end 149.999954 -0.999998)
		(stroke
			(width 1.524)
			(type default)
		)
		(layer "In8.Cu")
	)
	(gr_line
		(start 150.999952 0)
		(end 199.00011 0)
		(stroke
			(width 1.524)
			(type default)
		)
		(layer "In8.Cu")
	)
	(gr_arc
		(start 158.327852 -278.321516)
		(mid 158.708852 -278.702516)
		(end 159.089852 -278.321516)
		(stroke
			(width 0.2)
			(type default)
		)
		(layer "In8.Cu")
	)
	(gr_line
		(start 158.327852 -277.178516)
		(end 158.327852 -278.321516)
		(stroke
			(width 0.2)
			(type default)
		)
		(layer "In8.Cu")
	)
	(gr_arc
		(start 158.327852 -163.321492)
		(mid 158.708852 -163.702492)
		(end 159.089852 -163.321492)
		(stroke
			(width 0.2)
			(type default)
		)
		(layer "In8.Cu")
	)
	(gr_line
		(start 158.327852 -162.178492)
		(end 158.327852 -163.321492)
		(stroke
			(width 0.2)
			(type default)
		)
		(layer "In8.Cu")
	)
	(gr_arc
		(start 158.327852 -48.321468)
		(mid 158.708852 -48.702468)
		(end 159.089852 -48.321468)
		(stroke
			(width 0.2)
			(type default)
		)
		(layer "In8.Cu")
	)
	(gr_line
		(start 158.327852 -47.178468)
		(end 158.327852 -48.321468)
		(stroke
			(width 0.2)
			(type default)
		)
		(layer "In8.Cu")
	)
	(gr_line
		(start 159.089852 -278.321516)
		(end 159.089852 -277.17877)
		(stroke
			(width 0.2)
			(type default)
		)
		(layer "In8.Cu")
	)
	(gr_arc
		(start 159.089852 -277.17877)
		(mid 158.708979 -276.797516)
		(end 158.327852 -277.178516)
		(stroke
			(width 0.2)
			(type default)
		)
		(layer "In8.Cu")
	)
	(gr_line
		(start 159.089852 -163.321492)
		(end 159.089852 -162.178746)
		(stroke
			(width 0.2)
			(type default)
		)
		(layer "In8.Cu")
	)
	(gr_arc
		(start 159.089852 -162.178746)
		(mid 158.708979 -161.797492)
		(end 158.327852 -162.178492)
		(stroke
			(width 0.2)
			(type default)
		)
		(layer "In8.Cu")
	)
	(gr_line
		(start 159.089852 -48.321468)
		(end 159.089852 -47.178722)
		(stroke
			(width 0.2)
			(type default)
		)
		(layer "In8.Cu")
	)
	(gr_arc
		(start 159.089852 -47.178722)
		(mid 158.708979 -46.797468)
		(end 158.327852 -47.178468)
		(stroke
			(width 0.2)
			(type default)
		)
		(layer "In8.Cu")
	)
	(gr_line
		(start 189.6999 -349.199962)
		(end 0.999998 -349.199962)
		(stroke
			(width 1.524)
			(type default)
		)
		(layer "In8.Cu")
	)
	(gr_arc
		(start 189.877954 -278.321516)
		(mid 190.258954 -278.702516)
		(end 190.639954 -278.321516)
		(stroke
			(width 0.2)
			(type default)
		)
		(layer "In8.Cu")
	)
	(gr_line
		(start 189.877954 -277.178516)
		(end 189.877954 -278.321516)
		(stroke
			(width 0.2)
			(type default)
		)
		(layer "In8.Cu")
	)
	(gr_arc
		(start 189.877954 -163.321492)
		(mid 190.258954 -163.702492)
		(end 190.639954 -163.321492)
		(stroke
			(width 0.2)
			(type default)
		)
		(layer "In8.Cu")
	)
	(gr_line
		(start 189.877954 -162.178492)
		(end 189.877954 -163.321492)
		(stroke
			(width 0.2)
			(type default)
		)
		(layer "In8.Cu")
	)
	(gr_arc
		(start 189.877954 -48.321468)
		(mid 190.258954 -48.702468)
		(end 190.639954 -48.321468)
		(stroke
			(width 0.2)
			(type default)
		)
		(layer "In8.Cu")
	)
	(gr_line
		(start 189.877954 -47.178468)
		(end 189.877954 -48.321468)
		(stroke
			(width 0.2)
			(type default)
		)
		(layer "In8.Cu")
	)
	(gr_line
		(start 190.639954 -278.321516)
		(end 190.639954 -277.17877)
		(stroke
			(width 0.2)
			(type default)
		)
		(layer "In8.Cu")
	)
	(gr_arc
		(start 190.639954 -277.17877)
		(mid 190.259081 -276.797516)
		(end 189.877954 -277.178516)
		(stroke
			(width 0.2)
			(type default)
		)
		(layer "In8.Cu")
	)
	(gr_line
		(start 190.639954 -163.321492)
		(end 190.639954 -162.178746)
		(stroke
			(width 0.2)
			(type default)
		)
		(layer "In8.Cu")
	)
	(gr_arc
		(start 190.639954 -162.178746)
		(mid 190.259081 -161.797492)
		(end 189.877954 -162.178492)
		(stroke
			(width 0.2)
			(type default)
		)
		(layer "In8.Cu")
	)
	(gr_line
		(start 190.639954 -48.321468)
		(end 190.639954 -47.178722)
		(stroke
			(width 0.2)
			(type default)
		)
		(layer "In8.Cu")
	)
	(gr_arc
		(start 190.639954 -47.178722)
		(mid 190.259081 -46.797468)
		(end 189.877954 -47.178468)
		(stroke
			(width 0.2)
			(type default)
		)
		(layer "In8.Cu")
	)
	(gr_line
		(start 190.699898 -372.000018)
		(end 190.699898 -350.19996)
		(stroke
			(width 1.524)
			(type default)
		)
		(layer "In8.Cu")
	)
	(gr_arc
		(start 190.699898 -372.000018)
		(mid 190.992797 -372.707113)
		(end 191.699896 -373.000016)
		(stroke
			(width 1.524)
			(type default)
		)
		(layer "In8.Cu")
	)
	(gr_arc
		(start 190.699898 -350.19996)
		(mid 190.407005 -349.492855)
		(end 189.6999 -349.199962)
		(stroke
			(width 1.524)
			(type default)
		)
		(layer "In8.Cu")
	)
	(gr_line
		(start 199.00011 -373.000016)
		(end 191.699896 -373.000016)
		(stroke
			(width 1.524)
			(type default)
		)
		(layer "In8.Cu")
	)
	(gr_arc
		(start 199.00011 0)
		(mid 199.707215 0.292893)
		(end 200.000108 0.999998)
		(stroke
			(width 1.524)
			(type default)
		)
		(layer "In8.Cu")
	)
	(gr_line
		(start 200.000108 -420.200074)
		(end 200.000108 -374.000014)
		(stroke
			(width 1.524)
			(type default)
		)
		(layer "In8.Cu")
	)
	(gr_arc
		(start 200.000108 -420.200074)
		(mid 200.292992 -420.907194)
		(end 201.000106 -421.200072)
		(stroke
			(width 1.524)
			(type default)
		)
		(layer "In8.Cu")
	)
	(gr_arc
		(start 200.000108 -374.000014)
		(mid 199.707215 -373.292909)
		(end 199.00011 -373.000016)
		(stroke
			(width 1.524)
			(type default)
		)
		(layer "In8.Cu")
	)
	(gr_arc
		(start 201.000106 1.999996)
		(mid 200.292997 1.707105)
		(end 200.000108 0.999998)
		(stroke
			(width 1.524)
			(type default)
		)
		(layer "In8.Cu")
	)
	(gr_line
		(start 201.000106 1.999996)
		(end 219.00007 1.999996)
		(stroke
			(width 1.524)
			(type default)
		)
		(layer "In8.Cu")
	)
	(gr_arc
		(start 209.451448 -415.600134)
		(mid 210.000088 -416.148774)
		(end 210.548728 -415.600134)
		(stroke
			(width 0.2)
			(type default)
		)
		(layer "In8.Cu")
	)
	(gr_line
		(start 209.451448 -414.200086)
		(end 209.451448 -415.600134)
		(stroke
			(width 0.2)
			(type default)
		)
		(layer "In8.Cu")
	)
	(gr_arc
		(start 209.451448 -412.000192)
		(mid 210.000088 -412.548832)
		(end 210.548728 -412.000192)
		(stroke
			(width 0.2)
			(type default)
		)
		(layer "In8.Cu")
	)
	(gr_line
		(start 209.451448 -410.600144)
		(end 209.451448 -412.000192)
		(stroke
			(width 0.2)
			(type default)
		)
		(layer "In8.Cu")
	)
	(gr_arc
		(start 209.451448 -408.399996)
		(mid 210.000088 -408.948636)
		(end 210.548728 -408.399996)
		(stroke
			(width 0.2)
			(type default)
		)
		(layer "In8.Cu")
	)
	(gr_line
		(start 209.451448 -407.000202)
		(end 209.451448 -408.399996)
		(stroke
			(width 0.2)
			(type default)
		)
		(layer "In8.Cu")
	)
	(gr_line
		(start 210.548728 -415.600134)
		(end 210.548728 -414.20034)
		(stroke
			(width 0.2)
			(type default)
		)
		(layer "In8.Cu")
	)
	(gr_arc
		(start 210.548728 -414.20034)
		(mid 210.000215 -413.651446)
		(end 209.451448 -414.200086)
		(stroke
			(width 0.2)
			(type default)
		)
		(layer "In8.Cu")
	)
	(gr_line
		(start 210.548728 -412.000192)
		(end 210.548728 -410.600398)
		(stroke
			(width 0.2)
			(type default)
		)
		(layer "In8.Cu")
	)
	(gr_arc
		(start 210.548728 -410.600398)
		(mid 210.000215 -410.051504)
		(end 209.451448 -410.600144)
		(stroke
			(width 0.2)
			(type default)
		)
		(layer "In8.Cu")
	)
	(gr_line
		(start 210.548728 -408.399996)
		(end 210.548728 -407.000456)
		(stroke
			(width 0.2)
			(type default)
		)
		(layer "In8.Cu")
	)
	(gr_arc
		(start 210.548728 -407.000456)
		(mid 210.000215 -406.451562)
		(end 209.451448 -407.000202)
		(stroke
			(width 0.2)
			(type default)
		)
		(layer "In8.Cu")
	)
	(gr_arc
		(start 211.251546 -418.200078)
		(mid 211.800186 -418.748718)
		(end 212.348826 -418.200078)
		(stroke
			(width 0.2)
			(type default)
		)
		(layer "In8.Cu")
	)
	(gr_line
		(start 211.251546 -416.80003)
		(end 211.251546 -418.200078)
		(stroke
			(width 0.2)
			(type default)
		)
		(layer "In8.Cu")
	)
	(gr_arc
		(start 211.251546 -407.399998)
		(mid 211.800186 -407.948638)
		(end 212.348826 -407.399998)
		(stroke
			(width 0.2)
			(type default)
		)
		(layer "In8.Cu")
	)
	(gr_line
		(start 211.251546 -405.99995)
		(end 211.251546 -407.399998)
		(stroke
			(width 0.2)
			(type default)
		)
		(layer "In8.Cu")
	)
	(gr_line
		(start 212.348826 -418.200078)
		(end 212.348826 -416.800284)
		(stroke
			(width 0.2)
			(type default)
		)
		(layer "In8.Cu")
	)
	(gr_arc
		(start 212.348826 -416.800284)
		(mid 211.800313 -416.25139)
		(end 211.251546 -416.80003)
		(stroke
			(width 0.2)
			(type default)
		)
		(layer "In8.Cu")
	)
	(gr_line
		(start 212.348826 -407.399998)
		(end 212.348826 -406.000204)
		(stroke
			(width 0.2)
			(type default)
		)
		(layer "In8.Cu")
	)
	(gr_arc
		(start 212.348826 -406.000204)
		(mid 211.800313 -405.45131)
		(end 211.251546 -405.99995)
		(stroke
			(width 0.2)
			(type default)
		)
		(layer "In8.Cu")
	)
	(gr_arc
		(start 213.05139 -415.600134)
		(mid 213.60003 -416.148774)
		(end 214.14867 -415.600134)
		(stroke
			(width 0.2)
			(type default)
		)
		(layer "In8.Cu")
	)
	(gr_line
		(start 213.05139 -414.200086)
		(end 213.05139 -415.600134)
		(stroke
			(width 0.2)
			(type default)
		)
		(layer "In8.Cu")
	)
	(gr_arc
		(start 213.05139 -408.399996)
		(mid 213.60003 -408.948636)
		(end 214.14867 -408.399996)
		(stroke
			(width 0.2)
			(type default)
		)
		(layer "In8.Cu")
	)
	(gr_line
		(start 213.05139 -407.000202)
		(end 213.05139 -408.399996)
		(stroke
			(width 0.2)
			(type default)
		)
		(layer "In8.Cu")
	)
	(gr_line
		(start 214.14867 -415.600134)
		(end 214.14867 -414.20034)
		(stroke
			(width 0.2)
			(type default)
		)
		(layer "In8.Cu")
	)
	(gr_arc
		(start 214.14867 -414.20034)
		(mid 213.600157 -413.651446)
		(end 213.05139 -414.200086)
		(stroke
			(width 0.2)
			(type default)
		)
		(layer "In8.Cu")
	)
	(gr_line
		(start 214.14867 -408.399996)
		(end 214.14867 -407.000456)
		(stroke
			(width 0.2)
			(type default)
		)
		(layer "In8.Cu")
	)
	(gr_arc
		(start 214.14867 -407.000456)
		(mid 213.600157 -406.451562)
		(end 213.05139 -407.000202)
		(stroke
			(width 0.2)
			(type default)
		)
		(layer "In8.Cu")
	)
	(gr_arc
		(start 214.851488 -418.200078)
		(mid 215.400128 -418.748718)
		(end 215.948768 -418.200078)
		(stroke
			(width 0.2)
			(type default)
		)
		(layer "In8.Cu")
	)
	(gr_line
		(start 214.851488 -416.80003)
		(end 214.851488 -418.200078)
		(stroke
			(width 0.2)
			(type default)
		)
		(layer "In8.Cu")
	)
	(gr_arc
		(start 214.851488 -407.399998)
		(mid 215.400128 -407.948638)
		(end 215.948768 -407.399998)
		(stroke
			(width 0.2)
			(type default)
		)
		(layer "In8.Cu")
	)
	(gr_line
		(start 214.851488 -405.99995)
		(end 214.851488 -407.399998)
		(stroke
			(width 0.2)
			(type default)
		)
		(layer "In8.Cu")
	)
	(gr_line
		(start 215.948768 -418.200078)
		(end 215.948768 -416.800284)
		(stroke
			(width 0.2)
			(type default)
		)
		(layer "In8.Cu")
	)
	(gr_arc
		(start 215.948768 -416.800284)
		(mid 215.400255 -416.25139)
		(end 214.851488 -416.80003)
		(stroke
			(width 0.2)
			(type default)
		)
		(layer "In8.Cu")
	)
	(gr_line
		(start 215.948768 -407.399998)
		(end 215.948768 -406.000204)
		(stroke
			(width 0.2)
			(type default)
		)
		(layer "In8.Cu")
	)
	(gr_arc
		(start 215.948768 -406.000204)
		(mid 215.400255 -405.45131)
		(end 214.851488 -405.99995)
		(stroke
			(width 0.2)
			(type default)
		)
		(layer "In8.Cu")
	)
	(gr_arc
		(start 216.651332 -415.600134)
		(mid 217.199972 -416.148774)
		(end 217.748612 -415.600134)
		(stroke
			(width 0.2)
			(type default)
		)
		(layer "In8.Cu")
	)
	(gr_line
		(start 216.651332 -414.200086)
		(end 216.651332 -415.600134)
		(stroke
			(width 0.2)
			(type default)
		)
		(layer "In8.Cu")
	)
	(gr_arc
		(start 216.651332 -408.399996)
		(mid 217.199972 -408.948636)
		(end 217.748612 -408.399996)
		(stroke
			(width 0.2)
			(type default)
		)
		(layer "In8.Cu")
	)
	(gr_line
		(start 216.651332 -407.000202)
		(end 216.651332 -408.399996)
		(stroke
			(width 0.2)
			(type default)
		)
		(layer "In8.Cu")
	)
	(gr_line
		(start 217.748612 -415.600134)
		(end 217.748612 -414.20034)
		(stroke
			(width 0.2)
			(type default)
		)
		(layer "In8.Cu")
	)
	(gr_arc
		(start 217.748612 -414.20034)
		(mid 217.200099 -413.651446)
		(end 216.651332 -414.200086)
		(stroke
			(width 0.2)
			(type default)
		)
		(layer "In8.Cu")
	)
	(gr_line
		(start 217.748612 -408.399996)
		(end 217.748612 -407.000456)
		(stroke
			(width 0.2)
			(type default)
		)
		(layer "In8.Cu")
	)
	(gr_arc
		(start 217.748612 -407.000456)
		(mid 217.200099 -406.451562)
		(end 216.651332 -407.000202)
		(stroke
			(width 0.2)
			(type default)
		)
		(layer "In8.Cu")
	)
	(gr_arc
		(start 218.45143 -418.200078)
		(mid 219.00007 -418.748718)
		(end 219.54871 -418.200078)
		(stroke
			(width 0.2)
			(type default)
		)
		(layer "In8.Cu")
	)
	(gr_line
		(start 218.45143 -416.80003)
		(end 218.45143 -418.200078)
		(stroke
			(width 0.2)
			(type default)
		)
		(layer "In8.Cu")
	)
	(gr_arc
		(start 218.45143 -407.399998)
		(mid 219.00007 -407.948638)
		(end 219.54871 -407.399998)
		(stroke
			(width 0.2)
			(type default)
		)
		(layer "In8.Cu")
	)
	(gr_line
		(start 218.45143 -405.99995)
		(end 218.45143 -407.399998)
		(stroke
			(width 0.2)
			(type default)
		)
		(layer "In8.Cu")
	)
	(gr_arc
		(start 219.00007 1.999996)
		(mid 219.707175 2.292889)
		(end 220.000068 2.999994)
		(stroke
			(width 1.524)
			(type default)
		)
		(layer "In8.Cu")
	)
	(gr_line
		(start 219.54871 -418.200078)
		(end 219.54871 -416.800284)
		(stroke
			(width 0.2)
			(type default)
		)
		(layer "In8.Cu")
	)
	(gr_arc
		(start 219.54871 -416.800284)
		(mid 219.000197 -416.25139)
		(end 218.45143 -416.80003)
		(stroke
			(width 0.2)
			(type default)
		)
		(layer "In8.Cu")
	)
	(gr_line
		(start 219.54871 -407.399998)
		(end 219.54871 -406.000204)
		(stroke
			(width 0.2)
			(type default)
		)
		(layer "In8.Cu")
	)
	(gr_arc
		(start 219.54871 -406.000204)
		(mid 219.000197 -405.45131)
		(end 218.45143 -405.99995)
		(stroke
			(width 0.2)
			(type default)
		)
		(layer "In8.Cu")
	)
	(gr_line
		(start 220.000068 2.999994)
		(end 220.000068 37.800026)
		(stroke
			(width 1.524)
			(type default)
		)
		(layer "In8.Cu")
	)
	(gr_arc
		(start 220.251528 -415.600134)
		(mid 220.800168 -416.148774)
		(end 221.348808 -415.600134)
		(stroke
			(width 0.2)
			(type default)
		)
		(layer "In8.Cu")
	)
	(gr_line
		(start 220.251528 -414.200086)
		(end 220.251528 -415.600134)
		(stroke
			(width 0.2)
			(type default)
		)
		(layer "In8.Cu")
	)
	(gr_arc
		(start 220.251528 -408.399996)
		(mid 220.800168 -408.948636)
		(end 221.348808 -408.399996)
		(stroke
			(width 0.2)
			(type default)
		)
		(layer "In8.Cu")
	)
	(gr_line
		(start 220.251528 -407.000202)
		(end 220.251528 -408.399996)
		(stroke
			(width 0.2)
			(type default)
		)
		(layer "In8.Cu")
	)
	(gr_arc
		(start 221.000066 38.800024)
		(mid 220.292973 38.507121)
		(end 220.000068 37.800026)
		(stroke
			(width 1.524)
			(type default)
		)
		(layer "In8.Cu")
	)
	(gr_line
		(start 221.000066 38.800024)
		(end 298.99991 38.800024)
		(stroke
			(width 1.524)
			(type default)
		)
		(layer "In8.Cu")
	)
	(gr_line
		(start 221.348808 -415.600134)
		(end 221.348808 -414.20034)
		(stroke
			(width 0.2)
			(type default)
		)
		(layer "In8.Cu")
	)
	(gr_arc
		(start 221.348808 -414.20034)
		(mid 220.800295 -413.651446)
		(end 220.251528 -414.200086)
		(stroke
			(width 0.2)
			(type default)
		)
		(layer "In8.Cu")
	)
	(gr_line
		(start 221.348808 -408.399996)
		(end 221.348808 -407.000456)
		(stroke
			(width 0.2)
			(type default)
		)
		(layer "In8.Cu")
	)
	(gr_arc
		(start 221.348808 -407.000456)
		(mid 220.800295 -406.451562)
		(end 220.251528 -407.000202)
		(stroke
			(width 0.2)
			(type default)
		)
		(layer "In8.Cu")
	)
	(gr_arc
		(start 222.051372 -418.200078)
		(mid 222.600012 -418.748718)
		(end 223.148652 -418.200078)
		(stroke
			(width 0.2)
			(type default)
		)
		(layer "In8.Cu")
	)
	(gr_line
		(start 222.051372 -416.80003)
		(end 222.051372 -418.200078)
		(stroke
			(width 0.2)
			(type default)
		)
		(layer "In8.Cu")
	)
	(gr_arc
		(start 222.051372 -407.399998)
		(mid 222.600012 -407.948638)
		(end 223.148652 -407.399998)
		(stroke
			(width 0.2)
			(type default)
		)
		(layer "In8.Cu")
	)
	(gr_line
		(start 222.051372 -405.99995)
		(end 222.051372 -407.399998)
		(stroke
			(width 0.2)
			(type default)
		)
		(layer "In8.Cu")
	)
	(gr_line
		(start 223.148652 -418.200078)
		(end 223.148652 -416.800284)
		(stroke
			(width 0.2)
			(type default)
		)
		(layer "In8.Cu")
	)
	(gr_arc
		(start 223.148652 -416.800284)
		(mid 222.600139 -416.25139)
		(end 222.051372 -416.80003)
		(stroke
			(width 0.2)
			(type default)
		)
		(layer "In8.Cu")
	)
	(gr_line
		(start 223.148652 -407.399998)
		(end 223.148652 -406.000204)
		(stroke
			(width 0.2)
			(type default)
		)
		(layer "In8.Cu")
	)
	(gr_arc
		(start 223.148652 -406.000204)
		(mid 222.600139 -405.45131)
		(end 222.051372 -405.99995)
		(stroke
			(width 0.2)
			(type default)
		)
		(layer "In8.Cu")
	)
	(gr_arc
		(start 235.722922 -121.845578)
		(mid 235.39577 -122.827034)
		(end 236.377226 -123.154186)
		(stroke
			(width 0.2)
			(type default)
		)
		(layer "In8.Cu")
	)
	(gr_line
		(start 235.723938 -65.548002)
		(end 235.725208 -65.550288)
		(stroke
			(width 0.2)
			(type default)
		)
		(layer "In8.Cu")
	)
	(gr_line
		(start 235.724192 -177.848006)
		(end 235.725208 -177.850038)
		(stroke
			(width 0.2)
			(type default)
		)
		(layer "In8.Cu")
	)
	(gr_line
		(start 235.724192 -177.847752)
		(end 235.724192 -177.848006)
		(stroke
			(width 0.2)
			(type default)
		)
		(layer "In8.Cu")
	)
	(gr_line
		(start 235.724192 -173.848014)
		(end 235.725208 -173.850046)
		(stroke
			(width 0.2)
			(type default)
		)
		(layer "In8.Cu")
	)
	(gr_line
		(start 235.724192 -173.84776)
		(end 235.724192 -173.848014)
		(stroke
			(width 0.2)
			(type default)
		)
		(layer "In8.Cu")
	)
	(gr_line
		(start 235.724192 -169.848022)
		(end 235.725208 -169.850054)
		(stroke
			(width 0.2)
			(type default)
		)
		(layer "In8.Cu")
	)
	(gr_line
		(start 235.724192 -169.847768)
		(end 235.724192 -169.848022)
		(stroke
			(width 0.2)
			(type default)
		)
		(layer "In8.Cu")
	)
	(gr_line
		(start 235.724192 -165.84803)
		(end 235.725208 -165.850062)
		(stroke
			(width 0.2)
			(type default)
		)
		(layer "In8.Cu")
	)
	(gr_line
		(start 235.724192 -165.847776)
		(end 235.724192 -165.84803)
		(stroke
			(width 0.2)
			(type default)
		)
		(layer "In8.Cu")
	)
	(gr_line
		(start 235.724192 -137.848086)
		(end 235.725208 -137.850118)
		(stroke
			(width 0.2)
			(type default)
		)
		(layer "In8.Cu")
	)
	(gr_line
		(start 235.724192 -137.847832)
		(end 235.724192 -137.848086)
		(stroke
			(width 0.2)
			(type default)
		)
		(layer "In8.Cu")
	)
	(gr_line
		(start 235.724192 -81.548224)
		(end 235.725208 -81.550256)
		(stroke
			(width 0.2)
			(type default)
		)
		(layer "In8.Cu")
	)
	(gr_line
		(start 235.724192 -81.54797)
		(end 235.724192 -81.548224)
		(stroke
			(width 0.2)
			(type default)
		)
		(layer "In8.Cu")
	)
	(gr_line
		(start 235.724192 -77.548232)
		(end 235.725208 -77.550264)
		(stroke
			(width 0.2)
			(type default)
		)
		(layer "In8.Cu")
	)
	(gr_line
		(start 235.724192 -77.547978)
		(end 235.724192 -77.548232)
		(stroke
			(width 0.2)
			(type default)
		)
		(layer "In8.Cu")
	)
	(gr_line
		(start 235.724192 -73.54824)
		(end 235.725208 -73.550272)
		(stroke
			(width 0.2)
			(type default)
		)
		(layer "In8.Cu")
	)
	(gr_line
		(start 235.724192 -73.547986)
		(end 235.724192 -73.54824)
		(stroke
			(width 0.2)
			(type default)
		)
		(layer "In8.Cu")
	)
	(gr_line
		(start 235.724192 -69.548248)
		(end 235.725208 -69.55028)
		(stroke
			(width 0.2)
			(type default)
		)
		(layer "In8.Cu")
	)
	(gr_line
		(start 235.724192 -69.547994)
		(end 235.724192 -69.548248)
		(stroke
			(width 0.2)
			(type default)
		)
		(layer "In8.Cu")
	)
	(gr_line
		(start 235.724192 -61.548264)
		(end 235.725208 -61.550296)
		(stroke
			(width 0.2)
			(type default)
		)
		(layer "In8.Cu")
	)
	(gr_line
		(start 235.724192 -61.54801)
		(end 235.724192 -61.548264)
		(stroke
			(width 0.2)
			(type default)
		)
		(layer "In8.Cu")
	)
	(gr_line
		(start 235.724192 -57.548272)
		(end 235.725208 -57.550304)
		(stroke
			(width 0.2)
			(type default)
		)
		(layer "In8.Cu")
	)
	(gr_line
		(start 235.724192 -57.548018)
		(end 235.724192 -57.548272)
		(stroke
			(width 0.2)
			(type default)
		)
		(layer "In8.Cu")
	)
	(gr_line
		(start 235.724192 -53.54828)
		(end 235.725208 -53.550312)
		(stroke
			(width 0.2)
			(type default)
		)
		(layer "In8.Cu")
	)
	(gr_line
		(start 235.724192 -53.548026)
		(end 235.724192 -53.54828)
		(stroke
			(width 0.2)
			(type default)
		)
		(layer "In8.Cu")
	)
	(gr_line
		(start 235.724192 -49.548288)
		(end 235.725208 -49.55032)
		(stroke
			(width 0.2)
			(type default)
		)
		(layer "In8.Cu")
	)
	(gr_line
		(start 235.724192 -49.548034)
		(end 235.724192 -49.548288)
		(stroke
			(width 0.2)
			(type default)
		)
		(layer "In8.Cu")
	)
	(gr_line
		(start 235.724192 -45.548296)
		(end 235.725208 -45.550328)
		(stroke
			(width 0.2)
			(type default)
		)
		(layer "In8.Cu")
	)
	(gr_line
		(start 235.724192 -45.548042)
		(end 235.724192 -45.548296)
		(stroke
			(width 0.2)
			(type default)
		)
		(layer "In8.Cu")
	)
	(gr_line
		(start 235.724192 -41.548304)
		(end 235.725208 -41.550336)
		(stroke
			(width 0.2)
			(type default)
		)
		(layer "In8.Cu")
	)
	(gr_line
		(start 235.724192 -41.54805)
		(end 235.724192 -41.548304)
		(stroke
			(width 0.2)
			(type default)
		)
		(layer "In8.Cu")
	)
	(gr_line
		(start 235.724192 -37.548312)
		(end 235.725208 -37.550344)
		(stroke
			(width 0.2)
			(type default)
		)
		(layer "In8.Cu")
	)
	(gr_line
		(start 235.724192 -37.548058)
		(end 235.724192 -37.548312)
		(stroke
			(width 0.2)
			(type default)
		)
		(layer "In8.Cu")
	)
	(gr_line
		(start 235.724192 -17.548352)
		(end 235.725208 -17.550384)
		(stroke
			(width 0.2)
			(type default)
		)
		(layer "In8.Cu")
	)
	(gr_line
		(start 235.724192 -17.548098)
		(end 235.724192 -17.548352)
		(stroke
			(width 0.2)
			(type default)
		)
		(layer "In8.Cu")
	)
	(gr_arc
		(start 235.725208 -177.850038)
		(mid 235.400342 -178.824636)
		(end 236.37494 -179.149502)
		(stroke
			(width 0.2)
			(type default)
		)
		(layer "In8.Cu")
	)
	(gr_arc
		(start 235.725208 -173.850046)
		(mid 235.400342 -174.824644)
		(end 236.37494 -175.14951)
		(stroke
			(width 0.2)
			(type default)
		)
		(layer "In8.Cu")
	)
	(gr_arc
		(start 235.725208 -169.850054)
		(mid 235.400342 -170.824652)
		(end 236.37494 -171.149518)
		(stroke
			(width 0.2)
			(type default)
		)
		(layer "In8.Cu")
	)
	(gr_arc
		(start 235.725208 -165.850062)
		(mid 235.400342 -166.82466)
		(end 236.37494 -167.149526)
		(stroke
			(width 0.2)
			(type default)
		)
		(layer "In8.Cu")
	)
	(gr_arc
		(start 235.725208 -137.850118)
		(mid 235.400342 -138.824716)
		(end 236.37494 -139.149582)
		(stroke
			(width 0.2)
			(type default)
		)
		(layer "In8.Cu")
	)
	(gr_arc
		(start 235.725208 -81.550256)
		(mid 235.400342 -82.524854)
		(end 236.37494 -82.84972)
		(stroke
			(width 0.2)
			(type default)
		)
		(layer "In8.Cu")
	)
	(gr_arc
		(start 235.725208 -77.550264)
		(mid 235.400342 -78.524862)
		(end 236.37494 -78.849728)
		(stroke
			(width 0.2)
			(type default)
		)
		(layer "In8.Cu")
	)
	(gr_arc
		(start 235.725208 -73.550272)
		(mid 235.400342 -74.52487)
		(end 236.37494 -74.849736)
		(stroke
			(width 0.2)
			(type default)
		)
		(layer "In8.Cu")
	)
	(gr_arc
		(start 235.725208 -69.55028)
		(mid 235.400342 -70.524878)
		(end 236.37494 -70.849744)
		(stroke
			(width 0.2)
			(type default)
		)
		(layer "In8.Cu")
	)
	(gr_arc
		(start 235.725208 -65.550288)
		(mid 235.400342 -66.524886)
		(end 236.37494 -66.849752)
		(stroke
			(width 0.2)
			(type default)
		)
		(layer "In8.Cu")
	)
	(gr_arc
		(start 235.725208 -61.550296)
		(mid 235.400342 -62.524894)
		(end 236.37494 -62.84976)
		(stroke
			(width 0.2)
			(type default)
		)
		(layer "In8.Cu")
	)
	(gr_arc
		(start 235.725208 -57.550304)
		(mid 235.400342 -58.524902)
		(end 236.37494 -58.849768)
		(stroke
			(width 0.2)
			(type default)
		)
		(layer "In8.Cu")
	)
	(gr_arc
		(start 235.725208 -53.550312)
		(mid 235.400342 -54.52491)
		(end 236.37494 -54.849776)
		(stroke
			(width 0.2)
			(type default)
		)
		(layer "In8.Cu")
	)
	(gr_arc
		(start 235.725208 -49.55032)
		(mid 235.400342 -50.524918)
		(end 236.37494 -50.849784)
		(stroke
			(width 0.2)
			(type default)
		)
		(layer "In8.Cu")
	)
	(gr_arc
		(start 235.725208 -45.550328)
		(mid 235.400342 -46.524926)
		(end 236.37494 -46.849792)
		(stroke
			(width 0.2)
			(type default)
		)
		(layer "In8.Cu")
	)
	(gr_arc
		(start 235.725208 -41.550336)
		(mid 235.400342 -42.524934)
		(end 236.37494 -42.8498)
		(stroke
			(width 0.2)
			(type default)
		)
		(layer "In8.Cu")
	)
	(gr_arc
		(start 235.725208 -37.550344)
		(mid 235.400342 -38.524942)
		(end 236.37494 -38.849808)
		(stroke
			(width 0.2)
			(type default)
		)
		(layer "In8.Cu")
	)
	(gr_arc
		(start 235.725208 -17.550384)
		(mid 235.400342 -18.524982)
		(end 236.37494 -18.849848)
		(stroke
			(width 0.2)
			(type default)
		)
		(layer "In8.Cu")
	)
	(gr_arc
		(start 235.733844 -161.840164)
		(mid 235.393447 -162.821194)
		(end 236.377226 -163.154106)
		(stroke
			(width 0.2)
			(type default)
		)
		(layer "In8.Cu")
	)
	(gr_arc
		(start 235.733844 -157.840172)
		(mid 235.393447 -158.821202)
		(end 236.377226 -159.154114)
		(stroke
			(width 0.2)
			(type default)
		)
		(layer "In8.Cu")
	)
	(gr_arc
		(start 235.733844 -153.84018)
		(mid 235.393447 -154.82121)
		(end 236.377226 -155.154122)
		(stroke
			(width 0.2)
			(type default)
		)
		(layer "In8.Cu")
	)
	(gr_arc
		(start 235.733844 -149.840188)
		(mid 235.393447 -150.821218)
		(end 236.377226 -151.15413)
		(stroke
			(width 0.2)
			(type default)
		)
		(layer "In8.Cu")
	)
	(gr_arc
		(start 235.733844 -129.840228)
		(mid 235.393447 -130.821258)
		(end 236.377226 -131.15417)
		(stroke
			(width 0.2)
			(type default)
		)
		(layer "In8.Cu")
	)
	(gr_arc
		(start 235.733844 -125.840236)
		(mid 235.393447 -126.821266)
		(end 236.377226 -127.154178)
		(stroke
			(width 0.2)
			(type default)
		)
		(layer "In8.Cu")
	)
	(gr_arc
		(start 235.733844 -117.840252)
		(mid 235.393447 -118.821282)
		(end 236.377226 -119.154194)
		(stroke
			(width 0.2)
			(type default)
		)
		(layer "In8.Cu")
	)
	(gr_arc
		(start 235.733844 -113.84026)
		(mid 235.393447 -114.82129)
		(end 236.377226 -115.154202)
		(stroke
			(width 0.2)
			(type default)
		)
		(layer "In8.Cu")
	)
	(gr_arc
		(start 235.733844 -11.54049)
		(mid 235.393447 -12.52152)
		(end 236.377226 -12.854432)
		(stroke
			(width 0.2)
			(type default)
		)
		(layer "In8.Cu")
	)
	(gr_line
		(start 236.37494 -179.149502)
		(end 236.37621 -179.151788)
		(stroke
			(width 0.2)
			(type default)
		)
		(layer "In8.Cu")
	)
	(gr_line
		(start 236.37494 -175.14951)
		(end 236.37621 -175.151796)
		(stroke
			(width 0.2)
			(type default)
		)
		(layer "In8.Cu")
	)
	(gr_line
		(start 236.37494 -171.149518)
		(end 236.37621 -171.151804)
		(stroke
			(width 0.2)
			(type default)
		)
		(layer "In8.Cu")
	)
	(gr_line
		(start 236.37494 -167.149526)
		(end 236.37621 -167.151812)
		(stroke
			(width 0.2)
			(type default)
		)
		(layer "In8.Cu")
	)
	(gr_line
		(start 236.37494 -139.149582)
		(end 236.37621 -139.151868)
		(stroke
			(width 0.2)
			(type default)
		)
		(layer "In8.Cu")
	)
	(gr_line
		(start 236.37494 -82.84972)
		(end 236.37621 -82.852006)
		(stroke
			(width 0.2)
			(type default)
		)
		(layer "In8.Cu")
	)
	(gr_line
		(start 236.37494 -78.849728)
		(end 236.37621 -78.852014)
		(stroke
			(width 0.2)
			(type default)
		)
		(layer "In8.Cu")
	)
	(gr_line
		(start 236.37494 -74.849736)
		(end 236.37621 -74.852022)
		(stroke
			(width 0.2)
			(type default)
		)
		(layer "In8.Cu")
	)
	(gr_line
		(start 236.37494 -70.849744)
		(end 236.37621 -70.85203)
		(stroke
			(width 0.2)
			(type default)
		)
		(layer "In8.Cu")
	)
	(gr_line
		(start 236.37494 -66.849752)
		(end 236.37621 -66.852038)
		(stroke
			(width 0.2)
			(type default)
		)
		(layer "In8.Cu")
	)
	(gr_line
		(start 236.37494 -62.84976)
		(end 236.37621 -62.852046)
		(stroke
			(width 0.2)
			(type default)
		)
		(layer "In8.Cu")
	)
	(gr_line
		(start 236.37494 -58.849768)
		(end 236.37621 -58.852054)
		(stroke
			(width 0.2)
			(type default)
		)
		(layer "In8.Cu")
	)
	(gr_line
		(start 236.37494 -54.849776)
		(end 236.37621 -54.852062)
		(stroke
			(width 0.2)
			(type default)
		)
		(layer "In8.Cu")
	)
	(gr_line
		(start 236.37494 -50.849784)
		(end 236.37621 -50.85207)
		(stroke
			(width 0.2)
			(type default)
		)
		(layer "In8.Cu")
	)
	(gr_line
		(start 236.37494 -46.849792)
		(end 236.37621 -46.852078)
		(stroke
			(width 0.2)
			(type default)
		)
		(layer "In8.Cu")
	)
	(gr_line
		(start 236.37494 -42.8498)
		(end 236.37621 -42.852086)
		(stroke
			(width 0.2)
			(type default)
		)
		(layer "In8.Cu")
	)
	(gr_line
		(start 236.37494 -38.849808)
		(end 236.37621 -38.852094)
		(stroke
			(width 0.2)
			(type default)
		)
		(layer "In8.Cu")
	)
	(gr_line
		(start 236.37494 -18.849848)
		(end 236.37621 -18.852134)
		(stroke
			(width 0.2)
			(type default)
		)
		(layer "In8.Cu")
	)
	(gr_line
		(start 236.37621 -179.151788)
		(end 238.376206 -178.15179)
		(stroke
			(width 0.2)
			(type default)
		)
		(layer "In8.Cu")
	)
	(gr_line
		(start 236.37621 -175.151796)
		(end 238.376206 -174.151798)
		(stroke
			(width 0.2)
			(type default)
		)
		(layer "In8.Cu")
	)
	(gr_line
		(start 236.37621 -171.151804)
		(end 238.376206 -170.151806)
		(stroke
			(width 0.2)
			(type default)
		)
		(layer "In8.Cu")
	)
	(gr_line
		(start 236.37621 -167.151812)
		(end 238.376206 -166.151814)
		(stroke
			(width 0.2)
			(type default)
		)
		(layer "In8.Cu")
	)
	(gr_line
		(start 236.37621 -139.151868)
		(end 238.376206 -138.15187)
		(stroke
			(width 0.2)
			(type default)
		)
		(layer "In8.Cu")
	)
	(gr_line
		(start 236.37621 -82.852006)
		(end 238.376206 -81.852008)
		(stroke
			(width 0.2)
			(type default)
		)
		(layer "In8.Cu")
	)
	(gr_line
		(start 236.37621 -78.852014)
		(end 238.376206 -77.852016)
		(stroke
			(width 0.2)
			(type default)
		)
		(layer "In8.Cu")
	)
	(gr_line
		(start 236.37621 -74.852022)
		(end 238.376206 -73.852024)
		(stroke
			(width 0.2)
			(type default)
		)
		(layer "In8.Cu")
	)
	(gr_line
		(start 236.37621 -70.85203)
		(end 238.376206 -69.852032)
		(stroke
			(width 0.2)
			(type default)
		)
		(layer "In8.Cu")
	)
	(gr_line
		(start 236.37621 -66.852038)
		(end 238.375952 -65.85204)
		(stroke
			(width 0.2)
			(type default)
		)
		(layer "In8.Cu")
	)
	(gr_line
		(start 236.37621 -62.852046)
		(end 238.376206 -61.852048)
		(stroke
			(width 0.2)
			(type default)
		)
		(layer "In8.Cu")
	)
	(gr_line
		(start 236.37621 -58.852054)
		(end 238.376206 -57.852056)
		(stroke
			(width 0.2)
			(type default)
		)
		(layer "In8.Cu")
	)
	(gr_line
		(start 236.37621 -54.852062)
		(end 238.376206 -53.852064)
		(stroke
			(width 0.2)
			(type default)
		)
		(layer "In8.Cu")
	)
	(gr_line
		(start 236.37621 -50.85207)
		(end 238.376206 -49.852072)
		(stroke
			(width 0.2)
			(type default)
		)
		(layer "In8.Cu")
	)
	(gr_line
		(start 236.37621 -46.852078)
		(end 238.376206 -45.85208)
		(stroke
			(width 0.2)
			(type default)
		)
		(layer "In8.Cu")
	)
	(gr_line
		(start 236.37621 -42.852086)
		(end 238.376206 -41.852088)
		(stroke
			(width 0.2)
			(type default)
		)
		(layer "In8.Cu")
	)
	(gr_line
		(start 236.37621 -38.852094)
		(end 238.376206 -37.852096)
		(stroke
			(width 0.2)
			(type default)
		)
		(layer "In8.Cu")
	)
	(gr_line
		(start 236.37621 -18.852134)
		(end 238.376206 -17.852136)
		(stroke
			(width 0.2)
			(type default)
		)
		(layer "In8.Cu")
	)
	(gr_line
		(start 236.377226 -163.154106)
		(end 238.377222 -162.154108)
		(stroke
			(width 0.2)
			(type default)
		)
		(layer "In8.Cu")
	)
	(gr_line
		(start 236.377226 -159.154114)
		(end 238.377222 -158.154116)
		(stroke
			(width 0.2)
			(type default)
		)
		(layer "In8.Cu")
	)
	(gr_line
		(start 236.377226 -155.154122)
		(end 238.377222 -154.154124)
		(stroke
			(width 0.2)
			(type default)
		)
		(layer "In8.Cu")
	)
	(gr_line
		(start 236.377226 -151.15413)
		(end 238.377222 -150.154132)
		(stroke
			(width 0.2)
			(type default)
		)
		(layer "In8.Cu")
	)
	(gr_line
		(start 236.377226 -131.15417)
		(end 238.377222 -130.154172)
		(stroke
			(width 0.2)
			(type default)
		)
		(layer "In8.Cu")
	)
	(gr_line
		(start 236.377226 -127.154178)
		(end 238.377222 -126.15418)
		(stroke
			(width 0.2)
			(type default)
		)
		(layer "In8.Cu")
	)
	(gr_line
		(start 236.377226 -123.154186)
		(end 238.3663 -122.159522)
		(stroke
			(width 0.2)
			(type default)
		)
		(layer "In8.Cu")
	)
	(gr_line
		(start 236.377226 -119.154194)
		(end 238.377222 -118.154196)
		(stroke
			(width 0.2)
			(type default)
		)
		(layer "In8.Cu")
	)
	(gr_line
		(start 236.377226 -115.154202)
		(end 238.377222 -114.154204)
		(stroke
			(width 0.2)
			(type default)
		)
		(layer "In8.Cu")
	)
	(gr_line
		(start 236.377226 -12.854432)
		(end 238.377222 -11.854434)
		(stroke
			(width 0.2)
			(type default)
		)
		(layer "In8.Cu")
	)
	(gr_line
		(start 237.722918 -160.8455)
		(end 235.733844 -161.840164)
		(stroke
			(width 0.2)
			(type default)
		)
		(layer "In8.Cu")
	)
	(gr_line
		(start 237.722918 -156.845508)
		(end 235.733844 -157.840172)
		(stroke
			(width 0.2)
			(type default)
		)
		(layer "In8.Cu")
	)
	(gr_line
		(start 237.722918 -152.845516)
		(end 235.733844 -153.84018)
		(stroke
			(width 0.2)
			(type default)
		)
		(layer "In8.Cu")
	)
	(gr_line
		(start 237.722918 -148.845524)
		(end 235.733844 -149.840188)
		(stroke
			(width 0.2)
			(type default)
		)
		(layer "In8.Cu")
	)
	(gr_line
		(start 237.722918 -128.845564)
		(end 235.733844 -129.840228)
		(stroke
			(width 0.2)
			(type default)
		)
		(layer "In8.Cu")
	)
	(gr_line
		(start 237.722918 -124.845572)
		(end 235.733844 -125.840236)
		(stroke
			(width 0.2)
			(type default)
		)
		(layer "In8.Cu")
	)
	(gr_line
		(start 237.722918 -120.84558)
		(end 235.722922 -121.845578)
		(stroke
			(width 0.2)
			(type default)
		)
		(layer "In8.Cu")
	)
	(gr_line
		(start 237.722918 -116.845588)
		(end 235.733844 -117.840252)
		(stroke
			(width 0.2)
			(type default)
		)
		(layer "In8.Cu")
	)
	(gr_line
		(start 237.722918 -112.845596)
		(end 235.733844 -113.84026)
		(stroke
			(width 0.2)
			(type default)
		)
		(layer "In8.Cu")
	)
	(gr_line
		(start 237.722918 -10.545826)
		(end 235.733844 -11.54049)
		(stroke
			(width 0.2)
			(type default)
		)
		(layer "In8.Cu")
	)
	(gr_line
		(start 237.723934 -176.847754)
		(end 235.724192 -177.847752)
		(stroke
			(width 0.2)
			(type default)
		)
		(layer "In8.Cu")
	)
	(gr_line
		(start 237.723934 -172.847762)
		(end 235.724192 -173.84776)
		(stroke
			(width 0.2)
			(type default)
		)
		(layer "In8.Cu")
	)
	(gr_line
		(start 237.723934 -168.84777)
		(end 235.724192 -169.847768)
		(stroke
			(width 0.2)
			(type default)
		)
		(layer "In8.Cu")
	)
	(gr_line
		(start 237.723934 -164.847778)
		(end 235.724192 -165.847776)
		(stroke
			(width 0.2)
			(type default)
		)
		(layer "In8.Cu")
	)
	(gr_line
		(start 237.723934 -136.847834)
		(end 235.724192 -137.847832)
		(stroke
			(width 0.2)
			(type default)
		)
		(layer "In8.Cu")
	)
	(gr_line
		(start 237.723934 -80.547972)
		(end 235.724192 -81.54797)
		(stroke
			(width 0.2)
			(type default)
		)
		(layer "In8.Cu")
	)
	(gr_line
		(start 237.723934 -76.54798)
		(end 235.724192 -77.547978)
		(stroke
			(width 0.2)
			(type default)
		)
		(layer "In8.Cu")
	)
	(gr_line
		(start 237.723934 -72.547988)
		(end 235.724192 -73.547986)
		(stroke
			(width 0.2)
			(type default)
		)
		(layer "In8.Cu")
	)
	(gr_line
		(start 237.723934 -68.547996)
		(end 235.724192 -69.547994)
		(stroke
			(width 0.2)
			(type default)
		)
		(layer "In8.Cu")
	)
	(gr_line
		(start 237.723934 -64.548004)
		(end 235.723938 -65.548002)
		(stroke
			(width 0.2)
			(type default)
		)
		(layer "In8.Cu")
	)
	(gr_line
		(start 237.723934 -60.548012)
		(end 235.724192 -61.54801)
		(stroke
			(width 0.2)
			(type default)
		)
		(layer "In8.Cu")
	)
	(gr_line
		(start 237.723934 -56.54802)
		(end 235.724192 -57.548018)
		(stroke
			(width 0.2)
			(type default)
		)
		(layer "In8.Cu")
	)
	(gr_line
		(start 237.723934 -52.548028)
		(end 235.724192 -53.548026)
		(stroke
			(width 0.2)
			(type default)
		)
		(layer "In8.Cu")
	)
	(gr_line
		(start 237.723934 -48.548036)
		(end 235.724192 -49.548034)
		(stroke
			(width 0.2)
			(type default)
		)
		(layer "In8.Cu")
	)
	(gr_line
		(start 237.723934 -44.548044)
		(end 235.724192 -45.548042)
		(stroke
			(width 0.2)
			(type default)
		)
		(layer "In8.Cu")
	)
	(gr_line
		(start 237.723934 -40.548052)
		(end 235.724192 -41.54805)
		(stroke
			(width 0.2)
			(type default)
		)
		(layer "In8.Cu")
	)
	(gr_line
		(start 237.723934 -36.54806)
		(end 235.724192 -37.548058)
		(stroke
			(width 0.2)
			(type default)
		)
		(layer "In8.Cu")
	)
	(gr_line
		(start 237.723934 -16.5481)
		(end 235.724192 -17.548098)
		(stroke
			(width 0.2)
			(type default)
		)
		(layer "In8.Cu")
	)
	(gr_line
		(start 237.725204 -176.85004)
		(end 237.723934 -176.847754)
		(stroke
			(width 0.2)
			(type default)
		)
		(layer "In8.Cu")
	)
	(gr_line
		(start 237.725204 -172.850048)
		(end 237.723934 -172.847762)
		(stroke
			(width 0.2)
			(type default)
		)
		(layer "In8.Cu")
	)
	(gr_line
		(start 237.725204 -168.850056)
		(end 237.723934 -168.84777)
		(stroke
			(width 0.2)
			(type default)
		)
		(layer "In8.Cu")
	)
	(gr_line
		(start 237.725204 -164.850064)
		(end 237.723934 -164.847778)
		(stroke
			(width 0.2)
			(type default)
		)
		(layer "In8.Cu")
	)
	(gr_line
		(start 237.725204 -136.85012)
		(end 237.723934 -136.847834)
		(stroke
			(width 0.2)
			(type default)
		)
		(layer "In8.Cu")
	)
	(gr_line
		(start 237.725204 -80.550258)
		(end 237.723934 -80.547972)
		(stroke
			(width 0.2)
			(type default)
		)
		(layer "In8.Cu")
	)
	(gr_line
		(start 237.725204 -76.550266)
		(end 237.723934 -76.54798)
		(stroke
			(width 0.2)
			(type default)
		)
		(layer "In8.Cu")
	)
	(gr_line
		(start 237.725204 -72.550274)
		(end 237.723934 -72.547988)
		(stroke
			(width 0.2)
			(type default)
		)
		(layer "In8.Cu")
	)
	(gr_line
		(start 237.725204 -68.550282)
		(end 237.723934 -68.547996)
		(stroke
			(width 0.2)
			(type default)
		)
		(layer "In8.Cu")
	)
	(gr_line
		(start 237.725204 -64.55029)
		(end 237.723934 -64.548004)
		(stroke
			(width 0.2)
			(type default)
		)
		(layer "In8.Cu")
	)
	(gr_line
		(start 237.725204 -60.550298)
		(end 237.723934 -60.548012)
		(stroke
			(width 0.2)
			(type default)
		)
		(layer "In8.Cu")
	)
	(gr_line
		(start 237.725204 -56.550306)
		(end 237.723934 -56.54802)
		(stroke
			(width 0.2)
			(type default)
		)
		(layer "In8.Cu")
	)
	(gr_line
		(start 237.725204 -52.550314)
		(end 237.723934 -52.548028)
		(stroke
			(width 0.2)
			(type default)
		)
		(layer "In8.Cu")
	)
	(gr_line
		(start 237.725204 -48.550322)
		(end 237.723934 -48.548036)
		(stroke
			(width 0.2)
			(type default)
		)
		(layer "In8.Cu")
	)
	(gr_line
		(start 237.725204 -44.55033)
		(end 237.723934 -44.548044)
		(stroke
			(width 0.2)
			(type default)
		)
		(layer "In8.Cu")
	)
	(gr_line
		(start 237.725204 -40.550338)
		(end 237.723934 -40.548052)
		(stroke
			(width 0.2)
			(type default)
		)
		(layer "In8.Cu")
	)
	(gr_line
		(start 237.725204 -36.550346)
		(end 237.723934 -36.54806)
		(stroke
			(width 0.2)
			(type default)
		)
		(layer "In8.Cu")
	)
	(gr_line
		(start 237.725204 -16.550386)
		(end 237.723934 -16.5481)
		(stroke
			(width 0.2)
			(type default)
		)
		(layer "In8.Cu")
	)
	(gr_arc
		(start 238.3663 -122.159522)
		(mid 238.706697 -121.178492)
		(end 237.722918 -120.84558)
		(stroke
			(width 0.2)
			(type default)
		)
		(layer "In8.Cu")
	)
	(gr_arc
		(start 238.374936 -178.149504)
		(mid 238.699802 -177.174906)
		(end 237.725204 -176.85004)
		(stroke
			(width 0.2)
			(type default)
		)
		(layer "In8.Cu")
	)
	(gr_arc
		(start 238.374936 -174.149512)
		(mid 238.699802 -173.174914)
		(end 237.725204 -172.850048)
		(stroke
			(width 0.2)
			(type default)
		)
		(layer "In8.Cu")
	)
	(gr_arc
		(start 238.374936 -170.14952)
		(mid 238.699802 -169.174922)
		(end 237.725204 -168.850056)
		(stroke
			(width 0.2)
			(type default)
		)
		(layer "In8.Cu")
	)
	(gr_arc
		(start 238.374936 -166.149528)
		(mid 238.699802 -165.17493)
		(end 237.725204 -164.850064)
		(stroke
			(width 0.2)
			(type default)
		)
		(layer "In8.Cu")
	)
	(gr_arc
		(start 238.374936 -138.149584)
		(mid 238.699802 -137.174986)
		(end 237.725204 -136.85012)
		(stroke
			(width 0.2)
			(type default)
		)
		(layer "In8.Cu")
	)
	(gr_arc
		(start 238.374936 -81.849722)
		(mid 238.699802 -80.875124)
		(end 237.725204 -80.550258)
		(stroke
			(width 0.2)
			(type default)
		)
		(layer "In8.Cu")
	)
	(gr_arc
		(start 238.374936 -77.84973)
		(mid 238.699802 -76.875132)
		(end 237.725204 -76.550266)
		(stroke
			(width 0.2)
			(type default)
		)
		(layer "In8.Cu")
	)
	(gr_arc
		(start 238.374936 -73.849738)
		(mid 238.699802 -72.87514)
		(end 237.725204 -72.550274)
		(stroke
			(width 0.2)
			(type default)
		)
		(layer "In8.Cu")
	)
	(gr_arc
		(start 238.374936 -69.849746)
		(mid 238.699802 -68.875148)
		(end 237.725204 -68.550282)
		(stroke
			(width 0.2)
			(type default)
		)
		(layer "In8.Cu")
	)
	(gr_arc
		(start 238.374936 -65.849754)
		(mid 238.699802 -64.875156)
		(end 237.725204 -64.55029)
		(stroke
			(width 0.2)
			(type default)
		)
		(layer "In8.Cu")
	)
	(gr_arc
		(start 238.374936 -61.849762)
		(mid 238.699802 -60.875164)
		(end 237.725204 -60.550298)
		(stroke
			(width 0.2)
			(type default)
		)
		(layer "In8.Cu")
	)
	(gr_arc
		(start 238.374936 -57.84977)
		(mid 238.699802 -56.875172)
		(end 237.725204 -56.550306)
		(stroke
			(width 0.2)
			(type default)
		)
		(layer "In8.Cu")
	)
	(gr_arc
		(start 238.374936 -53.849778)
		(mid 238.699802 -52.87518)
		(end 237.725204 -52.550314)
		(stroke
			(width 0.2)
			(type default)
		)
		(layer "In8.Cu")
	)
	(gr_arc
		(start 238.374936 -49.849786)
		(mid 238.699802 -48.875188)
		(end 237.725204 -48.550322)
		(stroke
			(width 0.2)
			(type default)
		)
		(layer "In8.Cu")
	)
	(gr_arc
		(start 238.374936 -45.849794)
		(mid 238.699802 -44.875196)
		(end 237.725204 -44.55033)
		(stroke
			(width 0.2)
			(type default)
		)
		(layer "In8.Cu")
	)
	(gr_arc
		(start 238.374936 -41.849802)
		(mid 238.699802 -40.875204)
		(end 237.725204 -40.550338)
		(stroke
			(width 0.2)
			(type default)
		)
		(layer "In8.Cu")
	)
	(gr_arc
		(start 238.374936 -37.84981)
		(mid 238.699802 -36.875212)
		(end 237.725204 -36.550346)
		(stroke
			(width 0.2)
			(type default)
		)
		(layer "In8.Cu")
	)
	(gr_arc
		(start 238.374936 -17.84985)
		(mid 238.699802 -16.875252)
		(end 237.725204 -16.550386)
		(stroke
			(width 0.2)
			(type default)
		)
		(layer "In8.Cu")
	)
	(gr_line
		(start 238.375952 -65.85204)
		(end 238.375952 -65.851786)
		(stroke
			(width 0.2)
			(type default)
		)
		(layer "In8.Cu")
	)
	(gr_line
		(start 238.375952 -65.851786)
		(end 238.374936 -65.849754)
		(stroke
			(width 0.2)
			(type default)
		)
		(layer "In8.Cu")
	)
	(gr_line
		(start 238.376206 -178.15179)
		(end 238.374936 -178.149504)
		(stroke
			(width 0.2)
			(type default)
		)
		(layer "In8.Cu")
	)
	(gr_line
		(start 238.376206 -174.151798)
		(end 238.374936 -174.149512)
		(stroke
			(width 0.2)
			(type default)
		)
		(layer "In8.Cu")
	)
	(gr_line
		(start 238.376206 -170.151806)
		(end 238.374936 -170.14952)
		(stroke
			(width 0.2)
			(type default)
		)
		(layer "In8.Cu")
	)
	(gr_line
		(start 238.376206 -166.151814)
		(end 238.374936 -166.149528)
		(stroke
			(width 0.2)
			(type default)
		)
		(layer "In8.Cu")
	)
	(gr_line
		(start 238.376206 -138.15187)
		(end 238.374936 -138.149584)
		(stroke
			(width 0.2)
			(type default)
		)
		(layer "In8.Cu")
	)
	(gr_line
		(start 238.376206 -81.852008)
		(end 238.374936 -81.849722)
		(stroke
			(width 0.2)
			(type default)
		)
		(layer "In8.Cu")
	)
	(gr_line
		(start 238.376206 -77.852016)
		(end 238.374936 -77.84973)
		(stroke
			(width 0.2)
			(type default)
		)
		(layer "In8.Cu")
	)
	(gr_line
		(start 238.376206 -73.852024)
		(end 238.374936 -73.849738)
		(stroke
			(width 0.2)
			(type default)
		)
		(layer "In8.Cu")
	)
	(gr_line
		(start 238.376206 -69.852032)
		(end 238.374936 -69.849746)
		(stroke
			(width 0.2)
			(type default)
		)
		(layer "In8.Cu")
	)
	(gr_line
		(start 238.376206 -61.852048)
		(end 238.374936 -61.849762)
		(stroke
			(width 0.2)
			(type default)
		)
		(layer "In8.Cu")
	)
	(gr_line
		(start 238.376206 -57.852056)
		(end 238.374936 -57.84977)
		(stroke
			(width 0.2)
			(type default)
		)
		(layer "In8.Cu")
	)
	(gr_line
		(start 238.376206 -53.852064)
		(end 238.374936 -53.849778)
		(stroke
			(width 0.2)
			(type default)
		)
		(layer "In8.Cu")
	)
	(gr_line
		(start 238.376206 -49.852072)
		(end 238.374936 -49.849786)
		(stroke
			(width 0.2)
			(type default)
		)
		(layer "In8.Cu")
	)
	(gr_line
		(start 238.376206 -45.85208)
		(end 238.374936 -45.849794)
		(stroke
			(width 0.2)
			(type default)
		)
		(layer "In8.Cu")
	)
	(gr_line
		(start 238.376206 -41.852088)
		(end 238.374936 -41.849802)
		(stroke
			(width 0.2)
			(type default)
		)
		(layer "In8.Cu")
	)
	(gr_line
		(start 238.376206 -37.852096)
		(end 238.374936 -37.84981)
		(stroke
			(width 0.2)
			(type default)
		)
		(layer "In8.Cu")
	)
	(gr_line
		(start 238.376206 -17.852136)
		(end 238.374936 -17.84985)
		(stroke
			(width 0.2)
			(type default)
		)
		(layer "In8.Cu")
	)
	(gr_arc
		(start 238.377222 -162.154108)
		(mid 238.704374 -161.172652)
		(end 237.722918 -160.8455)
		(stroke
			(width 0.2)
			(type default)
		)
		(layer "In8.Cu")
	)
	(gr_arc
		(start 238.377222 -158.154116)
		(mid 238.704374 -157.17266)
		(end 237.722918 -156.845508)
		(stroke
			(width 0.2)
			(type default)
		)
		(layer "In8.Cu")
	)
	(gr_arc
		(start 238.377222 -154.154124)
		(mid 238.704374 -153.172668)
		(end 237.722918 -152.845516)
		(stroke
			(width 0.2)
			(type default)
		)
		(layer "In8.Cu")
	)
	(gr_arc
		(start 238.377222 -150.154132)
		(mid 238.704374 -149.172676)
		(end 237.722918 -148.845524)
		(stroke
			(width 0.2)
			(type default)
		)
		(layer "In8.Cu")
	)
	(gr_arc
		(start 238.377222 -130.154172)
		(mid 238.704374 -129.172716)
		(end 237.722918 -128.845564)
		(stroke
			(width 0.2)
			(type default)
		)
		(layer "In8.Cu")
	)
	(gr_arc
		(start 238.377222 -126.15418)
		(mid 238.704374 -125.172724)
		(end 237.722918 -124.845572)
		(stroke
			(width 0.2)
			(type default)
		)
		(layer "In8.Cu")
	)
	(gr_arc
		(start 238.377222 -118.154196)
		(mid 238.704374 -117.17274)
		(end 237.722918 -116.845588)
		(stroke
			(width 0.2)
			(type default)
		)
		(layer "In8.Cu")
	)
	(gr_arc
		(start 238.377222 -114.154204)
		(mid 238.704374 -113.172748)
		(end 237.722918 -112.845596)
		(stroke
			(width 0.2)
			(type default)
		)
		(layer "In8.Cu")
	)
	(gr_arc
		(start 238.377222 -11.854434)
		(mid 238.704374 -10.872978)
		(end 237.722918 -10.545826)
		(stroke
			(width 0.2)
			(type default)
		)
		(layer "In8.Cu")
	)
	(gr_line
		(start 240.219484 -128.161034)
		(end 242.21948 -129.161032)
		(stroke
			(width 0.2)
			(type default)
		)
		(layer "In8.Cu")
	)
	(gr_line
		(start 240.219484 -124.161042)
		(end 242.20805 -125.155198)
		(stroke
			(width 0.2)
			(type default)
		)
		(layer "In8.Cu")
	)
	(gr_line
		(start 240.222786 -164.154104)
		(end 242.222782 -165.154102)
		(stroke
			(width 0.2)
			(type default)
		)
		(layer "In8.Cu")
	)
	(gr_line
		(start 240.222786 -160.154112)
		(end 242.222528 -161.15411)
		(stroke
			(width 0.2)
			(type default)
		)
		(layer "In8.Cu")
	)
	(gr_line
		(start 240.222786 -156.15412)
		(end 242.222528 -157.154118)
		(stroke
			(width 0.2)
			(type default)
		)
		(layer "In8.Cu")
	)
	(gr_line
		(start 240.222786 -152.154128)
		(end 242.222782 -153.154126)
		(stroke
			(width 0.2)
			(type default)
		)
		(layer "In8.Cu")
	)
	(gr_line
		(start 240.222786 -120.154192)
		(end 242.222528 -121.15419)
		(stroke
			(width 0.2)
			(type default)
		)
		(layer "In8.Cu")
	)
	(gr_line
		(start 240.222786 -116.1542)
		(end 242.222782 -117.154198)
		(stroke
			(width 0.2)
			(type default)
		)
		(layer "In8.Cu")
	)
	(gr_line
		(start 240.223802 -136.151874)
		(end 242.223798 -137.151872)
		(stroke
			(width 0.2)
			(type default)
		)
		(layer "In8.Cu")
	)
	(gr_line
		(start 240.223802 -108.15193)
		(end 242.223798 -109.151928)
		(stroke
			(width 0.2)
			(type default)
		)
		(layer "In8.Cu")
	)
	(gr_line
		(start 240.223802 -35.8521)
		(end 242.223798 -36.852098)
		(stroke
			(width 0.2)
			(type default)
		)
		(layer "In8.Cu")
	)
	(gr_line
		(start 240.225072 -136.149588)
		(end 240.223802 -136.151874)
		(stroke
			(width 0.2)
			(type default)
		)
		(layer "In8.Cu")
	)
	(gr_line
		(start 240.225072 -108.149644)
		(end 240.223802 -108.15193)
		(stroke
			(width 0.2)
			(type default)
		)
		(layer "In8.Cu")
	)
	(gr_line
		(start 240.236502 -180.126894)
		(end 242.236498 -181.126892)
		(stroke
			(width 0.2)
			(type default)
		)
		(layer "In8.Cu")
	)
	(gr_line
		(start 240.236502 -176.126902)
		(end 242.236498 -177.1269)
		(stroke
			(width 0.2)
			(type default)
		)
		(layer "In8.Cu")
	)
	(gr_line
		(start 240.236502 -172.12691)
		(end 242.236498 -173.126908)
		(stroke
			(width 0.2)
			(type default)
		)
		(layer "In8.Cu")
	)
	(gr_line
		(start 240.236502 -168.126918)
		(end 242.236498 -169.126916)
		(stroke
			(width 0.2)
			(type default)
		)
		(layer "In8.Cu")
	)
	(gr_line
		(start 240.236502 -83.827112)
		(end 242.236498 -84.82711)
		(stroke
			(width 0.2)
			(type default)
		)
		(layer "In8.Cu")
	)
	(gr_line
		(start 240.236502 -79.82712)
		(end 242.228116 -80.8228)
		(stroke
			(width 0.2)
			(type default)
		)
		(layer "In8.Cu")
	)
	(gr_line
		(start 240.236502 -75.827128)
		(end 242.228116 -76.822808)
		(stroke
			(width 0.2)
			(type default)
		)
		(layer "In8.Cu")
	)
	(gr_line
		(start 240.236502 -71.827136)
		(end 242.228116 -72.822816)
		(stroke
			(width 0.2)
			(type default)
		)
		(layer "In8.Cu")
	)
	(gr_line
		(start 240.236502 -67.827144)
		(end 242.236498 -68.827142)
		(stroke
			(width 0.2)
			(type default)
		)
		(layer "In8.Cu")
	)
	(gr_line
		(start 240.236502 -63.827152)
		(end 242.236498 -64.82715)
		(stroke
			(width 0.2)
			(type default)
		)
		(layer "In8.Cu")
	)
	(gr_line
		(start 240.236502 -59.82716)
		(end 242.236498 -60.827158)
		(stroke
			(width 0.2)
			(type default)
		)
		(layer "In8.Cu")
	)
	(gr_line
		(start 240.236502 -55.827168)
		(end 242.236498 -56.827166)
		(stroke
			(width 0.2)
			(type default)
		)
		(layer "In8.Cu")
	)
	(gr_line
		(start 240.236502 -51.827176)
		(end 242.228116 -52.822856)
		(stroke
			(width 0.2)
			(type default)
		)
		(layer "In8.Cu")
	)
	(gr_line
		(start 240.236502 -47.827184)
		(end 242.236498 -48.827182)
		(stroke
			(width 0.2)
			(type default)
		)
		(layer "In8.Cu")
	)
	(gr_line
		(start 240.236502 -43.827192)
		(end 242.236498 -44.82719)
		(stroke
			(width 0.2)
			(type default)
		)
		(layer "In8.Cu")
	)
	(gr_line
		(start 240.236502 -39.8272)
		(end 242.236498 -40.827198)
		(stroke
			(width 0.2)
			(type default)
		)
		(layer "In8.Cu")
	)
	(gr_arc
		(start 240.863374 -78.572868)
		(mid 239.922812 -78.886558)
		(end 240.236502 -79.82712)
		(stroke
			(width 0.2)
			(type default)
		)
		(layer "In8.Cu")
	)
	(gr_arc
		(start 240.863374 -74.572876)
		(mid 239.922812 -74.886566)
		(end 240.236502 -75.827128)
		(stroke
			(width 0.2)
			(type default)
		)
		(layer "In8.Cu")
	)
	(gr_arc
		(start 240.863374 -70.572884)
		(mid 239.922812 -70.886574)
		(end 240.236502 -71.827136)
		(stroke
			(width 0.2)
			(type default)
		)
		(layer "In8.Cu")
	)
	(gr_arc
		(start 240.863374 -50.572924)
		(mid 239.922812 -50.886614)
		(end 240.236502 -51.827176)
		(stroke
			(width 0.2)
			(type default)
		)
		(layer "In8.Cu")
	)
	(gr_arc
		(start 240.871756 -178.87696)
		(mid 239.92498 -179.182145)
		(end 240.236502 -180.126894)
		(stroke
			(width 0.2)
			(type default)
		)
		(layer "In8.Cu")
	)
	(gr_arc
		(start 240.871756 -174.876968)
		(mid 239.92498 -175.182153)
		(end 240.236502 -176.126902)
		(stroke
			(width 0.2)
			(type default)
		)
		(layer "In8.Cu")
	)
	(gr_arc
		(start 240.871756 -170.876976)
		(mid 239.92498 -171.182161)
		(end 240.236502 -172.12691)
		(stroke
			(width 0.2)
			(type default)
		)
		(layer "In8.Cu")
	)
	(gr_arc
		(start 240.871756 -166.876984)
		(mid 239.92498 -167.182169)
		(end 240.236502 -168.126918)
		(stroke
			(width 0.2)
			(type default)
		)
		(layer "In8.Cu")
	)
	(gr_arc
		(start 240.871756 -82.577178)
		(mid 239.92498 -82.882363)
		(end 240.236502 -83.827112)
		(stroke
			(width 0.2)
			(type default)
		)
		(layer "In8.Cu")
	)
	(gr_arc
		(start 240.871756 -66.57721)
		(mid 239.92498 -66.882395)
		(end 240.236502 -67.827144)
		(stroke
			(width 0.2)
			(type default)
		)
		(layer "In8.Cu")
	)
	(gr_arc
		(start 240.871756 -62.577218)
		(mid 239.92498 -62.882403)
		(end 240.236502 -63.827152)
		(stroke
			(width 0.2)
			(type default)
		)
		(layer "In8.Cu")
	)
	(gr_arc
		(start 240.871756 -58.577226)
		(mid 239.92498 -58.882411)
		(end 240.236502 -59.82716)
		(stroke
			(width 0.2)
			(type default)
		)
		(layer "In8.Cu")
	)
	(gr_arc
		(start 240.871756 -54.577234)
		(mid 239.92498 -54.882419)
		(end 240.236502 -55.827168)
		(stroke
			(width 0.2)
			(type default)
		)
		(layer "In8.Cu")
	)
	(gr_arc
		(start 240.871756 -46.57725)
		(mid 239.92498 -46.882435)
		(end 240.236502 -47.827184)
		(stroke
			(width 0.2)
			(type default)
		)
		(layer "In8.Cu")
	)
	(gr_arc
		(start 240.871756 -42.577258)
		(mid 239.92498 -42.882443)
		(end 240.236502 -43.827192)
		(stroke
			(width 0.2)
			(type default)
		)
		(layer "In8.Cu")
	)
	(gr_arc
		(start 240.871756 -38.577266)
		(mid 239.92498 -38.882451)
		(end 240.236502 -39.8272)
		(stroke
			(width 0.2)
			(type default)
		)
		(layer "In8.Cu")
	)
	(gr_arc
		(start 240.874804 -134.850124)
		(mid 239.900206 -135.17499)
		(end 240.225072 -136.149588)
		(stroke
			(width 0.2)
			(type default)
		)
		(layer "In8.Cu")
	)
	(gr_arc
		(start 240.874804 -106.85018)
		(mid 239.900206 -107.175046)
		(end 240.225072 -108.149644)
		(stroke
			(width 0.2)
			(type default)
		)
		(layer "In8.Cu")
	)
	(gr_line
		(start 240.876074 -134.847838)
		(end 240.874804 -134.850124)
		(stroke
			(width 0.2)
			(type default)
		)
		(layer "In8.Cu")
	)
	(gr_line
		(start 240.876074 -106.847894)
		(end 240.874804 -106.85018)
		(stroke
			(width 0.2)
			(type default)
		)
		(layer "In8.Cu")
	)
	(gr_arc
		(start 240.876074 -34.548064)
		(mid 239.89792 -34.873946)
		(end 240.223802 -35.8521)
		(stroke
			(width 0.2)
			(type default)
		)
		(layer "In8.Cu")
	)
	(gr_arc
		(start 240.87709 -158.845504)
		(mid 239.895634 -159.172656)
		(end 240.222786 -160.154112)
		(stroke
			(width 0.2)
			(type default)
		)
		(layer "In8.Cu")
	)
	(gr_arc
		(start 240.87709 -154.845512)
		(mid 239.895634 -155.172664)
		(end 240.222786 -156.15412)
		(stroke
			(width 0.2)
			(type default)
		)
		(layer "In8.Cu")
	)
	(gr_arc
		(start 240.87709 -118.845584)
		(mid 239.895634 -119.172736)
		(end 240.222786 -120.154192)
		(stroke
			(width 0.2)
			(type default)
		)
		(layer "In8.Cu")
	)
	(gr_arc
		(start 240.877344 -162.845496)
		(mid 239.895939 -163.172546)
		(end 240.222786 -164.154104)
		(stroke
			(width 0.2)
			(type default)
		)
		(layer "In8.Cu")
	)
	(gr_arc
		(start 240.877344 -150.84552)
		(mid 239.895939 -151.17257)
		(end 240.222786 -152.154128)
		(stroke
			(width 0.2)
			(type default)
		)
		(layer "In8.Cu")
	)
	(gr_arc
		(start 240.877344 -114.845592)
		(mid 239.895939 -115.172642)
		(end 240.222786 -116.1542)
		(stroke
			(width 0.2)
			(type default)
		)
		(layer "In8.Cu")
	)
	(gr_arc
		(start 240.880392 -122.838718)
		(mid 239.888776 -123.169426)
		(end 240.219484 -124.161042)
		(stroke
			(width 0.2)
			(type default)
		)
		(layer "In8.Cu")
	)
	(gr_arc
		(start 240.891822 -126.844552)
		(mid 239.891674 -127.163691)
		(end 240.219484 -128.161034)
		(stroke
			(width 0.2)
			(type default)
		)
		(layer "In8.Cu")
	)
	(gr_arc
		(start 242.20805 -125.155198)
		(mid 243.208198 -124.836059)
		(end 242.880388 -123.838716)
		(stroke
			(width 0.2)
			(type default)
		)
		(layer "In8.Cu")
	)
	(gr_arc
		(start 242.21948 -129.161032)
		(mid 243.211096 -128.830324)
		(end 242.880388 -127.838708)
		(stroke
			(width 0.2)
			(type default)
		)
		(layer "In8.Cu")
	)
	(gr_arc
		(start 242.222528 -161.15411)
		(mid 243.204289 -160.82711)
		(end 242.877086 -159.845502)
		(stroke
			(width 0.2)
			(type default)
		)
		(layer "In8.Cu")
	)
	(gr_arc
		(start 242.222528 -157.154118)
		(mid 243.204289 -156.827118)
		(end 242.877086 -155.84551)
		(stroke
			(width 0.2)
			(type default)
		)
		(layer "In8.Cu")
	)
	(gr_arc
		(start 242.222528 -121.15419)
		(mid 243.204289 -120.82719)
		(end 242.877086 -119.845582)
		(stroke
			(width 0.2)
			(type default)
		)
		(layer "In8.Cu")
	)
	(gr_arc
		(start 242.222782 -165.154102)
		(mid 243.204238 -164.82695)
		(end 242.877086 -163.845494)
		(stroke
			(width 0.2)
			(type default)
		)
		(layer "In8.Cu")
	)
	(gr_arc
		(start 242.222782 -153.154126)
		(mid 243.204238 -152.826974)
		(end 242.877086 -151.845518)
		(stroke
			(width 0.2)
			(type default)
		)
		(layer "In8.Cu")
	)
	(gr_arc
		(start 242.222782 -117.154198)
		(mid 243.204238 -116.827046)
		(end 242.877086 -115.84559)
		(stroke
			(width 0.2)
			(type default)
		)
		(layer "In8.Cu")
	)
	(gr_line
		(start 242.223798 -137.151872)
		(end 242.224052 -137.151618)
		(stroke
			(width 0.2)
			(type default)
		)
		(layer "In8.Cu")
	)
	(gr_line
		(start 242.223798 -109.151928)
		(end 242.224052 -109.151674)
		(stroke
			(width 0.2)
			(type default)
		)
		(layer "In8.Cu")
	)
	(gr_arc
		(start 242.223798 -36.852098)
		(mid 243.201952 -36.526216)
		(end 242.87607 -35.548062)
		(stroke
			(width 0.2)
			(type default)
		)
		(layer "In8.Cu")
	)
	(gr_line
		(start 242.224052 -137.151618)
		(end 242.225068 -137.149586)
		(stroke
			(width 0.2)
			(type default)
		)
		(layer "In8.Cu")
	)
	(gr_line
		(start 242.224052 -109.151674)
		(end 242.225068 -109.149642)
		(stroke
			(width 0.2)
			(type default)
		)
		(layer "In8.Cu")
	)
	(gr_arc
		(start 242.225068 -137.149586)
		(mid 243.199666 -136.82472)
		(end 242.8748 -135.850122)
		(stroke
			(width 0.2)
			(type default)
		)
		(layer "In8.Cu")
	)
	(gr_arc
		(start 242.225068 -109.149642)
		(mid 243.199666 -108.824776)
		(end 242.8748 -107.850178)
		(stroke
			(width 0.2)
			(type default)
		)
		(layer "In8.Cu")
	)
	(gr_arc
		(start 242.228116 -80.8228)
		(mid 243.174892 -80.517615)
		(end 242.86337 -79.572866)
		(stroke
			(width 0.2)
			(type default)
		)
		(layer "In8.Cu")
	)
	(gr_arc
		(start 242.228116 -76.822808)
		(mid 243.174892 -76.517623)
		(end 242.86337 -75.572874)
		(stroke
			(width 0.2)
			(type default)
		)
		(layer "In8.Cu")
	)
	(gr_arc
		(start 242.228116 -72.822816)
		(mid 243.174892 -72.517631)
		(end 242.86337 -71.572882)
		(stroke
			(width 0.2)
			(type default)
		)
		(layer "In8.Cu")
	)
	(gr_arc
		(start 242.228116 -52.822856)
		(mid 243.174892 -52.517671)
		(end 242.86337 -51.572922)
		(stroke
			(width 0.2)
			(type default)
		)
		(layer "In8.Cu")
	)
	(gr_arc
		(start 242.236498 -181.126892)
		(mid 243.17706 -180.813202)
		(end 242.86337 -179.87264)
		(stroke
			(width 0.2)
			(type default)
		)
		(layer "In8.Cu")
	)
	(gr_arc
		(start 242.236498 -177.1269)
		(mid 243.17706 -176.81321)
		(end 242.86337 -175.872648)
		(stroke
			(width 0.2)
			(type default)
		)
		(layer "In8.Cu")
	)
	(gr_arc
		(start 242.236498 -173.126908)
		(mid 243.17706 -172.813218)
		(end 242.86337 -171.872656)
		(stroke
			(width 0.2)
			(type default)
		)
		(layer "In8.Cu")
	)
	(gr_arc
		(start 242.236498 -169.126916)
		(mid 243.17706 -168.813226)
		(end 242.86337 -167.872664)
		(stroke
			(width 0.2)
			(type default)
		)
		(layer "In8.Cu")
	)
	(gr_arc
		(start 242.236498 -84.82711)
		(mid 243.17706 -84.51342)
		(end 242.86337 -83.572858)
		(stroke
			(width 0.2)
			(type default)
		)
		(layer "In8.Cu")
	)
	(gr_arc
		(start 242.236498 -68.827142)
		(mid 243.17706 -68.513452)
		(end 242.86337 -67.57289)
		(stroke
			(width 0.2)
			(type default)
		)
		(layer "In8.Cu")
	)
	(gr_arc
		(start 242.236498 -64.82715)
		(mid 243.17706 -64.51346)
		(end 242.86337 -63.572898)
		(stroke
			(width 0.2)
			(type default)
		)
		(layer "In8.Cu")
	)
	(gr_arc
		(start 242.236498 -60.827158)
		(mid 243.17706 -60.513468)
		(end 242.86337 -59.572906)
		(stroke
			(width 0.2)
			(type default)
		)
		(layer "In8.Cu")
	)
	(gr_arc
		(start 242.236498 -56.827166)
		(mid 243.17706 -56.513476)
		(end 242.86337 -55.572914)
		(stroke
			(width 0.2)
			(type default)
		)
		(layer "In8.Cu")
	)
	(gr_arc
		(start 242.236498 -48.827182)
		(mid 243.17706 -48.513492)
		(end 242.86337 -47.57293)
		(stroke
			(width 0.2)
			(type default)
		)
		(layer "In8.Cu")
	)
	(gr_arc
		(start 242.236498 -44.82719)
		(mid 243.17706 -44.5135)
		(end 242.86337 -43.572938)
		(stroke
			(width 0.2)
			(type default)
		)
		(layer "In8.Cu")
	)
	(gr_arc
		(start 242.236498 -40.827198)
		(mid 243.17706 -40.513508)
		(end 242.86337 -39.572946)
		(stroke
			(width 0.2)
			(type default)
		)
		(layer "In8.Cu")
	)
	(gr_line
		(start 242.86337 -179.87264)
		(end 240.871756 -178.87696)
		(stroke
			(width 0.2)
			(type default)
		)
		(layer "In8.Cu")
	)
	(gr_line
		(start 242.86337 -175.872648)
		(end 240.871756 -174.876968)
		(stroke
			(width 0.2)
			(type default)
		)
		(layer "In8.Cu")
	)
	(gr_line
		(start 242.86337 -171.872656)
		(end 240.871756 -170.876976)
		(stroke
			(width 0.2)
			(type default)
		)
		(layer "In8.Cu")
	)
	(gr_line
		(start 242.86337 -167.872664)
		(end 240.871756 -166.876984)
		(stroke
			(width 0.2)
			(type default)
		)
		(layer "In8.Cu")
	)
	(gr_line
		(start 242.86337 -83.572858)
		(end 240.871756 -82.577178)
		(stroke
			(width 0.2)
			(type default)
		)
		(layer "In8.Cu")
	)
	(gr_line
		(start 242.86337 -79.572866)
		(end 240.863374 -78.572868)
		(stroke
			(width 0.2)
			(type default)
		)
		(layer "In8.Cu")
	)
	(gr_line
		(start 242.86337 -75.572874)
		(end 240.863374 -74.572876)
		(stroke
			(width 0.2)
			(type default)
		)
		(layer "In8.Cu")
	)
	(gr_line
		(start 242.86337 -71.572882)
		(end 240.863374 -70.572884)
		(stroke
			(width 0.2)
			(type default)
		)
		(layer "In8.Cu")
	)
	(gr_line
		(start 242.86337 -67.57289)
		(end 240.871756 -66.57721)
		(stroke
			(width 0.2)
			(type default)
		)
		(layer "In8.Cu")
	)
	(gr_line
		(start 242.86337 -63.572898)
		(end 240.871756 -62.577218)
		(stroke
			(width 0.2)
			(type default)
		)
		(layer "In8.Cu")
	)
	(gr_line
		(start 242.86337 -59.572906)
		(end 240.871756 -58.577226)
		(stroke
			(width 0.2)
			(type default)
		)
		(layer "In8.Cu")
	)
	(gr_line
		(start 242.86337 -55.572914)
		(end 240.871756 -54.577234)
		(stroke
			(width 0.2)
			(type default)
		)
		(layer "In8.Cu")
	)
	(gr_line
		(start 242.86337 -51.572922)
		(end 240.863374 -50.572924)
		(stroke
			(width 0.2)
			(type default)
		)
		(layer "In8.Cu")
	)
	(gr_line
		(start 242.86337 -47.57293)
		(end 240.871756 -46.57725)
		(stroke
			(width 0.2)
			(type default)
		)
		(layer "In8.Cu")
	)
	(gr_line
		(start 242.86337 -43.572938)
		(end 240.871756 -42.577258)
		(stroke
			(width 0.2)
			(type default)
		)
		(layer "In8.Cu")
	)
	(gr_line
		(start 242.86337 -39.572946)
		(end 240.871756 -38.577266)
		(stroke
			(width 0.2)
			(type default)
		)
		(layer "In8.Cu")
	)
	(gr_line
		(start 242.8748 -135.850122)
		(end 242.87607 -135.847836)
		(stroke
			(width 0.2)
			(type default)
		)
		(layer "In8.Cu")
	)
	(gr_line
		(start 242.8748 -107.850178)
		(end 242.87607 -107.847892)
		(stroke
			(width 0.2)
			(type default)
		)
		(layer "In8.Cu")
	)
	(gr_line
		(start 242.87607 -135.847836)
		(end 240.876074 -134.847838)
		(stroke
			(width 0.2)
			(type default)
		)
		(layer "In8.Cu")
	)
	(gr_line
		(start 242.87607 -107.847892)
		(end 240.876074 -106.847894)
		(stroke
			(width 0.2)
			(type default)
		)
		(layer "In8.Cu")
	)
	(gr_line
		(start 242.87607 -35.548062)
		(end 240.876074 -34.548064)
		(stroke
			(width 0.2)
			(type default)
		)
		(layer "In8.Cu")
	)
	(gr_line
		(start 242.877086 -163.845494)
		(end 240.877344 -162.845496)
		(stroke
			(width 0.2)
			(type default)
		)
		(layer "In8.Cu")
	)
	(gr_line
		(start 242.877086 -159.845502)
		(end 240.87709 -158.845504)
		(stroke
			(width 0.2)
			(type default)
		)
		(layer "In8.Cu")
	)
	(gr_line
		(start 242.877086 -155.84551)
		(end 240.87709 -154.845512)
		(stroke
			(width 0.2)
			(type default)
		)
		(layer "In8.Cu")
	)
	(gr_line
		(start 242.877086 -151.845518)
		(end 240.877344 -150.84552)
		(stroke
			(width 0.2)
			(type default)
		)
		(layer "In8.Cu")
	)
	(gr_line
		(start 242.877086 -119.845582)
		(end 240.87709 -118.845584)
		(stroke
			(width 0.2)
			(type default)
		)
		(layer "In8.Cu")
	)
	(gr_line
		(start 242.877086 -115.84559)
		(end 240.877344 -114.845592)
		(stroke
			(width 0.2)
			(type default)
		)
		(layer "In8.Cu")
	)
	(gr_line
		(start 242.880388 -127.838708)
		(end 240.891822 -126.844552)
		(stroke
			(width 0.2)
			(type default)
		)
		(layer "In8.Cu")
	)
	(gr_line
		(start 242.880388 -123.838716)
		(end 240.880392 -122.838718)
		(stroke
			(width 0.2)
			(type default)
		)
		(layer "In8.Cu")
	)
	(gr_line
		(start 271.9705 -359.885996)
		(end 273.1135 -359.885996)
		(stroke
			(width 0.2)
			(type default)
		)
		(layer "In8.Cu")
	)
	(gr_line
		(start 271.9705 -358.085898)
		(end 273.1135 -358.085898)
		(stroke
			(width 0.2)
			(type default)
		)
		(layer "In8.Cu")
	)
	(gr_line
		(start 271.9705 -356.286054)
		(end 273.1135 -356.286054)
		(stroke
			(width 0.2)
			(type default)
		)
		(layer "In8.Cu")
	)
	(gr_line
		(start 271.9705 -354.485956)
		(end 273.1135 -354.485956)
		(stroke
			(width 0.2)
			(type default)
		)
		(layer "In8.Cu")
	)
	(gr_line
		(start 271.9705 -352.686112)
		(end 273.1135 -352.686112)
		(stroke
			(width 0.2)
			(type default)
		)
		(layer "In8.Cu")
	)
	(gr_line
		(start 271.9705 -350.886014)
		(end 273.1135 -350.886014)
		(stroke
			(width 0.2)
			(type default)
		)
		(layer "In8.Cu")
	)
	(gr_line
		(start 271.9705 -338.28863)
		(end 273.1135 -338.28863)
		(stroke
			(width 0.2)
			(type default)
		)
		(layer "In8.Cu")
	)
	(gr_line
		(start 271.9705 -336.488532)
		(end 273.1135 -336.488532)
		(stroke
			(width 0.2)
			(type default)
		)
		(layer "In8.Cu")
	)
	(gr_line
		(start 271.9705 -334.688434)
		(end 273.1135 -334.688434)
		(stroke
			(width 0.2)
			(type default)
		)
		(layer "In8.Cu")
	)
	(gr_line
		(start 271.9705 -332.88859)
		(end 273.1135 -332.88859)
		(stroke
			(width 0.2)
			(type default)
		)
		(layer "In8.Cu")
	)
	(gr_line
		(start 271.9705 -331.088492)
		(end 273.1135 -331.088492)
		(stroke
			(width 0.2)
			(type default)
		)
		(layer "In8.Cu")
	)
	(gr_line
		(start 271.9705 -329.288648)
		(end 273.1135 -329.288648)
		(stroke
			(width 0.2)
			(type default)
		)
		(layer "In8.Cu")
	)
	(gr_line
		(start 271.9705 -316.68847)
		(end 273.1135 -316.68847)
		(stroke
			(width 0.2)
			(type default)
		)
		(layer "In8.Cu")
	)
	(gr_line
		(start 271.9705 -314.888626)
		(end 273.1135 -314.888626)
		(stroke
			(width 0.2)
			(type default)
		)
		(layer "In8.Cu")
	)
	(gr_line
		(start 271.9705 -313.088528)
		(end 273.1135 -313.088528)
		(stroke
			(width 0.2)
			(type default)
		)
		(layer "In8.Cu")
	)
	(gr_line
		(start 271.9705 -311.28843)
		(end 273.1135 -311.28843)
		(stroke
			(width 0.2)
			(type default)
		)
		(layer "In8.Cu")
	)
	(gr_line
		(start 271.9705 -309.488586)
		(end 273.1135 -309.488586)
		(stroke
			(width 0.2)
			(type default)
		)
		(layer "In8.Cu")
	)
	(gr_line
		(start 271.9705 -307.688488)
		(end 273.1135 -307.688488)
		(stroke
			(width 0.2)
			(type default)
		)
		(layer "In8.Cu")
	)
	(gr_arc
		(start 271.970754 -359.123996)
		(mid 271.5895 -359.504869)
		(end 271.9705 -359.885996)
		(stroke
			(width 0.2)
			(type default)
		)
		(layer "In8.Cu")
	)
	(gr_arc
		(start 271.970754 -357.323898)
		(mid 271.5895 -357.704771)
		(end 271.9705 -358.085898)
		(stroke
			(width 0.2)
			(type default)
		)
		(layer "In8.Cu")
	)
	(gr_arc
		(start 271.970754 -355.524054)
		(mid 271.5895 -355.904927)
		(end 271.9705 -356.286054)
		(stroke
			(width 0.2)
			(type default)
		)
		(layer "In8.Cu")
	)
	(gr_arc
		(start 271.970754 -353.723956)
		(mid 271.5895 -354.104829)
		(end 271.9705 -354.485956)
		(stroke
			(width 0.2)
			(type default)
		)
		(layer "In8.Cu")
	)
	(gr_arc
		(start 271.970754 -351.924112)
		(mid 271.5895 -352.304985)
		(end 271.9705 -352.686112)
		(stroke
			(width 0.2)
			(type default)
		)
		(layer "In8.Cu")
	)
	(gr_arc
		(start 271.970754 -350.124014)
		(mid 271.5895 -350.504887)
		(end 271.9705 -350.886014)
		(stroke
			(width 0.2)
			(type default)
		)
		(layer "In8.Cu")
	)
	(gr_arc
		(start 271.970754 -337.52155)
		(mid 271.58696 -337.904963)
		(end 271.9705 -338.28863)
		(stroke
			(width 0.2)
			(type default)
		)
		(layer "In8.Cu")
	)
	(gr_arc
		(start 271.970754 -335.721452)
		(mid 271.58696 -336.104865)
		(end 271.9705 -336.488532)
		(stroke
			(width 0.2)
			(type default)
		)
		(layer "In8.Cu")
	)
	(gr_arc
		(start 271.970754 -333.921354)
		(mid 271.58696 -334.304767)
		(end 271.9705 -334.688434)
		(stroke
			(width 0.2)
			(type default)
		)
		(layer "In8.Cu")
	)
	(gr_arc
		(start 271.970754 -332.12151)
		(mid 271.58696 -332.504923)
		(end 271.9705 -332.88859)
		(stroke
			(width 0.2)
			(type default)
		)
		(layer "In8.Cu")
	)
	(gr_arc
		(start 271.970754 -330.321412)
		(mid 271.58696 -330.704825)
		(end 271.9705 -331.088492)
		(stroke
			(width 0.2)
			(type default)
		)
		(layer "In8.Cu")
	)
	(gr_arc
		(start 271.970754 -328.521568)
		(mid 271.58696 -328.904981)
		(end 271.9705 -329.288648)
		(stroke
			(width 0.2)
			(type default)
		)
		(layer "In8.Cu")
	)
	(gr_arc
		(start 271.970754 -315.92139)
		(mid 271.58696 -316.304803)
		(end 271.9705 -316.68847)
		(stroke
			(width 0.2)
			(type default)
		)
		(layer "In8.Cu")
	)
	(gr_arc
		(start 271.970754 -314.121546)
		(mid 271.58696 -314.504959)
		(end 271.9705 -314.888626)
		(stroke
			(width 0.2)
			(type default)
		)
		(layer "In8.Cu")
	)
	(gr_arc
		(start 271.970754 -312.321448)
		(mid 271.58696 -312.704861)
		(end 271.9705 -313.088528)
		(stroke
			(width 0.2)
			(type default)
		)
		(layer "In8.Cu")
	)
	(gr_arc
		(start 271.970754 -310.52135)
		(mid 271.58696 -310.904763)
		(end 271.9705 -311.28843)
		(stroke
			(width 0.2)
			(type default)
		)
		(layer "In8.Cu")
	)
	(gr_arc
		(start 271.970754 -308.721506)
		(mid 271.58696 -309.104919)
		(end 271.9705 -309.488586)
		(stroke
			(width 0.2)
			(type default)
		)
		(layer "In8.Cu")
	)
	(gr_arc
		(start 271.970754 -306.921408)
		(mid 271.58696 -307.304821)
		(end 271.9705 -307.688488)
		(stroke
			(width 0.2)
			(type default)
		)
		(layer "In8.Cu")
	)
	(gr_arc
		(start 273.1135 -359.885996)
		(mid 273.4945 -359.504996)
		(end 273.1135 -359.123996)
		(stroke
			(width 0.2)
			(type default)
		)
		(layer "In8.Cu")
	)
	(gr_line
		(start 273.1135 -359.123996)
		(end 271.970754 -359.123996)
		(stroke
			(width 0.2)
			(type default)
		)
		(layer "In8.Cu")
	)
	(gr_arc
		(start 273.1135 -358.085898)
		(mid 273.4945 -357.704898)
		(end 273.1135 -357.323898)
		(stroke
			(width 0.2)
			(type default)
		)
		(layer "In8.Cu")
	)
	(gr_line
		(start 273.1135 -357.323898)
		(end 271.970754 -357.323898)
		(stroke
			(width 0.2)
			(type default)
		)
		(layer "In8.Cu")
	)
	(gr_arc
		(start 273.1135 -356.286054)
		(mid 273.4945 -355.905054)
		(end 273.1135 -355.524054)
		(stroke
			(width 0.2)
			(type default)
		)
		(layer "In8.Cu")
	)
	(gr_line
		(start 273.1135 -355.524054)
		(end 271.970754 -355.524054)
		(stroke
			(width 0.2)
			(type default)
		)
		(layer "In8.Cu")
	)
	(gr_arc
		(start 273.1135 -354.485956)
		(mid 273.4945 -354.104956)
		(end 273.1135 -353.723956)
		(stroke
			(width 0.2)
			(type default)
		)
		(layer "In8.Cu")
	)
	(gr_line
		(start 273.1135 -353.723956)
		(end 271.970754 -353.723956)
		(stroke
			(width 0.2)
			(type default)
		)
		(layer "In8.Cu")
	)
	(gr_arc
		(start 273.1135 -352.686112)
		(mid 273.4945 -352.305112)
		(end 273.1135 -351.924112)
		(stroke
			(width 0.2)
			(type default)
		)
		(layer "In8.Cu")
	)
	(gr_line
		(start 273.1135 -351.924112)
		(end 271.970754 -351.924112)
		(stroke
			(width 0.2)
			(type default)
		)
		(layer "In8.Cu")
	)
	(gr_arc
		(start 273.1135 -350.886014)
		(mid 273.4945 -350.505014)
		(end 273.1135 -350.124014)
		(stroke
			(width 0.2)
			(type default)
		)
		(layer "In8.Cu")
	)
	(gr_line
		(start 273.1135 -350.124014)
		(end 271.970754 -350.124014)
		(stroke
			(width 0.2)
			(type default)
		)
		(layer "In8.Cu")
	)
	(gr_arc
		(start 273.1135 -338.28863)
		(mid 273.49704 -337.90509)
		(end 273.1135 -337.52155)
		(stroke
			(width 0.2)
			(type default)
		)
		(layer "In8.Cu")
	)
	(gr_line
		(start 273.1135 -337.52155)
		(end 271.970754 -337.52155)
		(stroke
			(width 0.2)
			(type default)
		)
		(layer "In8.Cu")
	)
	(gr_arc
		(start 273.1135 -336.488532)
		(mid 273.49704 -336.104992)
		(end 273.1135 -335.721452)
		(stroke
			(width 0.2)
			(type default)
		)
		(layer "In8.Cu")
	)
	(gr_line
		(start 273.1135 -335.721452)
		(end 271.970754 -335.721452)
		(stroke
			(width 0.2)
			(type default)
		)
		(layer "In8.Cu")
	)
	(gr_arc
		(start 273.1135 -334.688434)
		(mid 273.49704 -334.304894)
		(end 273.1135 -333.921354)
		(stroke
			(width 0.2)
			(type default)
		)
		(layer "In8.Cu")
	)
	(gr_line
		(start 273.1135 -333.921354)
		(end 271.970754 -333.921354)
		(stroke
			(width 0.2)
			(type default)
		)
		(layer "In8.Cu")
	)
	(gr_arc
		(start 273.1135 -332.88859)
		(mid 273.49704 -332.50505)
		(end 273.1135 -332.12151)
		(stroke
			(width 0.2)
			(type default)
		)
		(layer "In8.Cu")
	)
	(gr_line
		(start 273.1135 -332.12151)
		(end 271.970754 -332.12151)
		(stroke
			(width 0.2)
			(type default)
		)
		(layer "In8.Cu")
	)
	(gr_arc
		(start 273.1135 -331.088492)
		(mid 273.49704 -330.704952)
		(end 273.1135 -330.321412)
		(stroke
			(width 0.2)
			(type default)
		)
		(layer "In8.Cu")
	)
	(gr_line
		(start 273.1135 -330.321412)
		(end 271.970754 -330.321412)
		(stroke
			(width 0.2)
			(type default)
		)
		(layer "In8.Cu")
	)
	(gr_arc
		(start 273.1135 -329.288648)
		(mid 273.49704 -328.905108)
		(end 273.1135 -328.521568)
		(stroke
			(width 0.2)
			(type default)
		)
		(layer "In8.Cu")
	)
	(gr_line
		(start 273.1135 -328.521568)
		(end 271.970754 -328.521568)
		(stroke
			(width 0.2)
			(type default)
		)
		(layer "In8.Cu")
	)
	(gr_arc
		(start 273.1135 -316.68847)
		(mid 273.49704 -316.30493)
		(end 273.1135 -315.92139)
		(stroke
			(width 0.2)
			(type default)
		)
		(layer "In8.Cu")
	)
	(gr_line
		(start 273.1135 -315.92139)
		(end 271.970754 -315.92139)
		(stroke
			(width 0.2)
			(type default)
		)
		(layer "In8.Cu")
	)
	(gr_arc
		(start 273.1135 -314.888626)
		(mid 273.49704 -314.505086)
		(end 273.1135 -314.121546)
		(stroke
			(width 0.2)
			(type default)
		)
		(layer "In8.Cu")
	)
	(gr_line
		(start 273.1135 -314.121546)
		(end 271.970754 -314.121546)
		(stroke
			(width 0.2)
			(type default)
		)
		(layer "In8.Cu")
	)
	(gr_arc
		(start 273.1135 -313.088528)
		(mid 273.49704 -312.704988)
		(end 273.1135 -312.321448)
		(stroke
			(width 0.2)
			(type default)
		)
		(layer "In8.Cu")
	)
	(gr_line
		(start 273.1135 -312.321448)
		(end 271.970754 -312.321448)
		(stroke
			(width 0.2)
			(type default)
		)
		(layer "In8.Cu")
	)
	(gr_arc
		(start 273.1135 -311.28843)
		(mid 273.49704 -310.90489)
		(end 273.1135 -310.52135)
		(stroke
			(width 0.2)
			(type default)
		)
		(layer "In8.Cu")
	)
	(gr_line
		(start 273.1135 -310.52135)
		(end 271.970754 -310.52135)
		(stroke
			(width 0.2)
			(type default)
		)
		(layer "In8.Cu")
	)
	(gr_arc
		(start 273.1135 -309.488586)
		(mid 273.49704 -309.105046)
		(end 273.1135 -308.721506)
		(stroke
			(width 0.2)
			(type default)
		)
		(layer "In8.Cu")
	)
	(gr_line
		(start 273.1135 -308.721506)
		(end 271.970754 -308.721506)
		(stroke
			(width 0.2)
			(type default)
		)
		(layer "In8.Cu")
	)
	(gr_arc
		(start 273.1135 -307.688488)
		(mid 273.49704 -307.304948)
		(end 273.1135 -306.921408)
		(stroke
			(width 0.2)
			(type default)
		)
		(layer "In8.Cu")
	)
	(gr_line
		(start 273.1135 -306.921408)
		(end 271.970754 -306.921408)
		(stroke
			(width 0.2)
			(type default)
		)
		(layer "In8.Cu")
	)
	(gr_line
		(start 278.23668 -356.453694)
		(end 279.636728 -356.453694)
		(stroke
			(width 0.2)
			(type default)
		)
		(layer "In8.Cu")
	)
	(gr_arc
		(start 278.23668 -355.356414)
		(mid 277.68804 -355.905054)
		(end 278.23668 -356.453694)
		(stroke
			(width 0.2)
			(type default)
		)
		(layer "In8.Cu")
	)
	(gr_line
		(start 278.23668 -352.853752)
		(end 279.636728 -352.853752)
		(stroke
			(width 0.2)
			(type default)
		)
		(layer "In8.Cu")
	)
	(gr_arc
		(start 278.23668 -351.756472)
		(mid 277.68804 -352.305112)
		(end 278.23668 -352.853752)
		(stroke
			(width 0.2)
			(type default)
		)
		(layer "In8.Cu")
	)
	(gr_line
		(start 278.23668 -349.25381)
		(end 279.636728 -349.25381)
		(stroke
			(width 0.2)
			(type default)
		)
		(layer "In8.Cu")
	)
	(gr_arc
		(start 278.23668 -348.15653)
		(mid 277.68804 -348.70517)
		(end 278.23668 -349.25381)
		(stroke
			(width 0.2)
			(type default)
		)
		(layer "In8.Cu")
	)
	(gr_line
		(start 278.23668 -345.653868)
		(end 279.636728 -345.653868)
		(stroke
			(width 0.2)
			(type default)
		)
		(layer "In8.Cu")
	)
	(gr_arc
		(start 278.23668 -344.556588)
		(mid 277.68804 -345.105228)
		(end 278.23668 -345.653868)
		(stroke
			(width 0.2)
			(type default)
		)
		(layer "In8.Cu")
	)
	(gr_line
		(start 278.23668 -342.053672)
		(end 279.636728 -342.053672)
		(stroke
			(width 0.2)
			(type default)
		)
		(layer "In8.Cu")
	)
	(gr_arc
		(start 278.23668 -340.956392)
		(mid 277.68804 -341.505032)
		(end 278.23668 -342.053672)
		(stroke
			(width 0.2)
			(type default)
		)
		(layer "In8.Cu")
	)
	(gr_line
		(start 278.23668 -338.45373)
		(end 279.636728 -338.45373)
		(stroke
			(width 0.2)
			(type default)
		)
		(layer "In8.Cu")
	)
	(gr_arc
		(start 278.23668 -337.35645)
		(mid 277.68804 -337.90509)
		(end 278.23668 -338.45373)
		(stroke
			(width 0.2)
			(type default)
		)
		(layer "In8.Cu")
	)
	(gr_line
		(start 278.23668 -334.853788)
		(end 279.636728 -334.853788)
		(stroke
			(width 0.2)
			(type default)
		)
		(layer "In8.Cu")
	)
	(gr_arc
		(start 278.23668 -333.756508)
		(mid 277.68804 -334.305148)
		(end 278.23668 -334.853788)
		(stroke
			(width 0.2)
			(type default)
		)
		(layer "In8.Cu")
	)
	(gr_line
		(start 278.23668 -331.253846)
		(end 279.636728 -331.253846)
		(stroke
			(width 0.2)
			(type default)
		)
		(layer "In8.Cu")
	)
	(gr_arc
		(start 278.23668 -330.156566)
		(mid 277.68804 -330.705206)
		(end 278.23668 -331.253846)
		(stroke
			(width 0.2)
			(type default)
		)
		(layer "In8.Cu")
	)
	(gr_line
		(start 278.23668 -327.653904)
		(end 279.636728 -327.653904)
		(stroke
			(width 0.2)
			(type default)
		)
		(layer "In8.Cu")
	)
	(gr_arc
		(start 278.23668 -326.556624)
		(mid 277.68804 -327.105264)
		(end 278.23668 -327.653904)
		(stroke
			(width 0.2)
			(type default)
		)
		(layer "In8.Cu")
	)
	(gr_line
		(start 278.23668 -324.053708)
		(end 279.636728 -324.053708)
		(stroke
			(width 0.2)
			(type default)
		)
		(layer "In8.Cu")
	)
	(gr_arc
		(start 278.23668 -322.956428)
		(mid 277.68804 -323.505068)
		(end 278.23668 -324.053708)
		(stroke
			(width 0.2)
			(type default)
		)
		(layer "In8.Cu")
	)
	(gr_line
		(start 278.23668 -320.453766)
		(end 279.636728 -320.453766)
		(stroke
			(width 0.2)
			(type default)
		)
		(layer "In8.Cu")
	)
	(gr_arc
		(start 278.23668 -319.356486)
		(mid 277.68804 -319.905126)
		(end 278.23668 -320.453766)
		(stroke
			(width 0.2)
			(type default)
		)
		(layer "In8.Cu")
	)
	(gr_line
		(start 278.23668 -316.853824)
		(end 279.636728 -316.853824)
		(stroke
			(width 0.2)
			(type default)
		)
		(layer "In8.Cu")
	)
	(gr_arc
		(start 278.23668 -315.756544)
		(mid 277.68804 -316.305184)
		(end 278.23668 -316.853824)
		(stroke
			(width 0.2)
			(type default)
		)
		(layer "In8.Cu")
	)
	(gr_line
		(start 278.23668 -313.253882)
		(end 279.636728 -313.253882)
		(stroke
			(width 0.2)
			(type default)
		)
		(layer "In8.Cu")
	)
	(gr_arc
		(start 278.23668 -312.156602)
		(mid 277.68804 -312.705242)
		(end 278.23668 -313.253882)
		(stroke
			(width 0.2)
			(type default)
		)
		(layer "In8.Cu")
	)
	(gr_line
		(start 278.23668 -309.653686)
		(end 279.636728 -309.653686)
		(stroke
			(width 0.2)
			(type default)
		)
		(layer "In8.Cu")
	)
	(gr_arc
		(start 278.23668 -308.556406)
		(mid 277.68804 -309.105046)
		(end 278.23668 -309.653686)
		(stroke
			(width 0.2)
			(type default)
		)
		(layer "In8.Cu")
	)
	(gr_line
		(start 278.23668 -306.053744)
		(end 279.636728 -306.053744)
		(stroke
			(width 0.2)
			(type default)
		)
		(layer "In8.Cu")
	)
	(gr_arc
		(start 278.23668 -304.956464)
		(mid 277.68804 -305.505104)
		(end 278.23668 -306.053744)
		(stroke
			(width 0.2)
			(type default)
		)
		(layer "In8.Cu")
	)
	(gr_line
		(start 278.23668 -302.453802)
		(end 279.636728 -302.453802)
		(stroke
			(width 0.2)
			(type default)
		)
		(layer "In8.Cu")
	)
	(gr_arc
		(start 278.23668 -301.356522)
		(mid 277.68804 -301.905162)
		(end 278.23668 -302.453802)
		(stroke
			(width 0.2)
			(type default)
		)
		(layer "In8.Cu")
	)
	(gr_line
		(start 278.23668 -298.85386)
		(end 279.636728 -298.85386)
		(stroke
			(width 0.2)
			(type default)
		)
		(layer "In8.Cu")
	)
	(gr_arc
		(start 278.23668 -297.75658)
		(mid 277.68804 -298.30522)
		(end 278.23668 -298.85386)
		(stroke
			(width 0.2)
			(type default)
		)
		(layer "In8.Cu")
	)
	(gr_line
		(start 278.23668 -295.253918)
		(end 279.636728 -295.253918)
		(stroke
			(width 0.2)
			(type default)
		)
		(layer "In8.Cu")
	)
	(gr_arc
		(start 278.23668 -294.156638)
		(mid 277.68804 -294.705278)
		(end 278.23668 -295.253918)
		(stroke
			(width 0.2)
			(type default)
		)
		(layer "In8.Cu")
	)
	(gr_line
		(start 278.23668 -262.453374)
		(end 279.636728 -262.453374)
		(stroke
			(width 0.2)
			(type default)
		)
		(layer "In8.Cu")
	)
	(gr_arc
		(start 278.23668 -261.351014)
		(mid 277.6855 -261.902194)
		(end 278.23668 -262.453374)
		(stroke
			(width 0.2)
			(type default)
		)
		(layer "In8.Cu")
	)
	(gr_line
		(start 278.23668 -258.853432)
		(end 279.636728 -258.853432)
		(stroke
			(width 0.2)
			(type default)
		)
		(layer "In8.Cu")
	)
	(gr_arc
		(start 278.23668 -257.751072)
		(mid 277.6855 -258.302252)
		(end 278.23668 -258.853432)
		(stroke
			(width 0.2)
			(type default)
		)
		(layer "In8.Cu")
	)
	(gr_line
		(start 278.23668 -255.25349)
		(end 279.636728 -255.25349)
		(stroke
			(width 0.2)
			(type default)
		)
		(layer "In8.Cu")
	)
	(gr_arc
		(start 278.23668 -254.15113)
		(mid 277.6855 -254.70231)
		(end 278.23668 -255.25349)
		(stroke
			(width 0.2)
			(type default)
		)
		(layer "In8.Cu")
	)
	(gr_line
		(start 278.23668 -251.653548)
		(end 279.636728 -251.653548)
		(stroke
			(width 0.2)
			(type default)
		)
		(layer "In8.Cu")
	)
	(gr_arc
		(start 278.23668 -250.551188)
		(mid 277.6855 -251.102368)
		(end 278.23668 -251.653548)
		(stroke
			(width 0.2)
			(type default)
		)
		(layer "In8.Cu")
	)
	(gr_line
		(start 278.236934 -355.356414)
		(end 278.23668 -355.356414)
		(stroke
			(width 0.2)
			(type default)
		)
		(layer "In8.Cu")
	)
	(gr_line
		(start 278.236934 -351.756472)
		(end 278.23668 -351.756472)
		(stroke
			(width 0.2)
			(type default)
		)
		(layer "In8.Cu")
	)
	(gr_line
		(start 278.236934 -348.15653)
		(end 278.23668 -348.15653)
		(stroke
			(width 0.2)
			(type default)
		)
		(layer "In8.Cu")
	)
	(gr_line
		(start 278.236934 -344.556588)
		(end 278.23668 -344.556588)
		(stroke
			(width 0.2)
			(type default)
		)
		(layer "In8.Cu")
	)
	(gr_line
		(start 278.236934 -340.956392)
		(end 278.23668 -340.956392)
		(stroke
			(width 0.2)
			(type default)
		)
		(layer "In8.Cu")
	)
	(gr_line
		(start 278.236934 -337.35645)
		(end 278.23668 -337.35645)
		(stroke
			(width 0.2)
			(type default)
		)
		(layer "In8.Cu")
	)
	(gr_line
		(start 278.236934 -333.756508)
		(end 278.23668 -333.756508)
		(stroke
			(width 0.2)
			(type default)
		)
		(layer "In8.Cu")
	)
	(gr_line
		(start 278.236934 -330.156566)
		(end 278.23668 -330.156566)
		(stroke
			(width 0.2)
			(type default)
		)
		(layer "In8.Cu")
	)
	(gr_line
		(start 278.236934 -326.556624)
		(end 278.23668 -326.556624)
		(stroke
			(width 0.2)
			(type default)
		)
		(layer "In8.Cu")
	)
	(gr_line
		(start 278.236934 -322.956428)
		(end 278.23668 -322.956428)
		(stroke
			(width 0.2)
			(type default)
		)
		(layer "In8.Cu")
	)
	(gr_line
		(start 278.236934 -319.356486)
		(end 278.23668 -319.356486)
		(stroke
			(width 0.2)
			(type default)
		)
		(layer "In8.Cu")
	)
	(gr_line
		(start 278.236934 -315.756544)
		(end 278.23668 -315.756544)
		(stroke
			(width 0.2)
			(type default)
		)
		(layer "In8.Cu")
	)
	(gr_line
		(start 278.236934 -312.156602)
		(end 278.23668 -312.156602)
		(stroke
			(width 0.2)
			(type default)
		)
		(layer "In8.Cu")
	)
	(gr_line
		(start 278.236934 -308.556406)
		(end 278.23668 -308.556406)
		(stroke
			(width 0.2)
			(type default)
		)
		(layer "In8.Cu")
	)
	(gr_line
		(start 278.236934 -304.956464)
		(end 278.23668 -304.956464)
		(stroke
			(width 0.2)
			(type default)
		)
		(layer "In8.Cu")
	)
	(gr_line
		(start 278.236934 -301.356522)
		(end 278.23668 -301.356522)
		(stroke
			(width 0.2)
			(type default)
		)
		(layer "In8.Cu")
	)
	(gr_line
		(start 278.236934 -297.75658)
		(end 278.23668 -297.75658)
		(stroke
			(width 0.2)
			(type default)
		)
		(layer "In8.Cu")
	)
	(gr_line
		(start 278.236934 -294.156638)
		(end 278.23668 -294.156638)
		(stroke
			(width 0.2)
			(type default)
		)
		(layer "In8.Cu")
	)
	(gr_line
		(start 278.236934 -261.351014)
		(end 278.23668 -261.351014)
		(stroke
			(width 0.2)
			(type default)
		)
		(layer "In8.Cu")
	)
	(gr_line
		(start 278.236934 -257.751072)
		(end 278.23668 -257.751072)
		(stroke
			(width 0.2)
			(type default)
		)
		(layer "In8.Cu")
	)
	(gr_line
		(start 278.236934 -254.15113)
		(end 278.23668 -254.15113)
		(stroke
			(width 0.2)
			(type default)
		)
		(layer "In8.Cu")
	)
	(gr_line
		(start 278.236934 -250.551188)
		(end 278.23668 -250.551188)
		(stroke
			(width 0.2)
			(type default)
		)
		(layer "In8.Cu")
	)
	(gr_line
		(start 278.424132 -177.848006)
		(end 278.425148 -177.850038)
		(stroke
			(width 0.2)
			(type default)
		)
		(layer "In8.Cu")
	)
	(gr_line
		(start 278.424132 -177.847752)
		(end 278.424132 -177.848006)
		(stroke
			(width 0.2)
			(type default)
		)
		(layer "In8.Cu")
	)
	(gr_line
		(start 278.424132 -173.848014)
		(end 278.425148 -173.850046)
		(stroke
			(width 0.2)
			(type default)
		)
		(layer "In8.Cu")
	)
	(gr_line
		(start 278.424132 -173.84776)
		(end 278.424132 -173.848014)
		(stroke
			(width 0.2)
			(type default)
		)
		(layer "In8.Cu")
	)
	(gr_line
		(start 278.424132 -169.848022)
		(end 278.425148 -169.850054)
		(stroke
			(width 0.2)
			(type default)
		)
		(layer "In8.Cu")
	)
	(gr_line
		(start 278.424132 -169.847768)
		(end 278.424132 -169.848022)
		(stroke
			(width 0.2)
			(type default)
		)
		(layer "In8.Cu")
	)
	(gr_line
		(start 278.424132 -165.84803)
		(end 278.425148 -165.850062)
		(stroke
			(width 0.2)
			(type default)
		)
		(layer "In8.Cu")
	)
	(gr_line
		(start 278.424132 -165.847776)
		(end 278.424132 -165.84803)
		(stroke
			(width 0.2)
			(type default)
		)
		(layer "In8.Cu")
	)
	(gr_line
		(start 278.424132 -137.848086)
		(end 278.425148 -137.850118)
		(stroke
			(width 0.2)
			(type default)
		)
		(layer "In8.Cu")
	)
	(gr_line
		(start 278.424132 -137.847832)
		(end 278.424132 -137.848086)
		(stroke
			(width 0.2)
			(type default)
		)
		(layer "In8.Cu")
	)
	(gr_line
		(start 278.424132 -81.548224)
		(end 278.425148 -81.550256)
		(stroke
			(width 0.2)
			(type default)
		)
		(layer "In8.Cu")
	)
	(gr_line
		(start 278.424132 -81.54797)
		(end 278.424132 -81.548224)
		(stroke
			(width 0.2)
			(type default)
		)
		(layer "In8.Cu")
	)
	(gr_line
		(start 278.424132 -77.548232)
		(end 278.425148 -77.550264)
		(stroke
			(width 0.2)
			(type default)
		)
		(layer "In8.Cu")
	)
	(gr_line
		(start 278.424132 -77.547978)
		(end 278.424132 -77.548232)
		(stroke
			(width 0.2)
			(type default)
		)
		(layer "In8.Cu")
	)
	(gr_line
		(start 278.424132 -73.54824)
		(end 278.425148 -73.550272)
		(stroke
			(width 0.2)
			(type default)
		)
		(layer "In8.Cu")
	)
	(gr_line
		(start 278.424132 -73.547986)
		(end 278.424132 -73.54824)
		(stroke
			(width 0.2)
			(type default)
		)
		(layer "In8.Cu")
	)
	(gr_line
		(start 278.424132 -69.548248)
		(end 278.425148 -69.55028)
		(stroke
			(width 0.2)
			(type default)
		)
		(layer "In8.Cu")
	)
	(gr_line
		(start 278.424132 -69.547994)
		(end 278.424132 -69.548248)
		(stroke
			(width 0.2)
			(type default)
		)
		(layer "In8.Cu")
	)
	(gr_line
		(start 278.424132 -65.548256)
		(end 278.425148 -65.550288)
		(stroke
			(width 0.2)
			(type default)
		)
		(layer "In8.Cu")
	)
	(gr_line
		(start 278.424132 -65.548002)
		(end 278.424132 -65.548256)
		(stroke
			(width 0.2)
			(type default)
		)
		(layer "In8.Cu")
	)
	(gr_line
		(start 278.424132 -61.548264)
		(end 278.425148 -61.550296)
		(stroke
			(width 0.2)
			(type default)
		)
		(layer "In8.Cu")
	)
	(gr_line
		(start 278.424132 -61.54801)
		(end 278.424132 -61.548264)
		(stroke
			(width 0.2)
			(type default)
		)
		(layer "In8.Cu")
	)
	(gr_line
		(start 278.424132 -57.548272)
		(end 278.425148 -57.550304)
		(stroke
			(width 0.2)
			(type default)
		)
		(layer "In8.Cu")
	)
	(gr_line
		(start 278.424132 -57.548018)
		(end 278.424132 -57.548272)
		(stroke
			(width 0.2)
			(type default)
		)
		(layer "In8.Cu")
	)
	(gr_line
		(start 278.424132 -53.54828)
		(end 278.425148 -53.550312)
		(stroke
			(width 0.2)
			(type default)
		)
		(layer "In8.Cu")
	)
	(gr_line
		(start 278.424132 -53.548026)
		(end 278.424132 -53.54828)
		(stroke
			(width 0.2)
			(type default)
		)
		(layer "In8.Cu")
	)
	(gr_line
		(start 278.424132 -49.548288)
		(end 278.425148 -49.55032)
		(stroke
			(width 0.2)
			(type default)
		)
		(layer "In8.Cu")
	)
	(gr_line
		(start 278.424132 -49.548034)
		(end 278.424132 -49.548288)
		(stroke
			(width 0.2)
			(type default)
		)
		(layer "In8.Cu")
	)
	(gr_line
		(start 278.424132 -45.548296)
		(end 278.425148 -45.550328)
		(stroke
			(width 0.2)
			(type default)
		)
		(layer "In8.Cu")
	)
	(gr_line
		(start 278.424132 -45.548042)
		(end 278.424132 -45.548296)
		(stroke
			(width 0.2)
			(type default)
		)
		(layer "In8.Cu")
	)
	(gr_line
		(start 278.424132 -41.548304)
		(end 278.425148 -41.550336)
		(stroke
			(width 0.2)
			(type default)
		)
		(layer "In8.Cu")
	)
	(gr_line
		(start 278.424132 -41.54805)
		(end 278.424132 -41.548304)
		(stroke
			(width 0.2)
			(type default)
		)
		(layer "In8.Cu")
	)
	(gr_line
		(start 278.424132 -37.548312)
		(end 278.425148 -37.550344)
		(stroke
			(width 0.2)
			(type default)
		)
		(layer "In8.Cu")
	)
	(gr_line
		(start 278.424132 -37.548058)
		(end 278.424132 -37.548312)
		(stroke
			(width 0.2)
			(type default)
		)
		(layer "In8.Cu")
	)
	(gr_line
		(start 278.424132 -17.548352)
		(end 278.425148 -17.550384)
		(stroke
			(width 0.2)
			(type default)
		)
		(layer "In8.Cu")
	)
	(gr_line
		(start 278.424132 -17.548098)
		(end 278.424132 -17.548352)
		(stroke
			(width 0.2)
			(type default)
		)
		(layer "In8.Cu")
	)
	(gr_arc
		(start 278.425148 -177.850038)
		(mid 278.100282 -178.824636)
		(end 279.07488 -179.149502)
		(stroke
			(width 0.2)
			(type default)
		)
		(layer "In8.Cu")
	)
	(gr_arc
		(start 278.425148 -173.850046)
		(mid 278.100282 -174.824644)
		(end 279.07488 -175.14951)
		(stroke
			(width 0.2)
			(type default)
		)
		(layer "In8.Cu")
	)
	(gr_arc
		(start 278.425148 -169.850054)
		(mid 278.100282 -170.824652)
		(end 279.07488 -171.149518)
		(stroke
			(width 0.2)
			(type default)
		)
		(layer "In8.Cu")
	)
	(gr_arc
		(start 278.425148 -165.850062)
		(mid 278.100282 -166.82466)
		(end 279.07488 -167.149526)
		(stroke
			(width 0.2)
			(type default)
		)
		(layer "In8.Cu")
	)
	(gr_arc
		(start 278.425148 -137.850118)
		(mid 278.100282 -138.824716)
		(end 279.07488 -139.149582)
		(stroke
			(width 0.2)
			(type default)
		)
		(layer "In8.Cu")
	)
	(gr_arc
		(start 278.425148 -81.550256)
		(mid 278.100282 -82.524854)
		(end 279.07488 -82.84972)
		(stroke
			(width 0.2)
			(type default)
		)
		(layer "In8.Cu")
	)
	(gr_arc
		(start 278.425148 -77.550264)
		(mid 278.100282 -78.524862)
		(end 279.07488 -78.849728)
		(stroke
			(width 0.2)
			(type default)
		)
		(layer "In8.Cu")
	)
	(gr_arc
		(start 278.425148 -73.550272)
		(mid 278.100282 -74.52487)
		(end 279.07488 -74.849736)
		(stroke
			(width 0.2)
			(type default)
		)
		(layer "In8.Cu")
	)
	(gr_arc
		(start 278.425148 -69.55028)
		(mid 278.100282 -70.524878)
		(end 279.07488 -70.849744)
		(stroke
			(width 0.2)
			(type default)
		)
		(layer "In8.Cu")
	)
	(gr_arc
		(start 278.425148 -65.550288)
		(mid 278.100282 -66.524886)
		(end 279.07488 -66.849752)
		(stroke
			(width 0.2)
			(type default)
		)
		(layer "In8.Cu")
	)
	(gr_arc
		(start 278.425148 -61.550296)
		(mid 278.100282 -62.524894)
		(end 279.07488 -62.84976)
		(stroke
			(width 0.2)
			(type default)
		)
		(layer "In8.Cu")
	)
	(gr_arc
		(start 278.425148 -57.550304)
		(mid 278.100282 -58.524902)
		(end 279.07488 -58.849768)
		(stroke
			(width 0.2)
			(type default)
		)
		(layer "In8.Cu")
	)
	(gr_arc
		(start 278.425148 -53.550312)
		(mid 278.100282 -54.52491)
		(end 279.07488 -54.849776)
		(stroke
			(width 0.2)
			(type default)
		)
		(layer "In8.Cu")
	)
	(gr_arc
		(start 278.425148 -49.55032)
		(mid 278.100282 -50.524918)
		(end 279.07488 -50.849784)
		(stroke
			(width 0.2)
			(type default)
		)
		(layer "In8.Cu")
	)
	(gr_arc
		(start 278.425148 -45.550328)
		(mid 278.100282 -46.524926)
		(end 279.07488 -46.849792)
		(stroke
			(width 0.2)
			(type default)
		)
		(layer "In8.Cu")
	)
	(gr_arc
		(start 278.425148 -41.550336)
		(mid 278.100282 -42.524934)
		(end 279.07488 -42.8498)
		(stroke
			(width 0.2)
			(type default)
		)
		(layer "In8.Cu")
	)
	(gr_arc
		(start 278.425148 -37.550344)
		(mid 278.100282 -38.524942)
		(end 279.07488 -38.849808)
		(stroke
			(width 0.2)
			(type default)
		)
		(layer "In8.Cu")
	)
	(gr_arc
		(start 278.425148 -17.550384)
		(mid 278.100282 -18.524982)
		(end 279.07488 -18.849848)
		(stroke
			(width 0.2)
			(type default)
		)
		(layer "In8.Cu")
	)
	(gr_arc
		(start 278.426418 -161.852356)
		(mid 278.102619 -162.8235)
		(end 279.073864 -163.147248)
		(stroke
			(width 0.2)
			(type default)
		)
		(layer "In8.Cu")
	)
	(gr_line
		(start 278.426418 -161.852102)
		(end 278.426418 -161.852356)
		(stroke
			(width 0.2)
			(type default)
		)
		(layer "In8.Cu")
	)
	(gr_arc
		(start 278.426418 -157.852364)
		(mid 278.102619 -158.823508)
		(end 279.073864 -159.147256)
		(stroke
			(width 0.2)
			(type default)
		)
		(layer "In8.Cu")
	)
	(gr_line
		(start 278.426418 -157.85211)
		(end 278.426418 -157.852364)
		(stroke
			(width 0.2)
			(type default)
		)
		(layer "In8.Cu")
	)
	(gr_arc
		(start 278.426418 -153.852372)
		(mid 278.102619 -154.823516)
		(end 279.073864 -155.147264)
		(stroke
			(width 0.2)
			(type default)
		)
		(layer "In8.Cu")
	)
	(gr_line
		(start 278.426418 -153.852118)
		(end 278.426418 -153.852372)
		(stroke
			(width 0.2)
			(type default)
		)
		(layer "In8.Cu")
	)
	(gr_arc
		(start 278.426418 -149.85238)
		(mid 278.102619 -150.823524)
		(end 279.073864 -151.147272)
		(stroke
			(width 0.2)
			(type default)
		)
		(layer "In8.Cu")
	)
	(gr_line
		(start 278.426418 -149.852126)
		(end 278.426418 -149.85238)
		(stroke
			(width 0.2)
			(type default)
		)
		(layer "In8.Cu")
	)
	(gr_arc
		(start 278.426418 -129.85242)
		(mid 278.102619 -130.823564)
		(end 279.073864 -131.147312)
		(stroke
			(width 0.2)
			(type default)
		)
		(layer "In8.Cu")
	)
	(gr_line
		(start 278.426418 -129.852166)
		(end 278.426418 -129.85242)
		(stroke
			(width 0.2)
			(type default)
		)
		(layer "In8.Cu")
	)
	(gr_arc
		(start 278.426418 -125.852428)
		(mid 278.102619 -126.823572)
		(end 279.073864 -127.14732)
		(stroke
			(width 0.2)
			(type default)
		)
		(layer "In8.Cu")
	)
	(gr_line
		(start 278.426418 -125.852174)
		(end 278.426418 -125.852428)
		(stroke
			(width 0.2)
			(type default)
		)
		(layer "In8.Cu")
	)
	(gr_arc
		(start 278.426418 -121.852436)
		(mid 278.102619 -122.82358)
		(end 279.073864 -123.147328)
		(stroke
			(width 0.2)
			(type default)
		)
		(layer "In8.Cu")
	)
	(gr_line
		(start 278.426418 -121.852182)
		(end 278.426418 -121.852436)
		(stroke
			(width 0.2)
			(type default)
		)
		(layer "In8.Cu")
	)
	(gr_arc
		(start 278.426418 -117.852444)
		(mid 278.102619 -118.823588)
		(end 279.073864 -119.147336)
		(stroke
			(width 0.2)
			(type default)
		)
		(layer "In8.Cu")
	)
	(gr_line
		(start 278.426418 -117.85219)
		(end 278.426418 -117.852444)
		(stroke
			(width 0.2)
			(type default)
		)
		(layer "In8.Cu")
	)
	(gr_arc
		(start 278.433784 -11.54049)
		(mid 278.093387 -12.52152)
		(end 279.077166 -12.854432)
		(stroke
			(width 0.2)
			(type default)
		)
		(layer "In8.Cu")
	)
	(gr_arc
		(start 278.44496 -113.868708)
		(mid 278.120865 -114.809139)
		(end 279.06345 -115.127024)
		(stroke
			(width 0.2)
			(type default)
		)
		(layer "In8.Cu")
	)
	(gr_line
		(start 279.06345 -115.127024)
		(end 281.063446 -114.127026)
		(stroke
			(width 0.2)
			(type default)
		)
		(layer "In8.Cu")
	)
	(gr_line
		(start 279.073864 -163.147248)
		(end 281.07386 -162.14725)
		(stroke
			(width 0.2)
			(type default)
		)
		(layer "In8.Cu")
	)
	(gr_line
		(start 279.073864 -159.147256)
		(end 281.07386 -158.147258)
		(stroke
			(width 0.2)
			(type default)
		)
		(layer "In8.Cu")
	)
	(gr_line
		(start 279.073864 -155.147264)
		(end 281.07386 -154.147266)
		(stroke
			(width 0.2)
			(type default)
		)
		(layer "In8.Cu")
	)
	(gr_line
		(start 279.073864 -151.147272)
		(end 281.07386 -150.147274)
		(stroke
			(width 0.2)
			(type default)
		)
		(layer "In8.Cu")
	)
	(gr_line
		(start 279.073864 -131.147312)
		(end 281.07386 -130.147314)
		(stroke
			(width 0.2)
			(type default)
		)
		(layer "In8.Cu")
	)
	(gr_line
		(start 279.073864 -127.14732)
		(end 281.07386 -126.147322)
		(stroke
			(width 0.2)
			(type default)
		)
		(layer "In8.Cu")
	)
	(gr_line
		(start 279.073864 -123.147328)
		(end 281.07386 -122.14733)
		(stroke
			(width 0.2)
			(type default)
		)
		(layer "In8.Cu")
	)
	(gr_line
		(start 279.073864 -119.147336)
		(end 281.07386 -118.147338)
		(stroke
			(width 0.2)
			(type default)
		)
		(layer "In8.Cu")
	)
	(gr_line
		(start 279.07488 -179.149502)
		(end 279.07615 -179.151788)
		(stroke
			(width 0.2)
			(type default)
		)
		(layer "In8.Cu")
	)
	(gr_line
		(start 279.07488 -175.14951)
		(end 279.07615 -175.151796)
		(stroke
			(width 0.2)
			(type default)
		)
		(layer "In8.Cu")
	)
	(gr_line
		(start 279.07488 -171.149518)
		(end 279.07615 -171.151804)
		(stroke
			(width 0.2)
			(type default)
		)
		(layer "In8.Cu")
	)
	(gr_line
		(start 279.07488 -167.149526)
		(end 279.07615 -167.151812)
		(stroke
			(width 0.2)
			(type default)
		)
		(layer "In8.Cu")
	)
	(gr_line
		(start 279.07488 -139.149582)
		(end 279.07615 -139.151868)
		(stroke
			(width 0.2)
			(type default)
		)
		(layer "In8.Cu")
	)
	(gr_line
		(start 279.07488 -82.84972)
		(end 279.07615 -82.852006)
		(stroke
			(width 0.2)
			(type default)
		)
		(layer "In8.Cu")
	)
	(gr_line
		(start 279.07488 -78.849728)
		(end 279.07615 -78.852014)
		(stroke
			(width 0.2)
			(type default)
		)
		(layer "In8.Cu")
	)
	(gr_line
		(start 279.07488 -74.849736)
		(end 279.07615 -74.852022)
		(stroke
			(width 0.2)
			(type default)
		)
		(layer "In8.Cu")
	)
	(gr_line
		(start 279.07488 -70.849744)
		(end 279.07615 -70.85203)
		(stroke
			(width 0.2)
			(type default)
		)
		(layer "In8.Cu")
	)
	(gr_line
		(start 279.07488 -66.849752)
		(end 279.07615 -66.852038)
		(stroke
			(width 0.2)
			(type default)
		)
		(layer "In8.Cu")
	)
	(gr_line
		(start 279.07488 -62.84976)
		(end 279.07615 -62.852046)
		(stroke
			(width 0.2)
			(type default)
		)
		(layer "In8.Cu")
	)
	(gr_line
		(start 279.07488 -58.849768)
		(end 279.07615 -58.852054)
		(stroke
			(width 0.2)
			(type default)
		)
		(layer "In8.Cu")
	)
	(gr_line
		(start 279.07488 -54.849776)
		(end 279.07615 -54.852062)
		(stroke
			(width 0.2)
			(type default)
		)
		(layer "In8.Cu")
	)
	(gr_line
		(start 279.07488 -50.849784)
		(end 279.07615 -50.85207)
		(stroke
			(width 0.2)
			(type default)
		)
		(layer "In8.Cu")
	)
	(gr_line
		(start 279.07488 -46.849792)
		(end 279.07615 -46.852078)
		(stroke
			(width 0.2)
			(type default)
		)
		(layer "In8.Cu")
	)
	(gr_line
		(start 279.07488 -42.8498)
		(end 279.07615 -42.852086)
		(stroke
			(width 0.2)
			(type default)
		)
		(layer "In8.Cu")
	)
	(gr_line
		(start 279.07488 -38.849808)
		(end 279.07615 -38.852094)
		(stroke
			(width 0.2)
			(type default)
		)
		(layer "In8.Cu")
	)
	(gr_line
		(start 279.07488 -18.849848)
		(end 279.07615 -18.852134)
		(stroke
			(width 0.2)
			(type default)
		)
		(layer "In8.Cu")
	)
	(gr_line
		(start 279.07615 -179.151788)
		(end 281.076146 -178.15179)
		(stroke
			(width 0.2)
			(type default)
		)
		(layer "In8.Cu")
	)
	(gr_line
		(start 279.07615 -175.151796)
		(end 281.076146 -174.151798)
		(stroke
			(width 0.2)
			(type default)
		)
		(layer "In8.Cu")
	)
	(gr_line
		(start 279.07615 -171.151804)
		(end 281.076146 -170.151806)
		(stroke
			(width 0.2)
			(type default)
		)
		(layer "In8.Cu")
	)
	(gr_line
		(start 279.07615 -167.151812)
		(end 281.076146 -166.151814)
		(stroke
			(width 0.2)
			(type default)
		)
		(layer "In8.Cu")
	)
	(gr_line
		(start 279.07615 -139.151868)
		(end 281.076146 -138.15187)
		(stroke
			(width 0.2)
			(type default)
		)
		(layer "In8.Cu")
	)
	(gr_line
		(start 279.07615 -82.852006)
		(end 281.076146 -81.852008)
		(stroke
			(width 0.2)
			(type default)
		)
		(layer "In8.Cu")
	)
	(gr_line
		(start 279.07615 -78.852014)
		(end 281.076146 -77.852016)
		(stroke
			(width 0.2)
			(type default)
		)
		(layer "In8.Cu")
	)
	(gr_line
		(start 279.07615 -74.852022)
		(end 281.076146 -73.852024)
		(stroke
			(width 0.2)
			(type default)
		)
		(layer "In8.Cu")
	)
	(gr_line
		(start 279.07615 -70.85203)
		(end 281.076146 -69.852032)
		(stroke
			(width 0.2)
			(type default)
		)
		(layer "In8.Cu")
	)
	(gr_line
		(start 279.07615 -66.852038)
		(end 281.076146 -65.85204)
		(stroke
			(width 0.2)
			(type default)
		)
		(layer "In8.Cu")
	)
	(gr_line
		(start 279.07615 -62.852046)
		(end 281.076146 -61.852048)
		(stroke
			(width 0.2)
			(type default)
		)
		(layer "In8.Cu")
	)
	(gr_line
		(start 279.07615 -58.852054)
		(end 281.076146 -57.852056)
		(stroke
			(width 0.2)
			(type default)
		)
		(layer "In8.Cu")
	)
	(gr_line
		(start 279.07615 -54.852062)
		(end 281.076146 -53.852064)
		(stroke
			(width 0.2)
			(type default)
		)
		(layer "In8.Cu")
	)
	(gr_line
		(start 279.07615 -50.85207)
		(end 281.076146 -49.852072)
		(stroke
			(width 0.2)
			(type default)
		)
		(layer "In8.Cu")
	)
	(gr_line
		(start 279.07615 -46.852078)
		(end 281.076146 -45.85208)
		(stroke
			(width 0.2)
			(type default)
		)
		(layer "In8.Cu")
	)
	(gr_line
		(start 279.07615 -42.852086)
		(end 281.076146 -41.852088)
		(stroke
			(width 0.2)
			(type default)
		)
		(layer "In8.Cu")
	)
	(gr_line
		(start 279.07615 -38.852094)
		(end 281.076146 -37.852096)
		(stroke
			(width 0.2)
			(type default)
		)
		(layer "In8.Cu")
	)
	(gr_line
		(start 279.07615 -18.852134)
		(end 281.076146 -17.852136)
		(stroke
			(width 0.2)
			(type default)
		)
		(layer "In8.Cu")
	)
	(gr_line
		(start 279.077166 -12.854432)
		(end 281.077162 -11.854434)
		(stroke
			(width 0.2)
			(type default)
		)
		(layer "In8.Cu")
	)
	(gr_line
		(start 279.236678 -358.253792)
		(end 280.636726 -358.253792)
		(stroke
			(width 0.2)
			(type default)
		)
		(layer "In8.Cu")
	)
	(gr_arc
		(start 279.236678 -357.156512)
		(mid 278.688038 -357.705152)
		(end 279.236678 -358.253792)
		(stroke
			(width 0.2)
			(type default)
		)
		(layer "In8.Cu")
	)
	(gr_line
		(start 279.236678 -354.65385)
		(end 280.636726 -354.65385)
		(stroke
			(width 0.2)
			(type default)
		)
		(layer "In8.Cu")
	)
	(gr_arc
		(start 279.236678 -353.55657)
		(mid 278.688038 -354.10521)
		(end 279.236678 -354.65385)
		(stroke
			(width 0.2)
			(type default)
		)
		(layer "In8.Cu")
	)
	(gr_line
		(start 279.236678 -351.053908)
		(end 280.636726 -351.053908)
		(stroke
			(width 0.2)
			(type default)
		)
		(layer "In8.Cu")
	)
	(gr_arc
		(start 279.236678 -349.956628)
		(mid 278.688038 -350.505268)
		(end 279.236678 -351.053908)
		(stroke
			(width 0.2)
			(type default)
		)
		(layer "In8.Cu")
	)
	(gr_line
		(start 279.236678 -347.453712)
		(end 280.636726 -347.453712)
		(stroke
			(width 0.2)
			(type default)
		)
		(layer "In8.Cu")
	)
	(gr_arc
		(start 279.236678 -346.356432)
		(mid 278.688038 -346.905072)
		(end 279.236678 -347.453712)
		(stroke
			(width 0.2)
			(type default)
		)
		(layer "In8.Cu")
	)
	(gr_line
		(start 279.236678 -343.85377)
		(end 280.636726 -343.85377)
		(stroke
			(width 0.2)
			(type default)
		)
		(layer "In8.Cu")
	)
	(gr_arc
		(start 279.236678 -342.75649)
		(mid 278.688038 -343.30513)
		(end 279.236678 -343.85377)
		(stroke
			(width 0.2)
			(type default)
		)
		(layer "In8.Cu")
	)
	(gr_line
		(start 279.236678 -340.253828)
		(end 280.636726 -340.253828)
		(stroke
			(width 0.2)
			(type default)
		)
		(layer "In8.Cu")
	)
	(gr_arc
		(start 279.236678 -339.156548)
		(mid 278.688038 -339.705188)
		(end 279.236678 -340.253828)
		(stroke
			(width 0.2)
			(type default)
		)
		(layer "In8.Cu")
	)
	(gr_line
		(start 279.236678 -336.653886)
		(end 280.636726 -336.653886)
		(stroke
			(width 0.2)
			(type default)
		)
		(layer "In8.Cu")
	)
	(gr_arc
		(start 279.236678 -335.556606)
		(mid 278.688038 -336.105246)
		(end 279.236678 -336.653886)
		(stroke
			(width 0.2)
			(type default)
		)
		(layer "In8.Cu")
	)
	(gr_line
		(start 279.236678 -333.05369)
		(end 280.636726 -333.05369)
		(stroke
			(width 0.2)
			(type default)
		)
		(layer "In8.Cu")
	)
	(gr_arc
		(start 279.236678 -331.95641)
		(mid 278.688038 -332.50505)
		(end 279.236678 -333.05369)
		(stroke
			(width 0.2)
			(type default)
		)
		(layer "In8.Cu")
	)
	(gr_line
		(start 279.236678 -329.453748)
		(end 280.636726 -329.453748)
		(stroke
			(width 0.2)
			(type default)
		)
		(layer "In8.Cu")
	)
	(gr_arc
		(start 279.236678 -328.356468)
		(mid 278.688038 -328.905108)
		(end 279.236678 -329.453748)
		(stroke
			(width 0.2)
			(type default)
		)
		(layer "In8.Cu")
	)
	(gr_line
		(start 279.236678 -325.853806)
		(end 280.636726 -325.853806)
		(stroke
			(width 0.2)
			(type default)
		)
		(layer "In8.Cu")
	)
	(gr_arc
		(start 279.236678 -324.756526)
		(mid 278.688038 -325.305166)
		(end 279.236678 -325.853806)
		(stroke
			(width 0.2)
			(type default)
		)
		(layer "In8.Cu")
	)
	(gr_line
		(start 279.236678 -322.253864)
		(end 280.636726 -322.253864)
		(stroke
			(width 0.2)
			(type default)
		)
		(layer "In8.Cu")
	)
	(gr_arc
		(start 279.236678 -321.156584)
		(mid 278.688038 -321.705224)
		(end 279.236678 -322.253864)
		(stroke
			(width 0.2)
			(type default)
		)
		(layer "In8.Cu")
	)
	(gr_line
		(start 279.236678 -318.653668)
		(end 280.636726 -318.653668)
		(stroke
			(width 0.2)
			(type default)
		)
		(layer "In8.Cu")
	)
	(gr_arc
		(start 279.236678 -317.556388)
		(mid 278.688038 -318.105028)
		(end 279.236678 -318.653668)
		(stroke
			(width 0.2)
			(type default)
		)
		(layer "In8.Cu")
	)
	(gr_line
		(start 279.236678 -315.053726)
		(end 280.636726 -315.053726)
		(stroke
			(width 0.2)
			(type default)
		)
		(layer "In8.Cu")
	)
	(gr_arc
		(start 279.236678 -313.956446)
		(mid 278.688038 -314.505086)
		(end 279.236678 -315.053726)
		(stroke
			(width 0.2)
			(type default)
		)
		(layer "In8.Cu")
	)
	(gr_line
		(start 279.236678 -311.453784)
		(end 280.636726 -311.453784)
		(stroke
			(width 0.2)
			(type default)
		)
		(layer "In8.Cu")
	)
	(gr_arc
		(start 279.236678 -310.356504)
		(mid 278.688038 -310.905144)
		(end 279.236678 -311.453784)
		(stroke
			(width 0.2)
			(type default)
		)
		(layer "In8.Cu")
	)
	(gr_line
		(start 279.236678 -307.853842)
		(end 280.636726 -307.853842)
		(stroke
			(width 0.2)
			(type default)
		)
		(layer "In8.Cu")
	)
	(gr_arc
		(start 279.236678 -306.756562)
		(mid 278.688038 -307.305202)
		(end 279.236678 -307.853842)
		(stroke
			(width 0.2)
			(type default)
		)
		(layer "In8.Cu")
	)
	(gr_line
		(start 279.236678 -304.2539)
		(end 280.636726 -304.2539)
		(stroke
			(width 0.2)
			(type default)
		)
		(layer "In8.Cu")
	)
	(gr_arc
		(start 279.236678 -303.15662)
		(mid 278.688038 -303.70526)
		(end 279.236678 -304.2539)
		(stroke
			(width 0.2)
			(type default)
		)
		(layer "In8.Cu")
	)
	(gr_line
		(start 279.236678 -300.653704)
		(end 280.636726 -300.653704)
		(stroke
			(width 0.2)
			(type default)
		)
		(layer "In8.Cu")
	)
	(gr_arc
		(start 279.236678 -299.556424)
		(mid 278.688038 -300.105064)
		(end 279.236678 -300.653704)
		(stroke
			(width 0.2)
			(type default)
		)
		(layer "In8.Cu")
	)
	(gr_line
		(start 279.236678 -297.053762)
		(end 280.636726 -297.053762)
		(stroke
			(width 0.2)
			(type default)
		)
		(layer "In8.Cu")
	)
	(gr_arc
		(start 279.236678 -295.956482)
		(mid 278.688038 -296.505122)
		(end 279.236678 -297.053762)
		(stroke
			(width 0.2)
			(type default)
		)
		(layer "In8.Cu")
	)
	(gr_line
		(start 279.236678 -264.253472)
		(end 280.636726 -264.253472)
		(stroke
			(width 0.2)
			(type default)
		)
		(layer "In8.Cu")
	)
	(gr_arc
		(start 279.236678 -263.151112)
		(mid 278.685498 -263.702292)
		(end 279.236678 -264.253472)
		(stroke
			(width 0.2)
			(type default)
		)
		(layer "In8.Cu")
	)
	(gr_line
		(start 279.236678 -260.65353)
		(end 280.636726 -260.65353)
		(stroke
			(width 0.2)
			(type default)
		)
		(layer "In8.Cu")
	)
	(gr_arc
		(start 279.236678 -259.55117)
		(mid 278.685498 -260.10235)
		(end 279.236678 -260.65353)
		(stroke
			(width 0.2)
			(type default)
		)
		(layer "In8.Cu")
	)
	(gr_line
		(start 279.236678 -257.053588)
		(end 280.636726 -257.053588)
		(stroke
			(width 0.2)
			(type default)
		)
		(layer "In8.Cu")
	)
	(gr_arc
		(start 279.236678 -255.951228)
		(mid 278.685498 -256.502408)
		(end 279.236678 -257.053588)
		(stroke
			(width 0.2)
			(type default)
		)
		(layer "In8.Cu")
	)
	(gr_line
		(start 279.236678 -253.453392)
		(end 280.636726 -253.453392)
		(stroke
			(width 0.2)
			(type default)
		)
		(layer "In8.Cu")
	)
	(gr_arc
		(start 279.236678 -252.351032)
		(mid 278.685498 -252.902212)
		(end 279.236678 -253.453392)
		(stroke
			(width 0.2)
			(type default)
		)
		(layer "In8.Cu")
	)
	(gr_line
		(start 279.236932 -357.156512)
		(end 279.236678 -357.156512)
		(stroke
			(width 0.2)
			(type default)
		)
		(layer "In8.Cu")
	)
	(gr_line
		(start 279.236932 -353.55657)
		(end 279.236678 -353.55657)
		(stroke
			(width 0.2)
			(type default)
		)
		(layer "In8.Cu")
	)
	(gr_line
		(start 279.236932 -349.956628)
		(end 279.236678 -349.956628)
		(stroke
			(width 0.2)
			(type default)
		)
		(layer "In8.Cu")
	)
	(gr_line
		(start 279.236932 -346.356432)
		(end 279.236678 -346.356432)
		(stroke
			(width 0.2)
			(type default)
		)
		(layer "In8.Cu")
	)
	(gr_line
		(start 279.236932 -342.75649)
		(end 279.236678 -342.75649)
		(stroke
			(width 0.2)
			(type default)
		)
		(layer "In8.Cu")
	)
	(gr_line
		(start 279.236932 -339.156548)
		(end 279.236678 -339.156548)
		(stroke
			(width 0.2)
			(type default)
		)
		(layer "In8.Cu")
	)
	(gr_line
		(start 279.236932 -335.556606)
		(end 279.236678 -335.556606)
		(stroke
			(width 0.2)
			(type default)
		)
		(layer "In8.Cu")
	)
	(gr_line
		(start 279.236932 -331.95641)
		(end 279.236678 -331.95641)
		(stroke
			(width 0.2)
			(type default)
		)
		(layer "In8.Cu")
	)
	(gr_line
		(start 279.236932 -328.356468)
		(end 279.236678 -328.356468)
		(stroke
			(width 0.2)
			(type default)
		)
		(layer "In8.Cu")
	)
	(gr_line
		(start 279.236932 -324.756526)
		(end 279.236678 -324.756526)
		(stroke
			(width 0.2)
			(type default)
		)
		(layer "In8.Cu")
	)
	(gr_line
		(start 279.236932 -321.156584)
		(end 279.236678 -321.156584)
		(stroke
			(width 0.2)
			(type default)
		)
		(layer "In8.Cu")
	)
	(gr_line
		(start 279.236932 -317.556388)
		(end 279.236678 -317.556388)
		(stroke
			(width 0.2)
			(type default)
		)
		(layer "In8.Cu")
	)
	(gr_line
		(start 279.236932 -313.956446)
		(end 279.236678 -313.956446)
		(stroke
			(width 0.2)
			(type default)
		)
		(layer "In8.Cu")
	)
	(gr_line
		(start 279.236932 -310.356504)
		(end 279.236678 -310.356504)
		(stroke
			(width 0.2)
			(type default)
		)
		(layer "In8.Cu")
	)
	(gr_line
		(start 279.236932 -306.756562)
		(end 279.236678 -306.756562)
		(stroke
			(width 0.2)
			(type default)
		)
		(layer "In8.Cu")
	)
	(gr_line
		(start 279.236932 -303.15662)
		(end 279.236678 -303.15662)
		(stroke
			(width 0.2)
			(type default)
		)
		(layer "In8.Cu")
	)
	(gr_line
		(start 279.236932 -299.556424)
		(end 279.236678 -299.556424)
		(stroke
			(width 0.2)
			(type default)
		)
		(layer "In8.Cu")
	)
	(gr_line
		(start 279.236932 -295.956482)
		(end 279.236678 -295.956482)
		(stroke
			(width 0.2)
			(type default)
		)
		(layer "In8.Cu")
	)
	(gr_line
		(start 279.236932 -263.151112)
		(end 279.236678 -263.151112)
		(stroke
			(width 0.2)
			(type default)
		)
		(layer "In8.Cu")
	)
	(gr_line
		(start 279.236932 -259.55117)
		(end 279.236678 -259.55117)
		(stroke
			(width 0.2)
			(type default)
		)
		(layer "In8.Cu")
	)
	(gr_line
		(start 279.236932 -255.951228)
		(end 279.236678 -255.951228)
		(stroke
			(width 0.2)
			(type default)
		)
		(layer "In8.Cu")
	)
	(gr_line
		(start 279.236932 -252.351032)
		(end 279.236678 -252.351032)
		(stroke
			(width 0.2)
			(type default)
		)
		(layer "In8.Cu")
	)
	(gr_arc
		(start 279.636728 -356.453694)
		(mid 280.185368 -355.905054)
		(end 279.636728 -355.356414)
		(stroke
			(width 0.2)
			(type default)
		)
		(layer "In8.Cu")
	)
	(gr_line
		(start 279.636728 -355.356414)
		(end 278.236934 -355.356414)
		(stroke
			(width 0.2)
			(type default)
		)
		(layer "In8.Cu")
	)
	(gr_arc
		(start 279.636728 -352.853752)
		(mid 280.185368 -352.305112)
		(end 279.636728 -351.756472)
		(stroke
			(width 0.2)
			(type default)
		)
		(layer "In8.Cu")
	)
	(gr_line
		(start 279.636728 -351.756472)
		(end 278.236934 -351.756472)
		(stroke
			(width 0.2)
			(type default)
		)
		(layer "In8.Cu")
	)
	(gr_arc
		(start 279.636728 -349.25381)
		(mid 280.185368 -348.70517)
		(end 279.636728 -348.15653)
		(stroke
			(width 0.2)
			(type default)
		)
		(layer "In8.Cu")
	)
	(gr_line
		(start 279.636728 -348.15653)
		(end 278.236934 -348.15653)
		(stroke
			(width 0.2)
			(type default)
		)
		(layer "In8.Cu")
	)
	(gr_arc
		(start 279.636728 -345.653868)
		(mid 280.185368 -345.105228)
		(end 279.636728 -344.556588)
		(stroke
			(width 0.2)
			(type default)
		)
		(layer "In8.Cu")
	)
	(gr_line
		(start 279.636728 -344.556588)
		(end 278.236934 -344.556588)
		(stroke
			(width 0.2)
			(type default)
		)
		(layer "In8.Cu")
	)
	(gr_arc
		(start 279.636728 -342.053672)
		(mid 280.185368 -341.505032)
		(end 279.636728 -340.956392)
		(stroke
			(width 0.2)
			(type default)
		)
		(layer "In8.Cu")
	)
	(gr_line
		(start 279.636728 -340.956392)
		(end 278.236934 -340.956392)
		(stroke
			(width 0.2)
			(type default)
		)
		(layer "In8.Cu")
	)
	(gr_arc
		(start 279.636728 -338.45373)
		(mid 280.185368 -337.90509)
		(end 279.636728 -337.35645)
		(stroke
			(width 0.2)
			(type default)
		)
		(layer "In8.Cu")
	)
	(gr_line
		(start 279.636728 -337.35645)
		(end 278.236934 -337.35645)
		(stroke
			(width 0.2)
			(type default)
		)
		(layer "In8.Cu")
	)
	(gr_arc
		(start 279.636728 -334.853788)
		(mid 280.185368 -334.305148)
		(end 279.636728 -333.756508)
		(stroke
			(width 0.2)
			(type default)
		)
		(layer "In8.Cu")
	)
	(gr_line
		(start 279.636728 -333.756508)
		(end 278.236934 -333.756508)
		(stroke
			(width 0.2)
			(type default)
		)
		(layer "In8.Cu")
	)
	(gr_arc
		(start 279.636728 -331.253846)
		(mid 280.185368 -330.705206)
		(end 279.636728 -330.156566)
		(stroke
			(width 0.2)
			(type default)
		)
		(layer "In8.Cu")
	)
	(gr_line
		(start 279.636728 -330.156566)
		(end 278.236934 -330.156566)
		(stroke
			(width 0.2)
			(type default)
		)
		(layer "In8.Cu")
	)
	(gr_arc
		(start 279.636728 -327.653904)
		(mid 280.185368 -327.105264)
		(end 279.636728 -326.556624)
		(stroke
			(width 0.2)
			(type default)
		)
		(layer "In8.Cu")
	)
	(gr_line
		(start 279.636728 -326.556624)
		(end 278.236934 -326.556624)
		(stroke
			(width 0.2)
			(type default)
		)
		(layer "In8.Cu")
	)
	(gr_arc
		(start 279.636728 -324.053708)
		(mid 280.185368 -323.505068)
		(end 279.636728 -322.956428)
		(stroke
			(width 0.2)
			(type default)
		)
		(layer "In8.Cu")
	)
	(gr_line
		(start 279.636728 -322.956428)
		(end 278.236934 -322.956428)
		(stroke
			(width 0.2)
			(type default)
		)
		(layer "In8.Cu")
	)
	(gr_arc
		(start 279.636728 -320.453766)
		(mid 280.185368 -319.905126)
		(end 279.636728 -319.356486)
		(stroke
			(width 0.2)
			(type default)
		)
		(layer "In8.Cu")
	)
	(gr_line
		(start 279.636728 -319.356486)
		(end 278.236934 -319.356486)
		(stroke
			(width 0.2)
			(type default)
		)
		(layer "In8.Cu")
	)
	(gr_arc
		(start 279.636728 -316.853824)
		(mid 280.185368 -316.305184)
		(end 279.636728 -315.756544)
		(stroke
			(width 0.2)
			(type default)
		)
		(layer "In8.Cu")
	)
	(gr_line
		(start 279.636728 -315.756544)
		(end 278.236934 -315.756544)
		(stroke
			(width 0.2)
			(type default)
		)
		(layer "In8.Cu")
	)
	(gr_arc
		(start 279.636728 -313.253882)
		(mid 280.185368 -312.705242)
		(end 279.636728 -312.156602)
		(stroke
			(width 0.2)
			(type default)
		)
		(layer "In8.Cu")
	)
	(gr_line
		(start 279.636728 -312.156602)
		(end 278.236934 -312.156602)
		(stroke
			(width 0.2)
			(type default)
		)
		(layer "In8.Cu")
	)
	(gr_arc
		(start 279.636728 -309.653686)
		(mid 280.185368 -309.105046)
		(end 279.636728 -308.556406)
		(stroke
			(width 0.2)
			(type default)
		)
		(layer "In8.Cu")
	)
	(gr_line
		(start 279.636728 -308.556406)
		(end 278.236934 -308.556406)
		(stroke
			(width 0.2)
			(type default)
		)
		(layer "In8.Cu")
	)
	(gr_arc
		(start 279.636728 -306.053744)
		(mid 280.185368 -305.505104)
		(end 279.636728 -304.956464)
		(stroke
			(width 0.2)
			(type default)
		)
		(layer "In8.Cu")
	)
	(gr_line
		(start 279.636728 -304.956464)
		(end 278.236934 -304.956464)
		(stroke
			(width 0.2)
			(type default)
		)
		(layer "In8.Cu")
	)
	(gr_arc
		(start 279.636728 -302.453802)
		(mid 280.185368 -301.905162)
		(end 279.636728 -301.356522)
		(stroke
			(width 0.2)
			(type default)
		)
		(layer "In8.Cu")
	)
	(gr_line
		(start 279.636728 -301.356522)
		(end 278.236934 -301.356522)
		(stroke
			(width 0.2)
			(type default)
		)
		(layer "In8.Cu")
	)
	(gr_arc
		(start 279.636728 -298.85386)
		(mid 280.185368 -298.30522)
		(end 279.636728 -297.75658)
		(stroke
			(width 0.2)
			(type default)
		)
		(layer "In8.Cu")
	)
	(gr_line
		(start 279.636728 -297.75658)
		(end 278.236934 -297.75658)
		(stroke
			(width 0.2)
			(type default)
		)
		(layer "In8.Cu")
	)
	(gr_arc
		(start 279.636728 -295.253918)
		(mid 280.185368 -294.705278)
		(end 279.636728 -294.156638)
		(stroke
			(width 0.2)
			(type default)
		)
		(layer "In8.Cu")
	)
	(gr_line
		(start 279.636728 -294.156638)
		(end 278.236934 -294.156638)
		(stroke
			(width 0.2)
			(type default)
		)
		(layer "In8.Cu")
	)
	(gr_arc
		(start 279.636728 -262.453374)
		(mid 280.187908 -261.902194)
		(end 279.636728 -261.351014)
		(stroke
			(width 0.2)
			(type default)
		)
		(layer "In8.Cu")
	)
	(gr_line
		(start 279.636728 -261.351014)
		(end 278.236934 -261.351014)
		(stroke
			(width 0.2)
			(type default)
		)
		(layer "In8.Cu")
	)
	(gr_arc
		(start 279.636728 -258.853432)
		(mid 280.187908 -258.302252)
		(end 279.636728 -257.751072)
		(stroke
			(width 0.2)
			(type default)
		)
		(layer "In8.Cu")
	)
	(gr_line
		(start 279.636728 -257.751072)
		(end 278.236934 -257.751072)
		(stroke
			(width 0.2)
			(type default)
		)
		(layer "In8.Cu")
	)
	(gr_arc
		(start 279.636728 -255.25349)
		(mid 280.187908 -254.70231)
		(end 279.636728 -254.15113)
		(stroke
			(width 0.2)
			(type default)
		)
		(layer "In8.Cu")
	)
	(gr_line
		(start 279.636728 -254.15113)
		(end 278.236934 -254.15113)
		(stroke
			(width 0.2)
			(type default)
		)
		(layer "In8.Cu")
	)
	(gr_arc
		(start 279.636728 -251.653548)
		(mid 280.187908 -251.102368)
		(end 279.636728 -250.551188)
		(stroke
			(width 0.2)
			(type default)
		)
		(layer "In8.Cu")
	)
	(gr_line
		(start 279.636728 -250.551188)
		(end 278.236934 -250.551188)
		(stroke
			(width 0.2)
			(type default)
		)
		(layer "In8.Cu")
	)
	(gr_line
		(start 280.422858 -10.545826)
		(end 278.433784 -11.54049)
		(stroke
			(width 0.2)
			(type default)
		)
		(layer "In8.Cu")
	)
	(gr_line
		(start 280.423874 -176.847754)
		(end 278.424132 -177.847752)
		(stroke
			(width 0.2)
			(type default)
		)
		(layer "In8.Cu")
	)
	(gr_line
		(start 280.423874 -172.847762)
		(end 278.424132 -173.84776)
		(stroke
			(width 0.2)
			(type default)
		)
		(layer "In8.Cu")
	)
	(gr_line
		(start 280.423874 -168.84777)
		(end 278.424132 -169.847768)
		(stroke
			(width 0.2)
			(type default)
		)
		(layer "In8.Cu")
	)
	(gr_line
		(start 280.423874 -164.847778)
		(end 278.424132 -165.847776)
		(stroke
			(width 0.2)
			(type default)
		)
		(layer "In8.Cu")
	)
	(gr_line
		(start 280.423874 -136.847834)
		(end 278.424132 -137.847832)
		(stroke
			(width 0.2)
			(type default)
		)
		(layer "In8.Cu")
	)
	(gr_line
		(start 280.423874 -80.547972)
		(end 278.424132 -81.54797)
		(stroke
			(width 0.2)
			(type default)
		)
		(layer "In8.Cu")
	)
	(gr_line
		(start 280.423874 -76.54798)
		(end 278.424132 -77.547978)
		(stroke
			(width 0.2)
			(type default)
		)
		(layer "In8.Cu")
	)
	(gr_line
		(start 280.423874 -72.547988)
		(end 278.424132 -73.547986)
		(stroke
			(width 0.2)
			(type default)
		)
		(layer "In8.Cu")
	)
	(gr_line
		(start 280.423874 -68.547996)
		(end 278.424132 -69.547994)
		(stroke
			(width 0.2)
			(type default)
		)
		(layer "In8.Cu")
	)
	(gr_line
		(start 280.423874 -64.548004)
		(end 278.424132 -65.548002)
		(stroke
			(width 0.2)
			(type default)
		)
		(layer "In8.Cu")
	)
	(gr_line
		(start 280.423874 -60.548012)
		(end 278.424132 -61.54801)
		(stroke
			(width 0.2)
			(type default)
		)
		(layer "In8.Cu")
	)
	(gr_line
		(start 280.423874 -56.54802)
		(end 278.424132 -57.548018)
		(stroke
			(width 0.2)
			(type default)
		)
		(layer "In8.Cu")
	)
	(gr_line
		(start 280.423874 -52.548028)
		(end 278.424132 -53.548026)
		(stroke
			(width 0.2)
			(type default)
		)
		(layer "In8.Cu")
	)
	(gr_line
		(start 280.423874 -48.548036)
		(end 278.424132 -49.548034)
		(stroke
			(width 0.2)
			(type default)
		)
		(layer "In8.Cu")
	)
	(gr_line
		(start 280.423874 -44.548044)
		(end 278.424132 -45.548042)
		(stroke
			(width 0.2)
			(type default)
		)
		(layer "In8.Cu")
	)
	(gr_line
		(start 280.423874 -40.548052)
		(end 278.424132 -41.54805)
		(stroke
			(width 0.2)
			(type default)
		)
		(layer "In8.Cu")
	)
	(gr_line
		(start 280.423874 -36.54806)
		(end 278.424132 -37.548058)
		(stroke
			(width 0.2)
			(type default)
		)
		(layer "In8.Cu")
	)
	(gr_line
		(start 280.423874 -16.5481)
		(end 278.424132 -17.548098)
		(stroke
			(width 0.2)
			(type default)
		)
		(layer "In8.Cu")
	)
	(gr_line
		(start 280.425144 -176.85004)
		(end 280.423874 -176.847754)
		(stroke
			(width 0.2)
			(type default)
		)
		(layer "In8.Cu")
	)
	(gr_line
		(start 280.425144 -172.850048)
		(end 280.423874 -172.847762)
		(stroke
			(width 0.2)
			(type default)
		)
		(layer "In8.Cu")
	)
	(gr_line
		(start 280.425144 -168.850056)
		(end 280.423874 -168.84777)
		(stroke
			(width 0.2)
			(type default)
		)
		(layer "In8.Cu")
	)
	(gr_line
		(start 280.425144 -164.850064)
		(end 280.423874 -164.847778)
		(stroke
			(width 0.2)
			(type default)
		)
		(layer "In8.Cu")
	)
	(gr_line
		(start 280.425144 -136.85012)
		(end 280.423874 -136.847834)
		(stroke
			(width 0.2)
			(type default)
		)
		(layer "In8.Cu")
	)
	(gr_line
		(start 280.425144 -80.550258)
		(end 280.423874 -80.547972)
		(stroke
			(width 0.2)
			(type default)
		)
		(layer "In8.Cu")
	)
	(gr_line
		(start 280.425144 -76.550266)
		(end 280.423874 -76.54798)
		(stroke
			(width 0.2)
			(type default)
		)
		(layer "In8.Cu")
	)
	(gr_line
		(start 280.425144 -72.550274)
		(end 280.423874 -72.547988)
		(stroke
			(width 0.2)
			(type default)
		)
		(layer "In8.Cu")
	)
	(gr_line
		(start 280.425144 -68.550282)
		(end 280.423874 -68.547996)
		(stroke
			(width 0.2)
			(type default)
		)
		(layer "In8.Cu")
	)
	(gr_line
		(start 280.425144 -64.55029)
		(end 280.423874 -64.548004)
		(stroke
			(width 0.2)
			(type default)
		)
		(layer "In8.Cu")
	)
	(gr_line
		(start 280.425144 -60.550298)
		(end 280.423874 -60.548012)
		(stroke
			(width 0.2)
			(type default)
		)
		(layer "In8.Cu")
	)
	(gr_line
		(start 280.425144 -56.550306)
		(end 280.423874 -56.54802)
		(stroke
			(width 0.2)
			(type default)
		)
		(layer "In8.Cu")
	)
	(gr_line
		(start 280.425144 -52.550314)
		(end 280.423874 -52.548028)
		(stroke
			(width 0.2)
			(type default)
		)
		(layer "In8.Cu")
	)
	(gr_line
		(start 280.425144 -48.550322)
		(end 280.423874 -48.548036)
		(stroke
			(width 0.2)
			(type default)
		)
		(layer "In8.Cu")
	)
	(gr_line
		(start 280.425144 -44.55033)
		(end 280.423874 -44.548044)
		(stroke
			(width 0.2)
			(type default)
		)
		(layer "In8.Cu")
	)
	(gr_line
		(start 280.425144 -40.550338)
		(end 280.423874 -40.548052)
		(stroke
			(width 0.2)
			(type default)
		)
		(layer "In8.Cu")
	)
	(gr_line
		(start 280.425144 -36.550346)
		(end 280.423874 -36.54806)
		(stroke
			(width 0.2)
			(type default)
		)
		(layer "In8.Cu")
	)
	(gr_line
		(start 280.425144 -16.550386)
		(end 280.423874 -16.5481)
		(stroke
			(width 0.2)
			(type default)
		)
		(layer "In8.Cu")
	)
	(gr_line
		(start 280.42616 -160.852358)
		(end 278.426418 -161.852102)
		(stroke
			(width 0.2)
			(type default)
		)
		(layer "In8.Cu")
	)
	(gr_line
		(start 280.42616 -156.852366)
		(end 278.426418 -157.85211)
		(stroke
			(width 0.2)
			(type default)
		)
		(layer "In8.Cu")
	)
	(gr_line
		(start 280.42616 -152.852374)
		(end 278.426418 -153.852118)
		(stroke
			(width 0.2)
			(type default)
		)
		(layer "In8.Cu")
	)
	(gr_line
		(start 280.42616 -148.852382)
		(end 278.426418 -149.852126)
		(stroke
			(width 0.2)
			(type default)
		)
		(layer "In8.Cu")
	)
	(gr_line
		(start 280.42616 -128.852422)
		(end 278.426418 -129.852166)
		(stroke
			(width 0.2)
			(type default)
		)
		(layer "In8.Cu")
	)
	(gr_line
		(start 280.42616 -124.85243)
		(end 278.426418 -125.852174)
		(stroke
			(width 0.2)
			(type default)
		)
		(layer "In8.Cu")
	)
	(gr_line
		(start 280.42616 -120.852438)
		(end 278.426418 -121.852182)
		(stroke
			(width 0.2)
			(type default)
		)
		(layer "In8.Cu")
	)
	(gr_line
		(start 280.42616 -116.852446)
		(end 278.426418 -117.85219)
		(stroke
			(width 0.2)
			(type default)
		)
		(layer "In8.Cu")
	)
	(gr_line
		(start 280.436574 -112.872774)
		(end 278.44496 -113.868708)
		(stroke
			(width 0.2)
			(type default)
		)
		(layer "In8.Cu")
	)
	(gr_arc
		(start 280.636726 -358.253792)
		(mid 281.185366 -357.705152)
		(end 280.636726 -357.156512)
		(stroke
			(width 0.2)
			(type default)
		)
		(layer "In8.Cu")
	)
	(gr_line
		(start 280.636726 -357.156512)
		(end 279.236932 -357.156512)
		(stroke
			(width 0.2)
			(type default)
		)
		(layer "In8.Cu")
	)
	(gr_arc
		(start 280.636726 -354.65385)
		(mid 281.185366 -354.10521)
		(end 280.636726 -353.55657)
		(stroke
			(width 0.2)
			(type default)
		)
		(layer "In8.Cu")
	)
	(gr_line
		(start 280.636726 -353.55657)
		(end 279.236932 -353.55657)
		(stroke
			(width 0.2)
			(type default)
		)
		(layer "In8.Cu")
	)
	(gr_arc
		(start 280.636726 -351.053908)
		(mid 281.185366 -350.505268)
		(end 280.636726 -349.956628)
		(stroke
			(width 0.2)
			(type default)
		)
		(layer "In8.Cu")
	)
	(gr_line
		(start 280.636726 -349.956628)
		(end 279.236932 -349.956628)
		(stroke
			(width 0.2)
			(type default)
		)
		(layer "In8.Cu")
	)
	(gr_arc
		(start 280.636726 -347.453712)
		(mid 281.185366 -346.905072)
		(end 280.636726 -346.356432)
		(stroke
			(width 0.2)
			(type default)
		)
		(layer "In8.Cu")
	)
	(gr_line
		(start 280.636726 -346.356432)
		(end 279.236932 -346.356432)
		(stroke
			(width 0.2)
			(type default)
		)
		(layer "In8.Cu")
	)
	(gr_arc
		(start 280.636726 -343.85377)
		(mid 281.185366 -343.30513)
		(end 280.636726 -342.75649)
		(stroke
			(width 0.2)
			(type default)
		)
		(layer "In8.Cu")
	)
	(gr_line
		(start 280.636726 -342.75649)
		(end 279.236932 -342.75649)
		(stroke
			(width 0.2)
			(type default)
		)
		(layer "In8.Cu")
	)
	(gr_arc
		(start 280.636726 -340.253828)
		(mid 281.185366 -339.705188)
		(end 280.636726 -339.156548)
		(stroke
			(width 0.2)
			(type default)
		)
		(layer "In8.Cu")
	)
	(gr_line
		(start 280.636726 -339.156548)
		(end 279.236932 -339.156548)
		(stroke
			(width 0.2)
			(type default)
		)
		(layer "In8.Cu")
	)
	(gr_arc
		(start 280.636726 -336.653886)
		(mid 281.185366 -336.105246)
		(end 280.636726 -335.556606)
		(stroke
			(width 0.2)
			(type default)
		)
		(layer "In8.Cu")
	)
	(gr_line
		(start 280.636726 -335.556606)
		(end 279.236932 -335.556606)
		(stroke
			(width 0.2)
			(type default)
		)
		(layer "In8.Cu")
	)
	(gr_arc
		(start 280.636726 -333.05369)
		(mid 281.185366 -332.50505)
		(end 280.636726 -331.95641)
		(stroke
			(width 0.2)
			(type default)
		)
		(layer "In8.Cu")
	)
	(gr_line
		(start 280.636726 -331.95641)
		(end 279.236932 -331.95641)
		(stroke
			(width 0.2)
			(type default)
		)
		(layer "In8.Cu")
	)
	(gr_arc
		(start 280.636726 -329.453748)
		(mid 281.185366 -328.905108)
		(end 280.636726 -328.356468)
		(stroke
			(width 0.2)
			(type default)
		)
		(layer "In8.Cu")
	)
	(gr_line
		(start 280.636726 -328.356468)
		(end 279.236932 -328.356468)
		(stroke
			(width 0.2)
			(type default)
		)
		(layer "In8.Cu")
	)
	(gr_arc
		(start 280.636726 -325.853806)
		(mid 281.185366 -325.305166)
		(end 280.636726 -324.756526)
		(stroke
			(width 0.2)
			(type default)
		)
		(layer "In8.Cu")
	)
	(gr_line
		(start 280.636726 -324.756526)
		(end 279.236932 -324.756526)
		(stroke
			(width 0.2)
			(type default)
		)
		(layer "In8.Cu")
	)
	(gr_arc
		(start 280.636726 -322.253864)
		(mid 281.185366 -321.705224)
		(end 280.636726 -321.156584)
		(stroke
			(width 0.2)
			(type default)
		)
		(layer "In8.Cu")
	)
	(gr_line
		(start 280.636726 -321.156584)
		(end 279.236932 -321.156584)
		(stroke
			(width 0.2)
			(type default)
		)
		(layer "In8.Cu")
	)
	(gr_arc
		(start 280.636726 -318.653668)
		(mid 281.185366 -318.105028)
		(end 280.636726 -317.556388)
		(stroke
			(width 0.2)
			(type default)
		)
		(layer "In8.Cu")
	)
	(gr_line
		(start 280.636726 -317.556388)
		(end 279.236932 -317.556388)
		(stroke
			(width 0.2)
			(type default)
		)
		(layer "In8.Cu")
	)
	(gr_arc
		(start 280.636726 -315.053726)
		(mid 281.185366 -314.505086)
		(end 280.636726 -313.956446)
		(stroke
			(width 0.2)
			(type default)
		)
		(layer "In8.Cu")
	)
	(gr_line
		(start 280.636726 -313.956446)
		(end 279.236932 -313.956446)
		(stroke
			(width 0.2)
			(type default)
		)
		(layer "In8.Cu")
	)
	(gr_arc
		(start 280.636726 -311.453784)
		(mid 281.185366 -310.905144)
		(end 280.636726 -310.356504)
		(stroke
			(width 0.2)
			(type default)
		)
		(layer "In8.Cu")
	)
	(gr_line
		(start 280.636726 -310.356504)
		(end 279.236932 -310.356504)
		(stroke
			(width 0.2)
			(type default)
		)
		(layer "In8.Cu")
	)
	(gr_arc
		(start 280.636726 -307.853842)
		(mid 281.185366 -307.305202)
		(end 280.636726 -306.756562)
		(stroke
			(width 0.2)
			(type default)
		)
		(layer "In8.Cu")
	)
	(gr_line
		(start 280.636726 -306.756562)
		(end 279.236932 -306.756562)
		(stroke
			(width 0.2)
			(type default)
		)
		(layer "In8.Cu")
	)
	(gr_arc
		(start 280.636726 -304.2539)
		(mid 281.185366 -303.70526)
		(end 280.636726 -303.15662)
		(stroke
			(width 0.2)
			(type default)
		)
		(layer "In8.Cu")
	)
	(gr_line
		(start 280.636726 -303.15662)
		(end 279.236932 -303.15662)
		(stroke
			(width 0.2)
			(type default)
		)
		(layer "In8.Cu")
	)
	(gr_arc
		(start 280.636726 -300.653704)
		(mid 281.185366 -300.105064)
		(end 280.636726 -299.556424)
		(stroke
			(width 0.2)
			(type default)
		)
		(layer "In8.Cu")
	)
	(gr_line
		(start 280.636726 -299.556424)
		(end 279.236932 -299.556424)
		(stroke
			(width 0.2)
			(type default)
		)
		(layer "In8.Cu")
	)
	(gr_arc
		(start 280.636726 -297.053762)
		(mid 281.185366 -296.505122)
		(end 280.636726 -295.956482)
		(stroke
			(width 0.2)
			(type default)
		)
		(layer "In8.Cu")
	)
	(gr_line
		(start 280.636726 -295.956482)
		(end 279.236932 -295.956482)
		(stroke
			(width 0.2)
			(type default)
		)
		(layer "In8.Cu")
	)
	(gr_arc
		(start 280.636726 -264.253472)
		(mid 281.187906 -263.702292)
		(end 280.636726 -263.151112)
		(stroke
			(width 0.2)
			(type default)
		)
		(layer "In8.Cu")
	)
	(gr_line
		(start 280.636726 -263.151112)
		(end 279.236932 -263.151112)
		(stroke
			(width 0.2)
			(type default)
		)
		(layer "In8.Cu")
	)
	(gr_arc
		(start 280.636726 -260.65353)
		(mid 281.187906 -260.10235)
		(end 280.636726 -259.55117)
		(stroke
			(width 0.2)
			(type default)
		)
		(layer "In8.Cu")
	)
	(gr_line
		(start 280.636726 -259.55117)
		(end 279.236932 -259.55117)
		(stroke
			(width 0.2)
			(type default)
		)
		(layer "In8.Cu")
	)
	(gr_arc
		(start 280.636726 -257.053588)
		(mid 281.187906 -256.502408)
		(end 280.636726 -255.951228)
		(stroke
			(width 0.2)
			(type default)
		)
		(layer "In8.Cu")
	)
	(gr_line
		(start 280.636726 -255.951228)
		(end 279.236932 -255.951228)
		(stroke
			(width 0.2)
			(type default)
		)
		(layer "In8.Cu")
	)
	(gr_arc
		(start 280.636726 -253.453392)
		(mid 281.187906 -252.902212)
		(end 280.636726 -252.351032)
		(stroke
			(width 0.2)
			(type default)
		)
		(layer "In8.Cu")
	)
	(gr_line
		(start 280.636726 -252.351032)
		(end 279.236932 -252.351032)
		(stroke
			(width 0.2)
			(type default)
		)
		(layer "In8.Cu")
	)
	(gr_arc
		(start 281.063446 -114.127026)
		(mid 281.377136 -113.186464)
		(end 280.436574 -112.872774)
		(stroke
			(width 0.2)
			(type default)
		)
		(layer "In8.Cu")
	)
	(gr_arc
		(start 281.07386 -162.14725)
		(mid 281.397456 -161.175954)
		(end 280.42616 -160.852358)
		(stroke
			(width 0.2)
			(type default)
		)
		(layer "In8.Cu")
	)
	(gr_arc
		(start 281.07386 -158.147258)
		(mid 281.397456 -157.175962)
		(end 280.42616 -156.852366)
		(stroke
			(width 0.2)
			(type default)
		)
		(layer "In8.Cu")
	)
	(gr_arc
		(start 281.07386 -154.147266)
		(mid 281.397456 -153.17597)
		(end 280.42616 -152.852374)
		(stroke
			(width 0.2)
			(type default)
		)
		(layer "In8.Cu")
	)
	(gr_arc
		(start 281.07386 -150.147274)
		(mid 281.397456 -149.175978)
		(end 280.42616 -148.852382)
		(stroke
			(width 0.2)
			(type default)
		)
		(layer "In8.Cu")
	)
	(gr_arc
		(start 281.07386 -130.147314)
		(mid 281.397456 -129.176018)
		(end 280.42616 -128.852422)
		(stroke
			(width 0.2)
			(type default)
		)
		(layer "In8.Cu")
	)
	(gr_arc
		(start 281.07386 -126.147322)
		(mid 281.397456 -125.176026)
		(end 280.42616 -124.85243)
		(stroke
			(width 0.2)
			(type default)
		)
		(layer "In8.Cu")
	)
	(gr_arc
		(start 281.07386 -122.14733)
		(mid 281.397456 -121.176034)
		(end 280.42616 -120.852438)
		(stroke
			(width 0.2)
			(type default)
		)
		(layer "In8.Cu")
	)
	(gr_arc
		(start 281.07386 -118.147338)
		(mid 281.397456 -117.176042)
		(end 280.42616 -116.852446)
		(stroke
			(width 0.2)
			(type default)
		)
		(layer "In8.Cu")
	)
	(gr_arc
		(start 281.074876 -178.149504)
		(mid 281.399742 -177.174906)
		(end 280.425144 -176.85004)
		(stroke
			(width 0.2)
			(type default)
		)
		(layer "In8.Cu")
	)
	(gr_arc
		(start 281.074876 -174.149512)
		(mid 281.399742 -173.174914)
		(end 280.425144 -172.850048)
		(stroke
			(width 0.2)
			(type default)
		)
		(layer "In8.Cu")
	)
	(gr_arc
		(start 281.074876 -170.14952)
		(mid 281.399742 -169.174922)
		(end 280.425144 -168.850056)
		(stroke
			(width 0.2)
			(type default)
		)
		(layer "In8.Cu")
	)
	(gr_arc
		(start 281.074876 -166.149528)
		(mid 281.399742 -165.17493)
		(end 280.425144 -164.850064)
		(stroke
			(width 0.2)
			(type default)
		)
		(layer "In8.Cu")
	)
	(gr_arc
		(start 281.074876 -138.149584)
		(mid 281.399742 -137.174986)
		(end 280.425144 -136.85012)
		(stroke
			(width 0.2)
			(type default)
		)
		(layer "In8.Cu")
	)
	(gr_arc
		(start 281.074876 -81.849722)
		(mid 281.399742 -80.875124)
		(end 280.425144 -80.550258)
		(stroke
			(width 0.2)
			(type default)
		)
		(layer "In8.Cu")
	)
	(gr_arc
		(start 281.074876 -77.84973)
		(mid 281.399742 -76.875132)
		(end 280.425144 -76.550266)
		(stroke
			(width 0.2)
			(type default)
		)
		(layer "In8.Cu")
	)
	(gr_arc
		(start 281.074876 -73.849738)
		(mid 281.399742 -72.87514)
		(end 280.425144 -72.550274)
		(stroke
			(width 0.2)
			(type default)
		)
		(layer "In8.Cu")
	)
	(gr_arc
		(start 281.074876 -69.849746)
		(mid 281.399742 -68.875148)
		(end 280.425144 -68.550282)
		(stroke
			(width 0.2)
			(type default)
		)
		(layer "In8.Cu")
	)
	(gr_arc
		(start 281.074876 -65.849754)
		(mid 281.399742 -64.875156)
		(end 280.425144 -64.55029)
		(stroke
			(width 0.2)
			(type default)
		)
		(layer "In8.Cu")
	)
	(gr_arc
		(start 281.074876 -61.849762)
		(mid 281.399742 -60.875164)
		(end 280.425144 -60.550298)
		(stroke
			(width 0.2)
			(type default)
		)
		(layer "In8.Cu")
	)
	(gr_arc
		(start 281.074876 -57.84977)
		(mid 281.399742 -56.875172)
		(end 280.425144 -56.550306)
		(stroke
			(width 0.2)
			(type default)
		)
		(layer "In8.Cu")
	)
	(gr_arc
		(start 281.074876 -53.849778)
		(mid 281.399742 -52.87518)
		(end 280.425144 -52.550314)
		(stroke
			(width 0.2)
			(type default)
		)
		(layer "In8.Cu")
	)
	(gr_arc
		(start 281.074876 -49.849786)
		(mid 281.399742 -48.875188)
		(end 280.425144 -48.550322)
		(stroke
			(width 0.2)
			(type default)
		)
		(layer "In8.Cu")
	)
	(gr_arc
		(start 281.074876 -45.849794)
		(mid 281.399742 -44.875196)
		(end 280.425144 -44.55033)
		(stroke
			(width 0.2)
			(type default)
		)
		(layer "In8.Cu")
	)
	(gr_arc
		(start 281.074876 -41.849802)
		(mid 281.399742 -40.875204)
		(end 280.425144 -40.550338)
		(stroke
			(width 0.2)
			(type default)
		)
		(layer "In8.Cu")
	)
	(gr_arc
		(start 281.074876 -37.84981)
		(mid 281.399742 -36.875212)
		(end 280.425144 -36.550346)
		(stroke
			(width 0.2)
			(type default)
		)
		(layer "In8.Cu")
	)
	(gr_arc
		(start 281.074876 -17.84985)
		(mid 281.399742 -16.875252)
		(end 280.425144 -16.550386)
		(stroke
			(width 0.2)
			(type default)
		)
		(layer "In8.Cu")
	)
	(gr_line
		(start 281.076146 -178.15179)
		(end 281.074876 -178.149504)
		(stroke
			(width 0.2)
			(type default)
		)
		(layer "In8.Cu")
	)
	(gr_line
		(start 281.076146 -174.151798)
		(end 281.074876 -174.149512)
		(stroke
			(width 0.2)
			(type default)
		)
		(layer "In8.Cu")
	)
	(gr_line
		(start 281.076146 -170.151806)
		(end 281.074876 -170.14952)
		(stroke
			(width 0.2)
			(type default)
		)
		(layer "In8.Cu")
	)
	(gr_line
		(start 281.076146 -166.151814)
		(end 281.074876 -166.149528)
		(stroke
			(width 0.2)
			(type default)
		)
		(layer "In8.Cu")
	)
	(gr_line
		(start 281.076146 -138.15187)
		(end 281.074876 -138.149584)
		(stroke
			(width 0.2)
			(type default)
		)
		(layer "In8.Cu")
	)
	(gr_line
		(start 281.076146 -81.852008)
		(end 281.074876 -81.849722)
		(stroke
			(width 0.2)
			(type default)
		)
		(layer "In8.Cu")
	)
	(gr_line
		(start 281.076146 -77.852016)
		(end 281.074876 -77.84973)
		(stroke
			(width 0.2)
			(type default)
		)
		(layer "In8.Cu")
	)
	(gr_line
		(start 281.076146 -73.852024)
		(end 281.074876 -73.849738)
		(stroke
			(width 0.2)
			(type default)
		)
		(layer "In8.Cu")
	)
	(gr_line
		(start 281.076146 -69.852032)
		(end 281.074876 -69.849746)
		(stroke
			(width 0.2)
			(type default)
		)
		(layer "In8.Cu")
	)
	(gr_line
		(start 281.076146 -65.85204)
		(end 281.074876 -65.849754)
		(stroke
			(width 0.2)
			(type default)
		)
		(layer "In8.Cu")
	)
	(gr_line
		(start 281.076146 -61.852048)
		(end 281.074876 -61.849762)
		(stroke
			(width 0.2)
			(type default)
		)
		(layer "In8.Cu")
	)
	(gr_line
		(start 281.076146 -57.852056)
		(end 281.074876 -57.84977)
		(stroke
			(width 0.2)
			(type default)
		)
		(layer "In8.Cu")
	)
	(gr_line
		(start 281.076146 -53.852064)
		(end 281.074876 -53.849778)
		(stroke
			(width 0.2)
			(type default)
		)
		(layer "In8.Cu")
	)
	(gr_line
		(start 281.076146 -49.852072)
		(end 281.074876 -49.849786)
		(stroke
			(width 0.2)
			(type default)
		)
		(layer "In8.Cu")
	)
	(gr_line
		(start 281.076146 -45.85208)
		(end 281.074876 -45.849794)
		(stroke
			(width 0.2)
			(type default)
		)
		(layer "In8.Cu")
	)
	(gr_line
		(start 281.076146 -41.852088)
		(end 281.074876 -41.849802)
		(stroke
			(width 0.2)
			(type default)
		)
		(layer "In8.Cu")
	)
	(gr_line
		(start 281.076146 -37.852096)
		(end 281.074876 -37.84981)
		(stroke
			(width 0.2)
			(type default)
		)
		(layer "In8.Cu")
	)
	(gr_line
		(start 281.076146 -17.852136)
		(end 281.074876 -17.84985)
		(stroke
			(width 0.2)
			(type default)
		)
		(layer "In8.Cu")
	)
	(gr_arc
		(start 281.077162 -11.854434)
		(mid 281.404314 -10.872978)
		(end 280.422858 -10.545826)
		(stroke
			(width 0.2)
			(type default)
		)
		(layer "In8.Cu")
	)
	(gr_line
		(start 282.83662 -264.250932)
		(end 284.236668 -264.250932)
		(stroke
			(width 0.2)
			(type default)
		)
		(layer "In8.Cu")
	)
	(gr_arc
		(start 282.83662 -263.153652)
		(mid 282.28798 -263.702292)
		(end 282.83662 -264.250932)
		(stroke
			(width 0.2)
			(type default)
		)
		(layer "In8.Cu")
	)
	(gr_line
		(start 282.922726 -35.854386)
		(end 284.922468 -36.854384)
		(stroke
			(width 0.2)
			(type default)
		)
		(layer "In8.Cu")
	)
	(gr_line
		(start 282.923742 -136.151874)
		(end 284.923738 -137.151872)
		(stroke
			(width 0.2)
			(type default)
		)
		(layer "In8.Cu")
	)
	(gr_line
		(start 282.923742 -108.15193)
		(end 284.923738 -109.151928)
		(stroke
			(width 0.2)
			(type default)
		)
		(layer "In8.Cu")
	)
	(gr_line
		(start 282.925012 -136.149588)
		(end 282.923742 -136.151874)
		(stroke
			(width 0.2)
			(type default)
		)
		(layer "In8.Cu")
	)
	(gr_line
		(start 282.936442 -180.126894)
		(end 284.928056 -181.122574)
		(stroke
			(width 0.2)
			(type default)
		)
		(layer "In8.Cu")
	)
	(gr_line
		(start 282.936442 -176.126902)
		(end 284.928056 -177.122582)
		(stroke
			(width 0.2)
			(type default)
		)
		(layer "In8.Cu")
	)
	(gr_line
		(start 282.936442 -172.12691)
		(end 284.928056 -173.12259)
		(stroke
			(width 0.2)
			(type default)
		)
		(layer "In8.Cu")
	)
	(gr_line
		(start 282.936442 -168.126918)
		(end 284.928056 -169.122598)
		(stroke
			(width 0.2)
			(type default)
		)
		(layer "In8.Cu")
	)
	(gr_line
		(start 282.936442 -164.126926)
		(end 284.928056 -165.122606)
		(stroke
			(width 0.2)
			(type default)
		)
		(layer "In8.Cu")
	)
	(gr_line
		(start 282.936442 -160.126934)
		(end 284.936438 -161.126932)
		(stroke
			(width 0.2)
			(type default)
		)
		(layer "In8.Cu")
	)
	(gr_line
		(start 282.936442 -156.126942)
		(end 284.928056 -157.122622)
		(stroke
			(width 0.2)
			(type default)
		)
		(layer "In8.Cu")
	)
	(gr_line
		(start 282.936442 -152.12695)
		(end 284.928056 -153.12263)
		(stroke
			(width 0.2)
			(type default)
		)
		(layer "In8.Cu")
	)
	(gr_line
		(start 282.936442 -128.126998)
		(end 284.928056 -129.122678)
		(stroke
			(width 0.2)
			(type default)
		)
		(layer "In8.Cu")
	)
	(gr_line
		(start 282.936442 -124.127006)
		(end 284.928056 -125.122686)
		(stroke
			(width 0.2)
			(type default)
		)
		(layer "In8.Cu")
	)
	(gr_line
		(start 282.936442 -120.127014)
		(end 284.928056 -121.122694)
		(stroke
			(width 0.2)
			(type default)
		)
		(layer "In8.Cu")
	)
	(gr_line
		(start 282.936442 -116.127022)
		(end 284.928056 -117.122702)
		(stroke
			(width 0.2)
			(type default)
		)
		(layer "In8.Cu")
	)
	(gr_line
		(start 282.936442 -83.827112)
		(end 284.928056 -84.822792)
		(stroke
			(width 0.2)
			(type default)
		)
		(layer "In8.Cu")
	)
	(gr_line
		(start 282.936442 -79.82712)
		(end 284.928056 -80.8228)
		(stroke
			(width 0.2)
			(type default)
		)
		(layer "In8.Cu")
	)
	(gr_line
		(start 282.936442 -75.827128)
		(end 284.928056 -76.822808)
		(stroke
			(width 0.2)
			(type default)
		)
		(layer "In8.Cu")
	)
	(gr_line
		(start 282.936442 -71.827136)
		(end 284.928056 -72.822816)
		(stroke
			(width 0.2)
			(type default)
		)
		(layer "In8.Cu")
	)
	(gr_line
		(start 282.936442 -67.827144)
		(end 284.928056 -68.822824)
		(stroke
			(width 0.2)
			(type default)
		)
		(layer "In8.Cu")
	)
	(gr_line
		(start 282.936442 -63.827152)
		(end 284.928056 -64.822832)
		(stroke
			(width 0.2)
			(type default)
		)
		(layer "In8.Cu")
	)
	(gr_line
		(start 282.936442 -59.82716)
		(end 284.928056 -60.82284)
		(stroke
			(width 0.2)
			(type default)
		)
		(layer "In8.Cu")
	)
	(gr_line
		(start 282.936442 -55.827168)
		(end 284.928056 -56.822848)
		(stroke
			(width 0.2)
			(type default)
		)
		(layer "In8.Cu")
	)
	(gr_line
		(start 282.936442 -51.827176)
		(end 284.928056 -52.822856)
		(stroke
			(width 0.2)
			(type default)
		)
		(layer "In8.Cu")
	)
	(gr_line
		(start 282.936442 -47.827184)
		(end 284.928056 -48.822864)
		(stroke
			(width 0.2)
			(type default)
		)
		(layer "In8.Cu")
	)
	(gr_line
		(start 282.936442 -43.827192)
		(end 284.928056 -44.822872)
		(stroke
			(width 0.2)
			(type default)
		)
		(layer "In8.Cu")
	)
	(gr_line
		(start 282.936442 -39.8272)
		(end 284.928056 -40.82288)
		(stroke
			(width 0.2)
			(type default)
		)
		(layer "In8.Cu")
	)
	(gr_arc
		(start 283.563314 -178.872642)
		(mid 282.622752 -179.186332)
		(end 282.936442 -180.126894)
		(stroke
			(width 0.2)
			(type default)
		)
		(layer "In8.Cu")
	)
	(gr_arc
		(start 283.563314 -174.87265)
		(mid 282.622752 -175.18634)
		(end 282.936442 -176.126902)
		(stroke
			(width 0.2)
			(type default)
		)
		(layer "In8.Cu")
	)
	(gr_arc
		(start 283.563314 -170.872658)
		(mid 282.622752 -171.186348)
		(end 282.936442 -172.12691)
		(stroke
			(width 0.2)
			(type default)
		)
		(layer "In8.Cu")
	)
	(gr_arc
		(start 283.563314 -166.872666)
		(mid 282.622752 -167.186356)
		(end 282.936442 -168.126918)
		(stroke
			(width 0.2)
			(type default)
		)
		(layer "In8.Cu")
	)
	(gr_arc
		(start 283.563314 -162.872674)
		(mid 282.622752 -163.186364)
		(end 282.936442 -164.126926)
		(stroke
			(width 0.2)
			(type default)
		)
		(layer "In8.Cu")
	)
	(gr_arc
		(start 283.563314 -154.87269)
		(mid 282.622752 -155.18638)
		(end 282.936442 -156.126942)
		(stroke
			(width 0.2)
			(type default)
		)
		(layer "In8.Cu")
	)
	(gr_arc
		(start 283.563314 -150.872698)
		(mid 282.622752 -151.186388)
		(end 282.936442 -152.12695)
		(stroke
			(width 0.2)
			(type default)
		)
		(layer "In8.Cu")
	)
	(gr_arc
		(start 283.563314 -126.872746)
		(mid 282.622752 -127.186436)
		(end 282.936442 -128.126998)
		(stroke
			(width 0.2)
			(type default)
		)
		(layer "In8.Cu")
	)
	(gr_arc
		(start 283.563314 -122.872754)
		(mid 282.622752 -123.186444)
		(end 282.936442 -124.127006)
		(stroke
			(width 0.2)
			(type default)
		)
		(layer "In8.Cu")
	)
	(gr_arc
		(start 283.563314 -118.872762)
		(mid 282.622752 -119.186452)
		(end 282.936442 -120.127014)
		(stroke
			(width 0.2)
			(type default)
		)
		(layer "In8.Cu")
	)
	(gr_arc
		(start 283.563314 -114.87277)
		(mid 282.622752 -115.18646)
		(end 282.936442 -116.127022)
		(stroke
			(width 0.2)
			(type default)
		)
		(layer "In8.Cu")
	)
	(gr_arc
		(start 283.563314 -82.57286)
		(mid 282.622752 -82.88655)
		(end 282.936442 -83.827112)
		(stroke
			(width 0.2)
			(type default)
		)
		(layer "In8.Cu")
	)
	(gr_arc
		(start 283.563314 -78.572868)
		(mid 282.622752 -78.886558)
		(end 282.936442 -79.82712)
		(stroke
			(width 0.2)
			(type default)
		)
		(layer "In8.Cu")
	)
	(gr_arc
		(start 283.563314 -74.572876)
		(mid 282.622752 -74.886566)
		(end 282.936442 -75.827128)
		(stroke
			(width 0.2)
			(type default)
		)
		(layer "In8.Cu")
	)
	(gr_arc
		(start 283.563314 -70.572884)
		(mid 282.622752 -70.886574)
		(end 282.936442 -71.827136)
		(stroke
			(width 0.2)
			(type default)
		)
		(layer "In8.Cu")
	)
	(gr_arc
		(start 283.563314 -66.572892)
		(mid 282.622752 -66.886582)
		(end 282.936442 -67.827144)
		(stroke
			(width 0.2)
			(type default)
		)
		(layer "In8.Cu")
	)
	(gr_arc
		(start 283.563314 -62.5729)
		(mid 282.622752 -62.88659)
		(end 282.936442 -63.827152)
		(stroke
			(width 0.2)
			(type default)
		)
		(layer "In8.Cu")
	)
	(gr_arc
		(start 283.563314 -58.572908)
		(mid 282.622752 -58.886598)
		(end 282.936442 -59.82716)
		(stroke
			(width 0.2)
			(type default)
		)
		(layer "In8.Cu")
	)
	(gr_arc
		(start 283.563314 -54.572916)
		(mid 282.622752 -54.886606)
		(end 282.936442 -55.827168)
		(stroke
			(width 0.2)
			(type default)
		)
		(layer "In8.Cu")
	)
	(gr_arc
		(start 283.563314 -50.572924)
		(mid 282.622752 -50.886614)
		(end 282.936442 -51.827176)
		(stroke
			(width 0.2)
			(type default)
		)
		(layer "In8.Cu")
	)
	(gr_arc
		(start 283.563314 -46.572932)
		(mid 282.622752 -46.886622)
		(end 282.936442 -47.827184)
		(stroke
			(width 0.2)
			(type default)
		)
		(layer "In8.Cu")
	)
	(gr_arc
		(start 283.563314 -42.57294)
		(mid 282.622752 -42.88663)
		(end 282.936442 -43.827192)
		(stroke
			(width 0.2)
			(type default)
		)
		(layer "In8.Cu")
	)
	(gr_arc
		(start 283.563314 -38.572948)
		(mid 282.622752 -38.886638)
		(end 282.936442 -39.8272)
		(stroke
			(width 0.2)
			(type default)
		)
		(layer "In8.Cu")
	)
	(gr_arc
		(start 283.571696 -158.877)
		(mid 282.62492 -159.182185)
		(end 282.936442 -160.126934)
		(stroke
			(width 0.2)
			(type default)
		)
		(layer "In8.Cu")
	)
	(gr_arc
		(start 283.574744 -134.850124)
		(mid 282.600146 -135.17499)
		(end 282.925012 -136.149588)
		(stroke
			(width 0.2)
			(type default)
		)
		(layer "In8.Cu")
	)
	(gr_line
		(start 283.576014 -134.847838)
		(end 283.574744 -134.850124)
		(stroke
			(width 0.2)
			(type default)
		)
		(layer "In8.Cu")
	)
	(gr_arc
		(start 283.576014 -106.847894)
		(mid 282.59786 -107.173776)
		(end 282.923742 -108.15193)
		(stroke
			(width 0.2)
			(type default)
		)
		(layer "In8.Cu")
	)
	(gr_arc
		(start 283.57703 -34.545778)
		(mid 282.595574 -34.87293)
		(end 282.922726 -35.854386)
		(stroke
			(width 0.2)
			(type default)
		)
		(layer "In8.Cu")
	)
	(gr_arc
		(start 284.236668 -264.250932)
		(mid 284.785308 -263.702292)
		(end 284.236668 -263.153652)
		(stroke
			(width 0.2)
			(type default)
		)
		(layer "In8.Cu")
	)
	(gr_line
		(start 284.236668 -263.153652)
		(end 282.83662 -263.153652)
		(stroke
			(width 0.2)
			(type default)
		)
		(layer "In8.Cu")
	)
	(gr_arc
		(start 284.922468 -36.854384)
		(mid 285.904229 -36.527384)
		(end 285.577026 -35.545776)
		(stroke
			(width 0.2)
			(type default)
		)
		(layer "In8.Cu")
	)
	(gr_line
		(start 284.923738 -137.151872)
		(end 284.923992 -137.151618)
		(stroke
			(width 0.2)
			(type default)
		)
		(layer "In8.Cu")
	)
	(gr_arc
		(start 284.923738 -109.151928)
		(mid 285.901892 -108.826046)
		(end 285.57601 -107.847892)
		(stroke
			(width 0.2)
			(type default)
		)
		(layer "In8.Cu")
	)
	(gr_line
		(start 284.923992 -137.151618)
		(end 284.925008 -137.149586)
		(stroke
			(width 0.2)
			(type default)
		)
		(layer "In8.Cu")
	)
	(gr_arc
		(start 284.925008 -137.149586)
		(mid 285.899606 -136.82472)
		(end 285.57474 -135.850122)
		(stroke
			(width 0.2)
			(type default)
		)
		(layer "In8.Cu")
	)
	(gr_arc
		(start 284.928056 -181.122574)
		(mid 285.874832 -180.817389)
		(end 285.56331 -179.87264)
		(stroke
			(width 0.2)
			(type default)
		)
		(layer "In8.Cu")
	)
	(gr_arc
		(start 284.928056 -177.122582)
		(mid 285.874832 -176.817397)
		(end 285.56331 -175.872648)
		(stroke
			(width 0.2)
			(type default)
		)
		(layer "In8.Cu")
	)
	(gr_arc
		(start 284.928056 -173.12259)
		(mid 285.874832 -172.817405)
		(end 285.56331 -171.872656)
		(stroke
			(width 0.2)
			(type default)
		)
		(layer "In8.Cu")
	)
	(gr_arc
		(start 284.928056 -169.122598)
		(mid 285.874832 -168.817413)
		(end 285.56331 -167.872664)
		(stroke
			(width 0.2)
			(type default)
		)
		(layer "In8.Cu")
	)
	(gr_arc
		(start 284.928056 -165.122606)
		(mid 285.874832 -164.817421)
		(end 285.56331 -163.872672)
		(stroke
			(width 0.2)
			(type default)
		)
		(layer "In8.Cu")
	)
	(gr_arc
		(start 284.928056 -157.122622)
		(mid 285.874832 -156.817437)
		(end 285.56331 -155.872688)
		(stroke
			(width 0.2)
			(type default)
		)
		(layer "In8.Cu")
	)
	(gr_arc
		(start 284.928056 -153.12263)
		(mid 285.874832 -152.817445)
		(end 285.56331 -151.872696)
		(stroke
			(width 0.2)
			(type default)
		)
		(layer "In8.Cu")
	)
	(gr_arc
		(start 284.928056 -129.122678)
		(mid 285.874832 -128.817493)
		(end 285.56331 -127.872744)
		(stroke
			(width 0.2)
			(type default)
		)
		(layer "In8.Cu")
	)
	(gr_arc
		(start 284.928056 -125.122686)
		(mid 285.874832 -124.817501)
		(end 285.56331 -123.872752)
		(stroke
			(width 0.2)
			(type default)
		)
		(layer "In8.Cu")
	)
	(gr_arc
		(start 284.928056 -121.122694)
		(mid 285.874832 -120.817509)
		(end 285.56331 -119.87276)
		(stroke
			(width 0.2)
			(type default)
		)
		(layer "In8.Cu")
	)
	(gr_arc
		(start 284.928056 -117.122702)
		(mid 285.874832 -116.817517)
		(end 285.56331 -115.872768)
		(stroke
			(width 0.2)
			(type default)
		)
		(layer "In8.Cu")
	)
	(gr_arc
		(start 284.928056 -84.822792)
		(mid 285.874832 -84.517607)
		(end 285.56331 -83.572858)
		(stroke
			(width 0.2)
			(type default)
		)
		(layer "In8.Cu")
	)
	(gr_arc
		(start 284.928056 -80.8228)
		(mid 285.874832 -80.517615)
		(end 285.56331 -79.572866)
		(stroke
			(width 0.2)
			(type default)
		)
		(layer "In8.Cu")
	)
	(gr_arc
		(start 284.928056 -76.822808)
		(mid 285.874832 -76.517623)
		(end 285.56331 -75.572874)
		(stroke
			(width 0.2)
			(type default)
		)
		(layer "In8.Cu")
	)
	(gr_arc
		(start 284.928056 -72.822816)
		(mid 285.874832 -72.517631)
		(end 285.56331 -71.572882)
		(stroke
			(width 0.2)
			(type default)
		)
		(layer "In8.Cu")
	)
	(gr_arc
		(start 284.928056 -68.822824)
		(mid 285.874832 -68.517639)
		(end 285.56331 -67.57289)
		(stroke
			(width 0.2)
			(type default)
		)
		(layer "In8.Cu")
	)
	(gr_arc
		(start 284.928056 -64.822832)
		(mid 285.874832 -64.517647)
		(end 285.56331 -63.572898)
		(stroke
			(width 0.2)
			(type default)
		)
		(layer "In8.Cu")
	)
	(gr_arc
		(start 284.928056 -60.82284)
		(mid 285.874832 -60.517655)
		(end 285.56331 -59.572906)
		(stroke
			(width 0.2)
			(type default)
		)
		(layer "In8.Cu")
	)
	(gr_arc
		(start 284.928056 -56.822848)
		(mid 285.874832 -56.517663)
		(end 285.56331 -55.572914)
		(stroke
			(width 0.2)
			(type default)
		)
		(layer "In8.Cu")
	)
	(gr_arc
		(start 284.928056 -52.822856)
		(mid 285.874832 -52.517671)
		(end 285.56331 -51.572922)
		(stroke
			(width 0.2)
			(type default)
		)
		(layer "In8.Cu")
	)
	(gr_arc
		(start 284.928056 -48.822864)
		(mid 285.874832 -48.517679)
		(end 285.56331 -47.57293)
		(stroke
			(width 0.2)
			(type default)
		)
		(layer "In8.Cu")
	)
	(gr_arc
		(start 284.928056 -44.822872)
		(mid 285.874832 -44.517687)
		(end 285.56331 -43.572938)
		(stroke
			(width 0.2)
			(type default)
		)
		(layer "In8.Cu")
	)
	(gr_arc
		(start 284.928056 -40.82288)
		(mid 285.874832 -40.517695)
		(end 285.56331 -39.572946)
		(stroke
			(width 0.2)
			(type default)
		)
		(layer "In8.Cu")
	)
	(gr_arc
		(start 284.936438 -161.126932)
		(mid 285.877 -160.813242)
		(end 285.56331 -159.87268)
		(stroke
			(width 0.2)
			(type default)
		)
		(layer "In8.Cu")
	)
	(gr_line
		(start 285.436564 -356.456234)
		(end 286.836612 -356.456234)
		(stroke
			(width 0.2)
			(type default)
		)
		(layer "In8.Cu")
	)
	(gr_arc
		(start 285.436564 -355.353874)
		(mid 284.885384 -355.905054)
		(end 285.436564 -356.456234)
		(stroke
			(width 0.2)
			(type default)
		)
		(layer "In8.Cu")
	)
	(gr_line
		(start 285.436564 -352.856292)
		(end 286.836612 -352.856292)
		(stroke
			(width 0.2)
			(type default)
		)
		(layer "In8.Cu")
	)
	(gr_arc
		(start 285.436564 -351.753932)
		(mid 284.885384 -352.305112)
		(end 285.436564 -352.856292)
		(stroke
			(width 0.2)
			(type default)
		)
		(layer "In8.Cu")
	)
	(gr_line
		(start 285.436564 -349.25635)
		(end 286.836612 -349.25635)
		(stroke
			(width 0.2)
			(type default)
		)
		(layer "In8.Cu")
	)
	(gr_arc
		(start 285.436564 -348.15399)
		(mid 284.885384 -348.70517)
		(end 285.436564 -349.25635)
		(stroke
			(width 0.2)
			(type default)
		)
		(layer "In8.Cu")
	)
	(gr_line
		(start 285.436564 -345.653868)
		(end 286.836612 -345.653868)
		(stroke
			(width 0.2)
			(type default)
		)
		(layer "In8.Cu")
	)
	(gr_arc
		(start 285.436564 -344.556588)
		(mid 284.887924 -345.105228)
		(end 285.436564 -345.653868)
		(stroke
			(width 0.2)
			(type default)
		)
		(layer "In8.Cu")
	)
	(gr_line
		(start 285.436564 -342.053672)
		(end 286.836612 -342.053672)
		(stroke
			(width 0.2)
			(type default)
		)
		(layer "In8.Cu")
	)
	(gr_arc
		(start 285.436564 -340.956392)
		(mid 284.887924 -341.505032)
		(end 285.436564 -342.053672)
		(stroke
			(width 0.2)
			(type default)
		)
		(layer "In8.Cu")
	)
	(gr_line
		(start 285.436564 -338.45373)
		(end 286.836612 -338.45373)
		(stroke
			(width 0.2)
			(type default)
		)
		(layer "In8.Cu")
	)
	(gr_arc
		(start 285.436564 -337.35645)
		(mid 284.887924 -337.90509)
		(end 285.436564 -338.45373)
		(stroke
			(width 0.2)
			(type default)
		)
		(layer "In8.Cu")
	)
	(gr_line
		(start 285.436564 -334.856328)
		(end 286.836612 -334.856328)
		(stroke
			(width 0.2)
			(type default)
		)
		(layer "In8.Cu")
	)
	(gr_arc
		(start 285.436564 -333.753968)
		(mid 284.885384 -334.305148)
		(end 285.436564 -334.856328)
		(stroke
			(width 0.2)
			(type default)
		)
		(layer "In8.Cu")
	)
	(gr_line
		(start 285.436564 -331.256386)
		(end 286.836612 -331.256386)
		(stroke
			(width 0.2)
			(type default)
		)
		(layer "In8.Cu")
	)
	(gr_arc
		(start 285.436564 -330.154026)
		(mid 284.885384 -330.705206)
		(end 285.436564 -331.256386)
		(stroke
			(width 0.2)
			(type default)
		)
		(layer "In8.Cu")
	)
	(gr_line
		(start 285.436564 -327.656444)
		(end 286.836612 -327.656444)
		(stroke
			(width 0.2)
			(type default)
		)
		(layer "In8.Cu")
	)
	(gr_arc
		(start 285.436564 -326.554084)
		(mid 284.885384 -327.105264)
		(end 285.436564 -327.656444)
		(stroke
			(width 0.2)
			(type default)
		)
		(layer "In8.Cu")
	)
	(gr_line
		(start 285.436564 -324.053708)
		(end 286.836612 -324.053708)
		(stroke
			(width 0.2)
			(type default)
		)
		(layer "In8.Cu")
	)
	(gr_arc
		(start 285.436564 -322.956428)
		(mid 284.887924 -323.505068)
		(end 285.436564 -324.053708)
		(stroke
			(width 0.2)
			(type default)
		)
		(layer "In8.Cu")
	)
	(gr_line
		(start 285.436564 -320.453766)
		(end 286.836612 -320.453766)
		(stroke
			(width 0.2)
			(type default)
		)
		(layer "In8.Cu")
	)
	(gr_arc
		(start 285.436564 -319.356486)
		(mid 284.887924 -319.905126)
		(end 285.436564 -320.453766)
		(stroke
			(width 0.2)
			(type default)
		)
		(layer "In8.Cu")
	)
	(gr_line
		(start 285.436564 -316.853824)
		(end 286.836612 -316.853824)
		(stroke
			(width 0.2)
			(type default)
		)
		(layer "In8.Cu")
	)
	(gr_arc
		(start 285.436564 -315.756544)
		(mid 284.887924 -316.305184)
		(end 285.436564 -316.853824)
		(stroke
			(width 0.2)
			(type default)
		)
		(layer "In8.Cu")
	)
	(gr_line
		(start 285.436564 -313.256422)
		(end 286.836612 -313.256422)
		(stroke
			(width 0.2)
			(type default)
		)
		(layer "In8.Cu")
	)
	(gr_arc
		(start 285.436564 -312.154062)
		(mid 284.885384 -312.705242)
		(end 285.436564 -313.256422)
		(stroke
			(width 0.2)
			(type default)
		)
		(layer "In8.Cu")
	)
	(gr_line
		(start 285.436564 -309.656226)
		(end 286.836612 -309.656226)
		(stroke
			(width 0.2)
			(type default)
		)
		(layer "In8.Cu")
	)
	(gr_arc
		(start 285.436564 -308.553866)
		(mid 284.885384 -309.105046)
		(end 285.436564 -309.656226)
		(stroke
			(width 0.2)
			(type default)
		)
		(layer "In8.Cu")
	)
	(gr_line
		(start 285.436564 -306.056284)
		(end 286.836612 -306.056284)
		(stroke
			(width 0.2)
			(type default)
		)
		(layer "In8.Cu")
	)
	(gr_arc
		(start 285.436564 -304.953924)
		(mid 284.885384 -305.505104)
		(end 285.436564 -306.056284)
		(stroke
			(width 0.2)
			(type default)
		)
		(layer "In8.Cu")
	)
	(gr_line
		(start 285.436564 -302.453802)
		(end 286.836612 -302.453802)
		(stroke
			(width 0.2)
			(type default)
		)
		(layer "In8.Cu")
	)
	(gr_arc
		(start 285.436564 -301.356522)
		(mid 284.887924 -301.905162)
		(end 285.436564 -302.453802)
		(stroke
			(width 0.2)
			(type default)
		)
		(layer "In8.Cu")
	)
	(gr_line
		(start 285.436564 -298.85386)
		(end 286.836612 -298.85386)
		(stroke
			(width 0.2)
			(type default)
		)
		(layer "In8.Cu")
	)
	(gr_arc
		(start 285.436564 -297.75658)
		(mid 284.887924 -298.30522)
		(end 285.436564 -298.85386)
		(stroke
			(width 0.2)
			(type default)
		)
		(layer "In8.Cu")
	)
	(gr_line
		(start 285.436564 -295.256458)
		(end 286.836612 -295.256458)
		(stroke
			(width 0.2)
			(type default)
		)
		(layer "In8.Cu")
	)
	(gr_arc
		(start 285.436564 -294.154098)
		(mid 284.885384 -294.705278)
		(end 285.436564 -295.256458)
		(stroke
			(width 0.2)
			(type default)
		)
		(layer "In8.Cu")
	)
	(gr_line
		(start 285.436564 -262.453374)
		(end 286.836612 -262.453374)
		(stroke
			(width 0.2)
			(type default)
		)
		(layer "In8.Cu")
	)
	(gr_arc
		(start 285.436564 -261.351014)
		(mid 284.885384 -261.902194)
		(end 285.436564 -262.453374)
		(stroke
			(width 0.2)
			(type default)
		)
		(layer "In8.Cu")
	)
	(gr_line
		(start 285.436564 -258.853432)
		(end 286.836612 -258.853432)
		(stroke
			(width 0.2)
			(type default)
		)
		(layer "In8.Cu")
	)
	(gr_arc
		(start 285.436564 -257.751072)
		(mid 284.885384 -258.302252)
		(end 285.436564 -258.853432)
		(stroke
			(width 0.2)
			(type default)
		)
		(layer "In8.Cu")
	)
	(gr_line
		(start 285.436564 -255.25349)
		(end 286.836612 -255.25349)
		(stroke
			(width 0.2)
			(type default)
		)
		(layer "In8.Cu")
	)
	(gr_arc
		(start 285.436564 -254.15113)
		(mid 284.885384 -254.70231)
		(end 285.436564 -255.25349)
		(stroke
			(width 0.2)
			(type default)
		)
		(layer "In8.Cu")
	)
	(gr_line
		(start 285.436564 -251.653548)
		(end 286.836612 -251.653548)
		(stroke
			(width 0.2)
			(type default)
		)
		(layer "In8.Cu")
	)
	(gr_arc
		(start 285.436564 -250.551188)
		(mid 284.885384 -251.102368)
		(end 285.436564 -251.653548)
		(stroke
			(width 0.2)
			(type default)
		)
		(layer "In8.Cu")
	)
	(gr_line
		(start 285.436818 -355.353874)
		(end 285.436564 -355.353874)
		(stroke
			(width 0.2)
			(type default)
		)
		(layer "In8.Cu")
	)
	(gr_line
		(start 285.436818 -351.753932)
		(end 285.436564 -351.753932)
		(stroke
			(width 0.2)
			(type default)
		)
		(layer "In8.Cu")
	)
	(gr_line
		(start 285.436818 -348.15399)
		(end 285.436564 -348.15399)
		(stroke
			(width 0.2)
			(type default)
		)
		(layer "In8.Cu")
	)
	(gr_line
		(start 285.436818 -344.556588)
		(end 285.436564 -344.556588)
		(stroke
			(width 0.2)
			(type default)
		)
		(layer "In8.Cu")
	)
	(gr_line
		(start 285.436818 -340.956392)
		(end 285.436564 -340.956392)
		(stroke
			(width 0.2)
			(type default)
		)
		(layer "In8.Cu")
	)
	(gr_line
		(start 285.436818 -337.35645)
		(end 285.436564 -337.35645)
		(stroke
			(width 0.2)
			(type default)
		)
		(layer "In8.Cu")
	)
	(gr_line
		(start 285.436818 -333.753968)
		(end 285.436564 -333.753968)
		(stroke
			(width 0.2)
			(type default)
		)
		(layer "In8.Cu")
	)
	(gr_line
		(start 285.436818 -330.154026)
		(end 285.436564 -330.154026)
		(stroke
			(width 0.2)
			(type default)
		)
		(layer "In8.Cu")
	)
	(gr_line
		(start 285.436818 -326.554084)
		(end 285.436564 -326.554084)
		(stroke
			(width 0.2)
			(type default)
		)
		(layer "In8.Cu")
	)
	(gr_line
		(start 285.436818 -322.956428)
		(end 285.436564 -322.956428)
		(stroke
			(width 0.2)
			(type default)
		)
		(layer "In8.Cu")
	)
	(gr_line
		(start 285.436818 -319.356486)
		(end 285.436564 -319.356486)
		(stroke
			(width 0.2)
			(type default)
		)
		(layer "In8.Cu")
	)
	(gr_line
		(start 285.436818 -315.756544)
		(end 285.436564 -315.756544)
		(stroke
			(width 0.2)
			(type default)
		)
		(layer "In8.Cu")
	)
	(gr_line
		(start 285.436818 -312.154062)
		(end 285.436564 -312.154062)
		(stroke
			(width 0.2)
			(type default)
		)
		(layer "In8.Cu")
	)
	(gr_line
		(start 285.436818 -308.553866)
		(end 285.436564 -308.553866)
		(stroke
			(width 0.2)
			(type default)
		)
		(layer "In8.Cu")
	)
	(gr_line
		(start 285.436818 -304.953924)
		(end 285.436564 -304.953924)
		(stroke
			(width 0.2)
			(type default)
		)
		(layer "In8.Cu")
	)
	(gr_line
		(start 285.436818 -301.356522)
		(end 285.436564 -301.356522)
		(stroke
			(width 0.2)
			(type default)
		)
		(layer "In8.Cu")
	)
	(gr_line
		(start 285.436818 -297.75658)
		(end 285.436564 -297.75658)
		(stroke
			(width 0.2)
			(type default)
		)
		(layer "In8.Cu")
	)
	(gr_line
		(start 285.436818 -294.154098)
		(end 285.436564 -294.154098)
		(stroke
			(width 0.2)
			(type default)
		)
		(layer "In8.Cu")
	)
	(gr_line
		(start 285.436818 -261.351014)
		(end 285.436564 -261.351014)
		(stroke
			(width 0.2)
			(type default)
		)
		(layer "In8.Cu")
	)
	(gr_line
		(start 285.436818 -257.751072)
		(end 285.436564 -257.751072)
		(stroke
			(width 0.2)
			(type default)
		)
		(layer "In8.Cu")
	)
	(gr_line
		(start 285.436818 -254.15113)
		(end 285.436564 -254.15113)
		(stroke
			(width 0.2)
			(type default)
		)
		(layer "In8.Cu")
	)
	(gr_line
		(start 285.436818 -250.551188)
		(end 285.436564 -250.551188)
		(stroke
			(width 0.2)
			(type default)
		)
		(layer "In8.Cu")
	)
	(gr_line
		(start 285.56331 -179.87264)
		(end 283.563314 -178.872642)
		(stroke
			(width 0.2)
			(type default)
		)
		(layer "In8.Cu")
	)
	(gr_line
		(start 285.56331 -175.872648)
		(end 283.563314 -174.87265)
		(stroke
			(width 0.2)
			(type default)
		)
		(layer "In8.Cu")
	)
	(gr_line
		(start 285.56331 -171.872656)
		(end 283.563314 -170.872658)
		(stroke
			(width 0.2)
			(type default)
		)
		(layer "In8.Cu")
	)
	(gr_line
		(start 285.56331 -167.872664)
		(end 283.563314 -166.872666)
		(stroke
			(width 0.2)
			(type default)
		)
		(layer "In8.Cu")
	)
	(gr_line
		(start 285.56331 -163.872672)
		(end 283.563314 -162.872674)
		(stroke
			(width 0.2)
			(type default)
		)
		(layer "In8.Cu")
	)
	(gr_line
		(start 285.56331 -159.87268)
		(end 283.571696 -158.877)
		(stroke
			(width 0.2)
			(type default)
		)
		(layer "In8.Cu")
	)
	(gr_line
		(start 285.56331 -155.872688)
		(end 283.563314 -154.87269)
		(stroke
			(width 0.2)
			(type default)
		)
		(layer "In8.Cu")
	)
	(gr_line
		(start 285.56331 -151.872696)
		(end 283.563314 -150.872698)
		(stroke
			(width 0.2)
			(type default)
		)
		(layer "In8.Cu")
	)
	(gr_line
		(start 285.56331 -127.872744)
		(end 283.563314 -126.872746)
		(stroke
			(width 0.2)
			(type default)
		)
		(layer "In8.Cu")
	)
	(gr_line
		(start 285.56331 -123.872752)
		(end 283.563314 -122.872754)
		(stroke
			(width 0.2)
			(type default)
		)
		(layer "In8.Cu")
	)
	(gr_line
		(start 285.56331 -119.87276)
		(end 283.563314 -118.872762)
		(stroke
			(width 0.2)
			(type default)
		)
		(layer "In8.Cu")
	)
	(gr_line
		(start 285.56331 -115.872768)
		(end 283.563314 -114.87277)
		(stroke
			(width 0.2)
			(type default)
		)
		(layer "In8.Cu")
	)
	(gr_line
		(start 285.56331 -83.572858)
		(end 283.563314 -82.57286)
		(stroke
			(width 0.2)
			(type default)
		)
		(layer "In8.Cu")
	)
	(gr_line
		(start 285.56331 -79.572866)
		(end 283.563314 -78.572868)
		(stroke
			(width 0.2)
			(type default)
		)
		(layer "In8.Cu")
	)
	(gr_line
		(start 285.56331 -75.572874)
		(end 283.563314 -74.572876)
		(stroke
			(width 0.2)
			(type default)
		)
		(layer "In8.Cu")
	)
	(gr_line
		(start 285.56331 -71.572882)
		(end 283.563314 -70.572884)
		(stroke
			(width 0.2)
			(type default)
		)
		(layer "In8.Cu")
	)
	(gr_line
		(start 285.56331 -67.57289)
		(end 283.563314 -66.572892)
		(stroke
			(width 0.2)
			(type default)
		)
		(layer "In8.Cu")
	)
	(gr_line
		(start 285.56331 -63.572898)
		(end 283.563314 -62.5729)
		(stroke
			(width 0.2)
			(type default)
		)
		(layer "In8.Cu")
	)
	(gr_line
		(start 285.56331 -59.572906)
		(end 283.563314 -58.572908)
		(stroke
			(width 0.2)
			(type default)
		)
		(layer "In8.Cu")
	)
	(gr_line
		(start 285.56331 -55.572914)
		(end 283.563314 -54.572916)
		(stroke
			(width 0.2)
			(type default)
		)
		(layer "In8.Cu")
	)
	(gr_line
		(start 285.56331 -51.572922)
		(end 283.563314 -50.572924)
		(stroke
			(width 0.2)
			(type default)
		)
		(layer "In8.Cu")
	)
	(gr_line
		(start 285.56331 -47.57293)
		(end 283.563314 -46.572932)
		(stroke
			(width 0.2)
			(type default)
		)
		(layer "In8.Cu")
	)
	(gr_line
		(start 285.56331 -43.572938)
		(end 283.563314 -42.57294)
		(stroke
			(width 0.2)
			(type default)
		)
		(layer "In8.Cu")
	)
	(gr_line
		(start 285.56331 -39.572946)
		(end 283.563314 -38.572948)
		(stroke
			(width 0.2)
			(type default)
		)
		(layer "In8.Cu")
	)
	(gr_line
		(start 285.57474 -135.850122)
		(end 285.57601 -135.847836)
		(stroke
			(width 0.2)
			(type default)
		)
		(layer "In8.Cu")
	)
	(gr_line
		(start 285.57601 -135.847836)
		(end 283.576014 -134.847838)
		(stroke
			(width 0.2)
			(type default)
		)
		(layer "In8.Cu")
	)
	(gr_line
		(start 285.57601 -107.847892)
		(end 283.576014 -106.847894)
		(stroke
			(width 0.2)
			(type default)
		)
		(layer "In8.Cu")
	)
	(gr_line
		(start 285.577026 -35.545776)
		(end 283.57703 -34.545778)
		(stroke
			(width 0.2)
			(type default)
		)
		(layer "In8.Cu")
	)
	(gr_line
		(start 286.436562 -358.256332)
		(end 287.83661 -358.256332)
		(stroke
			(width 0.2)
			(type default)
		)
		(layer "In8.Cu")
	)
	(gr_arc
		(start 286.436562 -357.153972)
		(mid 285.885382 -357.705152)
		(end 286.436562 -358.256332)
		(stroke
			(width 0.2)
			(type default)
		)
		(layer "In8.Cu")
	)
	(gr_line
		(start 286.436562 -354.65639)
		(end 287.83661 -354.65639)
		(stroke
			(width 0.2)
			(type default)
		)
		(layer "In8.Cu")
	)
	(gr_arc
		(start 286.436562 -353.55403)
		(mid 285.885382 -354.10521)
		(end 286.436562 -354.65639)
		(stroke
			(width 0.2)
			(type default)
		)
		(layer "In8.Cu")
	)
	(gr_line
		(start 286.436562 -351.056448)
		(end 287.83661 -351.056448)
		(stroke
			(width 0.2)
			(type default)
		)
		(layer "In8.Cu")
	)
	(gr_arc
		(start 286.436562 -349.954088)
		(mid 285.885382 -350.505268)
		(end 286.436562 -351.056448)
		(stroke
			(width 0.2)
			(type default)
		)
		(layer "In8.Cu")
	)
	(gr_line
		(start 286.436562 -347.453712)
		(end 287.83661 -347.453712)
		(stroke
			(width 0.2)
			(type default)
		)
		(layer "In8.Cu")
	)
	(gr_arc
		(start 286.436562 -346.356432)
		(mid 285.887922 -346.905072)
		(end 286.436562 -347.453712)
		(stroke
			(width 0.2)
			(type default)
		)
		(layer "In8.Cu")
	)
	(gr_line
		(start 286.436562 -343.85377)
		(end 287.83661 -343.85377)
		(stroke
			(width 0.2)
			(type default)
		)
		(layer "In8.Cu")
	)
	(gr_arc
		(start 286.436562 -342.75649)
		(mid 285.887922 -343.30513)
		(end 286.436562 -343.85377)
		(stroke
			(width 0.2)
			(type default)
		)
		(layer "In8.Cu")
	)
	(gr_line
		(start 286.436562 -340.253828)
		(end 287.83661 -340.253828)
		(stroke
			(width 0.2)
			(type default)
		)
		(layer "In8.Cu")
	)
	(gr_arc
		(start 286.436562 -339.156548)
		(mid 285.887922 -339.705188)
		(end 286.436562 -340.253828)
		(stroke
			(width 0.2)
			(type default)
		)
		(layer "In8.Cu")
	)
	(gr_line
		(start 286.436562 -336.656426)
		(end 287.83661 -336.656426)
		(stroke
			(width 0.2)
			(type default)
		)
		(layer "In8.Cu")
	)
	(gr_arc
		(start 286.436562 -335.554066)
		(mid 285.885382 -336.105246)
		(end 286.436562 -336.656426)
		(stroke
			(width 0.2)
			(type default)
		)
		(layer "In8.Cu")
	)
	(gr_line
		(start 286.436562 -333.05623)
		(end 287.83661 -333.05623)
		(stroke
			(width 0.2)
			(type default)
		)
		(layer "In8.Cu")
	)
	(gr_arc
		(start 286.436562 -331.95387)
		(mid 285.885382 -332.50505)
		(end 286.436562 -333.05623)
		(stroke
			(width 0.2)
			(type default)
		)
		(layer "In8.Cu")
	)
	(gr_line
		(start 286.436562 -329.456288)
		(end 287.83661 -329.456288)
		(stroke
			(width 0.2)
			(type default)
		)
		(layer "In8.Cu")
	)
	(gr_arc
		(start 286.436562 -328.353928)
		(mid 285.885382 -328.905108)
		(end 286.436562 -329.456288)
		(stroke
			(width 0.2)
			(type default)
		)
		(layer "In8.Cu")
	)
	(gr_line
		(start 286.436562 -325.853806)
		(end 287.83661 -325.853806)
		(stroke
			(width 0.2)
			(type default)
		)
		(layer "In8.Cu")
	)
	(gr_arc
		(start 286.436562 -324.756526)
		(mid 285.887922 -325.305166)
		(end 286.436562 -325.853806)
		(stroke
			(width 0.2)
			(type default)
		)
		(layer "In8.Cu")
	)
	(gr_line
		(start 286.436562 -322.253864)
		(end 287.83661 -322.253864)
		(stroke
			(width 0.2)
			(type default)
		)
		(layer "In8.Cu")
	)
	(gr_arc
		(start 286.436562 -321.156584)
		(mid 285.887922 -321.705224)
		(end 286.436562 -322.253864)
		(stroke
			(width 0.2)
			(type default)
		)
		(layer "In8.Cu")
	)
	(gr_line
		(start 286.436562 -318.653668)
		(end 287.83661 -318.653668)
		(stroke
			(width 0.2)
			(type default)
		)
		(layer "In8.Cu")
	)
	(gr_arc
		(start 286.436562 -317.556388)
		(mid 285.887922 -318.105028)
		(end 286.436562 -318.653668)
		(stroke
			(width 0.2)
			(type default)
		)
		(layer "In8.Cu")
	)
	(gr_line
		(start 286.436562 -315.056266)
		(end 287.83661 -315.056266)
		(stroke
			(width 0.2)
			(type default)
		)
		(layer "In8.Cu")
	)
	(gr_arc
		(start 286.436562 -313.953906)
		(mid 285.885382 -314.505086)
		(end 286.436562 -315.056266)
		(stroke
			(width 0.2)
			(type default)
		)
		(layer "In8.Cu")
	)
	(gr_line
		(start 286.436562 -311.456324)
		(end 287.83661 -311.456324)
		(stroke
			(width 0.2)
			(type default)
		)
		(layer "In8.Cu")
	)
	(gr_arc
		(start 286.436562 -310.353964)
		(mid 285.885382 -310.905144)
		(end 286.436562 -311.456324)
		(stroke
			(width 0.2)
			(type default)
		)
		(layer "In8.Cu")
	)
	(gr_line
		(start 286.436562 -307.856382)
		(end 287.83661 -307.856382)
		(stroke
			(width 0.2)
			(type default)
		)
		(layer "In8.Cu")
	)
	(gr_arc
		(start 286.436562 -306.754022)
		(mid 285.885382 -307.305202)
		(end 286.436562 -307.856382)
		(stroke
			(width 0.2)
			(type default)
		)
		(layer "In8.Cu")
	)
	(gr_line
		(start 286.436562 -304.2539)
		(end 287.83661 -304.2539)
		(stroke
			(width 0.2)
			(type default)
		)
		(layer "In8.Cu")
	)
	(gr_arc
		(start 286.436562 -303.15662)
		(mid 285.887922 -303.70526)
		(end 286.436562 -304.2539)
		(stroke
			(width 0.2)
			(type default)
		)
		(layer "In8.Cu")
	)
	(gr_line
		(start 286.436562 -300.653704)
		(end 287.83661 -300.653704)
		(stroke
			(width 0.2)
			(type default)
		)
		(layer "In8.Cu")
	)
	(gr_arc
		(start 286.436562 -299.556424)
		(mid 285.887922 -300.105064)
		(end 286.436562 -300.653704)
		(stroke
			(width 0.2)
			(type default)
		)
		(layer "In8.Cu")
	)
	(gr_line
		(start 286.436562 -297.056302)
		(end 287.83661 -297.056302)
		(stroke
			(width 0.2)
			(type default)
		)
		(layer "In8.Cu")
	)
	(gr_arc
		(start 286.436562 -295.953942)
		(mid 285.885382 -296.505122)
		(end 286.436562 -297.056302)
		(stroke
			(width 0.2)
			(type default)
		)
		(layer "In8.Cu")
	)
	(gr_line
		(start 286.436562 -264.253472)
		(end 287.83661 -264.253472)
		(stroke
			(width 0.2)
			(type default)
		)
		(layer "In8.Cu")
	)
	(gr_arc
		(start 286.436562 -263.151112)
		(mid 285.885382 -263.702292)
		(end 286.436562 -264.253472)
		(stroke
			(width 0.2)
			(type default)
		)
		(layer "In8.Cu")
	)
	(gr_line
		(start 286.436562 -260.65353)
		(end 287.83661 -260.65353)
		(stroke
			(width 0.2)
			(type default)
		)
		(layer "In8.Cu")
	)
	(gr_arc
		(start 286.436562 -259.55117)
		(mid 285.885382 -260.10235)
		(end 286.436562 -260.65353)
		(stroke
			(width 0.2)
			(type default)
		)
		(layer "In8.Cu")
	)
	(gr_line
		(start 286.436562 -257.053588)
		(end 287.83661 -257.053588)
		(stroke
			(width 0.2)
			(type default)
		)
		(layer "In8.Cu")
	)
	(gr_arc
		(start 286.436562 -255.951228)
		(mid 285.885382 -256.502408)
		(end 286.436562 -257.053588)
		(stroke
			(width 0.2)
			(type default)
		)
		(layer "In8.Cu")
	)
	(gr_line
		(start 286.436562 -253.453392)
		(end 287.83661 -253.453392)
		(stroke
			(width 0.2)
			(type default)
		)
		(layer "In8.Cu")
	)
	(gr_arc
		(start 286.436562 -252.351032)
		(mid 285.885382 -252.902212)
		(end 286.436562 -253.453392)
		(stroke
			(width 0.2)
			(type default)
		)
		(layer "In8.Cu")
	)
	(gr_line
		(start 286.436816 -357.153972)
		(end 286.436562 -357.153972)
		(stroke
			(width 0.2)
			(type default)
		)
		(layer "In8.Cu")
	)
	(gr_line
		(start 286.436816 -353.55403)
		(end 286.436562 -353.55403)
		(stroke
			(width 0.2)
			(type default)
		)
		(layer "In8.Cu")
	)
	(gr_line
		(start 286.436816 -349.954088)
		(end 286.436562 -349.954088)
		(stroke
			(width 0.2)
			(type default)
		)
		(layer "In8.Cu")
	)
	(gr_line
		(start 286.436816 -346.356432)
		(end 286.436562 -346.356432)
		(stroke
			(width 0.2)
			(type default)
		)
		(layer "In8.Cu")
	)
	(gr_line
		(start 286.436816 -342.75649)
		(end 286.436562 -342.75649)
		(stroke
			(width 0.2)
			(type default)
		)
		(layer "In8.Cu")
	)
	(gr_line
		(start 286.436816 -339.156548)
		(end 286.436562 -339.156548)
		(stroke
			(width 0.2)
			(type default)
		)
		(layer "In8.Cu")
	)
	(gr_line
		(start 286.436816 -335.554066)
		(end 286.436562 -335.554066)
		(stroke
			(width 0.2)
			(type default)
		)
		(layer "In8.Cu")
	)
	(gr_line
		(start 286.436816 -331.95387)
		(end 286.436562 -331.95387)
		(stroke
			(width 0.2)
			(type default)
		)
		(layer "In8.Cu")
	)
	(gr_line
		(start 286.436816 -328.353928)
		(end 286.436562 -328.353928)
		(stroke
			(width 0.2)
			(type default)
		)
		(layer "In8.Cu")
	)
	(gr_line
		(start 286.436816 -324.756526)
		(end 286.436562 -324.756526)
		(stroke
			(width 0.2)
			(type default)
		)
		(layer "In8.Cu")
	)
	(gr_line
		(start 286.436816 -321.156584)
		(end 286.436562 -321.156584)
		(stroke
			(width 0.2)
			(type default)
		)
		(layer "In8.Cu")
	)
	(gr_line
		(start 286.436816 -317.556388)
		(end 286.436562 -317.556388)
		(stroke
			(width 0.2)
			(type default)
		)
		(layer "In8.Cu")
	)
	(gr_line
		(start 286.436816 -313.953906)
		(end 286.436562 -313.953906)
		(stroke
			(width 0.2)
			(type default)
		)
		(layer "In8.Cu")
	)
	(gr_line
		(start 286.436816 -310.353964)
		(end 286.436562 -310.353964)
		(stroke
			(width 0.2)
			(type default)
		)
		(layer "In8.Cu")
	)
	(gr_line
		(start 286.436816 -306.754022)
		(end 286.436562 -306.754022)
		(stroke
			(width 0.2)
			(type default)
		)
		(layer "In8.Cu")
	)
	(gr_line
		(start 286.436816 -303.15662)
		(end 286.436562 -303.15662)
		(stroke
			(width 0.2)
			(type default)
		)
		(layer "In8.Cu")
	)
	(gr_line
		(start 286.436816 -299.556424)
		(end 286.436562 -299.556424)
		(stroke
			(width 0.2)
			(type default)
		)
		(layer "In8.Cu")
	)
	(gr_line
		(start 286.436816 -295.953942)
		(end 286.436562 -295.953942)
		(stroke
			(width 0.2)
			(type default)
		)
		(layer "In8.Cu")
	)
	(gr_line
		(start 286.436816 -263.151112)
		(end 286.436562 -263.151112)
		(stroke
			(width 0.2)
			(type default)
		)
		(layer "In8.Cu")
	)
	(gr_line
		(start 286.436816 -259.55117)
		(end 286.436562 -259.55117)
		(stroke
			(width 0.2)
			(type default)
		)
		(layer "In8.Cu")
	)
	(gr_line
		(start 286.436816 -255.951228)
		(end 286.436562 -255.951228)
		(stroke
			(width 0.2)
			(type default)
		)
		(layer "In8.Cu")
	)
	(gr_line
		(start 286.436816 -252.351032)
		(end 286.436562 -252.351032)
		(stroke
			(width 0.2)
			(type default)
		)
		(layer "In8.Cu")
	)
	(gr_arc
		(start 286.836612 -356.456234)
		(mid 287.387792 -355.905054)
		(end 286.836612 -355.353874)
		(stroke
			(width 0.2)
			(type default)
		)
		(layer "In8.Cu")
	)
	(gr_line
		(start 286.836612 -355.353874)
		(end 285.436818 -355.353874)
		(stroke
			(width 0.2)
			(type default)
		)
		(layer "In8.Cu")
	)
	(gr_arc
		(start 286.836612 -352.856292)
		(mid 287.387792 -352.305112)
		(end 286.836612 -351.753932)
		(stroke
			(width 0.2)
			(type default)
		)
		(layer "In8.Cu")
	)
	(gr_line
		(start 286.836612 -351.753932)
		(end 285.436818 -351.753932)
		(stroke
			(width 0.2)
			(type default)
		)
		(layer "In8.Cu")
	)
	(gr_arc
		(start 286.836612 -349.25635)
		(mid 287.387792 -348.70517)
		(end 286.836612 -348.15399)
		(stroke
			(width 0.2)
			(type default)
		)
		(layer "In8.Cu")
	)
	(gr_line
		(start 286.836612 -348.15399)
		(end 285.436818 -348.15399)
		(stroke
			(width 0.2)
			(type default)
		)
		(layer "In8.Cu")
	)
	(gr_arc
		(start 286.836612 -345.653868)
		(mid 287.385252 -345.105228)
		(end 286.836612 -344.556588)
		(stroke
			(width 0.2)
			(type default)
		)
		(layer "In8.Cu")
	)
	(gr_line
		(start 286.836612 -344.556588)
		(end 285.436818 -344.556588)
		(stroke
			(width 0.2)
			(type default)
		)
		(layer "In8.Cu")
	)
	(gr_arc
		(start 286.836612 -342.053672)
		(mid 287.385252 -341.505032)
		(end 286.836612 -340.956392)
		(stroke
			(width 0.2)
			(type default)
		)
		(layer "In8.Cu")
	)
	(gr_line
		(start 286.836612 -340.956392)
		(end 285.436818 -340.956392)
		(stroke
			(width 0.2)
			(type default)
		)
		(layer "In8.Cu")
	)
	(gr_arc
		(start 286.836612 -338.45373)
		(mid 287.385252 -337.90509)
		(end 286.836612 -337.35645)
		(stroke
			(width 0.2)
			(type default)
		)
		(layer "In8.Cu")
	)
	(gr_line
		(start 286.836612 -337.35645)
		(end 285.436818 -337.35645)
		(stroke
			(width 0.2)
			(type default)
		)
		(layer "In8.Cu")
	)
	(gr_arc
		(start 286.836612 -334.856328)
		(mid 287.387792 -334.305148)
		(end 286.836612 -333.753968)
		(stroke
			(width 0.2)
			(type default)
		)
		(layer "In8.Cu")
	)
	(gr_line
		(start 286.836612 -333.753968)
		(end 285.436818 -333.753968)
		(stroke
			(width 0.2)
			(type default)
		)
		(layer "In8.Cu")
	)
	(gr_arc
		(start 286.836612 -331.256386)
		(mid 287.387792 -330.705206)
		(end 286.836612 -330.154026)
		(stroke
			(width 0.2)
			(type default)
		)
		(layer "In8.Cu")
	)
	(gr_line
		(start 286.836612 -330.154026)
		(end 285.436818 -330.154026)
		(stroke
			(width 0.2)
			(type default)
		)
		(layer "In8.Cu")
	)
	(gr_arc
		(start 286.836612 -327.656444)
		(mid 287.387792 -327.105264)
		(end 286.836612 -326.554084)
		(stroke
			(width 0.2)
			(type default)
		)
		(layer "In8.Cu")
	)
	(gr_line
		(start 286.836612 -326.554084)
		(end 285.436818 -326.554084)
		(stroke
			(width 0.2)
			(type default)
		)
		(layer "In8.Cu")
	)
	(gr_arc
		(start 286.836612 -324.053708)
		(mid 287.385252 -323.505068)
		(end 286.836612 -322.956428)
		(stroke
			(width 0.2)
			(type default)
		)
		(layer "In8.Cu")
	)
	(gr_line
		(start 286.836612 -322.956428)
		(end 285.436818 -322.956428)
		(stroke
			(width 0.2)
			(type default)
		)
		(layer "In8.Cu")
	)
	(gr_arc
		(start 286.836612 -320.453766)
		(mid 287.385252 -319.905126)
		(end 286.836612 -319.356486)
		(stroke
			(width 0.2)
			(type default)
		)
		(layer "In8.Cu")
	)
	(gr_line
		(start 286.836612 -319.356486)
		(end 285.436818 -319.356486)
		(stroke
			(width 0.2)
			(type default)
		)
		(layer "In8.Cu")
	)
	(gr_arc
		(start 286.836612 -316.853824)
		(mid 287.385252 -316.305184)
		(end 286.836612 -315.756544)
		(stroke
			(width 0.2)
			(type default)
		)
		(layer "In8.Cu")
	)
	(gr_line
		(start 286.836612 -315.756544)
		(end 285.436818 -315.756544)
		(stroke
			(width 0.2)
			(type default)
		)
		(layer "In8.Cu")
	)
	(gr_arc
		(start 286.836612 -313.256422)
		(mid 287.387792 -312.705242)
		(end 286.836612 -312.154062)
		(stroke
			(width 0.2)
			(type default)
		)
		(layer "In8.Cu")
	)
	(gr_line
		(start 286.836612 -312.154062)
		(end 285.436818 -312.154062)
		(stroke
			(width 0.2)
			(type default)
		)
		(layer "In8.Cu")
	)
	(gr_arc
		(start 286.836612 -309.656226)
		(mid 287.387792 -309.105046)
		(end 286.836612 -308.553866)
		(stroke
			(width 0.2)
			(type default)
		)
		(layer "In8.Cu")
	)
	(gr_line
		(start 286.836612 -308.553866)
		(end 285.436818 -308.553866)
		(stroke
			(width 0.2)
			(type default)
		)
		(layer "In8.Cu")
	)
	(gr_arc
		(start 286.836612 -306.056284)
		(mid 287.387792 -305.505104)
		(end 286.836612 -304.953924)
		(stroke
			(width 0.2)
			(type default)
		)
		(layer "In8.Cu")
	)
	(gr_line
		(start 286.836612 -304.953924)
		(end 285.436818 -304.953924)
		(stroke
			(width 0.2)
			(type default)
		)
		(layer "In8.Cu")
	)
	(gr_arc
		(start 286.836612 -302.453802)
		(mid 287.385252 -301.905162)
		(end 286.836612 -301.356522)
		(stroke
			(width 0.2)
			(type default)
		)
		(layer "In8.Cu")
	)
	(gr_line
		(start 286.836612 -301.356522)
		(end 285.436818 -301.356522)
		(stroke
			(width 0.2)
			(type default)
		)
		(layer "In8.Cu")
	)
	(gr_arc
		(start 286.836612 -298.85386)
		(mid 287.385252 -298.30522)
		(end 286.836612 -297.75658)
		(stroke
			(width 0.2)
			(type default)
		)
		(layer "In8.Cu")
	)
	(gr_line
		(start 286.836612 -297.75658)
		(end 285.436818 -297.75658)
		(stroke
			(width 0.2)
			(type default)
		)
		(layer "In8.Cu")
	)
	(gr_arc
		(start 286.836612 -295.256458)
		(mid 287.387792 -294.705278)
		(end 286.836612 -294.154098)
		(stroke
			(width 0.2)
			(type default)
		)
		(layer "In8.Cu")
	)
	(gr_line
		(start 286.836612 -294.154098)
		(end 285.436818 -294.154098)
		(stroke
			(width 0.2)
			(type default)
		)
		(layer "In8.Cu")
	)
	(gr_arc
		(start 286.836612 -262.453374)
		(mid 287.387792 -261.902194)
		(end 286.836612 -261.351014)
		(stroke
			(width 0.2)
			(type default)
		)
		(layer "In8.Cu")
	)
	(gr_line
		(start 286.836612 -261.351014)
		(end 285.436818 -261.351014)
		(stroke
			(width 0.2)
			(type default)
		)
		(layer "In8.Cu")
	)
	(gr_arc
		(start 286.836612 -258.853432)
		(mid 287.387792 -258.302252)
		(end 286.836612 -257.751072)
		(stroke
			(width 0.2)
			(type default)
		)
		(layer "In8.Cu")
	)
	(gr_line
		(start 286.836612 -257.751072)
		(end 285.436818 -257.751072)
		(stroke
			(width 0.2)
			(type default)
		)
		(layer "In8.Cu")
	)
	(gr_arc
		(start 286.836612 -255.25349)
		(mid 287.387792 -254.70231)
		(end 286.836612 -254.15113)
		(stroke
			(width 0.2)
			(type default)
		)
		(layer "In8.Cu")
	)
	(gr_line
		(start 286.836612 -254.15113)
		(end 285.436818 -254.15113)
		(stroke
			(width 0.2)
			(type default)
		)
		(layer "In8.Cu")
	)
	(gr_arc
		(start 286.836612 -251.653548)
		(mid 287.387792 -251.102368)
		(end 286.836612 -250.551188)
		(stroke
			(width 0.2)
			(type default)
		)
		(layer "In8.Cu")
	)
	(gr_line
		(start 286.836612 -250.551188)
		(end 285.436818 -250.551188)
		(stroke
			(width 0.2)
			(type default)
		)
		(layer "In8.Cu")
	)
	(gr_arc
		(start 287.83661 -358.256332)
		(mid 288.38779 -357.705152)
		(end 287.83661 -357.153972)
		(stroke
			(width 0.2)
			(type default)
		)
		(layer "In8.Cu")
	)
	(gr_line
		(start 287.83661 -357.153972)
		(end 286.436816 -357.153972)
		(stroke
			(width 0.2)
			(type default)
		)
		(layer "In8.Cu")
	)
	(gr_arc
		(start 287.83661 -354.65639)
		(mid 288.38779 -354.10521)
		(end 287.83661 -353.55403)
		(stroke
			(width 0.2)
			(type default)
		)
		(layer "In8.Cu")
	)
	(gr_line
		(start 287.83661 -353.55403)
		(end 286.436816 -353.55403)
		(stroke
			(width 0.2)
			(type default)
		)
		(layer "In8.Cu")
	)
	(gr_arc
		(start 287.83661 -351.056448)
		(mid 288.38779 -350.505268)
		(end 287.83661 -349.954088)
		(stroke
			(width 0.2)
			(type default)
		)
		(layer "In8.Cu")
	)
	(gr_line
		(start 287.83661 -349.954088)
		(end 286.436816 -349.954088)
		(stroke
			(width 0.2)
			(type default)
		)
		(layer "In8.Cu")
	)
	(gr_arc
		(start 287.83661 -347.453712)
		(mid 288.38525 -346.905072)
		(end 287.83661 -346.356432)
		(stroke
			(width 0.2)
			(type default)
		)
		(layer "In8.Cu")
	)
	(gr_line
		(start 287.83661 -346.356432)
		(end 286.436816 -346.356432)
		(stroke
			(width 0.2)
			(type default)
		)
		(layer "In8.Cu")
	)
	(gr_arc
		(start 287.83661 -343.85377)
		(mid 288.38525 -343.30513)
		(end 287.83661 -342.75649)
		(stroke
			(width 0.2)
			(type default)
		)
		(layer "In8.Cu")
	)
	(gr_line
		(start 287.83661 -342.75649)
		(end 286.436816 -342.75649)
		(stroke
			(width 0.2)
			(type default)
		)
		(layer "In8.Cu")
	)
	(gr_arc
		(start 287.83661 -340.253828)
		(mid 288.38525 -339.705188)
		(end 287.83661 -339.156548)
		(stroke
			(width 0.2)
			(type default)
		)
		(layer "In8.Cu")
	)
	(gr_line
		(start 287.83661 -339.156548)
		(end 286.436816 -339.156548)
		(stroke
			(width 0.2)
			(type default)
		)
		(layer "In8.Cu")
	)
	(gr_arc
		(start 287.83661 -336.656426)
		(mid 288.38779 -336.105246)
		(end 287.83661 -335.554066)
		(stroke
			(width 0.2)
			(type default)
		)
		(layer "In8.Cu")
	)
	(gr_line
		(start 287.83661 -335.554066)
		(end 286.436816 -335.554066)
		(stroke
			(width 0.2)
			(type default)
		)
		(layer "In8.Cu")
	)
	(gr_arc
		(start 287.83661 -333.05623)
		(mid 288.38779 -332.50505)
		(end 287.83661 -331.95387)
		(stroke
			(width 0.2)
			(type default)
		)
		(layer "In8.Cu")
	)
	(gr_line
		(start 287.83661 -331.95387)
		(end 286.436816 -331.95387)
		(stroke
			(width 0.2)
			(type default)
		)
		(layer "In8.Cu")
	)
	(gr_arc
		(start 287.83661 -329.456288)
		(mid 288.38779 -328.905108)
		(end 287.83661 -328.353928)
		(stroke
			(width 0.2)
			(type default)
		)
		(layer "In8.Cu")
	)
	(gr_line
		(start 287.83661 -328.353928)
		(end 286.436816 -328.353928)
		(stroke
			(width 0.2)
			(type default)
		)
		(layer "In8.Cu")
	)
	(gr_arc
		(start 287.83661 -325.853806)
		(mid 288.38525 -325.305166)
		(end 287.83661 -324.756526)
		(stroke
			(width 0.2)
			(type default)
		)
		(layer "In8.Cu")
	)
	(gr_line
		(start 287.83661 -324.756526)
		(end 286.436816 -324.756526)
		(stroke
			(width 0.2)
			(type default)
		)
		(layer "In8.Cu")
	)
	(gr_arc
		(start 287.83661 -322.253864)
		(mid 288.38525 -321.705224)
		(end 287.83661 -321.156584)
		(stroke
			(width 0.2)
			(type default)
		)
		(layer "In8.Cu")
	)
	(gr_line
		(start 287.83661 -321.156584)
		(end 286.436816 -321.156584)
		(stroke
			(width 0.2)
			(type default)
		)
		(layer "In8.Cu")
	)
	(gr_arc
		(start 287.83661 -318.653668)
		(mid 288.38525 -318.105028)
		(end 287.83661 -317.556388)
		(stroke
			(width 0.2)
			(type default)
		)
		(layer "In8.Cu")
	)
	(gr_line
		(start 287.83661 -317.556388)
		(end 286.436816 -317.556388)
		(stroke
			(width 0.2)
			(type default)
		)
		(layer "In8.Cu")
	)
	(gr_arc
		(start 287.83661 -315.056266)
		(mid 288.38779 -314.505086)
		(end 287.83661 -313.953906)
		(stroke
			(width 0.2)
			(type default)
		)
		(layer "In8.Cu")
	)
	(gr_line
		(start 287.83661 -313.953906)
		(end 286.436816 -313.953906)
		(stroke
			(width 0.2)
			(type default)
		)
		(layer "In8.Cu")
	)
	(gr_arc
		(start 287.83661 -311.456324)
		(mid 288.38779 -310.905144)
		(end 287.83661 -310.353964)
		(stroke
			(width 0.2)
			(type default)
		)
		(layer "In8.Cu")
	)
	(gr_line
		(start 287.83661 -310.353964)
		(end 286.436816 -310.353964)
		(stroke
			(width 0.2)
			(type default)
		)
		(layer "In8.Cu")
	)
	(gr_arc
		(start 287.83661 -307.856382)
		(mid 288.38779 -307.305202)
		(end 287.83661 -306.754022)
		(stroke
			(width 0.2)
			(type default)
		)
		(layer "In8.Cu")
	)
	(gr_line
		(start 287.83661 -306.754022)
		(end 286.436816 -306.754022)
		(stroke
			(width 0.2)
			(type default)
		)
		(layer "In8.Cu")
	)
	(gr_arc
		(start 287.83661 -304.2539)
		(mid 288.38525 -303.70526)
		(end 287.83661 -303.15662)
		(stroke
			(width 0.2)
			(type default)
		)
		(layer "In8.Cu")
	)
	(gr_line
		(start 287.83661 -303.15662)
		(end 286.436816 -303.15662)
		(stroke
			(width 0.2)
			(type default)
		)
		(layer "In8.Cu")
	)
	(gr_arc
		(start 287.83661 -300.653704)
		(mid 288.38525 -300.105064)
		(end 287.83661 -299.556424)
		(stroke
			(width 0.2)
			(type default)
		)
		(layer "In8.Cu")
	)
	(gr_line
		(start 287.83661 -299.556424)
		(end 286.436816 -299.556424)
		(stroke
			(width 0.2)
			(type default)
		)
		(layer "In8.Cu")
	)
	(gr_arc
		(start 287.83661 -297.056302)
		(mid 288.38779 -296.505122)
		(end 287.83661 -295.953942)
		(stroke
			(width 0.2)
			(type default)
		)
		(layer "In8.Cu")
	)
	(gr_line
		(start 287.83661 -295.953942)
		(end 286.436816 -295.953942)
		(stroke
			(width 0.2)
			(type default)
		)
		(layer "In8.Cu")
	)
	(gr_arc
		(start 287.83661 -264.253472)
		(mid 288.38779 -263.702292)
		(end 287.83661 -263.151112)
		(stroke
			(width 0.2)
			(type default)
		)
		(layer "In8.Cu")
	)
	(gr_line
		(start 287.83661 -263.151112)
		(end 286.436816 -263.151112)
		(stroke
			(width 0.2)
			(type default)
		)
		(layer "In8.Cu")
	)
	(gr_arc
		(start 287.83661 -260.65353)
		(mid 288.38779 -260.10235)
		(end 287.83661 -259.55117)
		(stroke
			(width 0.2)
			(type default)
		)
		(layer "In8.Cu")
	)
	(gr_line
		(start 287.83661 -259.55117)
		(end 286.436816 -259.55117)
		(stroke
			(width 0.2)
			(type default)
		)
		(layer "In8.Cu")
	)
	(gr_arc
		(start 287.83661 -257.053588)
		(mid 288.38779 -256.502408)
		(end 287.83661 -255.951228)
		(stroke
			(width 0.2)
			(type default)
		)
		(layer "In8.Cu")
	)
	(gr_line
		(start 287.83661 -255.951228)
		(end 286.436816 -255.951228)
		(stroke
			(width 0.2)
			(type default)
		)
		(layer "In8.Cu")
	)
	(gr_arc
		(start 287.83661 -253.453392)
		(mid 288.38779 -252.902212)
		(end 287.83661 -252.351032)
		(stroke
			(width 0.2)
			(type default)
		)
		(layer "In8.Cu")
	)
	(gr_line
		(start 287.83661 -252.351032)
		(end 286.436816 -252.351032)
		(stroke
			(width 0.2)
			(type default)
		)
		(layer "In8.Cu")
	)
	(gr_arc
		(start 295.699942 -373.000016)
		(mid 295.992835 -373.707121)
		(end 296.69994 -374.000014)
		(stroke
			(width 1.524)
			(type default)
		)
		(layer "In8.Cu")
	)
	(gr_line
		(start 295.699942 -350.19996)
		(end 295.699942 -373.000016)
		(stroke
			(width 1.524)
			(type default)
		)
		(layer "In8.Cu")
	)
	(gr_line
		(start 296.69994 -374.000014)
		(end 308.99989 -374.000014)
		(stroke
			(width 1.524)
			(type default)
		)
		(layer "In8.Cu")
	)
	(gr_arc
		(start 296.69994 -349.199962)
		(mid 295.992835 -349.492855)
		(end 295.699942 -350.19996)
		(stroke
			(width 1.524)
			(type default)
		)
		(layer "In8.Cu")
	)
	(gr_arc
		(start 299.999908 0.999998)
		(mid 300.292801 0.292893)
		(end 300.999906 0)
		(stroke
			(width 1.524)
			(type default)
		)
		(layer "In8.Cu")
	)
	(gr_arc
		(start 299.999908 37.800026)
		(mid 299.707007 38.507118)
		(end 298.99991 38.800024)
		(stroke
			(width 1.524)
			(type default)
		)
		(layer "In8.Cu")
	)
	(gr_line
		(start 299.999908 37.800026)
		(end 299.999908 0.999998)
		(stroke
			(width 1.524)
			(type default)
		)
		(layer "In8.Cu")
	)
	(gr_line
		(start 300.999906 0)
		(end 347.000068 0)
		(stroke
			(width 1.524)
			(type default)
		)
		(layer "In8.Cu")
	)
	(gr_line
		(start 308.99989 -421.200072)
		(end 201.000106 -421.200072)
		(stroke
			(width 1.524)
			(type default)
		)
		(layer "In8.Cu")
	)
	(gr_arc
		(start 308.99989 -421.200072)
		(mid 309.706993 -420.907181)
		(end 309.999888 -420.200074)
		(stroke
			(width 1.524)
			(type default)
		)
		(layer "In8.Cu")
	)
	(gr_arc
		(start 309.999888 -375.000012)
		(mid 309.706999 -374.292902)
		(end 308.99989 -374.000014)
		(stroke
			(width 1.524)
			(type default)
		)
		(layer "In8.Cu")
	)
	(gr_line
		(start 309.999888 -375.000012)
		(end 309.999888 -420.200074)
		(stroke
			(width 1.524)
			(type default)
		)
		(layer "In8.Cu")
	)
	(gr_line
		(start 319.2145 -43.008042)
		(end 320.3575 -43.008042)
		(stroke
			(width 0.2)
			(type default)
		)
		(layer "In8.Cu")
	)
	(gr_arc
		(start 319.214754 -42.246042)
		(mid 318.8335 -42.626915)
		(end 319.2145 -43.008042)
		(stroke
			(width 0.2)
			(type default)
		)
		(layer "In8.Cu")
	)
	(gr_arc
		(start 319.56756 -274.511516)
		(mid 319.9892 -274.933156)
		(end 320.41084 -274.511516)
		(stroke
			(width 0.2)
			(type default)
		)
		(layer "In8.Cu")
	)
	(gr_line
		(start 319.56756 -273.368516)
		(end 319.56756 -274.511516)
		(stroke
			(width 0.2)
			(type default)
		)
		(layer "In8.Cu")
	)
	(gr_arc
		(start 319.6082 -159.511238)
		(mid 319.989073 -159.892492)
		(end 320.3702 -159.511492)
		(stroke
			(width 0.2)
			(type default)
		)
		(layer "In8.Cu")
	)
	(gr_line
		(start 319.6082 -158.368492)
		(end 319.6082 -159.511238)
		(stroke
			(width 0.2)
			(type default)
		)
		(layer "In8.Cu")
	)
	(gr_arc
		(start 320.3575 -43.008042)
		(mid 320.7385 -42.627042)
		(end 320.3575 -42.246042)
		(stroke
			(width 0.2)
			(type default)
		)
		(layer "In8.Cu")
	)
	(gr_line
		(start 320.3575 -42.246042)
		(end 319.214754 -42.246042)
		(stroke
			(width 0.2)
			(type default)
		)
		(layer "In8.Cu")
	)
	(gr_line
		(start 320.3702 -159.511492)
		(end 320.3702 -158.368492)
		(stroke
			(width 0.2)
			(type default)
		)
		(layer "In8.Cu")
	)
	(gr_arc
		(start 320.3702 -158.368492)
		(mid 319.9892 -157.987492)
		(end 319.6082 -158.368492)
		(stroke
			(width 0.2)
			(type default)
		)
		(layer "In8.Cu")
	)
	(gr_line
		(start 320.41084 -274.511516)
		(end 320.41084 -273.36877)
		(stroke
			(width 0.2)
			(type default)
		)
		(layer "In8.Cu")
	)
	(gr_arc
		(start 320.41084 -273.36877)
		(mid 319.989327 -272.946876)
		(end 319.56756 -273.368516)
		(stroke
			(width 0.2)
			(type default)
		)
		(layer "In8.Cu")
	)
	(gr_line
		(start 322.6816 -46.818042)
		(end 323.824346 -46.818042)
		(stroke
			(width 0.2)
			(type default)
		)
		(layer "In8.Cu")
	)
	(gr_arc
		(start 322.6816 -46.056042)
		(mid 322.3006 -46.437042)
		(end 322.6816 -46.818042)
		(stroke
			(width 0.2)
			(type default)
		)
		(layer "In8.Cu")
	)
	(gr_arc
		(start 323.824346 -46.818042)
		(mid 324.2056 -46.437169)
		(end 323.8246 -46.056042)
		(stroke
			(width 0.2)
			(type default)
		)
		(layer "In8.Cu")
	)
	(gr_line
		(start 323.8246 -46.056042)
		(end 322.6816 -46.056042)
		(stroke
			(width 0.2)
			(type default)
		)
		(layer "In8.Cu")
	)
	(gr_arc
		(start 324.358 -278.321516)
		(mid 324.739 -278.702516)
		(end 325.12 -278.321516)
		(stroke
			(width 0.2)
			(type default)
		)
		(layer "In8.Cu")
	)
	(gr_line
		(start 324.358 -277.178516)
		(end 324.358 -278.321516)
		(stroke
			(width 0.2)
			(type default)
		)
		(layer "In8.Cu")
	)
	(gr_arc
		(start 324.358 -163.321492)
		(mid 324.739 -163.702492)
		(end 325.12 -163.321492)
		(stroke
			(width 0.2)
			(type default)
		)
		(layer "In8.Cu")
	)
	(gr_line
		(start 324.358 -162.178492)
		(end 324.358 -163.321492)
		(stroke
			(width 0.2)
			(type default)
		)
		(layer "In8.Cu")
	)
	(gr_line
		(start 325.12 -278.321516)
		(end 325.12 -277.17877)
		(stroke
			(width 0.2)
			(type default)
		)
		(layer "In8.Cu")
	)
	(gr_arc
		(start 325.12 -277.17877)
		(mid 324.739127 -276.797516)
		(end 324.358 -277.178516)
		(stroke
			(width 0.2)
			(type default)
		)
		(layer "In8.Cu")
	)
	(gr_line
		(start 325.12 -163.321492)
		(end 325.12 -162.178746)
		(stroke
			(width 0.2)
			(type default)
		)
		(layer "In8.Cu")
	)
	(gr_arc
		(start 325.12 -162.178746)
		(mid 324.739127 -161.797492)
		(end 324.358 -162.178492)
		(stroke
			(width 0.2)
			(type default)
		)
		(layer "In8.Cu")
	)
	(gr_arc
		(start 348.000066 -13.999972)
		(mid 348.292959 -14.707077)
		(end 349.000064 -14.99997)
		(stroke
			(width 1.524)
			(type default)
		)
		(layer "In8.Cu")
	)
	(gr_arc
		(start 348.000066 -0.999998)
		(mid 347.707171 -0.292905)
		(end 347.000068 0)
		(stroke
			(width 1.524)
			(type default)
		)
		(layer "In8.Cu")
	)
	(gr_line
		(start 348.000066 -0.999998)
		(end 348.000066 -13.999972)
		(stroke
			(width 1.524)
			(type default)
		)
		(layer "In8.Cu")
	)
	(gr_line
		(start 349.000064 -14.99997)
		(end 394.999972 -14.99997)
		(stroke
			(width 1.524)
			(type default)
		)
		(layer "In8.Cu")
	)
	(gr_line
		(start 350.764602 -43.013122)
		(end 351.907602 -43.013122)
		(stroke
			(width 0.2)
			(type default)
		)
		(layer "In8.Cu")
	)
	(gr_arc
		(start 350.764856 -42.240962)
		(mid 350.378522 -42.626915)
		(end 350.764602 -43.013122)
		(stroke
			(width 0.2)
			(type default)
		)
		(layer "In8.Cu")
	)
	(gr_arc
		(start 351.158302 -274.511262)
		(mid 351.539175 -274.892516)
		(end 351.920302 -274.511516)
		(stroke
			(width 0.2)
			(type default)
		)
		(layer "In8.Cu")
	)
	(gr_line
		(start 351.158302 -273.368516)
		(end 351.158302 -274.511262)
		(stroke
			(width 0.2)
			(type default)
		)
		(layer "In8.Cu")
	)
	(gr_arc
		(start 351.158302 -159.511238)
		(mid 351.539175 -159.892492)
		(end 351.920302 -159.511492)
		(stroke
			(width 0.2)
			(type default)
		)
		(layer "In8.Cu")
	)
	(gr_line
		(start 351.158302 -158.368492)
		(end 351.158302 -159.511238)
		(stroke
			(width 0.2)
			(type default)
		)
		(layer "In8.Cu")
	)
	(gr_arc
		(start 351.907602 -43.013122)
		(mid 352.293682 -42.627042)
		(end 351.907602 -42.240962)
		(stroke
			(width 0.2)
			(type default)
		)
		(layer "In8.Cu")
	)
	(gr_line
		(start 351.907602 -42.240962)
		(end 350.764856 -42.240962)
		(stroke
			(width 0.2)
			(type default)
		)
		(layer "In8.Cu")
	)
	(gr_line
		(start 351.920302 -274.511516)
		(end 351.920302 -273.368516)
		(stroke
			(width 0.2)
			(type default)
		)
		(layer "In8.Cu")
	)
	(gr_arc
		(start 351.920302 -273.368516)
		(mid 351.539302 -272.987516)
		(end 351.158302 -273.368516)
		(stroke
			(width 0.2)
			(type default)
		)
		(layer "In8.Cu")
	)
	(gr_line
		(start 351.920302 -159.511492)
		(end 351.920302 -158.368492)
		(stroke
			(width 0.2)
			(type default)
		)
		(layer "In8.Cu")
	)
	(gr_arc
		(start 351.920302 -158.368492)
		(mid 351.539302 -157.987492)
		(end 351.158302 -158.368492)
		(stroke
			(width 0.2)
			(type default)
		)
		(layer "In8.Cu")
	)
	(gr_arc
		(start 354.601272 -22.350222)
		(mid 355.149912 -22.898862)
		(end 355.698552 -22.350222)
		(stroke
			(width 0.2)
			(type default)
		)
		(layer "In8.Cu")
	)
	(gr_line
		(start 354.601272 -20.950174)
		(end 354.601272 -22.350222)
		(stroke
			(width 0.2)
			(type default)
		)
		(layer "In8.Cu")
	)
	(gr_arc
		(start 354.601272 -18.750026)
		(mid 355.149912 -19.298666)
		(end 355.698552 -18.750026)
		(stroke
			(width 0.2)
			(type default)
		)
		(layer "In8.Cu")
	)
	(gr_line
		(start 354.601272 -17.349978)
		(end 354.601272 -18.750026)
		(stroke
			(width 0.2)
			(type default)
		)
		(layer "In8.Cu")
	)
	(gr_line
		(start 355.698552 -22.350222)
		(end 355.698552 -20.950428)
		(stroke
			(width 0.2)
			(type default)
		)
		(layer "In8.Cu")
	)
	(gr_arc
		(start 355.698552 -20.950428)
		(mid 355.150039 -20.401534)
		(end 354.601272 -20.950174)
		(stroke
			(width 0.2)
			(type default)
		)
		(layer "In8.Cu")
	)
	(gr_line
		(start 355.698552 -18.750026)
		(end 355.698552 -17.350232)
		(stroke
			(width 0.2)
			(type default)
		)
		(layer "In8.Cu")
	)
	(gr_arc
		(start 355.698552 -17.350232)
		(mid 355.150039 -16.801338)
		(end 354.601272 -17.349978)
		(stroke
			(width 0.2)
			(type default)
		)
		(layer "In8.Cu")
	)
	(gr_arc
		(start 355.903022 -48.321468)
		(mid 356.289102 -48.707548)
		(end 356.675182 -48.321468)
		(stroke
			(width 0.2)
			(type default)
		)
		(layer "In8.Cu")
	)
	(gr_line
		(start 355.903022 -47.178468)
		(end 355.903022 -48.321468)
		(stroke
			(width 0.2)
			(type default)
		)
		(layer "In8.Cu")
	)
	(gr_arc
		(start 355.908102 -278.321516)
		(mid 356.289102 -278.702516)
		(end 356.670102 -278.321516)
		(stroke
			(width 0.2)
			(type default)
		)
		(layer "In8.Cu")
	)
	(gr_line
		(start 355.908102 -277.178516)
		(end 355.908102 -278.321516)
		(stroke
			(width 0.2)
			(type default)
		)
		(layer "In8.Cu")
	)
	(gr_arc
		(start 355.908102 -163.321492)
		(mid 356.289102 -163.702492)
		(end 356.670102 -163.321492)
		(stroke
			(width 0.2)
			(type default)
		)
		(layer "In8.Cu")
	)
	(gr_line
		(start 355.908102 -162.178492)
		(end 355.908102 -163.321492)
		(stroke
			(width 0.2)
			(type default)
		)
		(layer "In8.Cu")
	)
	(gr_arc
		(start 356.40137 -23.35022)
		(mid 356.95001 -23.89886)
		(end 357.49865 -23.35022)
		(stroke
			(width 0.2)
			(type default)
		)
		(layer "In8.Cu")
	)
	(gr_line
		(start 356.40137 -21.950172)
		(end 356.40137 -23.35022)
		(stroke
			(width 0.2)
			(type default)
		)
		(layer "In8.Cu")
	)
	(gr_arc
		(start 356.40137 -19.750024)
		(mid 356.95001 -20.298664)
		(end 357.49865 -19.750024)
		(stroke
			(width 0.2)
			(type default)
		)
		(layer "In8.Cu")
	)
	(gr_line
		(start 356.40137 -18.35023)
		(end 356.40137 -19.750024)
		(stroke
			(width 0.2)
			(type default)
		)
		(layer "In8.Cu")
	)
	(gr_line
		(start 356.670102 -278.321516)
		(end 356.670102 -277.17877)
		(stroke
			(width 0.2)
			(type default)
		)
		(layer "In8.Cu")
	)
	(gr_arc
		(start 356.670102 -277.17877)
		(mid 356.289229 -276.797516)
		(end 355.908102 -277.178516)
		(stroke
			(width 0.2)
			(type default)
		)
		(layer "In8.Cu")
	)
	(gr_line
		(start 356.670102 -163.321492)
		(end 356.670102 -162.178746)
		(stroke
			(width 0.2)
			(type default)
		)
		(layer "In8.Cu")
	)
	(gr_arc
		(start 356.670102 -162.178746)
		(mid 356.289229 -161.797492)
		(end 355.908102 -162.178492)
		(stroke
			(width 0.2)
			(type default)
		)
		(layer "In8.Cu")
	)
	(gr_line
		(start 356.675182 -48.321468)
		(end 356.675182 -47.178722)
		(stroke
			(width 0.2)
			(type default)
		)
		(layer "In8.Cu")
	)
	(gr_arc
		(start 356.675182 -47.178722)
		(mid 356.289229 -46.792388)
		(end 355.903022 -47.178468)
		(stroke
			(width 0.2)
			(type default)
		)
		(layer "In8.Cu")
	)
	(gr_line
		(start 357.49865 -23.35022)
		(end 357.49865 -21.950426)
		(stroke
			(width 0.2)
			(type default)
		)
		(layer "In8.Cu")
	)
	(gr_arc
		(start 357.49865 -21.950426)
		(mid 356.950137 -21.401532)
		(end 356.40137 -21.950172)
		(stroke
			(width 0.2)
			(type default)
		)
		(layer "In8.Cu")
	)
	(gr_line
		(start 357.49865 -19.750024)
		(end 357.49865 -18.350484)
		(stroke
			(width 0.2)
			(type default)
		)
		(layer "In8.Cu")
	)
	(gr_arc
		(start 357.49865 -18.350484)
		(mid 356.950137 -17.80159)
		(end 356.40137 -18.35023)
		(stroke
			(width 0.2)
			(type default)
		)
		(layer "In8.Cu")
	)
	(gr_arc
		(start 358.201468 -22.350222)
		(mid 358.750108 -22.898862)
		(end 359.298748 -22.350222)
		(stroke
			(width 0.2)
			(type default)
		)
		(layer "In8.Cu")
	)
	(gr_line
		(start 358.201468 -20.950174)
		(end 358.201468 -22.350222)
		(stroke
			(width 0.2)
			(type default)
		)
		(layer "In8.Cu")
	)
	(gr_arc
		(start 358.201468 -18.750026)
		(mid 358.750108 -19.298666)
		(end 359.298748 -18.750026)
		(stroke
			(width 0.2)
			(type default)
		)
		(layer "In8.Cu")
	)
	(gr_line
		(start 358.201468 -17.349978)
		(end 358.201468 -18.750026)
		(stroke
			(width 0.2)
			(type default)
		)
		(layer "In8.Cu")
	)
	(gr_line
		(start 359.298748 -22.350222)
		(end 359.298748 -20.950428)
		(stroke
			(width 0.2)
			(type default)
		)
		(layer "In8.Cu")
	)
	(gr_arc
		(start 359.298748 -20.950428)
		(mid 358.750235 -20.401534)
		(end 358.201468 -20.950174)
		(stroke
			(width 0.2)
			(type default)
		)
		(layer "In8.Cu")
	)
	(gr_line
		(start 359.298748 -18.750026)
		(end 359.298748 -17.350232)
		(stroke
			(width 0.2)
			(type default)
		)
		(layer "In8.Cu")
	)
	(gr_arc
		(start 359.298748 -17.350232)
		(mid 358.750235 -16.801338)
		(end 358.201468 -17.349978)
		(stroke
			(width 0.2)
			(type default)
		)
		(layer "In8.Cu")
	)
	(gr_arc
		(start 360.001312 -23.35022)
		(mid 360.549952 -23.89886)
		(end 361.098592 -23.35022)
		(stroke
			(width 0.2)
			(type default)
		)
		(layer "In8.Cu")
	)
	(gr_line
		(start 360.001312 -21.950172)
		(end 360.001312 -23.35022)
		(stroke
			(width 0.2)
			(type default)
		)
		(layer "In8.Cu")
	)
	(gr_arc
		(start 360.001312 -19.750024)
		(mid 360.549952 -20.298664)
		(end 361.098592 -19.750024)
		(stroke
			(width 0.2)
			(type default)
		)
		(layer "In8.Cu")
	)
	(gr_line
		(start 360.001312 -18.35023)
		(end 360.001312 -19.750024)
		(stroke
			(width 0.2)
			(type default)
		)
		(layer "In8.Cu")
	)
	(gr_line
		(start 361.098592 -23.35022)
		(end 361.098592 -21.950426)
		(stroke
			(width 0.2)
			(type default)
		)
		(layer "In8.Cu")
	)
	(gr_arc
		(start 361.098592 -21.950426)
		(mid 360.550079 -21.401532)
		(end 360.001312 -21.950172)
		(stroke
			(width 0.2)
			(type default)
		)
		(layer "In8.Cu")
	)
	(gr_line
		(start 361.098592 -19.750024)
		(end 361.098592 -18.350484)
		(stroke
			(width 0.2)
			(type default)
		)
		(layer "In8.Cu")
	)
	(gr_arc
		(start 361.098592 -18.350484)
		(mid 360.550079 -17.80159)
		(end 360.001312 -18.35023)
		(stroke
			(width 0.2)
			(type default)
		)
		(layer "In8.Cu")
	)
	(gr_arc
		(start 361.80141 -29.550106)
		(mid 362.35005 -30.098746)
		(end 362.89869 -29.550106)
		(stroke
			(width 0.2)
			(type default)
		)
		(layer "In8.Cu")
	)
	(gr_line
		(start 361.80141 -28.150058)
		(end 361.80141 -29.550106)
		(stroke
			(width 0.2)
			(type default)
		)
		(layer "In8.Cu")
	)
	(gr_arc
		(start 361.80141 -22.350222)
		(mid 362.35005 -22.898862)
		(end 362.89869 -22.350222)
		(stroke
			(width 0.2)
			(type default)
		)
		(layer "In8.Cu")
	)
	(gr_line
		(start 361.80141 -20.950174)
		(end 361.80141 -22.350222)
		(stroke
			(width 0.2)
			(type default)
		)
		(layer "In8.Cu")
	)
	(gr_arc
		(start 361.80141 -18.750026)
		(mid 362.35005 -19.298666)
		(end 362.89869 -18.750026)
		(stroke
			(width 0.2)
			(type default)
		)
		(layer "In8.Cu")
	)
	(gr_line
		(start 361.80141 -17.349978)
		(end 361.80141 -18.750026)
		(stroke
			(width 0.2)
			(type default)
		)
		(layer "In8.Cu")
	)
	(gr_line
		(start 362.89869 -29.550106)
		(end 362.89869 -28.150312)
		(stroke
			(width 0.2)
			(type default)
		)
		(layer "In8.Cu")
	)
	(gr_arc
		(start 362.89869 -28.150312)
		(mid 362.350177 -27.601418)
		(end 361.80141 -28.150058)
		(stroke
			(width 0.2)
			(type default)
		)
		(layer "In8.Cu")
	)
	(gr_line
		(start 362.89869 -22.350222)
		(end 362.89869 -20.950428)
		(stroke
			(width 0.2)
			(type default)
		)
		(layer "In8.Cu")
	)
	(gr_arc
		(start 362.89869 -20.950428)
		(mid 362.350177 -20.401534)
		(end 361.80141 -20.950174)
		(stroke
			(width 0.2)
			(type default)
		)
		(layer "In8.Cu")
	)
	(gr_line
		(start 362.89869 -18.750026)
		(end 362.89869 -17.350232)
		(stroke
			(width 0.2)
			(type default)
		)
		(layer "In8.Cu")
	)
	(gr_arc
		(start 362.89869 -17.350232)
		(mid 362.350177 -16.801338)
		(end 361.80141 -17.349978)
		(stroke
			(width 0.2)
			(type default)
		)
		(layer "In8.Cu")
	)
	(gr_arc
		(start 363.601254 -23.35022)
		(mid 364.149894 -23.89886)
		(end 364.698534 -23.35022)
		(stroke
			(width 0.2)
			(type default)
		)
		(layer "In8.Cu")
	)
	(gr_line
		(start 363.601254 -21.950172)
		(end 363.601254 -23.35022)
		(stroke
			(width 0.2)
			(type default)
		)
		(layer "In8.Cu")
	)
	(gr_arc
		(start 363.601254 -19.750024)
		(mid 364.149894 -20.298664)
		(end 364.698534 -19.750024)
		(stroke
			(width 0.2)
			(type default)
		)
		(layer "In8.Cu")
	)
	(gr_line
		(start 363.601254 -18.35023)
		(end 363.601254 -19.750024)
		(stroke
			(width 0.2)
			(type default)
		)
		(layer "In8.Cu")
	)
	(gr_line
		(start 364.698534 -23.35022)
		(end 364.698534 -21.950426)
		(stroke
			(width 0.2)
			(type default)
		)
		(layer "In8.Cu")
	)
	(gr_arc
		(start 364.698534 -21.950426)
		(mid 364.150021 -21.401532)
		(end 363.601254 -21.950172)
		(stroke
			(width 0.2)
			(type default)
		)
		(layer "In8.Cu")
	)
	(gr_line
		(start 364.698534 -19.750024)
		(end 364.698534 -18.350484)
		(stroke
			(width 0.2)
			(type default)
		)
		(layer "In8.Cu")
	)
	(gr_arc
		(start 364.698534 -18.350484)
		(mid 364.150021 -17.80159)
		(end 363.601254 -18.35023)
		(stroke
			(width 0.2)
			(type default)
		)
		(layer "In8.Cu")
	)
	(gr_arc
		(start 365.401352 -22.350222)
		(mid 365.949992 -22.898862)
		(end 366.498632 -22.350222)
		(stroke
			(width 0.2)
			(type default)
		)
		(layer "In8.Cu")
	)
	(gr_line
		(start 365.401352 -20.950174)
		(end 365.401352 -22.350222)
		(stroke
			(width 0.2)
			(type default)
		)
		(layer "In8.Cu")
	)
	(gr_arc
		(start 365.401352 -18.750026)
		(mid 365.949992 -19.298666)
		(end 366.498632 -18.750026)
		(stroke
			(width 0.2)
			(type default)
		)
		(layer "In8.Cu")
	)
	(gr_line
		(start 365.401352 -17.349978)
		(end 365.401352 -18.750026)
		(stroke
			(width 0.2)
			(type default)
		)
		(layer "In8.Cu")
	)
	(gr_line
		(start 366.498632 -22.350222)
		(end 366.498632 -20.950428)
		(stroke
			(width 0.2)
			(type default)
		)
		(layer "In8.Cu")
	)
	(gr_arc
		(start 366.498632 -20.950428)
		(mid 365.950119 -20.401534)
		(end 365.401352 -20.950174)
		(stroke
			(width 0.2)
			(type default)
		)
		(layer "In8.Cu")
	)
	(gr_line
		(start 366.498632 -18.750026)
		(end 366.498632 -17.350232)
		(stroke
			(width 0.2)
			(type default)
		)
		(layer "In8.Cu")
	)
	(gr_arc
		(start 366.498632 -17.350232)
		(mid 365.950119 -16.801338)
		(end 365.401352 -17.349978)
		(stroke
			(width 0.2)
			(type default)
		)
		(layer "In8.Cu")
	)
	(gr_arc
		(start 367.19891 -30.54985)
		(mid 367.749963 -31.101284)
		(end 368.30127 -30.550104)
		(stroke
			(width 0.2)
			(type default)
		)
		(layer "In8.Cu")
	)
	(gr_line
		(start 367.19891 -29.150056)
		(end 367.19891 -30.54985)
		(stroke
			(width 0.2)
			(type default)
		)
		(layer "In8.Cu")
	)
	(gr_arc
		(start 367.20145 -23.35022)
		(mid 367.75009 -23.89886)
		(end 368.29873 -23.35022)
		(stroke
			(width 0.2)
			(type default)
		)
		(layer "In8.Cu")
	)
	(gr_line
		(start 367.20145 -21.950172)
		(end 367.20145 -23.35022)
		(stroke
			(width 0.2)
			(type default)
		)
		(layer "In8.Cu")
	)
	(gr_arc
		(start 367.20145 -19.750024)
		(mid 367.75009 -20.298664)
		(end 368.29873 -19.750024)
		(stroke
			(width 0.2)
			(type default)
		)
		(layer "In8.Cu")
	)
	(gr_line
		(start 367.20145 -18.35023)
		(end 367.20145 -19.750024)
		(stroke
			(width 0.2)
			(type default)
		)
		(layer "In8.Cu")
	)
	(gr_line
		(start 368.29873 -23.35022)
		(end 368.29873 -21.950426)
		(stroke
			(width 0.2)
			(type default)
		)
		(layer "In8.Cu")
	)
	(gr_arc
		(start 368.29873 -21.950426)
		(mid 367.750217 -21.401532)
		(end 367.20145 -21.950172)
		(stroke
			(width 0.2)
			(type default)
		)
		(layer "In8.Cu")
	)
	(gr_line
		(start 368.29873 -19.750024)
		(end 368.29873 -18.350484)
		(stroke
			(width 0.2)
			(type default)
		)
		(layer "In8.Cu")
	)
	(gr_arc
		(start 368.29873 -18.350484)
		(mid 367.750217 -17.80159)
		(end 367.20145 -18.35023)
		(stroke
			(width 0.2)
			(type default)
		)
		(layer "In8.Cu")
	)
	(gr_line
		(start 368.30127 -30.550104)
		(end 368.30127 -29.150056)
		(stroke
			(width 0.2)
			(type default)
		)
		(layer "In8.Cu")
	)
	(gr_arc
		(start 368.30127 -29.150056)
		(mid 367.75009 -28.598876)
		(end 367.19891 -29.150056)
		(stroke
			(width 0.2)
			(type default)
		)
		(layer "In8.Cu")
	)
	(gr_arc
		(start 376.201432 -22.350222)
		(mid 376.750072 -22.898862)
		(end 377.298712 -22.350222)
		(stroke
			(width 0.2)
			(type default)
		)
		(layer "In8.Cu")
	)
	(gr_line
		(start 376.201432 -20.950174)
		(end 376.201432 -22.350222)
		(stroke
			(width 0.2)
			(type default)
		)
		(layer "In8.Cu")
	)
	(gr_arc
		(start 376.201432 -18.750026)
		(mid 376.750072 -19.298666)
		(end 377.298712 -18.750026)
		(stroke
			(width 0.2)
			(type default)
		)
		(layer "In8.Cu")
	)
	(gr_line
		(start 376.201432 -17.349978)
		(end 376.201432 -18.750026)
		(stroke
			(width 0.2)
			(type default)
		)
		(layer "In8.Cu")
	)
	(gr_line
		(start 377.298712 -22.350222)
		(end 377.298712 -20.950428)
		(stroke
			(width 0.2)
			(type default)
		)
		(layer "In8.Cu")
	)
	(gr_arc
		(start 377.298712 -20.950428)
		(mid 376.750199 -20.401534)
		(end 376.201432 -20.950174)
		(stroke
			(width 0.2)
			(type default)
		)
		(layer "In8.Cu")
	)
	(gr_line
		(start 377.298712 -18.750026)
		(end 377.298712 -17.350232)
		(stroke
			(width 0.2)
			(type default)
		)
		(layer "In8.Cu")
	)
	(gr_arc
		(start 377.298712 -17.350232)
		(mid 376.750199 -16.801338)
		(end 376.201432 -17.349978)
		(stroke
			(width 0.2)
			(type default)
		)
		(layer "In8.Cu")
	)
	(gr_arc
		(start 378.001276 -23.35022)
		(mid 378.549916 -23.89886)
		(end 379.098556 -23.35022)
		(stroke
			(width 0.2)
			(type default)
		)
		(layer "In8.Cu")
	)
	(gr_line
		(start 378.001276 -21.950172)
		(end 378.001276 -23.35022)
		(stroke
			(width 0.2)
			(type default)
		)
		(layer "In8.Cu")
	)
	(gr_arc
		(start 378.001276 -19.750024)
		(mid 378.549916 -20.298664)
		(end 379.098556 -19.750024)
		(stroke
			(width 0.2)
			(type default)
		)
		(layer "In8.Cu")
	)
	(gr_line
		(start 378.001276 -18.35023)
		(end 378.001276 -19.750024)
		(stroke
			(width 0.2)
			(type default)
		)
		(layer "In8.Cu")
	)
	(gr_line
		(start 379.098556 -23.35022)
		(end 379.098556 -21.950426)
		(stroke
			(width 0.2)
			(type default)
		)
		(layer "In8.Cu")
	)
	(gr_arc
		(start 379.098556 -21.950426)
		(mid 378.550043 -21.401532)
		(end 378.001276 -21.950172)
		(stroke
			(width 0.2)
			(type default)
		)
		(layer "In8.Cu")
	)
	(gr_line
		(start 379.098556 -19.750024)
		(end 379.098556 -18.350484)
		(stroke
			(width 0.2)
			(type default)
		)
		(layer "In8.Cu")
	)
	(gr_arc
		(start 379.098556 -18.350484)
		(mid 378.550043 -17.80159)
		(end 378.001276 -18.35023)
		(stroke
			(width 0.2)
			(type default)
		)
		(layer "In8.Cu")
	)
	(gr_arc
		(start 379.801374 -22.350222)
		(mid 380.350014 -22.898862)
		(end 380.898654 -22.350222)
		(stroke
			(width 0.2)
			(type default)
		)
		(layer "In8.Cu")
	)
	(gr_line
		(start 379.801374 -20.950174)
		(end 379.801374 -22.350222)
		(stroke
			(width 0.2)
			(type default)
		)
		(layer "In8.Cu")
	)
	(gr_arc
		(start 379.801374 -18.750026)
		(mid 380.350014 -19.298666)
		(end 380.898654 -18.750026)
		(stroke
			(width 0.2)
			(type default)
		)
		(layer "In8.Cu")
	)
	(gr_line
		(start 379.801374 -17.349978)
		(end 379.801374 -18.750026)
		(stroke
			(width 0.2)
			(type default)
		)
		(layer "In8.Cu")
	)
	(gr_line
		(start 380.898654 -22.350222)
		(end 380.898654 -20.950428)
		(stroke
			(width 0.2)
			(type default)
		)
		(layer "In8.Cu")
	)
	(gr_arc
		(start 380.898654 -20.950428)
		(mid 380.350141 -20.401534)
		(end 379.801374 -20.950174)
		(stroke
			(width 0.2)
			(type default)
		)
		(layer "In8.Cu")
	)
	(gr_line
		(start 380.898654 -18.750026)
		(end 380.898654 -17.350232)
		(stroke
			(width 0.2)
			(type default)
		)
		(layer "In8.Cu")
	)
	(gr_arc
		(start 380.898654 -17.350232)
		(mid 380.350141 -16.801338)
		(end 379.801374 -17.349978)
		(stroke
			(width 0.2)
			(type default)
		)
		(layer "In8.Cu")
	)
	(gr_arc
		(start 381.598932 -30.550104)
		(mid 382.150112 -31.101284)
		(end 382.701292 -30.550104)
		(stroke
			(width 0.2)
			(type default)
		)
		(layer "In8.Cu")
	)
	(gr_line
		(start 381.598932 -29.150056)
		(end 381.598932 -30.550104)
		(stroke
			(width 0.2)
			(type default)
		)
		(layer "In8.Cu")
	)
	(gr_arc
		(start 381.601472 -23.35022)
		(mid 382.150112 -23.89886)
		(end 382.698752 -23.35022)
		(stroke
			(width 0.2)
			(type default)
		)
		(layer "In8.Cu")
	)
	(gr_line
		(start 381.601472 -21.950172)
		(end 381.601472 -23.35022)
		(stroke
			(width 0.2)
			(type default)
		)
		(layer "In8.Cu")
	)
	(gr_arc
		(start 381.601472 -19.750024)
		(mid 382.150112 -20.298664)
		(end 382.698752 -19.750024)
		(stroke
			(width 0.2)
			(type default)
		)
		(layer "In8.Cu")
	)
	(gr_line
		(start 381.601472 -18.35023)
		(end 381.601472 -19.750024)
		(stroke
			(width 0.2)
			(type default)
		)
		(layer "In8.Cu")
	)
	(gr_line
		(start 382.698752 -23.35022)
		(end 382.698752 -21.950426)
		(stroke
			(width 0.2)
			(type default)
		)
		(layer "In8.Cu")
	)
	(gr_arc
		(start 382.698752 -21.950426)
		(mid 382.150239 -21.401532)
		(end 381.601472 -21.950172)
		(stroke
			(width 0.2)
			(type default)
		)
		(layer "In8.Cu")
	)
	(gr_line
		(start 382.698752 -19.750024)
		(end 382.698752 -18.350484)
		(stroke
			(width 0.2)
			(type default)
		)
		(layer "In8.Cu")
	)
	(gr_arc
		(start 382.698752 -18.350484)
		(mid 382.150239 -17.80159)
		(end 381.601472 -18.35023)
		(stroke
			(width 0.2)
			(type default)
		)
		(layer "In8.Cu")
	)
	(gr_line
		(start 382.701292 -30.550104)
		(end 382.701292 -29.15031)
		(stroke
			(width 0.2)
			(type default)
		)
		(layer "In8.Cu")
	)
	(gr_arc
		(start 382.701292 -29.15031)
		(mid 382.150239 -28.598876)
		(end 381.598932 -29.150056)
		(stroke
			(width 0.2)
			(type default)
		)
		(layer "In8.Cu")
	)
	(gr_arc
		(start 382.70815 -274.511262)
		(mid 383.089023 -274.892516)
		(end 383.47015 -274.511516)
		(stroke
			(width 0.2)
			(type default)
		)
		(layer "In8.Cu")
	)
	(gr_line
		(start 382.70815 -273.368516)
		(end 382.70815 -274.511262)
		(stroke
			(width 0.2)
			(type default)
		)
		(layer "In8.Cu")
	)
	(gr_arc
		(start 382.70815 -159.511238)
		(mid 383.089023 -159.892492)
		(end 383.47015 -159.511492)
		(stroke
			(width 0.2)
			(type default)
		)
		(layer "In8.Cu")
	)
	(gr_line
		(start 382.70815 -158.368492)
		(end 382.70815 -159.511238)
		(stroke
			(width 0.2)
			(type default)
		)
		(layer "In8.Cu")
	)
	(gr_line
		(start 382.7653 -46.5328)
		(end 383.908046 -46.5328)
		(stroke
			(width 0.2)
			(type default)
		)
		(layer "In8.Cu")
	)
	(gr_arc
		(start 382.7653 -45.7708)
		(mid 382.3843 -46.1518)
		(end 382.7653 -46.5328)
		(stroke
			(width 0.2)
			(type default)
		)
		(layer "In8.Cu")
	)
	(gr_arc
		(start 383.401316 -22.350222)
		(mid 383.949956 -22.898862)
		(end 384.498596 -22.350222)
		(stroke
			(width 0.2)
			(type default)
		)
		(layer "In8.Cu")
	)
	(gr_line
		(start 383.401316 -20.950174)
		(end 383.401316 -22.350222)
		(stroke
			(width 0.2)
			(type default)
		)
		(layer "In8.Cu")
	)
	(gr_arc
		(start 383.401316 -18.750026)
		(mid 383.949956 -19.298666)
		(end 384.498596 -18.750026)
		(stroke
			(width 0.2)
			(type default)
		)
		(layer "In8.Cu")
	)
	(gr_line
		(start 383.401316 -17.349978)
		(end 383.401316 -18.750026)
		(stroke
			(width 0.2)
			(type default)
		)
		(layer "In8.Cu")
	)
	(gr_line
		(start 383.47015 -274.511516)
		(end 383.47015 -273.368516)
		(stroke
			(width 0.2)
			(type default)
		)
		(layer "In8.Cu")
	)
	(gr_arc
		(start 383.47015 -273.368516)
		(mid 383.08915 -272.987516)
		(end 382.70815 -273.368516)
		(stroke
			(width 0.2)
			(type default)
		)
		(layer "In8.Cu")
	)
	(gr_line
		(start 383.47015 -159.511492)
		(end 383.47015 -158.368492)
		(stroke
			(width 0.2)
			(type default)
		)
		(layer "In8.Cu")
	)
	(gr_arc
		(start 383.47015 -158.368492)
		(mid 383.08915 -157.987492)
		(end 382.70815 -158.368492)
		(stroke
			(width 0.2)
			(type default)
		)
		(layer "In8.Cu")
	)
	(gr_arc
		(start 383.908046 -46.5328)
		(mid 384.2893 -46.151927)
		(end 383.9083 -45.7708)
		(stroke
			(width 0.2)
			(type default)
		)
		(layer "In8.Cu")
	)
	(gr_line
		(start 383.9083 -45.7708)
		(end 382.7653 -45.7708)
		(stroke
			(width 0.2)
			(type default)
		)
		(layer "In8.Cu")
	)
	(gr_line
		(start 384.498596 -22.350222)
		(end 384.498596 -20.950428)
		(stroke
			(width 0.2)
			(type default)
		)
		(layer "In8.Cu")
	)
	(gr_arc
		(start 384.498596 -20.950428)
		(mid 383.950083 -20.401534)
		(end 383.401316 -20.950174)
		(stroke
			(width 0.2)
			(type default)
		)
		(layer "In8.Cu")
	)
	(gr_line
		(start 384.498596 -18.750026)
		(end 384.498596 -17.350232)
		(stroke
			(width 0.2)
			(type default)
		)
		(layer "In8.Cu")
	)
	(gr_arc
		(start 384.498596 -17.350232)
		(mid 383.950083 -16.801338)
		(end 383.401316 -17.349978)
		(stroke
			(width 0.2)
			(type default)
		)
		(layer "In8.Cu")
	)
	(gr_arc
		(start 385.201414 -23.35022)
		(mid 385.750054 -23.89886)
		(end 386.298694 -23.35022)
		(stroke
			(width 0.2)
			(type default)
		)
		(layer "In8.Cu")
	)
	(gr_line
		(start 385.201414 -21.950172)
		(end 385.201414 -23.35022)
		(stroke
			(width 0.2)
			(type default)
		)
		(layer "In8.Cu")
	)
	(gr_arc
		(start 385.201414 -19.750024)
		(mid 385.750054 -20.298664)
		(end 386.298694 -19.750024)
		(stroke
			(width 0.2)
			(type default)
		)
		(layer "In8.Cu")
	)
	(gr_line
		(start 385.201414 -18.35023)
		(end 385.201414 -19.750024)
		(stroke
			(width 0.2)
			(type default)
		)
		(layer "In8.Cu")
	)
	(gr_line
		(start 386.298694 -23.35022)
		(end 386.298694 -21.950426)
		(stroke
			(width 0.2)
			(type default)
		)
		(layer "In8.Cu")
	)
	(gr_arc
		(start 386.298694 -21.950426)
		(mid 385.750181 -21.401532)
		(end 385.201414 -21.950172)
		(stroke
			(width 0.2)
			(type default)
		)
		(layer "In8.Cu")
	)
	(gr_line
		(start 386.298694 -19.750024)
		(end 386.298694 -18.350484)
		(stroke
			(width 0.2)
			(type default)
		)
		(layer "In8.Cu")
	)
	(gr_arc
		(start 386.298694 -18.350484)
		(mid 385.750181 -17.80159)
		(end 385.201414 -18.35023)
		(stroke
			(width 0.2)
			(type default)
		)
		(layer "In8.Cu")
	)
	(gr_arc
		(start 387.001258 -22.350222)
		(mid 387.549898 -22.898862)
		(end 388.098538 -22.350222)
		(stroke
			(width 0.2)
			(type default)
		)
		(layer "In8.Cu")
	)
	(gr_line
		(start 387.001258 -20.950174)
		(end 387.001258 -22.350222)
		(stroke
			(width 0.2)
			(type default)
		)
		(layer "In8.Cu")
	)
	(gr_arc
		(start 387.001258 -18.750026)
		(mid 387.549898 -19.298666)
		(end 388.098538 -18.750026)
		(stroke
			(width 0.2)
			(type default)
		)
		(layer "In8.Cu")
	)
	(gr_line
		(start 387.001258 -17.349978)
		(end 387.001258 -18.750026)
		(stroke
			(width 0.2)
			(type default)
		)
		(layer "In8.Cu")
	)
	(gr_arc
		(start 387.45795 -278.321516)
		(mid 387.83895 -278.702516)
		(end 388.21995 -278.321516)
		(stroke
			(width 0.2)
			(type default)
		)
		(layer "In8.Cu")
	)
	(gr_line
		(start 387.45795 -277.178516)
		(end 387.45795 -278.321516)
		(stroke
			(width 0.2)
			(type default)
		)
		(layer "In8.Cu")
	)
	(gr_arc
		(start 387.45795 -163.321492)
		(mid 387.83895 -163.702492)
		(end 388.21995 -163.321492)
		(stroke
			(width 0.2)
			(type default)
		)
		(layer "In8.Cu")
	)
	(gr_line
		(start 387.45795 -162.178492)
		(end 387.45795 -163.321492)
		(stroke
			(width 0.2)
			(type default)
		)
		(layer "In8.Cu")
	)
	(gr_arc
		(start 387.45795 -48.321468)
		(mid 387.83895 -48.702468)
		(end 388.21995 -48.321468)
		(stroke
			(width 0.2)
			(type default)
		)
		(layer "In8.Cu")
	)
	(gr_line
		(start 387.45795 -47.178468)
		(end 387.45795 -48.321468)
		(stroke
			(width 0.2)
			(type default)
		)
		(layer "In8.Cu")
	)
	(gr_line
		(start 388.098538 -22.350222)
		(end 388.098538 -20.950428)
		(stroke
			(width 0.2)
			(type default)
		)
		(layer "In8.Cu")
	)
	(gr_arc
		(start 388.098538 -20.950428)
		(mid 387.550025 -20.401534)
		(end 387.001258 -20.950174)
		(stroke
			(width 0.2)
			(type default)
		)
		(layer "In8.Cu")
	)
	(gr_line
		(start 388.098538 -18.750026)
		(end 388.098538 -17.350232)
		(stroke
			(width 0.2)
			(type default)
		)
		(layer "In8.Cu")
	)
	(gr_arc
		(start 388.098538 -17.350232)
		(mid 387.550025 -16.801338)
		(end 387.001258 -17.349978)
		(stroke
			(width 0.2)
			(type default)
		)
		(layer "In8.Cu")
	)
	(gr_line
		(start 388.21995 -278.321516)
		(end 388.21995 -277.17877)
		(stroke
			(width 0.2)
			(type default)
		)
		(layer "In8.Cu")
	)
	(gr_arc
		(start 388.21995 -277.17877)
		(mid 387.839077 -276.797516)
		(end 387.45795 -277.178516)
		(stroke
			(width 0.2)
			(type default)
		)
		(layer "In8.Cu")
	)
	(gr_line
		(start 388.21995 -163.321492)
		(end 388.21995 -162.178746)
		(stroke
			(width 0.2)
			(type default)
		)
		(layer "In8.Cu")
	)
	(gr_arc
		(start 388.21995 -162.178746)
		(mid 387.839077 -161.797492)
		(end 387.45795 -162.178492)
		(stroke
			(width 0.2)
			(type default)
		)
		(layer "In8.Cu")
	)
	(gr_line
		(start 388.21995 -48.321468)
		(end 388.21995 -47.178722)
		(stroke
			(width 0.2)
			(type default)
		)
		(layer "In8.Cu")
	)
	(gr_arc
		(start 388.21995 -47.178722)
		(mid 387.839077 -46.797468)
		(end 387.45795 -47.178468)
		(stroke
			(width 0.2)
			(type default)
		)
		(layer "In8.Cu")
	)
	(gr_arc
		(start 388.801356 -30.550104)
		(mid 389.349996 -31.098744)
		(end 389.898636 -30.550104)
		(stroke
			(width 0.2)
			(type default)
		)
		(layer "In8.Cu")
	)
	(gr_line
		(start 388.801356 -29.150056)
		(end 388.801356 -30.550104)
		(stroke
			(width 0.2)
			(type default)
		)
		(layer "In8.Cu")
	)
	(gr_arc
		(start 388.801356 -23.35022)
		(mid 389.349996 -23.89886)
		(end 389.898636 -23.35022)
		(stroke
			(width 0.2)
			(type default)
		)
		(layer "In8.Cu")
	)
	(gr_line
		(start 388.801356 -21.950172)
		(end 388.801356 -23.35022)
		(stroke
			(width 0.2)
			(type default)
		)
		(layer "In8.Cu")
	)
	(gr_arc
		(start 388.801356 -19.750024)
		(mid 389.349996 -20.298664)
		(end 389.898636 -19.750024)
		(stroke
			(width 0.2)
			(type default)
		)
		(layer "In8.Cu")
	)
	(gr_line
		(start 388.801356 -18.35023)
		(end 388.801356 -19.750024)
		(stroke
			(width 0.2)
			(type default)
		)
		(layer "In8.Cu")
	)
	(gr_line
		(start 389.898636 -30.550104)
		(end 389.898636 -29.15031)
		(stroke
			(width 0.2)
			(type default)
		)
		(layer "In8.Cu")
	)
	(gr_arc
		(start 389.898636 -29.15031)
		(mid 389.350123 -28.601416)
		(end 388.801356 -29.150056)
		(stroke
			(width 0.2)
			(type default)
		)
		(layer "In8.Cu")
	)
	(gr_line
		(start 389.898636 -23.35022)
		(end 389.898636 -21.950426)
		(stroke
			(width 0.2)
			(type default)
		)
		(layer "In8.Cu")
	)
	(gr_arc
		(start 389.898636 -21.950426)
		(mid 389.350123 -21.401532)
		(end 388.801356 -21.950172)
		(stroke
			(width 0.2)
			(type default)
		)
		(layer "In8.Cu")
	)
	(gr_line
		(start 389.898636 -19.750024)
		(end 389.898636 -18.350484)
		(stroke
			(width 0.2)
			(type default)
		)
		(layer "In8.Cu")
	)
	(gr_arc
		(start 389.898636 -18.350484)
		(mid 389.350123 -17.80159)
		(end 388.801356 -18.35023)
		(stroke
			(width 0.2)
			(type default)
		)
		(layer "In8.Cu")
	)
	(gr_arc
		(start 394.999972 -14.99997)
		(mid 395.707077 -14.707077)
		(end 395.99997 -13.999972)
		(stroke
			(width 1.524)
			(type default)
		)
		(layer "In8.Cu")
	)
	(gr_line
		(start 395.99997 -13.999972)
		(end 395.99997 -0.999998)
		(stroke
			(width 1.524)
			(type default)
		)
		(layer "In8.Cu")
	)
	(gr_arc
		(start 396.999968 0)
		(mid 396.292883 -0.292904)
		(end 395.99997 -0.999998)
		(stroke
			(width 1.524)
			(type default)
		)
		(layer "In8.Cu")
	)
	(gr_line
		(start 396.999968 0)
		(end 490.450124 0)
		(stroke
			(width 1.524)
			(type default)
		)
		(layer "In8.Cu")
	)
	(gr_arc
		(start 414.258252 -274.511262)
		(mid 414.639125 -274.892516)
		(end 415.020252 -274.511516)
		(stroke
			(width 0.2)
			(type default)
		)
		(layer "In8.Cu")
	)
	(gr_line
		(start 414.258252 -273.368516)
		(end 414.258252 -274.511262)
		(stroke
			(width 0.2)
			(type default)
		)
		(layer "In8.Cu")
	)
	(gr_arc
		(start 414.258252 -159.511238)
		(mid 414.639125 -159.892492)
		(end 415.020252 -159.511492)
		(stroke
			(width 0.2)
			(type default)
		)
		(layer "In8.Cu")
	)
	(gr_line
		(start 414.258252 -158.368492)
		(end 414.258252 -159.511238)
		(stroke
			(width 0.2)
			(type default)
		)
		(layer "In8.Cu")
	)
	(gr_arc
		(start 414.258252 -44.511214)
		(mid 414.639125 -44.892468)
		(end 415.020252 -44.511468)
		(stroke
			(width 0.2)
			(type default)
		)
		(layer "In8.Cu")
	)
	(gr_line
		(start 414.258252 -43.368468)
		(end 414.258252 -44.511214)
		(stroke
			(width 0.2)
			(type default)
		)
		(layer "In8.Cu")
	)
	(gr_line
		(start 415.020252 -274.511516)
		(end 415.020252 -273.368516)
		(stroke
			(width 0.2)
			(type default)
		)
		(layer "In8.Cu")
	)
	(gr_arc
		(start 415.020252 -273.368516)
		(mid 414.639252 -272.987516)
		(end 414.258252 -273.368516)
		(stroke
			(width 0.2)
			(type default)
		)
		(layer "In8.Cu")
	)
	(gr_line
		(start 415.020252 -159.511492)
		(end 415.020252 -158.368492)
		(stroke
			(width 0.2)
			(type default)
		)
		(layer "In8.Cu")
	)
	(gr_arc
		(start 415.020252 -158.368492)
		(mid 414.639252 -157.987492)
		(end 414.258252 -158.368492)
		(stroke
			(width 0.2)
			(type default)
		)
		(layer "In8.Cu")
	)
	(gr_line
		(start 415.020252 -44.511468)
		(end 415.020252 -43.368468)
		(stroke
			(width 0.2)
			(type default)
		)
		(layer "In8.Cu")
	)
	(gr_arc
		(start 415.020252 -43.368468)
		(mid 414.639252 -42.987468)
		(end 414.258252 -43.368468)
		(stroke
			(width 0.2)
			(type default)
		)
		(layer "In8.Cu")
	)
	(gr_arc
		(start 419.008052 -278.321516)
		(mid 419.389052 -278.702516)
		(end 419.770052 -278.321516)
		(stroke
			(width 0.2)
			(type default)
		)
		(layer "In8.Cu")
	)
	(gr_line
		(start 419.008052 -277.178516)
		(end 419.008052 -278.321516)
		(stroke
			(width 0.2)
			(type default)
		)
		(layer "In8.Cu")
	)
	(gr_arc
		(start 419.008052 -163.321492)
		(mid 419.389052 -163.702492)
		(end 419.770052 -163.321492)
		(stroke
			(width 0.2)
			(type default)
		)
		(layer "In8.Cu")
	)
	(gr_line
		(start 419.008052 -162.178492)
		(end 419.008052 -163.321492)
		(stroke
			(width 0.2)
			(type default)
		)
		(layer "In8.Cu")
	)
	(gr_arc
		(start 419.008052 -48.321468)
		(mid 419.389052 -48.702468)
		(end 419.770052 -48.321468)
		(stroke
			(width 0.2)
			(type default)
		)
		(layer "In8.Cu")
	)
	(gr_line
		(start 419.008052 -47.178468)
		(end 419.008052 -48.321468)
		(stroke
			(width 0.2)
			(type default)
		)
		(layer "In8.Cu")
	)
	(gr_line
		(start 419.770052 -278.321516)
		(end 419.770052 -277.17877)
		(stroke
			(width 0.2)
			(type default)
		)
		(layer "In8.Cu")
	)
	(gr_arc
		(start 419.770052 -277.17877)
		(mid 419.389179 -276.797516)
		(end 419.008052 -277.178516)
		(stroke
			(width 0.2)
			(type default)
		)
		(layer "In8.Cu")
	)
	(gr_line
		(start 419.770052 -163.321492)
		(end 419.770052 -162.178746)
		(stroke
			(width 0.2)
			(type default)
		)
		(layer "In8.Cu")
	)
	(gr_arc
		(start 419.770052 -162.178746)
		(mid 419.389179 -161.797492)
		(end 419.008052 -162.178492)
		(stroke
			(width 0.2)
			(type default)
		)
		(layer "In8.Cu")
	)
	(gr_line
		(start 419.770052 -48.321468)
		(end 419.770052 -47.178722)
		(stroke
			(width 0.2)
			(type default)
		)
		(layer "In8.Cu")
	)
	(gr_arc
		(start 419.770052 -47.178722)
		(mid 419.389179 -46.797468)
		(end 419.008052 -47.178468)
		(stroke
			(width 0.2)
			(type default)
		)
		(layer "In8.Cu")
	)
	(gr_arc
		(start 437.8579 -163.321492)
		(mid 438.2389 -163.702492)
		(end 438.6199 -163.321492)
		(stroke
			(width 0.2)
			(type default)
		)
		(layer "In8.Cu")
	)
	(gr_line
		(start 437.8579 -162.178492)
		(end 437.8579 -163.321492)
		(stroke
			(width 0.2)
			(type default)
		)
		(layer "In8.Cu")
	)
	(gr_line
		(start 438.6199 -163.321492)
		(end 438.6199 -162.178746)
		(stroke
			(width 0.2)
			(type default)
		)
		(layer "In8.Cu")
	)
	(gr_arc
		(start 438.6199 -162.178746)
		(mid 438.239027 -161.797492)
		(end 437.8579 -162.178492)
		(stroke
			(width 0.2)
			(type default)
		)
		(layer "In8.Cu")
	)
	(gr_arc
		(start 439.4581 -159.511238)
		(mid 439.838973 -159.892492)
		(end 440.2201 -159.511492)
		(stroke
			(width 0.2)
			(type default)
		)
		(layer "In8.Cu")
	)
	(gr_line
		(start 439.4581 -158.368492)
		(end 439.4581 -159.511238)
		(stroke
			(width 0.2)
			(type default)
		)
		(layer "In8.Cu")
	)
	(gr_line
		(start 440.2201 -159.511492)
		(end 440.2201 -158.368492)
		(stroke
			(width 0.2)
			(type default)
		)
		(layer "In8.Cu")
	)
	(gr_arc
		(start 440.2201 -158.368492)
		(mid 439.8391 -157.987492)
		(end 439.4581 -158.368492)
		(stroke
			(width 0.2)
			(type default)
		)
		(layer "In8.Cu")
	)
	(gr_arc
		(start 445.8081 -274.511262)
		(mid 446.188973 -274.892516)
		(end 446.5701 -274.511516)
		(stroke
			(width 0.2)
			(type default)
		)
		(layer "In8.Cu")
	)
	(gr_line
		(start 445.8081 -273.368516)
		(end 445.8081 -274.511262)
		(stroke
			(width 0.2)
			(type default)
		)
		(layer "In8.Cu")
	)
	(gr_arc
		(start 445.8081 -44.511214)
		(mid 446.188973 -44.892468)
		(end 446.5701 -44.511468)
		(stroke
			(width 0.2)
			(type default)
		)
		(layer "In8.Cu")
	)
	(gr_line
		(start 445.8081 -43.368468)
		(end 445.8081 -44.511214)
		(stroke
			(width 0.2)
			(type default)
		)
		(layer "In8.Cu")
	)
	(gr_line
		(start 446.5701 -274.511516)
		(end 446.5701 -273.368516)
		(stroke
			(width 0.2)
			(type default)
		)
		(layer "In8.Cu")
	)
	(gr_arc
		(start 446.5701 -273.368516)
		(mid 446.1891 -272.987516)
		(end 445.8081 -273.368516)
		(stroke
			(width 0.2)
			(type default)
		)
		(layer "In8.Cu")
	)
	(gr_line
		(start 446.5701 -44.511468)
		(end 446.5701 -43.368468)
		(stroke
			(width 0.2)
			(type default)
		)
		(layer "In8.Cu")
	)
	(gr_arc
		(start 446.5701 -43.368468)
		(mid 446.1891 -42.987468)
		(end 445.8081 -43.368468)
		(stroke
			(width 0.2)
			(type default)
		)
		(layer "In8.Cu")
	)
	(gr_arc
		(start 450.5579 -278.321516)
		(mid 450.9389 -278.702516)
		(end 451.3199 -278.321516)
		(stroke
			(width 0.2)
			(type default)
		)
		(layer "In8.Cu")
	)
	(gr_line
		(start 450.5579 -277.178516)
		(end 450.5579 -278.321516)
		(stroke
			(width 0.2)
			(type default)
		)
		(layer "In8.Cu")
	)
	(gr_arc
		(start 450.5579 -48.321468)
		(mid 450.9389 -48.702468)
		(end 451.3199 -48.321468)
		(stroke
			(width 0.2)
			(type default)
		)
		(layer "In8.Cu")
	)
	(gr_line
		(start 450.5579 -47.178468)
		(end 450.5579 -48.321468)
		(stroke
			(width 0.2)
			(type default)
		)
		(layer "In8.Cu")
	)
	(gr_line
		(start 451.3199 -278.321516)
		(end 451.3199 -277.17877)
		(stroke
			(width 0.2)
			(type default)
		)
		(layer "In8.Cu")
	)
	(gr_arc
		(start 451.3199 -277.17877)
		(mid 450.939027 -276.797516)
		(end 450.5579 -277.178516)
		(stroke
			(width 0.2)
			(type default)
		)
		(layer "In8.Cu")
	)
	(gr_line
		(start 451.3199 -48.321468)
		(end 451.3199 -47.178722)
		(stroke
			(width 0.2)
			(type default)
		)
		(layer "In8.Cu")
	)
	(gr_arc
		(start 451.3199 -47.178722)
		(mid 450.939027 -46.797468)
		(end 450.5579 -47.178468)
		(stroke
			(width 0.2)
			(type default)
		)
		(layer "In8.Cu")
	)
	(gr_arc
		(start 477.358202 -274.511262)
		(mid 477.739075 -274.892516)
		(end 478.120202 -274.511516)
		(stroke
			(width 0.2)
			(type default)
		)
		(layer "In8.Cu")
	)
	(gr_line
		(start 477.358202 -273.368516)
		(end 477.358202 -274.511262)
		(stroke
			(width 0.2)
			(type default)
		)
		(layer "In8.Cu")
	)
	(gr_arc
		(start 477.358202 -159.511238)
		(mid 477.739075 -159.892492)
		(end 478.120202 -159.511492)
		(stroke
			(width 0.2)
			(type default)
		)
		(layer "In8.Cu")
	)
	(gr_line
		(start 477.358202 -158.368492)
		(end 477.358202 -159.511238)
		(stroke
			(width 0.2)
			(type default)
		)
		(layer "In8.Cu")
	)
	(gr_arc
		(start 477.358202 -44.511214)
		(mid 477.739075 -44.892468)
		(end 478.120202 -44.511468)
		(stroke
			(width 0.2)
			(type default)
		)
		(layer "In8.Cu")
	)
	(gr_line
		(start 477.358202 -43.368468)
		(end 477.358202 -44.511214)
		(stroke
			(width 0.2)
			(type default)
		)
		(layer "In8.Cu")
	)
	(gr_line
		(start 478.120202 -274.511516)
		(end 478.120202 -273.368516)
		(stroke
			(width 0.2)
			(type default)
		)
		(layer "In8.Cu")
	)
	(gr_arc
		(start 478.120202 -273.368516)
		(mid 477.739202 -272.987516)
		(end 477.358202 -273.368516)
		(stroke
			(width 0.2)
			(type default)
		)
		(layer "In8.Cu")
	)
	(gr_line
		(start 478.120202 -159.511492)
		(end 478.120202 -158.368492)
		(stroke
			(width 0.2)
			(type default)
		)
		(layer "In8.Cu")
	)
	(gr_arc
		(start 478.120202 -158.368492)
		(mid 477.739202 -157.987492)
		(end 477.358202 -158.368492)
		(stroke
			(width 0.2)
			(type default)
		)
		(layer "In8.Cu")
	)
	(gr_line
		(start 478.120202 -44.511468)
		(end 478.120202 -43.368468)
		(stroke
			(width 0.2)
			(type default)
		)
		(layer "In8.Cu")
	)
	(gr_arc
		(start 478.120202 -43.368468)
		(mid 477.739202 -42.987468)
		(end 477.358202 -43.368468)
		(stroke
			(width 0.2)
			(type default)
		)
		(layer "In8.Cu")
	)
	(gr_arc
		(start 482.108002 -278.321516)
		(mid 482.489002 -278.702516)
		(end 482.870002 -278.321516)
		(stroke
			(width 0.2)
			(type default)
		)
		(layer "In8.Cu")
	)
	(gr_line
		(start 482.108002 -277.178516)
		(end 482.108002 -278.321516)
		(stroke
			(width 0.2)
			(type default)
		)
		(layer "In8.Cu")
	)
	(gr_arc
		(start 482.108002 -163.321492)
		(mid 482.489002 -163.702492)
		(end 482.870002 -163.321492)
		(stroke
			(width 0.2)
			(type default)
		)
		(layer "In8.Cu")
	)
	(gr_line
		(start 482.108002 -162.178492)
		(end 482.108002 -163.321492)
		(stroke
			(width 0.2)
			(type default)
		)
		(layer "In8.Cu")
	)
	(gr_arc
		(start 482.108002 -48.321468)
		(mid 482.489002 -48.702468)
		(end 482.870002 -48.321468)
		(stroke
			(width 0.2)
			(type default)
		)
		(layer "In8.Cu")
	)
	(gr_line
		(start 482.108002 -47.178468)
		(end 482.108002 -48.321468)
		(stroke
			(width 0.2)
			(type default)
		)
		(layer "In8.Cu")
	)
	(gr_line
		(start 482.870002 -278.321516)
		(end 482.870002 -277.17877)
		(stroke
			(width 0.2)
			(type default)
		)
		(layer "In8.Cu")
	)
	(gr_arc
		(start 482.870002 -277.17877)
		(mid 482.489129 -276.797516)
		(end 482.108002 -277.178516)
		(stroke
			(width 0.2)
			(type default)
		)
		(layer "In8.Cu")
	)
	(gr_line
		(start 482.870002 -163.321492)
		(end 482.870002 -162.178746)
		(stroke
			(width 0.2)
			(type default)
		)
		(layer "In8.Cu")
	)
	(gr_arc
		(start 482.870002 -162.178746)
		(mid 482.489129 -161.797492)
		(end 482.108002 -162.178492)
		(stroke
			(width 0.2)
			(type default)
		)
		(layer "In8.Cu")
	)
	(gr_line
		(start 482.870002 -48.321468)
		(end 482.870002 -47.178722)
		(stroke
			(width 0.2)
			(type default)
		)
		(layer "In8.Cu")
	)
	(gr_arc
		(start 482.870002 -47.178722)
		(mid 482.489129 -46.797468)
		(end 482.108002 -47.178468)
		(stroke
			(width 0.2)
			(type default)
		)
		(layer "In8.Cu")
	)
	(gr_line
		(start 490.450124 -349.199962)
		(end 296.69994 -349.199962)
		(stroke
			(width 1.524)
			(type default)
		)
		(layer "In8.Cu")
	)
	(gr_arc
		(start 490.450124 -349.199962)
		(mid 491.157201 -348.907059)
		(end 491.450122 -348.199964)
		(stroke
			(width 1.524)
			(type default)
		)
		(layer "In8.Cu")
	)
	(gr_arc
		(start 491.450122 -0.999998)
		(mid 491.15723 -0.292885)
		(end 490.450124 0)
		(stroke
			(width 1.524)
			(type default)
		)
		(layer "In8.Cu")
	)
	(gr_line
		(start 491.450122 -0.999998)
		(end 491.450122 -348.199964)
		(stroke
			(width 1.524)
			(type default)
		)
		(layer "In8.Cu")
	)
	(gr_line
		(start 109.149896 -18.3388)
		(end 109.149896 -18.750026)
		(stroke
			(width 0.06985)
			(type default)
		)
		(layer "In9.Cu")
	)
	(gr_arc
		(start 109.149896 -17.761458)
		(mid 109.159529 -17.809976)
		(end 109.18698 -17.85112)
		(stroke
			(width 0.06985)
			(type default)
		)
		(layer "In9.Cu")
	)
	(gr_line
		(start 109.149896 -17.349978)
		(end 109.149896 -17.761458)
		(stroke
			(width 0.06985)
			(type default)
		)
		(layer "In9.Cu")
	)
	(gr_arc
		(start 109.18698 -18.249138)
		(mid 109.159526 -18.290284)
		(end 109.149896 -18.3388)
		(stroke
			(width 0.06985)
			(type default)
		)
		(layer "In9.Cu")
	)
	(gr_line
		(start 109.18698 -18.249138)
		(end 109.202728 -18.23339)
		(stroke
			(width 0.06985)
			(type default)
		)
		(layer "In9.Cu")
	)
	(gr_line
		(start 109.18698 -17.85112)
		(end 109.202728 -17.866868)
		(stroke
			(width 0.06985)
			(type default)
		)
		(layer "In9.Cu")
	)
	(gr_arc
		(start 109.202728 -17.866868)
		(mid 109.243879 -17.894301)
		(end 109.29239 -17.903952)
		(stroke
			(width 0.06985)
			(type default)
		)
		(layer "In9.Cu")
	)
	(gr_arc
		(start 109.29239 -18.196306)
		(mid 109.24389 -18.205969)
		(end 109.202728 -18.23339)
		(stroke
			(width 0.06985)
			(type default)
		)
		(layer "In9.Cu")
	)
	(gr_arc
		(start 109.903768 -35.547808)
		(mid 109.909671 -35.587987)
		(end 109.926882 -35.62477)
		(stroke
			(width 0.06985)
			(type default)
		)
		(layer "In9.Cu")
	)
	(gr_line
		(start 109.926882 -35.62477)
		(end 109.930692 -35.630612)
		(stroke
			(width 0.06985)
			(type default)
		)
		(layer "In9.Cu")
	)
	(gr_line
		(start 110.949994 -19.338798)
		(end 110.949994 -19.750024)
		(stroke
			(width 0.06985)
			(type default)
		)
		(layer "In9.Cu")
	)
	(gr_arc
		(start 110.949994 -18.761456)
		(mid 110.959627 -18.809974)
		(end 110.987078 -18.851118)
		(stroke
			(width 0.06985)
			(type default)
		)
		(layer "In9.Cu")
	)
	(gr_line
		(start 110.949994 -18.35023)
		(end 110.949994 -18.761456)
		(stroke
			(width 0.06985)
			(type default)
		)
		(layer "In9.Cu")
	)
	(gr_arc
		(start 110.987078 -19.249136)
		(mid 110.959624 -19.290282)
		(end 110.949994 -19.338798)
		(stroke
			(width 0.06985)
			(type default)
		)
		(layer "In9.Cu")
	)
	(gr_line
		(start 110.987078 -19.249136)
		(end 111.002826 -19.233388)
		(stroke
			(width 0.06985)
			(type default)
		)
		(layer "In9.Cu")
	)
	(gr_line
		(start 110.987078 -18.851118)
		(end 111.002826 -18.866866)
		(stroke
			(width 0.06985)
			(type default)
		)
		(layer "In9.Cu")
	)
	(gr_arc
		(start 111.002826 -18.866866)
		(mid 111.043977 -18.894299)
		(end 111.092488 -18.90395)
		(stroke
			(width 0.06985)
			(type default)
		)
		(layer "In9.Cu")
	)
	(gr_arc
		(start 111.092488 -19.196304)
		(mid 111.043988 -19.205968)
		(end 111.002826 -19.233388)
		(stroke
			(width 0.06985)
			(type default)
		)
		(layer "In9.Cu")
	)
	(gr_line
		(start 111.703866 -32.077914)
		(end 111.73079 -32.118554)
		(stroke
			(width 0.06985)
			(type default)
		)
		(layer "In9.Cu")
	)
	(gr_line
		(start 112.750092 -18.3388)
		(end 112.750092 -18.750026)
		(stroke
			(width 0.06985)
			(type default)
		)
		(layer "In9.Cu")
	)
	(gr_arc
		(start 112.750092 -17.776698)
		(mid 112.756956 -17.811205)
		(end 112.776508 -17.840452)
		(stroke
			(width 0.06985)
			(type default)
		)
		(layer "In9.Cu")
	)
	(gr_line
		(start 112.750092 -17.349978)
		(end 112.750092 -17.776698)
		(stroke
			(width 0.06985)
			(type default)
		)
		(layer "In9.Cu")
	)
	(gr_line
		(start 112.776508 -17.840452)
		(end 112.802924 -17.866868)
		(stroke
			(width 0.06985)
			(type default)
		)
		(layer "In9.Cu")
	)
	(gr_arc
		(start 112.787176 -18.249138)
		(mid 112.759723 -18.290284)
		(end 112.750092 -18.3388)
		(stroke
			(width 0.06985)
			(type default)
		)
		(layer "In9.Cu")
	)
	(gr_line
		(start 112.787176 -18.249138)
		(end 112.802924 -18.23339)
		(stroke
			(width 0.06985)
			(type default)
		)
		(layer "In9.Cu")
	)
	(gr_arc
		(start 112.802924 -17.866868)
		(mid 112.844075 -17.894301)
		(end 112.892586 -17.903952)
		(stroke
			(width 0.06985)
			(type default)
		)
		(layer "In9.Cu")
	)
	(gr_arc
		(start 112.892586 -18.196306)
		(mid 112.844087 -18.205971)
		(end 112.802924 -18.23339)
		(stroke
			(width 0.06985)
			(type default)
		)
		(layer "In9.Cu")
	)
	(gr_line
		(start 113.503964 -31.924498)
		(end 113.530888 -31.965138)
		(stroke
			(width 0.06985)
			(type default)
		)
		(layer "In9.Cu")
	)
	(gr_line
		(start 114.549936 -19.338798)
		(end 114.549936 -19.750024)
		(stroke
			(width 0.06985)
			(type default)
		)
		(layer "In9.Cu")
	)
	(gr_arc
		(start 114.549936 -18.761456)
		(mid 114.559569 -18.809974)
		(end 114.58702 -18.851118)
		(stroke
			(width 0.06985)
			(type default)
		)
		(layer "In9.Cu")
	)
	(gr_line
		(start 114.549936 -18.35023)
		(end 114.549936 -18.761456)
		(stroke
			(width 0.06985)
			(type default)
		)
		(layer "In9.Cu")
	)
	(gr_arc
		(start 114.58702 -19.249136)
		(mid 114.559557 -19.29028)
		(end 114.549936 -19.338798)
		(stroke
			(width 0.06985)
			(type default)
		)
		(layer "In9.Cu")
	)
	(gr_line
		(start 114.58702 -19.249136)
		(end 114.602768 -19.233388)
		(stroke
			(width 0.06985)
			(type default)
		)
		(layer "In9.Cu")
	)
	(gr_line
		(start 114.58702 -18.851118)
		(end 114.602768 -18.866866)
		(stroke
			(width 0.06985)
			(type default)
		)
		(layer "In9.Cu")
	)
	(gr_arc
		(start 114.602768 -18.866866)
		(mid 114.643919 -18.894299)
		(end 114.69243 -18.90395)
		(stroke
			(width 0.06985)
			(type default)
		)
		(layer "In9.Cu")
	)
	(gr_arc
		(start 114.69243 -19.196304)
		(mid 114.643922 -19.205954)
		(end 114.602768 -19.233388)
		(stroke
			(width 0.06985)
			(type default)
		)
		(layer "In9.Cu")
	)
	(gr_line
		(start 115.303808 -32.696658)
		(end 115.330732 -32.737298)
		(stroke
			(width 0.06985)
			(type default)
		)
		(layer "In9.Cu")
	)
	(gr_line
		(start 116.350034 -18.3388)
		(end 116.350034 -18.750026)
		(stroke
			(width 0.06985)
			(type default)
		)
		(layer "In9.Cu")
	)
	(gr_arc
		(start 116.350034 -17.776698)
		(mid 116.356898 -17.811205)
		(end 116.37645 -17.840452)
		(stroke
			(width 0.06985)
			(type default)
		)
		(layer "In9.Cu")
	)
	(gr_line
		(start 116.350034 -17.349978)
		(end 116.350034 -17.776698)
		(stroke
			(width 0.06985)
			(type default)
		)
		(layer "In9.Cu")
	)
	(gr_line
		(start 116.37645 -17.840452)
		(end 116.402866 -17.866868)
		(stroke
			(width 0.06985)
			(type default)
		)
		(layer "In9.Cu")
	)
	(gr_arc
		(start 116.387118 -18.249138)
		(mid 116.359656 -18.290282)
		(end 116.350034 -18.3388)
		(stroke
			(width 0.06985)
			(type default)
		)
		(layer "In9.Cu")
	)
	(gr_line
		(start 116.387118 -18.249138)
		(end 116.402866 -18.23339)
		(stroke
			(width 0.06985)
			(type default)
		)
		(layer "In9.Cu")
	)
	(gr_arc
		(start 116.402866 -17.866868)
		(mid 116.444017 -17.894301)
		(end 116.492528 -17.903952)
		(stroke
			(width 0.06985)
			(type default)
		)
		(layer "In9.Cu")
	)
	(gr_arc
		(start 116.492528 -18.196306)
		(mid 116.44402 -18.205957)
		(end 116.402866 -18.23339)
		(stroke
			(width 0.06985)
			(type default)
		)
		(layer "In9.Cu")
	)
	(gr_line
		(start 117.103906 -33.269682)
		(end 117.13083 -33.310322)
		(stroke
			(width 0.06985)
			(type default)
		)
		(layer "In9.Cu")
	)
	(gr_line
		(start 118.149878 -19.338798)
		(end 118.149878 -19.750024)
		(stroke
			(width 0.06985)
			(type default)
		)
		(layer "In9.Cu")
	)
	(gr_arc
		(start 118.149878 -18.761456)
		(mid 118.159511 -18.809974)
		(end 118.186962 -18.851118)
		(stroke
			(width 0.06985)
			(type default)
		)
		(layer "In9.Cu")
	)
	(gr_line
		(start 118.149878 -18.35023)
		(end 118.149878 -18.761456)
		(stroke
			(width 0.06985)
			(type default)
		)
		(layer "In9.Cu")
	)
	(gr_arc
		(start 118.186962 -19.249136)
		(mid 118.159511 -19.290283)
		(end 118.149878 -19.338798)
		(stroke
			(width 0.06985)
			(type default)
		)
		(layer "In9.Cu")
	)
	(gr_line
		(start 118.186962 -19.249136)
		(end 118.20271 -19.233388)
		(stroke
			(width 0.06985)
			(type default)
		)
		(layer "In9.Cu")
	)
	(gr_line
		(start 118.186962 -18.851118)
		(end 118.20271 -18.866866)
		(stroke
			(width 0.06985)
			(type default)
		)
		(layer "In9.Cu")
	)
	(gr_arc
		(start 118.20271 -18.866866)
		(mid 118.243861 -18.894299)
		(end 118.292372 -18.90395)
		(stroke
			(width 0.06985)
			(type default)
		)
		(layer "In9.Cu")
	)
	(gr_arc
		(start 118.292372 -19.196304)
		(mid 118.243855 -19.20594)
		(end 118.20271 -19.233388)
		(stroke
			(width 0.06985)
			(type default)
		)
		(layer "In9.Cu")
	)
	(gr_line
		(start 118.90375 -30.655768)
		(end 118.930674 -30.696408)
		(stroke
			(width 0.06985)
			(type default)
		)
		(layer "In9.Cu")
	)
	(gr_arc
		(start 119.836946 -50.67554)
		(mid 119.854308 -50.697015)
		(end 119.875554 -50.714656)
		(stroke
			(width 0.06985)
			(type default)
		)
		(layer "In9.Cu")
	)
	(gr_line
		(start 119.949976 -18.3388)
		(end 119.949976 -18.750026)
		(stroke
			(width 0.06985)
			(type default)
		)
		(layer "In9.Cu")
	)
	(gr_arc
		(start 119.949976 -17.776698)
		(mid 119.95684 -17.811205)
		(end 119.976392 -17.840452)
		(stroke
			(width 0.06985)
			(type default)
		)
		(layer "In9.Cu")
	)
	(gr_line
		(start 119.949976 -17.349978)
		(end 119.949976 -17.776698)
		(stroke
			(width 0.06985)
			(type default)
		)
		(layer "In9.Cu")
	)
	(gr_line
		(start 119.976392 -17.840452)
		(end 120.002808 -17.866868)
		(stroke
			(width 0.06985)
			(type default)
		)
		(layer "In9.Cu")
	)
	(gr_arc
		(start 119.98706 -18.249138)
		(mid 119.959611 -18.290285)
		(end 119.949976 -18.3388)
		(stroke
			(width 0.06985)
			(type default)
		)
		(layer "In9.Cu")
	)
	(gr_line
		(start 119.98706 -18.249138)
		(end 120.002808 -18.23339)
		(stroke
			(width 0.06985)
			(type default)
		)
		(layer "In9.Cu")
	)
	(gr_arc
		(start 120.002808 -17.866868)
		(mid 120.043959 -17.894301)
		(end 120.09247 -17.903952)
		(stroke
			(width 0.06985)
			(type default)
		)
		(layer "In9.Cu")
	)
	(gr_arc
		(start 120.09247 -18.196306)
		(mid 120.043953 -18.205943)
		(end 120.002808 -18.23339)
		(stroke
			(width 0.06985)
			(type default)
		)
		(layer "In9.Cu")
	)
	(gr_line
		(start 120.703848 -31.449518)
		(end 120.730772 -31.490158)
		(stroke
			(width 0.06985)
			(type default)
		)
		(layer "In9.Cu")
	)
	(gr_line
		(start 121.750074 -19.338798)
		(end 121.750074 -19.750024)
		(stroke
			(width 0.06985)
			(type default)
		)
		(layer "In9.Cu")
	)
	(gr_arc
		(start 121.750074 -18.761456)
		(mid 121.759707 -18.809974)
		(end 121.787158 -18.851118)
		(stroke
			(width 0.06985)
			(type default)
		)
		(layer "In9.Cu")
	)
	(gr_line
		(start 121.750074 -18.35023)
		(end 121.750074 -18.761456)
		(stroke
			(width 0.06985)
			(type default)
		)
		(layer "In9.Cu")
	)
	(gr_arc
		(start 121.787158 -19.249136)
		(mid 121.759687 -19.290278)
		(end 121.750074 -19.338798)
		(stroke
			(width 0.06985)
			(type default)
		)
		(layer "In9.Cu")
	)
	(gr_line
		(start 121.787158 -19.249136)
		(end 121.802906 -19.233388)
		(stroke
			(width 0.06985)
			(type default)
		)
		(layer "In9.Cu")
	)
	(gr_line
		(start 121.787158 -18.851118)
		(end 121.802906 -18.866866)
		(stroke
			(width 0.06985)
			(type default)
		)
		(layer "In9.Cu")
	)
	(gr_arc
		(start 121.802906 -18.866866)
		(mid 121.844057 -18.894299)
		(end 121.892568 -18.90395)
		(stroke
			(width 0.06985)
			(type default)
		)
		(layer "In9.Cu")
	)
	(gr_arc
		(start 121.892568 -19.196304)
		(mid 121.844052 -19.205942)
		(end 121.802906 -19.233388)
		(stroke
			(width 0.06985)
			(type default)
		)
		(layer "In9.Cu")
	)
	(gr_line
		(start 121.947432 -40.623998)
		(end 121.96064 -40.644064)
		(stroke
			(width 0.06985)
			(type default)
		)
		(layer "In9.Cu")
	)
	(gr_line
		(start 121.96064 -40.644064)
		(end 121.980198 -40.657018)
		(stroke
			(width 0.06985)
			(type default)
		)
		(layer "In9.Cu")
	)
	(gr_line
		(start 122.600212 -30.387798)
		(end 122.604276 -30.407356)
		(stroke
			(width 0.06985)
			(type default)
		)
		(layer "In9.Cu")
	)
	(gr_line
		(start 122.604276 -30.407356)
		(end 122.615198 -30.423866)
		(stroke
			(width 0.06985)
			(type default)
		)
		(layer "In9.Cu")
	)
	(gr_line
		(start 123.160028 -35.179)
		(end 123.18111 -35.211258)
		(stroke
			(width 0.06985)
			(type default)
		)
		(layer "In9.Cu")
	)
	(gr_line
		(start 123.18111 -35.211258)
		(end 123.216162 -35.229292)
		(stroke
			(width 0.06985)
			(type default)
		)
		(layer "In9.Cu")
	)
	(gr_line
		(start 124.70765 -33.585658)
		(end 124.729748 -33.618932)
		(stroke
			(width 0.06985)
			(type default)
		)
		(layer "In9.Cu")
	)
	(gr_line
		(start 124.729748 -33.618932)
		(end 124.765308 -33.63722)
		(stroke
			(width 0.06985)
			(type default)
		)
		(layer "In9.Cu")
	)
	(gr_line
		(start 125.414024 -52.898548)
		(end 125.4252 -52.915566)
		(stroke
			(width 0.06985)
			(type default)
		)
		(layer "In9.Cu")
	)
	(gr_line
		(start 125.4252 -52.915566)
		(end 125.441964 -52.926742)
		(stroke
			(width 0.06985)
			(type default)
		)
		(layer "In9.Cu")
	)
	(gr_line
		(start 126.477268 -42.158158)
		(end 126.488444 -42.175176)
		(stroke
			(width 0.06985)
			(type default)
		)
		(layer "In9.Cu")
	)
	(gr_line
		(start 126.488444 -42.175176)
		(end 126.505208 -42.186352)
		(stroke
			(width 0.06985)
			(type default)
		)
		(layer "In9.Cu")
	)
	(gr_line
		(start 126.598934 -49.858422)
		(end 126.611126 -49.876964)
		(stroke
			(width 0.06985)
			(type default)
		)
		(layer "In9.Cu")
	)
	(gr_line
		(start 126.611126 -49.876964)
		(end 126.629668 -49.889156)
		(stroke
			(width 0.06985)
			(type default)
		)
		(layer "In9.Cu")
	)
	(gr_line
		(start 127.029718 -52.467764)
		(end 127.040894 -52.484782)
		(stroke
			(width 0.06985)
			(type default)
		)
		(layer "In9.Cu")
	)
	(gr_line
		(start 127.040894 -52.484782)
		(end 127.057658 -52.495958)
		(stroke
			(width 0.06985)
			(type default)
		)
		(layer "In9.Cu")
	)
	(gr_line
		(start 130.750056 -18.3388)
		(end 130.750056 -18.750026)
		(stroke
			(width 0.06985)
			(type default)
		)
		(layer "In9.Cu")
	)
	(gr_arc
		(start 130.750056 -17.776698)
		(mid 130.75692 -17.811205)
		(end 130.776472 -17.840452)
		(stroke
			(width 0.06985)
			(type default)
		)
		(layer "In9.Cu")
	)
	(gr_line
		(start 130.750056 -17.349978)
		(end 130.750056 -17.776698)
		(stroke
			(width 0.06985)
			(type default)
		)
		(layer "In9.Cu")
	)
	(gr_line
		(start 130.776472 -17.840452)
		(end 130.802888 -17.866868)
		(stroke
			(width 0.06985)
			(type default)
		)
		(layer "In9.Cu")
	)
	(gr_arc
		(start 130.78714 -18.249138)
		(mid 130.759674 -18.290281)
		(end 130.750056 -18.3388)
		(stroke
			(width 0.06985)
			(type default)
		)
		(layer "In9.Cu")
	)
	(gr_line
		(start 130.78714 -18.249138)
		(end 130.802888 -18.23339)
		(stroke
			(width 0.06985)
			(type default)
		)
		(layer "In9.Cu")
	)
	(gr_arc
		(start 130.802888 -17.866868)
		(mid 130.844039 -17.894301)
		(end 130.89255 -17.903952)
		(stroke
			(width 0.06985)
			(type default)
		)
		(layer "In9.Cu")
	)
	(gr_arc
		(start 130.89255 -18.196306)
		(mid 130.844037 -18.20595)
		(end 130.802888 -18.23339)
		(stroke
			(width 0.06985)
			(type default)
		)
		(layer "In9.Cu")
	)
	(gr_line
		(start 131.503928 -31.703772)
		(end 131.530852 -31.744412)
		(stroke
			(width 0.06985)
			(type default)
		)
		(layer "In9.Cu")
	)
	(gr_line
		(start 132.5499 -19.338798)
		(end 132.5499 -19.750024)
		(stroke
			(width 0.06985)
			(type default)
		)
		(layer "In9.Cu")
	)
	(gr_arc
		(start 132.5499 -18.761456)
		(mid 132.559533 -18.809974)
		(end 132.586984 -18.851118)
		(stroke
			(width 0.06985)
			(type default)
		)
		(layer "In9.Cu")
	)
	(gr_line
		(start 132.5499 -18.35023)
		(end 132.5499 -18.761456)
		(stroke
			(width 0.06985)
			(type default)
		)
		(layer "In9.Cu")
	)
	(gr_arc
		(start 132.586984 -19.249136)
		(mid 132.559529 -19.290282)
		(end 132.5499 -19.338798)
		(stroke
			(width 0.06985)
			(type default)
		)
		(layer "In9.Cu")
	)
	(gr_line
		(start 132.586984 -19.249136)
		(end 132.602732 -19.233388)
		(stroke
			(width 0.06985)
			(type default)
		)
		(layer "In9.Cu")
	)
	(gr_line
		(start 132.586984 -18.851118)
		(end 132.602732 -18.866866)
		(stroke
			(width 0.06985)
			(type default)
		)
		(layer "In9.Cu")
	)
	(gr_arc
		(start 132.602732 -18.866866)
		(mid 132.643883 -18.894299)
		(end 132.692394 -18.90395)
		(stroke
			(width 0.06985)
			(type default)
		)
		(layer "In9.Cu")
	)
	(gr_arc
		(start 132.692394 -19.196304)
		(mid 132.643893 -19.205966)
		(end 132.602732 -19.233388)
		(stroke
			(width 0.06985)
			(type default)
		)
		(layer "In9.Cu")
	)
	(gr_line
		(start 133.303772 -31.07944)
		(end 133.330696 -31.12008)
		(stroke
			(width 0.06985)
			(type default)
		)
		(layer "In9.Cu")
	)
	(gr_line
		(start 133.407658 -34.594038)
		(end 133.418834 -34.611056)
		(stroke
			(width 0.06985)
			(type default)
		)
		(layer "In9.Cu")
	)
	(gr_line
		(start 133.418834 -34.611056)
		(end 133.435598 -34.622232)
		(stroke
			(width 0.06985)
			(type default)
		)
		(layer "In9.Cu")
	)
	(gr_line
		(start 134.349998 -18.3388)
		(end 134.349998 -18.750026)
		(stroke
			(width 0.06985)
			(type default)
		)
		(layer "In9.Cu")
	)
	(gr_arc
		(start 134.349998 -17.761458)
		(mid 134.359631 -17.809976)
		(end 134.387082 -17.85112)
		(stroke
			(width 0.06985)
			(type default)
		)
		(layer "In9.Cu")
	)
	(gr_line
		(start 134.349998 -17.349978)
		(end 134.349998 -17.761458)
		(stroke
			(width 0.06985)
			(type default)
		)
		(layer "In9.Cu")
	)
	(gr_arc
		(start 134.387082 -18.249138)
		(mid 134.359628 -18.290284)
		(end 134.349998 -18.3388)
		(stroke
			(width 0.06985)
			(type default)
		)
		(layer "In9.Cu")
	)
	(gr_line
		(start 134.387082 -18.249138)
		(end 134.40283 -18.23339)
		(stroke
			(width 0.06985)
			(type default)
		)
		(layer "In9.Cu")
	)
	(gr_line
		(start 134.387082 -17.85112)
		(end 134.40283 -17.866868)
		(stroke
			(width 0.06985)
			(type default)
		)
		(layer "In9.Cu")
	)
	(gr_arc
		(start 134.40283 -17.866868)
		(mid 134.443981 -17.894301)
		(end 134.492492 -17.903952)
		(stroke
			(width 0.06985)
			(type default)
		)
		(layer "In9.Cu")
	)
	(gr_arc
		(start 134.492492 -18.196306)
		(mid 134.443992 -18.205969)
		(end 134.40283 -18.23339)
		(stroke
			(width 0.06985)
			(type default)
		)
		(layer "In9.Cu")
	)
	(gr_line
		(start 135.10387 -31.668974)
		(end 135.130794 -31.709614)
		(stroke
			(width 0.06985)
			(type default)
		)
		(layer "In9.Cu")
	)
	(gr_line
		(start 135.482838 -34.38779)
		(end 135.494268 -34.405062)
		(stroke
			(width 0.06985)
			(type default)
		)
		(layer "In9.Cu")
	)
	(gr_line
		(start 135.494268 -34.405316)
		(end 135.512048 -34.417508)
		(stroke
			(width 0.06985)
			(type default)
		)
		(layer "In9.Cu")
	)
	(gr_line
		(start 135.494268 -34.405062)
		(end 135.494268 -34.405316)
		(stroke
			(width 0.06985)
			(type default)
		)
		(layer "In9.Cu")
	)
	(gr_line
		(start 136.150096 -19.338798)
		(end 136.150096 -19.750024)
		(stroke
			(width 0.06985)
			(type default)
		)
		(layer "In9.Cu")
	)
	(gr_arc
		(start 136.150096 -18.761456)
		(mid 136.159729 -18.809974)
		(end 136.18718 -18.851118)
		(stroke
			(width 0.06985)
			(type default)
		)
		(layer "In9.Cu")
	)
	(gr_line
		(start 136.150096 -18.35023)
		(end 136.150096 -18.761456)
		(stroke
			(width 0.06985)
			(type default)
		)
		(layer "In9.Cu")
	)
	(gr_arc
		(start 136.18718 -19.249136)
		(mid 136.159726 -19.290282)
		(end 136.150096 -19.338798)
		(stroke
			(width 0.06985)
			(type default)
		)
		(layer "In9.Cu")
	)
	(gr_line
		(start 136.18718 -19.249136)
		(end 136.202928 -19.233388)
		(stroke
			(width 0.06985)
			(type default)
		)
		(layer "In9.Cu")
	)
	(gr_line
		(start 136.18718 -18.851118)
		(end 136.202928 -18.866866)
		(stroke
			(width 0.06985)
			(type default)
		)
		(layer "In9.Cu")
	)
	(gr_arc
		(start 136.202928 -18.866866)
		(mid 136.244079 -18.894299)
		(end 136.29259 -18.90395)
		(stroke
			(width 0.06985)
			(type default)
		)
		(layer "In9.Cu")
	)
	(gr_arc
		(start 136.29259 -19.196304)
		(mid 136.24409 -19.205967)
		(end 136.202928 -19.233388)
		(stroke
			(width 0.06985)
			(type default)
		)
		(layer "In9.Cu")
	)
	(gr_line
		(start 136.422384 -33.671256)
		(end 136.43356 -33.688274)
		(stroke
			(width 0.06985)
			(type default)
		)
		(layer "In9.Cu")
	)
	(gr_line
		(start 136.43356 -33.688274)
		(end 136.450324 -33.69945)
		(stroke
			(width 0.06985)
			(type default)
		)
		(layer "In9.Cu")
	)
	(gr_line
		(start 136.903968 -31.516066)
		(end 136.930892 -31.556706)
		(stroke
			(width 0.06985)
			(type default)
		)
		(layer "In9.Cu")
	)
	(gr_line
		(start 137.94994 -18.3388)
		(end 137.94994 -18.750026)
		(stroke
			(width 0.06985)
			(type default)
		)
		(layer "In9.Cu")
	)
	(gr_arc
		(start 137.94994 -17.761458)
		(mid 137.959573 -17.809976)
		(end 137.987024 -17.85112)
		(stroke
			(width 0.06985)
			(type default)
		)
		(layer "In9.Cu")
	)
	(gr_line
		(start 137.94994 -17.349978)
		(end 137.94994 -17.761458)
		(stroke
			(width 0.06985)
			(type default)
		)
		(layer "In9.Cu")
	)
	(gr_arc
		(start 137.987024 -18.249138)
		(mid 137.959561 -18.290282)
		(end 137.94994 -18.3388)
		(stroke
			(width 0.06985)
			(type default)
		)
		(layer "In9.Cu")
	)
	(gr_line
		(start 137.987024 -18.249138)
		(end 138.002772 -18.23339)
		(stroke
			(width 0.06985)
			(type default)
		)
		(layer "In9.Cu")
	)
	(gr_line
		(start 137.987024 -17.85112)
		(end 138.002772 -17.866868)
		(stroke
			(width 0.06985)
			(type default)
		)
		(layer "In9.Cu")
	)
	(gr_arc
		(start 138.002772 -17.866868)
		(mid 138.043923 -17.894301)
		(end 138.092434 -17.903952)
		(stroke
			(width 0.06985)
			(type default)
		)
		(layer "In9.Cu")
	)
	(gr_arc
		(start 138.092434 -18.196306)
		(mid 138.043925 -18.205955)
		(end 138.002772 -18.23339)
		(stroke
			(width 0.06985)
			(type default)
		)
		(layer "In9.Cu")
	)
	(gr_line
		(start 138.28522 -33.613344)
		(end 138.296396 -33.630362)
		(stroke
			(width 0.06985)
			(type default)
		)
		(layer "In9.Cu")
	)
	(gr_line
		(start 138.296396 -33.630362)
		(end 138.31316 -33.641538)
		(stroke
			(width 0.06985)
			(type default)
		)
		(layer "In9.Cu")
	)
	(gr_line
		(start 138.703812 -31.942532)
		(end 138.730736 -31.983172)
		(stroke
			(width 0.06985)
			(type default)
		)
		(layer "In9.Cu")
	)
	(gr_line
		(start 139.04722 -32.464248)
		(end 139.058396 -32.481266)
		(stroke
			(width 0.06985)
			(type default)
		)
		(layer "In9.Cu")
	)
	(gr_line
		(start 139.058396 -32.481266)
		(end 139.07516 -32.492442)
		(stroke
			(width 0.06985)
			(type default)
		)
		(layer "In9.Cu")
	)
	(gr_line
		(start 139.750038 -19.338798)
		(end 139.750038 -19.750024)
		(stroke
			(width 0.06985)
			(type default)
		)
		(layer "In9.Cu")
	)
	(gr_arc
		(start 139.750038 -18.761456)
		(mid 139.759671 -18.809974)
		(end 139.787122 -18.851118)
		(stroke
			(width 0.06985)
			(type default)
		)
		(layer "In9.Cu")
	)
	(gr_line
		(start 139.750038 -18.35023)
		(end 139.750038 -18.761456)
		(stroke
			(width 0.06985)
			(type default)
		)
		(layer "In9.Cu")
	)
	(gr_arc
		(start 139.787122 -19.249136)
		(mid 139.759659 -19.29028)
		(end 139.750038 -19.338798)
		(stroke
			(width 0.06985)
			(type default)
		)
		(layer "In9.Cu")
	)
	(gr_line
		(start 139.787122 -19.249136)
		(end 139.80287 -19.233388)
		(stroke
			(width 0.06985)
			(type default)
		)
		(layer "In9.Cu")
	)
	(gr_line
		(start 139.787122 -18.851118)
		(end 139.80287 -18.866866)
		(stroke
			(width 0.06985)
			(type default)
		)
		(layer "In9.Cu")
	)
	(gr_arc
		(start 139.80287 -18.866866)
		(mid 139.844021 -18.894299)
		(end 139.892532 -18.90395)
		(stroke
			(width 0.06985)
			(type default)
		)
		(layer "In9.Cu")
	)
	(gr_arc
		(start 139.892532 -19.196304)
		(mid 139.844023 -19.205953)
		(end 139.80287 -19.233388)
		(stroke
			(width 0.06985)
			(type default)
		)
		(layer "In9.Cu")
	)
	(gr_line
		(start 140.50391 -31.672276)
		(end 140.531342 -31.713932)
		(stroke
			(width 0.06985)
			(type default)
		)
		(layer "In9.Cu")
	)
	(gr_line
		(start 140.548868 -51.662076)
		(end 140.566648 -51.674014)
		(stroke
			(width 0.06985)
			(type default)
		)
		(layer "In9.Cu")
	)
	(gr_line
		(start 140.566648 -51.674014)
		(end 140.588238 -51.678332)
		(stroke
			(width 0.06985)
			(type default)
		)
		(layer "In9.Cu")
	)
	(gr_line
		(start 140.922502 -32.307276)
		(end 140.933932 -32.324294)
		(stroke
			(width 0.06985)
			(type default)
		)
		(layer "In9.Cu")
	)
	(gr_line
		(start 140.933932 -32.324294)
		(end 140.950696 -32.33547)
		(stroke
			(width 0.06985)
			(type default)
		)
		(layer "In9.Cu")
	)
	(gr_line
		(start 141.549882 -18.3388)
		(end 141.549882 -18.750026)
		(stroke
			(width 0.06985)
			(type default)
		)
		(layer "In9.Cu")
	)
	(gr_arc
		(start 141.549882 -17.761458)
		(mid 141.559515 -17.809976)
		(end 141.586966 -17.85112)
		(stroke
			(width 0.06985)
			(type default)
		)
		(layer "In9.Cu")
	)
	(gr_line
		(start 141.549882 -17.349978)
		(end 141.549882 -17.761458)
		(stroke
			(width 0.06985)
			(type default)
		)
		(layer "In9.Cu")
	)
	(gr_arc
		(start 141.586966 -18.249138)
		(mid 141.559515 -18.290285)
		(end 141.549882 -18.3388)
		(stroke
			(width 0.06985)
			(type default)
		)
		(layer "In9.Cu")
	)
	(gr_line
		(start 141.586966 -18.249138)
		(end 141.602714 -18.23339)
		(stroke
			(width 0.06985)
			(type default)
		)
		(layer "In9.Cu")
	)
	(gr_line
		(start 141.586966 -17.85112)
		(end 141.602714 -17.866868)
		(stroke
			(width 0.06985)
			(type default)
		)
		(layer "In9.Cu")
	)
	(gr_arc
		(start 141.602714 -17.866868)
		(mid 141.643865 -17.894301)
		(end 141.692376 -17.903952)
		(stroke
			(width 0.06985)
			(type default)
		)
		(layer "In9.Cu")
	)
	(gr_arc
		(start 141.692376 -18.196306)
		(mid 141.643858 -18.205941)
		(end 141.602714 -18.23339)
		(stroke
			(width 0.06985)
			(type default)
		)
		(layer "In9.Cu")
	)
	(gr_line
		(start 142.290546 -34.660586)
		(end 142.307564 -34.672016)
		(stroke
			(width 0.06985)
			(type default)
		)
		(layer "In9.Cu")
	)
	(gr_line
		(start 142.303754 -31.719774)
		(end 142.330678 -31.760414)
		(stroke
			(width 0.06985)
			(type default)
		)
		(layer "In9.Cu")
	)
	(gr_line
		(start 142.307564 -34.672016)
		(end 142.32763 -34.675826)
		(stroke
			(width 0.06985)
			(type default)
		)
		(layer "In9.Cu")
	)
	(gr_line
		(start 142.596108 -33.445704)
		(end 142.613126 -33.457134)
		(stroke
			(width 0.06985)
			(type default)
		)
		(layer "In9.Cu")
	)
	(gr_line
		(start 142.599664 -32.169354)
		(end 142.61084 -32.186372)
		(stroke
			(width 0.06985)
			(type default)
		)
		(layer "In9.Cu")
	)
	(gr_line
		(start 142.61084 -32.186372)
		(end 142.627604 -32.197548)
		(stroke
			(width 0.06985)
			(type default)
		)
		(layer "In9.Cu")
	)
	(gr_line
		(start 142.613126 -33.457134)
		(end 142.633192 -33.460944)
		(stroke
			(width 0.06985)
			(type default)
		)
		(layer "In9.Cu")
	)
	(gr_line
		(start 142.97025 -32.428434)
		(end 142.987268 -32.439864)
		(stroke
			(width 0.06985)
			(type default)
		)
		(layer "In9.Cu")
	)
	(gr_line
		(start 142.987268 -32.439864)
		(end 143.007334 -32.443928)
		(stroke
			(width 0.06985)
			(type default)
		)
		(layer "In9.Cu")
	)
	(gr_line
		(start 143.34998 -19.389852)
		(end 143.34998 -19.750024)
		(stroke
			(width 0.06985)
			(type default)
		)
		(layer "In9.Cu")
	)
	(gr_arc
		(start 143.34998 -18.710148)
		(mid 143.406743 -18.847187)
		(end 143.543782 -18.90395)
		(stroke
			(width 0.06985)
			(type default)
		)
		(layer "In9.Cu")
	)
	(gr_line
		(start 143.34998 -18.35023)
		(end 143.34998 -18.710148)
		(stroke
			(width 0.06985)
			(type default)
		)
		(layer "In9.Cu")
	)
	(gr_arc
		(start 143.543782 -19.19605)
		(mid 143.406738 -19.252817)
		(end 143.34998 -19.389852)
		(stroke
			(width 0.06985)
			(type default)
		)
		(layer "In9.Cu")
	)
	(gr_line
		(start 144.382236 -55.48376)
		(end 144.398746 -55.494682)
		(stroke
			(width 0.06985)
			(type default)
		)
		(layer "In9.Cu")
	)
	(gr_line
		(start 144.398746 -55.494682)
		(end 144.418304 -55.498746)
		(stroke
			(width 0.06985)
			(type default)
		)
		(layer "In9.Cu")
	)
	(gr_line
		(start 146.017742 -43.11523)
		(end 146.035522 -43.127168)
		(stroke
			(width 0.06985)
			(type default)
		)
		(layer "In9.Cu")
	)
	(gr_line
		(start 146.035522 -43.127168)
		(end 146.057112 -43.131486)
		(stroke
			(width 0.06985)
			(type default)
		)
		(layer "In9.Cu")
	)
	(gr_line
		(start 146.585432 -40.53586)
		(end 146.60245 -40.54729)
		(stroke
			(width 0.06985)
			(type default)
		)
		(layer "In9.Cu")
	)
	(gr_line
		(start 146.60245 -40.54729)
		(end 146.623278 -40.551608)
		(stroke
			(width 0.06985)
			(type default)
		)
		(layer "In9.Cu")
	)
	(gr_line
		(start 146.760946 -39.340536)
		(end 146.777964 -39.351966)
		(stroke
			(width 0.06985)
			(type default)
		)
		(layer "In9.Cu")
	)
	(gr_line
		(start 146.777964 -39.351966)
		(end 146.778218 -39.351966)
		(stroke
			(width 0.06985)
			(type default)
		)
		(layer "In9.Cu")
	)
	(gr_line
		(start 146.778218 -39.351966)
		(end 146.798284 -39.35603)
		(stroke
			(width 0.06985)
			(type default)
		)
		(layer "In9.Cu")
	)
	(gr_line
		(start 147.105116 -42.23639)
		(end 147.121372 -42.247312)
		(stroke
			(width 0.06985)
			(type default)
		)
		(layer "In9.Cu")
	)
	(gr_line
		(start 147.121372 -42.247312)
		(end 147.141184 -42.251376)
		(stroke
			(width 0.06985)
			(type default)
		)
		(layer "In9.Cu")
	)
	(gr_line
		(start 153.640028 -50.902362)
		(end 153.643584 -50.90414)
		(stroke
			(width 0.06985)
			(type default)
		)
		(layer "In9.Cu")
	)
	(gr_line
		(start 153.643584 -50.90414)
		(end 153.64714 -50.904902)
		(stroke
			(width 0.06985)
			(type default)
		)
		(layer "In9.Cu")
	)
	(gr_line
		(start 155.327604 -68.830698)
		(end 155.344622 -68.841874)
		(stroke
			(width 0.06985)
			(type default)
		)
		(layer "In9.Cu")
	)
	(gr_line
		(start 155.344622 -68.841874)
		(end 155.364942 -68.845938)
		(stroke
			(width 0.06985)
			(type default)
		)
		(layer "In9.Cu")
	)
	(gr_line
		(start 155.985464 -49.720754)
		(end 155.98775 -49.722024)
		(stroke
			(width 0.06985)
			(type default)
		)
		(layer "In9.Cu")
	)
	(gr_line
		(start 155.98775 -49.722024)
		(end 155.99029 -49.722532)
		(stroke
			(width 0.06985)
			(type default)
		)
		(layer "In9.Cu")
	)
	(gr_line
		(start 157.049724 -75.788266)
		(end 157.06598 -75.799188)
		(stroke
			(width 0.06985)
			(type default)
		)
		(layer "In9.Cu")
	)
	(gr_line
		(start 157.06598 -75.799188)
		(end 157.086046 -75.803252)
		(stroke
			(width 0.06985)
			(type default)
		)
		(layer "In9.Cu")
	)
	(gr_line
		(start 157.196028 -74.346054)
		(end 157.212284 -74.356976)
		(stroke
			(width 0.06985)
			(type default)
		)
		(layer "In9.Cu")
	)
	(gr_line
		(start 157.212284 -74.356976)
		(end 157.23235 -74.36104)
		(stroke
			(width 0.06985)
			(type default)
		)
		(layer "In9.Cu")
	)
	(gr_line
		(start 157.479238 -73.01611)
		(end 157.495494 -73.027032)
		(stroke
			(width 0.06985)
			(type default)
		)
		(layer "In9.Cu")
	)
	(gr_line
		(start 157.495494 -73.027032)
		(end 157.51556 -73.031096)
		(stroke
			(width 0.06985)
			(type default)
		)
		(layer "In9.Cu")
	)
	(gr_line
		(start 157.638242 -42.791888)
		(end 157.658308 -42.795952)
		(stroke
			(width 0.06985)
			(type default)
		)
		(layer "In9.Cu")
	)
	(gr_line
		(start 157.658308 -42.795952)
		(end 157.678374 -42.792142)
		(stroke
			(width 0.06985)
			(type default)
		)
		(layer "In9.Cu")
	)
	(gr_line
		(start 157.694122 -41.519094)
		(end 157.714188 -41.523158)
		(stroke
			(width 0.06985)
			(type default)
		)
		(layer "In9.Cu")
	)
	(gr_line
		(start 157.714188 -41.523158)
		(end 157.734254 -41.519094)
		(stroke
			(width 0.06985)
			(type default)
		)
		(layer "In9.Cu")
	)
	(gr_line
		(start 159.20339 -35.65906)
		(end 159.223456 -35.663124)
		(stroke
			(width 0.06985)
			(type default)
		)
		(layer "In9.Cu")
	)
	(gr_line
		(start 159.223456 -35.663124)
		(end 159.243268 -35.65906)
		(stroke
			(width 0.06985)
			(type default)
		)
		(layer "In9.Cu")
	)
	(gr_line
		(start 160.551114 -37.041836)
		(end 160.571434 -37.0459)
		(stroke
			(width 0.06985)
			(type default)
		)
		(layer "In9.Cu")
	)
	(gr_line
		(start 160.571434 -37.0459)
		(end 160.590992 -37.04209)
		(stroke
			(width 0.06985)
			(type default)
		)
		(layer "In9.Cu")
	)
	(gr_line
		(start 161.164524 -38.43782)
		(end 161.184844 -38.441884)
		(stroke
			(width 0.06985)
			(type default)
		)
		(layer "In9.Cu")
	)
	(gr_line
		(start 161.184844 -38.441884)
		(end 161.204402 -38.438074)
		(stroke
			(width 0.06985)
			(type default)
		)
		(layer "In9.Cu")
	)
	(gr_line
		(start 162.434016 -45.28185)
		(end 162.452558 -45.285406)
		(stroke
			(width 0.06985)
			(type default)
		)
		(layer "In9.Cu")
	)
	(gr_line
		(start 162.452558 -45.285406)
		(end 162.4711 -45.28185)
		(stroke
			(width 0.06985)
			(type default)
		)
		(layer "In9.Cu")
	)
	(gr_line
		(start 162.504374 -46.39056)
		(end 162.522916 -46.394116)
		(stroke
			(width 0.06985)
			(type default)
		)
		(layer "In9.Cu")
	)
	(gr_line
		(start 162.522916 -46.394116)
		(end 162.541458 -46.39056)
		(stroke
			(width 0.06985)
			(type default)
		)
		(layer "In9.Cu")
	)
	(gr_line
		(start 173.653196 -61.46673)
		(end 173.675802 -61.471302)
		(stroke
			(width 0.06985)
			(type default)
		)
		(layer "In9.Cu")
	)
	(gr_line
		(start 173.675802 -61.471302)
		(end 173.697646 -61.46673)
		(stroke
			(width 0.06985)
			(type default)
		)
		(layer "In9.Cu")
	)
	(gr_line
		(start 176.616614 -53.891434)
		(end 176.63795 -53.895752)
		(stroke
			(width 0.06985)
			(type default)
		)
		(layer "In9.Cu")
	)
	(gr_line
		(start 176.63795 -53.895752)
		(end 176.659286 -53.891434)
		(stroke
			(width 0.06985)
			(type default)
		)
		(layer "In9.Cu")
	)
	(gr_line
		(start 176.725326 -55.59933)
		(end 176.748186 -55.603902)
		(stroke
			(width 0.06985)
			(type default)
		)
		(layer "In9.Cu")
	)
	(gr_line
		(start 176.748186 -55.603902)
		(end 176.77003 -55.59933)
		(stroke
			(width 0.06985)
			(type default)
		)
		(layer "In9.Cu")
	)
	(gr_line
		(start 177.629312 -59.01436)
		(end 177.649886 -59.018424)
		(stroke
			(width 0.06985)
			(type default)
		)
		(layer "In9.Cu")
	)
	(gr_line
		(start 177.649886 -59.018424)
		(end 177.671222 -59.014106)
		(stroke
			(width 0.06985)
			(type default)
		)
		(layer "In9.Cu")
	)
	(gr_line
		(start 181.357778 -42.43578)
		(end 181.372764 -42.432986)
		(stroke
			(width 0.06985)
			(type default)
		)
		(layer "In9.Cu")
	)
	(gr_line
		(start 181.372764 -42.432986)
		(end 181.387242 -42.435526)
		(stroke
			(width 0.06985)
			(type default)
		)
		(layer "In9.Cu")
	)
	(gr_line
		(start 186.570112 -27.531822)
		(end 186.590686 -27.535886)
		(stroke
			(width 0.06985)
			(type default)
		)
		(layer "In9.Cu")
	)
	(gr_line
		(start 186.590686 -27.535886)
		(end 186.611768 -27.531568)
		(stroke
			(width 0.06985)
			(type default)
		)
		(layer "In9.Cu")
	)
	(gr_line
		(start 193.346578 -38.982142)
		(end 193.36512 -38.978586)
		(stroke
			(width 0.06985)
			(type default)
		)
		(layer "In9.Cu")
	)
	(gr_line
		(start 193.36512 -38.978586)
		(end 193.383916 -38.982142)
		(stroke
			(width 0.06985)
			(type default)
		)
		(layer "In9.Cu")
	)
	(gr_line
		(start 194.980306 -35.243008)
		(end 195.000372 -35.238944)
		(stroke
			(width 0.06985)
			(type default)
		)
		(layer "In9.Cu")
	)
	(gr_line
		(start 195.000372 -35.238944)
		(end 195.020438 -35.243008)
		(stroke
			(width 0.06985)
			(type default)
		)
		(layer "In9.Cu")
	)
	(gr_line
		(start 196.07276 -51.262534)
		(end 196.093334 -51.258216)
		(stroke
			(width 0.06985)
			(type default)
		)
		(layer "In9.Cu")
	)
	(gr_line
		(start 196.093334 -51.258216)
		(end 196.114162 -51.26228)
		(stroke
			(width 0.06985)
			(type default)
		)
		(layer "In9.Cu")
	)
	(gr_line
		(start 200.66889 -48.70831)
		(end 200.688448 -48.704246)
		(stroke
			(width 0.06985)
			(type default)
		)
		(layer "In9.Cu")
	)
	(gr_line
		(start 200.688448 -48.704246)
		(end 200.70826 -48.708056)
		(stroke
			(width 0.06985)
			(type default)
		)
		(layer "In9.Cu")
	)
	(gr_line
		(start 201.12228 -339.262974)
		(end 201.130916 -339.301328)
		(stroke
			(width 0.06985)
			(type default)
		)
		(layer "In9.Cu")
	)
	(gr_line
		(start 201.12228 -339.262974)
		(end 201.133456 -339.226144)
		(stroke
			(width 0.06985)
			(type default)
		)
		(layer "In9.Cu")
	)
	(gr_line
		(start 201.696828 -53.697632)
		(end 201.71791 -53.693314)
		(stroke
			(width 0.06985)
			(type default)
		)
		(layer "In9.Cu")
	)
	(gr_line
		(start 201.71791 -53.693314)
		(end 201.73823 -53.697378)
		(stroke
			(width 0.06985)
			(type default)
		)
		(layer "In9.Cu")
	)
	(gr_line
		(start 201.74077 -32.667194)
		(end 201.760836 -32.66313)
		(stroke
			(width 0.06985)
			(type default)
		)
		(layer "In9.Cu")
	)
	(gr_line
		(start 201.760836 -32.66313)
		(end 201.780902 -32.667194)
		(stroke
			(width 0.06985)
			(type default)
		)
		(layer "In9.Cu")
	)
	(gr_line
		(start 202.097132 -55.21706)
		(end 202.118214 -55.212742)
		(stroke
			(width 0.06985)
			(type default)
		)
		(layer "In9.Cu")
	)
	(gr_line
		(start 202.118214 -55.212742)
		(end 202.138788 -55.216806)
		(stroke
			(width 0.06985)
			(type default)
		)
		(layer "In9.Cu")
	)
	(gr_line
		(start 202.650344 -393.007342)
		(end 202.65644 -393.034266)
		(stroke
			(width 0.06985)
			(type default)
		)
		(layer "In9.Cu")
	)
	(gr_line
		(start 202.650344 -393.007342)
		(end 202.65644 -392.980672)
		(stroke
			(width 0.06985)
			(type default)
		)
		(layer "In9.Cu")
	)
	(gr_line
		(start 202.65644 -393.03452)
		(end 202.65644 -393.034774)
		(stroke
			(width 0.06985)
			(type default)
		)
		(layer "In9.Cu")
	)
	(gr_line
		(start 202.755754 -339.697314)
		(end 202.76439 -339.735668)
		(stroke
			(width 0.06985)
			(type default)
		)
		(layer "In9.Cu")
	)
	(gr_line
		(start 202.755754 -339.697314)
		(end 202.76693 -339.660484)
		(stroke
			(width 0.06985)
			(type default)
		)
		(layer "In9.Cu")
	)
	(gr_line
		(start 203.222098 -82.10931)
		(end 203.242672 -82.113374)
		(stroke
			(width 0.06985)
			(type default)
		)
		(layer "In9.Cu")
	)
	(gr_line
		(start 203.242672 -82.113374)
		(end 203.263754 -82.109056)
		(stroke
			(width 0.06985)
			(type default)
		)
		(layer "In9.Cu")
	)
	(gr_line
		(start 203.763372 -78.463394)
		(end 203.787248 -78.46822)
		(stroke
			(width 0.06985)
			(type default)
		)
		(layer "In9.Cu")
	)
	(gr_line
		(start 203.787248 -78.46822)
		(end 203.811378 -78.462886)
		(stroke
			(width 0.06985)
			(type default)
		)
		(layer "In9.Cu")
	)
	(gr_line
		(start 204.182218 -392.956796)
		(end 204.18806 -392.930126)
		(stroke
			(width 0.06985)
			(type default)
		)
		(layer "In9.Cu")
	)
	(gr_line
		(start 204.182218 -392.956796)
		(end 204.188314 -392.984228)
		(stroke
			(width 0.06985)
			(type default)
		)
		(layer "In9.Cu")
	)
	(gr_line
		(start 204.188314 -392.983974)
		(end 204.188314 -392.984482)
		(stroke
			(width 0.06985)
			(type default)
		)
		(layer "In9.Cu")
	)
	(gr_line
		(start 204.391006 -339.942424)
		(end 204.399642 -339.980778)
		(stroke
			(width 0.06985)
			(type default)
		)
		(layer "In9.Cu")
	)
	(gr_line
		(start 204.391006 -339.942424)
		(end 204.402182 -339.905594)
		(stroke
			(width 0.06985)
			(type default)
		)
		(layer "In9.Cu")
	)
	(gr_line
		(start 206.268828 -340.832694)
		(end 206.277464 -340.871048)
		(stroke
			(width 0.06985)
			(type default)
		)
		(layer "In9.Cu")
	)
	(gr_line
		(start 206.268828 -340.832694)
		(end 206.280004 -340.795864)
		(stroke
			(width 0.06985)
			(type default)
		)
		(layer "In9.Cu")
	)
	(gr_arc
		(start 206.87538 -387.286754)
		(mid 206.872024 -387.317233)
		(end 206.87538 -387.347714)
		(stroke
			(width 0.06985)
			(type default)
		)
		(layer "In9.Cu")
	)
	(gr_line
		(start 207.320896 -413.671258)
		(end 207.33131 -413.717232)
		(stroke
			(width 0.06985)
			(type default)
		)
		(layer "In9.Cu")
	)
	(gr_line
		(start 207.90535 -341.25535)
		(end 207.913986 -341.293704)
		(stroke
			(width 0.06985)
			(type default)
		)
		(layer "In9.Cu")
	)
	(gr_line
		(start 207.90535 -341.25535)
		(end 207.91678 -341.216996)
		(stroke
			(width 0.06985)
			(type default)
		)
		(layer "In9.Cu")
	)
	(gr_line
		(start 208.118456 -410.349446)
		(end 208.129124 -410.396182)
		(stroke
			(width 0.06985)
			(type default)
		)
		(layer "In9.Cu")
	)
	(gr_arc
		(start 208.204054 -369.295172)
		(mid 208.207418 -369.264692)
		(end 208.204054 -369.234212)
		(stroke
			(width 0.06985)
			(type default)
		)
		(layer "In9.Cu")
	)
	(gr_arc
		(start 208.601056 -386.838698)
		(mid 208.597688 -386.869179)
		(end 208.601056 -386.899658)
		(stroke
			(width 0.06985)
			(type default)
		)
		(layer "In9.Cu")
	)
	(gr_line
		(start 209.593688 -341.44077)
		(end 209.602324 -341.479124)
		(stroke
			(width 0.06985)
			(type default)
		)
		(layer "In9.Cu")
	)
	(gr_line
		(start 209.593688 -341.44077)
		(end 209.604864 -341.40394)
		(stroke
			(width 0.06985)
			(type default)
		)
		(layer "In9.Cu")
	)
	(gr_line
		(start 209.706464 -84.783422)
		(end 209.727038 -84.787486)
		(stroke
			(width 0.06985)
			(type default)
		)
		(layer "In9.Cu")
	)
	(gr_line
		(start 209.727038 -84.787486)
		(end 209.74812 -84.783168)
		(stroke
			(width 0.06985)
			(type default)
		)
		(layer "In9.Cu")
	)
	(gr_line
		(start 209.732626 -369.259612)
		(end 209.738722 -369.232434)
		(stroke
			(width 0.06985)
			(type default)
		)
		(layer "In9.Cu")
	)
	(gr_line
		(start 209.732626 -369.205256)
		(end 209.738722 -369.232434)
		(stroke
			(width 0.06985)
			(type default)
		)
		(layer "In9.Cu")
	)
	(gr_arc
		(start 209.788252 -414.75406)
		(mid 209.938082 -414.692033)
		(end 210.000088 -414.542224)
		(stroke
			(width 0.06985)
			(type default)
		)
		(layer "In9.Cu")
	)
	(gr_arc
		(start 209.821018 -411.154118)
		(mid 209.869518 -411.144454)
		(end 209.91068 -411.117034)
		(stroke
			(width 0.06985)
			(type default)
		)
		(layer "In9.Cu")
	)
	(gr_arc
		(start 209.910172 -411.483302)
		(mid 209.869021 -411.455869)
		(end 209.82051 -411.446218)
		(stroke
			(width 0.06985)
			(type default)
		)
		(layer "In9.Cu")
	)
	(gr_line
		(start 209.910172 -411.483302)
		(end 209.963004 -411.536134)
		(stroke
			(width 0.06985)
			(type default)
		)
		(layer "In9.Cu")
	)
	(gr_line
		(start 209.91068 -411.117034)
		(end 209.963004 -411.06471)
		(stroke
			(width 0.06985)
			(type default)
		)
		(layer "In9.Cu")
	)
	(gr_arc
		(start 209.963004 -411.06471)
		(mid 209.990444 -411.023562)
		(end 210.000088 -410.975048)
		(stroke
			(width 0.06985)
			(type default)
		)
		(layer "In9.Cu")
	)
	(gr_arc
		(start 210.000088 -415.257996)
		(mid 209.938043 -415.108205)
		(end 209.788252 -415.04616)
		(stroke
			(width 0.06985)
			(type default)
		)
		(layer "In9.Cu")
	)
	(gr_line
		(start 210.000088 -415.257996)
		(end 210.000088 -415.600134)
		(stroke
			(width 0.06985)
			(type default)
		)
		(layer "In9.Cu")
	)
	(gr_line
		(start 210.000088 -414.200086)
		(end 210.000088 -414.542224)
		(stroke
			(width 0.06985)
			(type default)
		)
		(layer "In9.Cu")
	)
	(gr_arc
		(start 210.000088 -411.625796)
		(mid 209.990455 -411.577278)
		(end 209.963004 -411.536134)
		(stroke
			(width 0.06985)
			(type default)
		)
		(layer "In9.Cu")
	)
	(gr_line
		(start 210.000088 -411.625796)
		(end 210.000088 -412.000192)
		(stroke
			(width 0.06985)
			(type default)
		)
		(layer "In9.Cu")
	)
	(gr_line
		(start 210.000088 -410.600144)
		(end 210.000088 -410.975048)
		(stroke
			(width 0.06985)
			(type default)
		)
		(layer "In9.Cu")
	)
	(gr_arc
		(start 210.278726 -387.88975)
		(mid 210.27601 -387.918874)
		(end 210.279488 -387.947916)
		(stroke
			(width 0.06985)
			(type default)
		)
		(layer "In9.Cu")
	)
	(gr_arc
		(start 210.754214 -404.506176)
		(mid 210.753299 -404.490709)
		(end 210.750658 -404.475442)
		(stroke
			(width 0.06985)
			(type default)
		)
		(layer "In9.Cu")
	)
	(gr_line
		(start 211.044028 -404.447502)
		(end 211.046314 -404.457916)
		(stroke
			(width 0.06985)
			(type default)
		)
		(layer "In9.Cu")
	)
	(gr_line
		(start 211.239608 -368.935254)
		(end 211.245704 -368.908076)
		(stroke
			(width 0.06985)
			(type default)
		)
		(layer "In9.Cu")
	)
	(gr_line
		(start 211.239608 -368.880898)
		(end 211.245704 -368.908076)
		(stroke
			(width 0.06985)
			(type default)
		)
		(layer "In9.Cu")
	)
	(gr_line
		(start 211.290154 -341.734902)
		(end 211.29879 -341.773256)
		(stroke
			(width 0.06985)
			(type default)
		)
		(layer "In9.Cu")
	)
	(gr_line
		(start 211.290154 -341.734902)
		(end 211.30133 -341.698072)
		(stroke
			(width 0.06985)
			(type default)
		)
		(layer "In9.Cu")
	)
	(gr_arc
		(start 211.621116 -417.354004)
		(mid 211.669615 -417.344339)
		(end 211.710778 -417.31692)
		(stroke
			(width 0.06985)
			(type default)
		)
		(layer "In9.Cu")
	)
	(gr_arc
		(start 211.71027 -417.683188)
		(mid 211.669119 -417.655755)
		(end 211.620608 -417.646104)
		(stroke
			(width 0.06985)
			(type default)
		)
		(layer "In9.Cu")
	)
	(gr_line
		(start 211.71027 -417.683188)
		(end 211.763102 -417.73602)
		(stroke
			(width 0.06985)
			(type default)
		)
		(layer "In9.Cu")
	)
	(gr_line
		(start 211.710778 -417.31692)
		(end 211.763102 -417.264596)
		(stroke
			(width 0.06985)
			(type default)
		)
		(layer "In9.Cu")
	)
	(gr_arc
		(start 211.763102 -417.264596)
		(mid 211.790538 -417.223447)
		(end 211.800186 -417.174934)
		(stroke
			(width 0.06985)
			(type default)
		)
		(layer "In9.Cu")
	)
	(gr_arc
		(start 211.800186 -417.825682)
		(mid 211.790553 -417.777164)
		(end 211.763102 -417.73602)
		(stroke
			(width 0.06985)
			(type default)
		)
		(layer "In9.Cu")
	)
	(gr_line
		(start 211.800186 -417.825682)
		(end 211.800186 -418.200078)
		(stroke
			(width 0.06985)
			(type default)
		)
		(layer "In9.Cu")
	)
	(gr_line
		(start 211.800186 -416.80003)
		(end 211.800186 -417.174934)
		(stroke
			(width 0.06985)
			(type default)
		)
		(layer "In9.Cu")
	)
	(gr_arc
		(start 212.137498 -386.275326)
		(mid 212.134135 -386.305806)
		(end 212.137498 -386.336286)
		(stroke
			(width 0.06985)
			(type default)
		)
		(layer "In9.Cu")
	)
	(gr_arc
		(start 212.554058 -404.388066)
		(mid 212.553143 -404.372599)
		(end 212.550502 -404.357332)
		(stroke
			(width 0.06985)
			(type default)
		)
		(layer "In9.Cu")
	)
	(gr_line
		(start 212.843872 -404.329392)
		(end 212.846158 -404.339806)
		(stroke
			(width 0.06985)
			(type default)
		)
		(layer "In9.Cu")
	)
	(gr_line
		(start 212.846158 -342.42375)
		(end 212.854794 -342.462104)
		(stroke
			(width 0.06985)
			(type default)
		)
		(layer "In9.Cu")
	)
	(gr_line
		(start 212.846158 -342.42375)
		(end 212.857334 -342.38692)
		(stroke
			(width 0.06985)
			(type default)
		)
		(layer "In9.Cu")
	)
	(gr_line
		(start 212.889846 -368.8334)
		(end 212.895942 -368.806222)
		(stroke
			(width 0.06985)
			(type default)
		)
		(layer "In9.Cu")
	)
	(gr_line
		(start 212.889846 -368.779044)
		(end 212.895942 -368.806222)
		(stroke
			(width 0.06985)
			(type default)
		)
		(layer "In9.Cu")
	)
	(gr_arc
		(start 213.388194 -414.75406)
		(mid 213.537997 -414.692018)
		(end 213.60003 -414.542224)
		(stroke
			(width 0.06985)
			(type default)
		)
		(layer "In9.Cu")
	)
	(gr_arc
		(start 213.60003 -415.257996)
		(mid 213.537985 -415.108205)
		(end 213.388194 -415.04616)
		(stroke
			(width 0.06985)
			(type default)
		)
		(layer "In9.Cu")
	)
	(gr_line
		(start 213.60003 -415.257996)
		(end 213.60003 -415.600134)
		(stroke
			(width 0.06985)
			(type default)
		)
		(layer "In9.Cu")
	)
	(gr_line
		(start 213.60003 -414.200086)
		(end 213.60003 -414.542224)
		(stroke
			(width 0.06985)
			(type default)
		)
		(layer "In9.Cu")
	)
	(gr_arc
		(start 213.73338 -387.642862)
		(mid 213.730532 -387.672226)
		(end 213.733888 -387.701536)
		(stroke
			(width 0.06985)
			(type default)
		)
		(layer "In9.Cu")
	)
	(gr_arc
		(start 214.354156 -405.96947)
		(mid 214.353241 -405.954003)
		(end 214.3506 -405.938736)
		(stroke
			(width 0.06985)
			(type default)
		)
		(layer "In9.Cu")
	)
	(gr_line
		(start 214.406734 -368.67211)
		(end 214.412068 -368.695732)
		(stroke
			(width 0.06985)
			(type default)
		)
		(layer "In9.Cu")
	)
	(gr_line
		(start 214.407242 -368.719608)
		(end 214.412068 -368.695732)
		(stroke
			(width 0.06985)
			(type default)
		)
		(layer "In9.Cu")
	)
	(gr_line
		(start 214.46744 -342.89873)
		(end 214.476076 -342.937084)
		(stroke
			(width 0.06985)
			(type default)
		)
		(layer "In9.Cu")
	)
	(gr_line
		(start 214.46744 -342.89873)
		(end 214.478616 -342.8619)
		(stroke
			(width 0.06985)
			(type default)
		)
		(layer "In9.Cu")
	)
	(gr_line
		(start 214.593678 -21.371814)
		(end 214.61476 -21.367496)
		(stroke
			(width 0.06985)
			(type default)
		)
		(layer "In9.Cu")
	)
	(gr_line
		(start 214.61476 -21.367496)
		(end 214.635334 -21.37156)
		(stroke
			(width 0.06985)
			(type default)
		)
		(layer "In9.Cu")
	)
	(gr_line
		(start 214.64397 -405.910796)
		(end 214.646256 -405.92121)
		(stroke
			(width 0.06985)
			(type default)
		)
		(layer "In9.Cu")
	)
	(gr_arc
		(start 215.221058 -417.354004)
		(mid 215.269569 -417.344358)
		(end 215.31072 -417.31692)
		(stroke
			(width 0.06985)
			(type default)
		)
		(layer "In9.Cu")
	)
	(gr_arc
		(start 215.310212 -417.683188)
		(mid 215.269061 -417.655755)
		(end 215.22055 -417.646104)
		(stroke
			(width 0.06985)
			(type default)
		)
		(layer "In9.Cu")
	)
	(gr_line
		(start 215.310212 -417.683188)
		(end 215.363044 -417.73602)
		(stroke
			(width 0.06985)
			(type default)
		)
		(layer "In9.Cu")
	)
	(gr_line
		(start 215.31072 -417.31692)
		(end 215.363044 -417.264596)
		(stroke
			(width 0.06985)
			(type default)
		)
		(layer "In9.Cu")
	)
	(gr_arc
		(start 215.363044 -417.264596)
		(mid 215.390492 -417.22345)
		(end 215.400128 -417.174934)
		(stroke
			(width 0.06985)
			(type default)
		)
		(layer "In9.Cu")
	)
	(gr_arc
		(start 215.400128 -417.825682)
		(mid 215.390495 -417.777164)
		(end 215.363044 -417.73602)
		(stroke
			(width 0.06985)
			(type default)
		)
		(layer "In9.Cu")
	)
	(gr_line
		(start 215.400128 -417.825682)
		(end 215.400128 -418.200078)
		(stroke
			(width 0.06985)
			(type default)
		)
		(layer "In9.Cu")
	)
	(gr_line
		(start 215.400128 -416.80003)
		(end 215.400128 -417.174934)
		(stroke
			(width 0.06985)
			(type default)
		)
		(layer "In9.Cu")
	)
	(gr_line
		(start 215.52408 -87.410544)
		(end 215.544654 -87.414608)
		(stroke
			(width 0.06985)
			(type default)
		)
		(layer "In9.Cu")
	)
	(gr_line
		(start 215.544654 -87.414608)
		(end 215.565736 -87.41029)
		(stroke
			(width 0.06985)
			(type default)
		)
		(layer "In9.Cu")
	)
	(gr_arc
		(start 215.563704 -386.769356)
		(mid 215.560348 -386.799835)
		(end 215.563704 -386.830316)
		(stroke
			(width 0.06985)
			(type default)
		)
		(layer "In9.Cu")
	)
	(gr_arc
		(start 216.154 -404.105618)
		(mid 216.153085 -404.090151)
		(end 216.150444 -404.074884)
		(stroke
			(width 0.06985)
			(type default)
		)
		(layer "In9.Cu")
	)
	(gr_line
		(start 216.188798 -369.317524)
		(end 216.194894 -369.2906)
		(stroke
			(width 0.06985)
			(type default)
		)
		(layer "In9.Cu")
	)
	(gr_line
		(start 216.188798 -369.263422)
		(end 216.194894 -369.2906)
		(stroke
			(width 0.06985)
			(type default)
		)
		(layer "In9.Cu")
	)
	(gr_line
		(start 216.443814 -404.046944)
		(end 216.4461 -404.057358)
		(stroke
			(width 0.06985)
			(type default)
		)
		(layer "In9.Cu")
	)
	(gr_line
		(start 216.961466 -27.302206)
		(end 216.981532 -27.298142)
		(stroke
			(width 0.06985)
			(type default)
		)
		(layer "In9.Cu")
	)
	(gr_line
		(start 216.981532 -27.298142)
		(end 217.001598 -27.302206)
		(stroke
			(width 0.06985)
			(type default)
		)
		(layer "In9.Cu")
	)
	(gr_arc
		(start 216.988136 -414.75406)
		(mid 217.137912 -414.692003)
		(end 217.199972 -414.542224)
		(stroke
			(width 0.06985)
			(type default)
		)
		(layer "In9.Cu")
	)
	(gr_arc
		(start 217.199972 -415.257996)
		(mid 217.137927 -415.108205)
		(end 216.988136 -415.04616)
		(stroke
			(width 0.06985)
			(type default)
		)
		(layer "In9.Cu")
	)
	(gr_line
		(start 217.199972 -415.257996)
		(end 217.199972 -415.600134)
		(stroke
			(width 0.06985)
			(type default)
		)
		(layer "In9.Cu")
	)
	(gr_line
		(start 217.199972 -414.200086)
		(end 217.199972 -414.542224)
		(stroke
			(width 0.06985)
			(type default)
		)
		(layer "In9.Cu")
	)
	(gr_arc
		(start 217.368374 -386.932932)
		(mid 217.365659 -386.96231)
		(end 217.369136 -386.991606)
		(stroke
			(width 0.06985)
			(type default)
		)
		(layer "In9.Cu")
	)
	(gr_line
		(start 217.617294 -23.925022)
		(end 217.636852 -23.921212)
		(stroke
			(width 0.06985)
			(type default)
		)
		(layer "In9.Cu")
	)
	(gr_line
		(start 217.636852 -23.921212)
		(end 217.656918 -23.925276)
		(stroke
			(width 0.06985)
			(type default)
		)
		(layer "In9.Cu")
	)
	(gr_line
		(start 217.78722 -369.139978)
		(end 217.792808 -369.165124)
		(stroke
			(width 0.06985)
			(type default)
		)
		(layer "In9.Cu")
	)
	(gr_line
		(start 217.787728 -369.19027)
		(end 217.787728 -369.190524)
		(stroke
			(width 0.06985)
			(type default)
		)
		(layer "In9.Cu")
	)
	(gr_line
		(start 217.787728 -369.190016)
		(end 217.792808 -369.165124)
		(stroke
			(width 0.06985)
			(type default)
		)
		(layer "In9.Cu")
	)
	(gr_arc
		(start 217.954098 -406.366726)
		(mid 217.953183 -406.351259)
		(end 217.950542 -406.335992)
		(stroke
			(width 0.06985)
			(type default)
		)
		(layer "In9.Cu")
	)
	(gr_line
		(start 218.243912 -406.308052)
		(end 218.246198 -406.318466)
		(stroke
			(width 0.06985)
			(type default)
		)
		(layer "In9.Cu")
	)
	(gr_line
		(start 218.271344 -25.54097)
		(end 218.290902 -25.53716)
		(stroke
			(width 0.06985)
			(type default)
		)
		(layer "In9.Cu")
	)
	(gr_line
		(start 218.290902 -25.53716)
		(end 218.311222 -25.541224)
		(stroke
			(width 0.06985)
			(type default)
		)
		(layer "In9.Cu")
	)
	(gr_arc
		(start 218.821 -417.354004)
		(mid 218.869503 -417.344345)
		(end 218.910662 -417.31692)
		(stroke
			(width 0.06985)
			(type default)
		)
		(layer "In9.Cu")
	)
	(gr_arc
		(start 218.910154 -417.683188)
		(mid 218.869003 -417.655755)
		(end 218.820492 -417.646104)
		(stroke
			(width 0.06985)
			(type default)
		)
		(layer "In9.Cu")
	)
	(gr_line
		(start 218.910154 -417.683188)
		(end 218.962986 -417.73602)
		(stroke
			(width 0.06985)
			(type default)
		)
		(layer "In9.Cu")
	)
	(gr_line
		(start 218.910662 -417.31692)
		(end 218.962986 -417.264596)
		(stroke
			(width 0.06985)
			(type default)
		)
		(layer "In9.Cu")
	)
	(gr_arc
		(start 218.962986 -417.264596)
		(mid 218.990425 -417.223448)
		(end 219.00007 -417.174934)
		(stroke
			(width 0.06985)
			(type default)
		)
		(layer "In9.Cu")
	)
	(gr_arc
		(start 219.00007 -417.825682)
		(mid 218.990437 -417.777164)
		(end 218.962986 -417.73602)
		(stroke
			(width 0.06985)
			(type default)
		)
		(layer "In9.Cu")
	)
	(gr_line
		(start 219.00007 -417.825682)
		(end 219.00007 -418.200078)
		(stroke
			(width 0.06985)
			(type default)
		)
		(layer "In9.Cu")
	)
	(gr_line
		(start 219.00007 -416.80003)
		(end 219.00007 -417.174934)
		(stroke
			(width 0.06985)
			(type default)
		)
		(layer "In9.Cu")
	)
	(gr_line
		(start 219.47251 -370.457222)
		(end 219.478606 -370.430298)
		(stroke
			(width 0.06985)
			(type default)
		)
		(layer "In9.Cu")
	)
	(gr_line
		(start 219.47251 -370.40312)
		(end 219.478606 -370.430298)
		(stroke
			(width 0.06985)
			(type default)
		)
		(layer "In9.Cu")
	)
	(gr_line
		(start 219.733368 -145.602706)
		(end 219.739464 -145.629884)
		(stroke
			(width 0.06985)
			(type default)
		)
		(layer "In9.Cu")
	)
	(gr_line
		(start 219.733368 -145.602706)
		(end 219.739464 -145.575528)
		(stroke
			(width 0.06985)
			(type default)
		)
		(layer "In9.Cu")
	)
	(gr_arc
		(start 219.754196 -405.36622)
		(mid 219.753281 -405.350753)
		(end 219.75064 -405.335486)
		(stroke
			(width 0.06985)
			(type default)
		)
		(layer "In9.Cu")
	)
	(gr_line
		(start 220.04401 -405.307546)
		(end 220.046296 -405.31796)
		(stroke
			(width 0.06985)
			(type default)
		)
		(layer "In9.Cu")
	)
	(gr_arc
		(start 220.588332 -414.75406)
		(mid 220.73811 -414.692005)
		(end 220.800168 -414.542224)
		(stroke
			(width 0.06985)
			(type default)
		)
		(layer "In9.Cu")
	)
	(gr_arc
		(start 220.800168 -415.257996)
		(mid 220.738123 -415.108205)
		(end 220.588332 -415.04616)
		(stroke
			(width 0.06985)
			(type default)
		)
		(layer "In9.Cu")
	)
	(gr_line
		(start 220.800168 -415.257996)
		(end 220.800168 -415.600134)
		(stroke
			(width 0.06985)
			(type default)
		)
		(layer "In9.Cu")
	)
	(gr_line
		(start 220.800168 -414.200086)
		(end 220.800168 -414.542224)
		(stroke
			(width 0.06985)
			(type default)
		)
		(layer "In9.Cu")
	)
	(gr_line
		(start 220.99905 -370.435886)
		(end 221.004638 -370.461032)
		(stroke
			(width 0.06985)
			(type default)
		)
		(layer "In9.Cu")
	)
	(gr_line
		(start 220.999558 -370.486432)
		(end 220.999558 -370.48694)
		(stroke
			(width 0.06985)
			(type default)
		)
		(layer "In9.Cu")
	)
	(gr_line
		(start 220.999558 -370.486178)
		(end 221.004638 -370.461032)
		(stroke
			(width 0.06985)
			(type default)
		)
		(layer "In9.Cu")
	)
	(gr_line
		(start 221.290388 -145.377916)
		(end 221.296484 -145.405094)
		(stroke
			(width 0.06985)
			(type default)
		)
		(layer "In9.Cu")
	)
	(gr_line
		(start 221.290388 -145.377916)
		(end 221.296484 -145.350738)
		(stroke
			(width 0.06985)
			(type default)
		)
		(layer "In9.Cu")
	)
	(gr_arc
		(start 221.55404 -405.505158)
		(mid 221.553125 -405.489691)
		(end 221.550484 -405.474424)
		(stroke
			(width 0.06985)
			(type default)
		)
		(layer "In9.Cu")
	)
	(gr_line
		(start 221.843854 -405.446484)
		(end 221.84614 -405.456898)
		(stroke
			(width 0.06985)
			(type default)
		)
		(layer "In9.Cu")
	)
	(gr_arc
		(start 222.420942 -417.354004)
		(mid 222.469457 -417.344363)
		(end 222.510604 -417.31692)
		(stroke
			(width 0.06985)
			(type default)
		)
		(layer "In9.Cu")
	)
	(gr_arc
		(start 222.510096 -417.683188)
		(mid 222.468945 -417.655755)
		(end 222.420434 -417.646104)
		(stroke
			(width 0.06985)
			(type default)
		)
		(layer "In9.Cu")
	)
	(gr_line
		(start 222.510096 -417.683188)
		(end 222.562928 -417.73602)
		(stroke
			(width 0.06985)
			(type default)
		)
		(layer "In9.Cu")
	)
	(gr_line
		(start 222.510604 -417.31692)
		(end 222.562928 -417.264596)
		(stroke
			(width 0.06985)
			(type default)
		)
		(layer "In9.Cu")
	)
	(gr_arc
		(start 222.562928 -417.264596)
		(mid 222.590358 -417.223446)
		(end 222.600012 -417.174934)
		(stroke
			(width 0.06985)
			(type default)
		)
		(layer "In9.Cu")
	)
	(gr_arc
		(start 222.600012 -417.825682)
		(mid 222.590379 -417.777164)
		(end 222.562928 -417.73602)
		(stroke
			(width 0.06985)
			(type default)
		)
		(layer "In9.Cu")
	)
	(gr_line
		(start 222.600012 -417.825682)
		(end 222.600012 -418.200078)
		(stroke
			(width 0.06985)
			(type default)
		)
		(layer "In9.Cu")
	)
	(gr_line
		(start 222.600012 -416.80003)
		(end 222.600012 -417.174934)
		(stroke
			(width 0.06985)
			(type default)
		)
		(layer "In9.Cu")
	)
	(gr_line
		(start 222.975932 -145.132044)
		(end 222.982028 -145.158968)
		(stroke
			(width 0.06985)
			(type default)
		)
		(layer "In9.Cu")
	)
	(gr_line
		(start 222.975932 -145.132044)
		(end 222.982028 -145.10512)
		(stroke
			(width 0.06985)
			(type default)
		)
		(layer "In9.Cu")
	)
	(gr_line
		(start 223.29648 -161.350198)
		(end 223.299782 -161.364676)
		(stroke
			(width 0.06985)
			(type default)
		)
		(layer "In9.Cu")
	)
	(gr_line
		(start 223.299782 -161.364676)
		(end 223.308164 -161.37763)
		(stroke
			(width 0.06985)
			(type default)
		)
		(layer "In9.Cu")
	)
	(gr_line
		(start 223.651064 -45.197776)
		(end 224.258886 -45.316648)
		(stroke
			(width 0.06985)
			(type default)
		)
		(layer "In9.Cu")
	)
	(gr_line
		(start 223.670876 -44.901866)
		(end 223.831912 -44.793408)
		(stroke
			(width 0.06985)
			(type default)
		)
		(layer "In9.Cu")
	)
	(gr_line
		(start 223.831912 -44.793408)
		(end 224.243392 -44.873926)
		(stroke
			(width 0.06985)
			(type default)
		)
		(layer "In9.Cu")
	)
	(gr_line
		(start 224.243392 -44.873926)
		(end 224.35185 -45.034962)
		(stroke
			(width 0.06985)
			(type default)
		)
		(layer "In9.Cu")
	)
	(gr_line
		(start 224.456752 -159.36976)
		(end 224.460054 -159.384238)
		(stroke
			(width 0.06985)
			(type default)
		)
		(layer "In9.Cu")
	)
	(gr_line
		(start 224.460054 -159.384238)
		(end 224.468436 -159.397192)
		(stroke
			(width 0.06985)
			(type default)
		)
		(layer "In9.Cu")
	)
	(gr_line
		(start 224.748344 -45.412406)
		(end 225.357182 -45.531532)
		(stroke
			(width 0.06985)
			(type default)
		)
		(layer "In9.Cu")
	)
	(gr_line
		(start 224.767902 -45.116242)
		(end 224.928938 -45.007784)
		(stroke
			(width 0.06985)
			(type default)
		)
		(layer "In9.Cu")
	)
	(gr_line
		(start 224.781872 -145.123662)
		(end 224.787968 -145.15084)
		(stroke
			(width 0.06985)
			(type default)
		)
		(layer "In9.Cu")
	)
	(gr_line
		(start 224.781872 -145.123662)
		(end 224.787968 -145.096484)
		(stroke
			(width 0.06985)
			(type default)
		)
		(layer "In9.Cu")
	)
	(gr_line
		(start 224.928938 -45.007784)
		(end 225.340164 -45.088302)
		(stroke
			(width 0.06985)
			(type default)
		)
		(layer "In9.Cu")
	)
	(gr_line
		(start 225.340164 -45.088302)
		(end 225.448622 -45.249338)
		(stroke
			(width 0.06985)
			(type default)
		)
		(layer "In9.Cu")
	)
	(gr_line
		(start 225.558858 -53.915818)
		(end 226.168712 -54.036214)
		(stroke
			(width 0.06985)
			(type default)
		)
		(layer "In9.Cu")
	)
	(gr_line
		(start 225.580702 -53.619654)
		(end 225.741992 -53.511704)
		(stroke
			(width 0.06985)
			(type default)
		)
		(layer "In9.Cu")
	)
	(gr_line
		(start 225.68535 -157.099254)
		(end 225.688906 -157.115002)
		(stroke
			(width 0.06985)
			(type default)
		)
		(layer "In9.Cu")
	)
	(gr_line
		(start 225.688906 -157.115002)
		(end 225.697542 -157.127956)
		(stroke
			(width 0.06985)
			(type default)
		)
		(layer "In9.Cu")
	)
	(gr_line
		(start 225.741992 -53.511704)
		(end 226.153218 -53.592984)
		(stroke
			(width 0.06985)
			(type default)
		)
		(layer "In9.Cu")
	)
	(gr_line
		(start 225.843592 -45.626782)
		(end 226.453192 -45.745908)
		(stroke
			(width 0.06985)
			(type default)
		)
		(layer "In9.Cu")
	)
	(gr_line
		(start 225.864674 -45.330872)
		(end 226.02571 -45.222414)
		(stroke
			(width 0.06985)
			(type default)
		)
		(layer "In9.Cu")
	)
	(gr_line
		(start 226.02571 -45.222414)
		(end 226.436936 -45.302678)
		(stroke
			(width 0.06985)
			(type default)
		)
		(layer "In9.Cu")
	)
	(gr_line
		(start 226.153218 -53.592984)
		(end 226.261168 -53.754274)
		(stroke
			(width 0.06985)
			(type default)
		)
		(layer "In9.Cu")
	)
	(gr_line
		(start 226.436936 -45.302678)
		(end 226.54514 -45.463714)
		(stroke
			(width 0.06985)
			(type default)
		)
		(layer "In9.Cu")
	)
	(gr_line
		(start 226.471988 -50.195226)
		(end 227.0887 -50.297334)
		(stroke
			(width 0.06985)
			(type default)
		)
		(layer "In9.Cu")
	)
	(gr_line
		(start 226.48672 -49.898808)
		(end 226.644454 -49.785778)
		(stroke
			(width 0.06985)
			(type default)
		)
		(layer "In9.Cu")
	)
	(gr_line
		(start 226.582732 -60.072778)
		(end 226.613212 -60.078874)
		(stroke
			(width 0.06985)
			(type default)
		)
		(layer "In9.Cu")
	)
	(gr_line
		(start 226.613212 -60.078874)
		(end 226.638104 -60.097924)
		(stroke
			(width 0.06985)
			(type default)
		)
		(layer "In9.Cu")
	)
	(gr_line
		(start 226.644454 -49.785778)
		(end 227.057966 -49.854358)
		(stroke
			(width 0.06985)
			(type default)
		)
		(layer "In9.Cu")
	)
	(gr_line
		(start 226.655122 -54.13248)
		(end 227.264976 -54.252876)
		(stroke
			(width 0.06985)
			(type default)
		)
		(layer "In9.Cu")
	)
	(gr_line
		(start 226.67722 -53.836316)
		(end 226.83851 -53.728366)
		(stroke
			(width 0.06985)
			(type default)
		)
		(layer "In9.Cu")
	)
	(gr_line
		(start 226.83851 -53.728366)
		(end 227.249482 -53.809646)
		(stroke
			(width 0.06985)
			(type default)
		)
		(layer "In9.Cu")
	)
	(gr_line
		(start 227.057966 -49.854358)
		(end 227.170996 -50.012092)
		(stroke
			(width 0.06985)
			(type default)
		)
		(layer "In9.Cu")
	)
	(gr_line
		(start 227.113592 -155.424632)
		(end 227.116894 -155.43911)
		(stroke
			(width 0.06985)
			(type default)
		)
		(layer "In9.Cu")
	)
	(gr_line
		(start 227.116894 -155.43911)
		(end 227.125276 -155.452064)
		(stroke
			(width 0.06985)
			(type default)
		)
		(layer "In9.Cu")
	)
	(gr_line
		(start 227.249482 -53.809646)
		(end 227.357432 -53.970682)
		(stroke
			(width 0.06985)
			(type default)
		)
		(layer "In9.Cu")
	)
	(gr_line
		(start 227.49764 -50.068734)
		(end 227.58654 -50.083466)
		(stroke
			(width 0.06985)
			(type default)
		)
		(layer "In9.Cu")
	)
	(gr_line
		(start 227.500688 -50.365406)
		(end 227.543868 -50.372518)
		(stroke
			(width 0.06985)
			(type default)
		)
		(layer "In9.Cu")
	)
	(gr_line
		(start 227.530406 -57.72658)
		(end 228.140514 -57.846214)
		(stroke
			(width 0.06985)
			(type default)
		)
		(layer "In9.Cu")
	)
	(gr_line
		(start 227.55225 -57.43067)
		(end 227.71354 -57.322212)
		(stroke
			(width 0.06985)
			(type default)
		)
		(layer "In9.Cu")
	)
	(gr_line
		(start 227.57765 -50.377852)
		(end 228.190044 -50.479452)
		(stroke
			(width 0.06985)
			(type default)
		)
		(layer "In9.Cu")
	)
	(gr_line
		(start 227.589588 -50.081434)
		(end 227.747068 -49.968404)
		(stroke
			(width 0.06985)
			(type default)
		)
		(layer "In9.Cu")
	)
	(gr_line
		(start 227.71354 -57.322212)
		(end 228.124766 -57.402984)
		(stroke
			(width 0.06985)
			(type default)
		)
		(layer "In9.Cu")
	)
	(gr_line
		(start 227.747068 -49.968404)
		(end 228.16058 -50.03673)
		(stroke
			(width 0.06985)
			(type default)
		)
		(layer "In9.Cu")
	)
	(gr_line
		(start 227.75164 -54.349142)
		(end 228.361494 -54.469538)
		(stroke
			(width 0.06985)
			(type default)
		)
		(layer "In9.Cu")
	)
	(gr_line
		(start 227.773738 -54.052978)
		(end 227.934774 -53.945028)
		(stroke
			(width 0.06985)
			(type default)
		)
		(layer "In9.Cu")
	)
	(gr_line
		(start 227.934774 -53.945028)
		(end 228.346 -54.026308)
		(stroke
			(width 0.06985)
			(type default)
		)
		(layer "In9.Cu")
	)
	(gr_line
		(start 228.124766 -57.402984)
		(end 228.23297 -57.564274)
		(stroke
			(width 0.06985)
			(type default)
		)
		(layer "In9.Cu")
	)
	(gr_line
		(start 228.16058 -50.03673)
		(end 228.27361 -50.194718)
		(stroke
			(width 0.06985)
			(type default)
		)
		(layer "In9.Cu")
	)
	(gr_line
		(start 228.313742 -42.158412)
		(end 228.92258 -42.279316)
		(stroke
			(width 0.06985)
			(type default)
		)
		(layer "In9.Cu")
	)
	(gr_line
		(start 228.33584 -41.862248)
		(end 228.49713 -41.754552)
		(stroke
			(width 0.06985)
			(type default)
		)
		(layer "In9.Cu")
	)
	(gr_line
		(start 228.346 -54.026308)
		(end 228.45395 -54.187344)
		(stroke
			(width 0.06985)
			(type default)
		)
		(layer "In9.Cu")
	)
	(gr_line
		(start 228.494844 -76.521818)
		(end 228.60127 -76.359258)
		(stroke
			(width 0.06985)
			(type default)
		)
		(layer "In9.Cu")
	)
	(gr_line
		(start 228.49713 -41.754552)
		(end 228.908102 -41.83634)
		(stroke
			(width 0.06985)
			(type default)
		)
		(layer "In9.Cu")
	)
	(gr_line
		(start 228.590602 -76.802742)
		(end 229.199948 -76.67498)
		(stroke
			(width 0.06985)
			(type default)
		)
		(layer "In9.Cu")
	)
	(gr_line
		(start 228.60127 -76.359258)
		(end 229.01148 -76.273406)
		(stroke
			(width 0.06985)
			(type default)
		)
		(layer "In9.Cu")
	)
	(gr_line
		(start 228.627686 -57.941718)
		(end 229.23754 -58.061352)
		(stroke
			(width 0.06985)
			(type default)
		)
		(layer "In9.Cu")
	)
	(gr_line
		(start 228.648768 -57.645808)
		(end 228.810058 -57.537604)
		(stroke
			(width 0.06985)
			(type default)
		)
		(layer "In9.Cu")
	)
	(gr_line
		(start 228.678994 -50.560224)
		(end 229.29342 -50.662078)
		(stroke
			(width 0.06985)
			(type default)
		)
		(layer "In9.Cu")
	)
	(gr_line
		(start 228.691948 -50.263806)
		(end 228.849682 -50.150776)
		(stroke
			(width 0.06985)
			(type default)
		)
		(layer "In9.Cu")
	)
	(gr_line
		(start 228.784658 -59.106308)
		(end 228.813868 -59.11215)
		(stroke
			(width 0.06985)
			(type default)
		)
		(layer "In9.Cu")
	)
	(gr_line
		(start 228.810058 -57.537604)
		(end 229.221284 -57.618122)
		(stroke
			(width 0.06985)
			(type default)
		)
		(layer "In9.Cu")
	)
	(gr_line
		(start 228.813868 -59.11215)
		(end 228.83749 -59.130184)
		(stroke
			(width 0.06985)
			(type default)
		)
		(layer "In9.Cu")
	)
	(gr_line
		(start 228.849682 -50.150776)
		(end 229.263194 -50.219356)
		(stroke
			(width 0.06985)
			(type default)
		)
		(layer "In9.Cu")
	)
	(gr_line
		(start 228.908102 -41.83634)
		(end 229.015798 -41.997376)
		(stroke
			(width 0.06985)
			(type default)
		)
		(layer "In9.Cu")
	)
	(gr_line
		(start 229.01148 -76.273406)
		(end 229.17404 -76.379578)
		(stroke
			(width 0.06985)
			(type default)
		)
		(layer "In9.Cu")
	)
	(gr_line
		(start 229.221284 -57.618122)
		(end 229.329742 -57.779412)
		(stroke
			(width 0.06985)
			(type default)
		)
		(layer "In9.Cu")
	)
	(gr_line
		(start 229.263194 -50.219356)
		(end 229.376224 -50.37709)
		(stroke
			(width 0.06985)
			(type default)
		)
		(layer "In9.Cu")
	)
	(gr_line
		(start 229.37089 -42.070782)
		(end 229.429056 -42.082212)
		(stroke
			(width 0.06985)
			(type default)
		)
		(layer "In9.Cu")
	)
	(gr_line
		(start 229.411022 -42.376344)
		(end 230.01859 -42.496994)
		(stroke
			(width 0.06985)
			(type default)
		)
		(layer "In9.Cu")
	)
	(gr_line
		(start 229.432104 -42.08018)
		(end 229.59314 -41.972484)
		(stroke
			(width 0.06985)
			(type default)
		)
		(layer "In9.Cu")
	)
	(gr_line
		(start 229.493826 -72.467978)
		(end 229.597966 -72.304402)
		(stroke
			(width 0.06985)
			(type default)
		)
		(layer "In9.Cu")
	)
	(gr_line
		(start 229.589076 -76.292456)
		(end 229.694994 -76.13015)
		(stroke
			(width 0.06985)
			(type default)
		)
		(layer "In9.Cu")
	)
	(gr_line
		(start 229.592886 -72.747886)
		(end 230.19893 -72.61352)
		(stroke
			(width 0.06985)
			(type default)
		)
		(layer "In9.Cu")
	)
	(gr_line
		(start 229.59314 -41.972484)
		(end 230.004366 -42.054272)
		(stroke
			(width 0.06985)
			(type default)
		)
		(layer "In9.Cu")
	)
	(gr_line
		(start 229.597966 -72.304402)
		(end 230.006906 -72.213724)
		(stroke
			(width 0.06985)
			(type default)
		)
		(layer "In9.Cu")
	)
	(gr_line
		(start 229.619302 -38.490144)
		(end 230.232712 -38.61181)
		(stroke
			(width 0.06985)
			(type default)
		)
		(layer "In9.Cu")
	)
	(gr_line
		(start 229.644194 -38.194488)
		(end 229.805484 -38.086538)
		(stroke
			(width 0.06985)
			(type default)
		)
		(layer "In9.Cu")
	)
	(gr_line
		(start 229.68458 -76.573634)
		(end 230.293926 -76.445872)
		(stroke
			(width 0.06985)
			(type default)
		)
		(layer "In9.Cu")
	)
	(gr_line
		(start 229.694994 -76.13015)
		(end 230.105204 -76.044298)
		(stroke
			(width 0.06985)
			(type default)
		)
		(layer "In9.Cu")
	)
	(gr_line
		(start 229.723696 -58.15711)
		(end 230.333804 -58.276744)
		(stroke
			(width 0.06985)
			(type default)
		)
		(layer "In9.Cu")
	)
	(gr_line
		(start 229.74554 -57.860946)
		(end 229.90683 -57.752742)
		(stroke
			(width 0.06985)
			(type default)
		)
		(layer "In9.Cu")
	)
	(gr_line
		(start 229.805484 -38.086538)
		(end 230.21671 -38.168072)
		(stroke
			(width 0.06985)
			(type default)
		)
		(layer "In9.Cu")
	)
	(gr_line
		(start 229.837488 -99.9998)
		(end 229.84079 -99.985322)
		(stroke
			(width 0.06985)
			(type default)
		)
		(layer "In9.Cu")
	)
	(gr_line
		(start 229.84079 -99.985322)
		(end 229.848664 -99.97313)
		(stroke
			(width 0.06985)
			(type default)
		)
		(layer "In9.Cu")
	)
	(gr_line
		(start 229.880922 -84.109814)
		(end 229.987348 -83.947254)
		(stroke
			(width 0.06985)
			(type default)
		)
		(layer "In9.Cu")
	)
	(gr_line
		(start 229.90683 -57.752742)
		(end 230.318056 -57.833514)
		(stroke
			(width 0.06985)
			(type default)
		)
		(layer "In9.Cu")
	)
	(gr_line
		(start 229.975918 -84.390738)
		(end 230.586788 -84.262976)
		(stroke
			(width 0.06985)
			(type default)
		)
		(layer "In9.Cu")
	)
	(gr_line
		(start 229.987348 -83.947254)
		(end 230.397558 -83.861402)
		(stroke
			(width 0.06985)
			(type default)
		)
		(layer "In9.Cu")
	)
	(gr_line
		(start 230.004366 -42.054272)
		(end 230.112062 -42.215308)
		(stroke
			(width 0.06985)
			(type default)
		)
		(layer "In9.Cu")
	)
	(gr_line
		(start 230.006906 -72.213724)
		(end 230.170482 -72.317864)
		(stroke
			(width 0.06985)
			(type default)
		)
		(layer "In9.Cu")
	)
	(gr_line
		(start 230.105204 -76.044298)
		(end 230.267764 -76.150216)
		(stroke
			(width 0.06985)
			(type default)
		)
		(layer "In9.Cu")
	)
	(gr_line
		(start 230.21671 -38.168072)
		(end 230.324406 -38.329362)
		(stroke
			(width 0.06985)
			(type default)
		)
		(layer "In9.Cu")
	)
	(gr_line
		(start 230.220266 -42.239438)
		(end 230.525066 -42.300144)
		(stroke
			(width 0.06985)
			(type default)
		)
		(layer "In9.Cu")
	)
	(gr_line
		(start 230.318056 -57.833514)
		(end 230.42626 -57.994804)
		(stroke
			(width 0.06985)
			(type default)
		)
		(layer "In9.Cu")
	)
	(gr_line
		(start 230.326438 -38.33241)
		(end 230.457248 -38.358318)
		(stroke
			(width 0.06985)
			(type default)
		)
		(layer "In9.Cu")
	)
	(gr_line
		(start 230.397558 -83.861402)
		(end 230.560118 -83.967574)
		(stroke
			(width 0.06985)
			(type default)
		)
		(layer "In9.Cu")
	)
	(gr_line
		(start 230.46182 -42.585386)
		(end 230.474266 -42.587926)
		(stroke
			(width 0.06985)
			(type default)
		)
		(layer "In9.Cu")
	)
	(gr_line
		(start 230.469186 -72.553576)
		(end 230.653336 -72.512682)
		(stroke
			(width 0.06985)
			(type default)
		)
		(layer "In9.Cu")
	)
	(gr_line
		(start 230.506016 -42.594276)
		(end 231.11587 -42.715434)
		(stroke
			(width 0.06985)
			(type default)
		)
		(layer "In9.Cu")
	)
	(gr_line
		(start 230.517192 -72.243696)
		(end 230.582724 -72.229218)
		(stroke
			(width 0.06985)
			(type default)
		)
		(layer "In9.Cu")
	)
	(gr_line
		(start 230.528114 -42.298112)
		(end 230.689404 -42.190416)
		(stroke
			(width 0.06985)
			(type default)
		)
		(layer "In9.Cu")
	)
	(gr_line
		(start 230.584756 -72.22617)
		(end 230.688896 -72.062594)
		(stroke
			(width 0.06985)
			(type default)
		)
		(layer "In9.Cu")
	)
	(gr_line
		(start 230.6828 -76.063348)
		(end 230.788972 -75.901042)
		(stroke
			(width 0.06985)
			(type default)
		)
		(layer "In9.Cu")
	)
	(gr_line
		(start 230.683562 -72.506078)
		(end 231.291892 -72.371204)
		(stroke
			(width 0.06985)
			(type default)
		)
		(layer "In9.Cu")
	)
	(gr_line
		(start 230.688896 -72.062594)
		(end 231.09809 -71.971916)
		(stroke
			(width 0.06985)
			(type default)
		)
		(layer "In9.Cu")
	)
	(gr_line
		(start 230.689404 -42.190416)
		(end 231.100376 -42.27195)
		(stroke
			(width 0.06985)
			(type default)
		)
		(layer "In9.Cu")
	)
	(gr_line
		(start 230.718106 -38.707822)
		(end 231.328976 -38.829234)
		(stroke
			(width 0.06985)
			(type default)
		)
		(layer "In9.Cu")
	)
	(gr_line
		(start 230.740712 -38.411912)
		(end 230.901748 -38.304216)
		(stroke
			(width 0.06985)
			(type default)
		)
		(layer "In9.Cu")
	)
	(gr_line
		(start 230.77805 -76.344526)
		(end 231.386634 -76.217018)
		(stroke
			(width 0.06985)
			(type default)
		)
		(layer "In9.Cu")
	)
	(gr_line
		(start 230.788972 -75.901042)
		(end 231.199182 -75.814936)
		(stroke
			(width 0.06985)
			(type default)
		)
		(layer "In9.Cu")
	)
	(gr_line
		(start 230.888794 -61.078872)
		(end 231.381808 -61.458856)
		(stroke
			(width 0.06985)
			(type default)
		)
		(layer "In9.Cu")
	)
	(gr_line
		(start 230.901748 -38.304216)
		(end 231.312974 -38.38575)
		(stroke
			(width 0.06985)
			(type default)
		)
		(layer "In9.Cu")
	)
	(gr_line
		(start 230.9749 -83.880706)
		(end 231.081072 -83.718146)
		(stroke
			(width 0.06985)
			(type default)
		)
		(layer "In9.Cu")
	)
	(gr_line
		(start 231.040686 -60.82411)
		(end 231.233218 -60.799218)
		(stroke
			(width 0.06985)
			(type default)
		)
		(layer "In9.Cu")
	)
	(gr_line
		(start 231.070404 -84.16163)
		(end 231.678988 -84.034122)
		(stroke
			(width 0.06985)
			(type default)
		)
		(layer "In9.Cu")
	)
	(gr_line
		(start 231.081072 -83.718146)
		(end 231.491282 -83.632294)
		(stroke
			(width 0.06985)
			(type default)
		)
		(layer "In9.Cu")
	)
	(gr_line
		(start 231.09809 -71.971916)
		(end 231.26192 -72.076056)
		(stroke
			(width 0.06985)
			(type default)
		)
		(layer "In9.Cu")
	)
	(gr_line
		(start 231.100376 -42.27195)
		(end 231.208326 -42.43324)
		(stroke
			(width 0.06985)
			(type default)
		)
		(layer "In9.Cu")
	)
	(gr_line
		(start 231.199182 -75.814936)
		(end 231.361488 -75.921108)
		(stroke
			(width 0.06985)
			(type default)
		)
		(layer "In9.Cu")
	)
	(gr_line
		(start 231.217216 -100.577396)
		(end 231.220518 -100.562918)
		(stroke
			(width 0.06985)
			(type default)
		)
		(layer "In9.Cu")
	)
	(gr_line
		(start 231.220518 -100.562918)
		(end 231.228392 -100.550726)
		(stroke
			(width 0.06985)
			(type default)
		)
		(layer "In9.Cu")
	)
	(gr_line
		(start 231.233218 -60.799218)
		(end 231.565196 -61.054996)
		(stroke
			(width 0.06985)
			(type default)
		)
		(layer "In9.Cu")
	)
	(gr_line
		(start 231.312974 -38.38575)
		(end 231.42067 -38.54704)
		(stroke
			(width 0.06985)
			(type default)
		)
		(layer "In9.Cu")
	)
	(gr_line
		(start 231.405938 -64.139064)
		(end 231.898698 -64.518794)
		(stroke
			(width 0.06985)
			(type default)
		)
		(layer "In9.Cu")
	)
	(gr_line
		(start 231.491282 -83.632294)
		(end 231.653842 -83.738466)
		(stroke
			(width 0.06985)
			(type default)
		)
		(layer "In9.Cu")
	)
	(gr_line
		(start 231.55783 -63.884302)
		(end 231.750362 -63.85941)
		(stroke
			(width 0.06985)
			(type default)
		)
		(layer "In9.Cu")
	)
	(gr_line
		(start 231.565196 -61.054996)
		(end 231.590088 -61.247274)
		(stroke
			(width 0.06985)
			(type default)
		)
		(layer "In9.Cu")
	)
	(gr_line
		(start 231.675686 -71.984362)
		(end 231.78008 -71.820532)
		(stroke
			(width 0.06985)
			(type default)
		)
		(layer "In9.Cu")
	)
	(gr_line
		(start 231.750362 -63.85941)
		(end 232.08234 -64.115188)
		(stroke
			(width 0.06985)
			(type default)
		)
		(layer "In9.Cu")
	)
	(gr_line
		(start 231.773476 -72.264524)
		(end 232.381806 -72.12965)
		(stroke
			(width 0.06985)
			(type default)
		)
		(layer "In9.Cu")
	)
	(gr_line
		(start 231.775 -61.761624)
		(end 232.267252 -62.140592)
		(stroke
			(width 0.06985)
			(type default)
		)
		(layer "In9.Cu")
	)
	(gr_line
		(start 231.78008 -71.820532)
		(end 232.189274 -71.729854)
		(stroke
			(width 0.06985)
			(type default)
		)
		(layer "In9.Cu")
	)
	(gr_line
		(start 231.812592 -38.925246)
		(end 232.424478 -39.046658)
		(stroke
			(width 0.06985)
			(type default)
		)
		(layer "In9.Cu")
	)
	(gr_line
		(start 231.836722 -38.62959)
		(end 231.998012 -38.52164)
		(stroke
			(width 0.06985)
			(type default)
		)
		(layer "In9.Cu")
	)
	(gr_line
		(start 231.843834 -79.854806)
		(end 231.850184 -79.853536)
		(stroke
			(width 0.06985)
			(type default)
		)
		(layer "In9.Cu")
	)
	(gr_line
		(start 231.852216 -79.850488)
		(end 231.958388 -79.687928)
		(stroke
			(width 0.06985)
			(type default)
		)
		(layer "In9.Cu")
	)
	(gr_line
		(start 231.910382 -80.139286)
		(end 231.916732 -80.138016)
		(stroke
			(width 0.06985)
			(type default)
		)
		(layer "In9.Cu")
	)
	(gr_line
		(start 231.92613 -61.5061)
		(end 232.118662 -61.481208)
		(stroke
			(width 0.06985)
			(type default)
		)
		(layer "In9.Cu")
	)
	(gr_line
		(start 231.94772 -80.131666)
		(end 232.252012 -80.067658)
		(stroke
			(width 0.06985)
			(type default)
		)
		(layer "In9.Cu")
	)
	(gr_line
		(start 231.958388 -79.687928)
		(end 232.368598 -79.602076)
		(stroke
			(width 0.06985)
			(type default)
		)
		(layer "In9.Cu")
	)
	(gr_line
		(start 231.998012 -38.52164)
		(end 232.409238 -38.603174)
		(stroke
			(width 0.06985)
			(type default)
		)
		(layer "In9.Cu")
	)
	(gr_line
		(start 232.068878 -83.651344)
		(end 232.17505 -83.489038)
		(stroke
			(width 0.06985)
			(type default)
		)
		(layer "In9.Cu")
	)
	(gr_line
		(start 232.08234 -64.115188)
		(end 232.107232 -64.30772)
		(stroke
			(width 0.06985)
			(type default)
		)
		(layer "In9.Cu")
	)
	(gr_line
		(start 232.1179 -96.47809)
		(end 232.123234 -96.469962)
		(stroke
			(width 0.06985)
			(type default)
		)
		(layer "In9.Cu")
	)
	(gr_line
		(start 232.118662 -61.481208)
		(end 232.45064 -61.736986)
		(stroke
			(width 0.06985)
			(type default)
		)
		(layer "In9.Cu")
	)
	(gr_line
		(start 232.123234 -96.469962)
		(end 232.1306 -96.46412)
		(stroke
			(width 0.06985)
			(type default)
		)
		(layer "In9.Cu")
	)
	(gr_line
		(start 232.16362 -83.932776)
		(end 232.772966 -83.805014)
		(stroke
			(width 0.06985)
			(type default)
		)
		(layer "In9.Cu")
	)
	(gr_line
		(start 232.17505 -83.489038)
		(end 232.58526 -83.402932)
		(stroke
			(width 0.06985)
			(type default)
		)
		(layer "In9.Cu")
	)
	(gr_line
		(start 232.189274 -71.729854)
		(end 232.353104 -71.834248)
		(stroke
			(width 0.06985)
			(type default)
		)
		(layer "In9.Cu")
	)
	(gr_line
		(start 232.252012 -80.067658)
		(end 232.556304 -80.003904)
		(stroke
			(width 0.06985)
			(type default)
		)
		(layer "In9.Cu")
	)
	(gr_line
		(start 232.292144 -64.821816)
		(end 232.784142 -65.200784)
		(stroke
			(width 0.06985)
			(type default)
		)
		(layer "In9.Cu")
	)
	(gr_line
		(start 232.368598 -79.602076)
		(end 232.531158 -79.708248)
		(stroke
			(width 0.06985)
			(type default)
		)
		(layer "In9.Cu")
	)
	(gr_line
		(start 232.409238 -38.603174)
		(end 232.516934 -38.764464)
		(stroke
			(width 0.06985)
			(type default)
		)
		(layer "In9.Cu")
	)
	(gr_line
		(start 232.443274 -64.566292)
		(end 232.635806 -64.5414)
		(stroke
			(width 0.06985)
			(type default)
		)
		(layer "In9.Cu")
	)
	(gr_line
		(start 232.45064 -61.736986)
		(end 232.475532 -61.929264)
		(stroke
			(width 0.06985)
			(type default)
		)
		(layer "In9.Cu")
	)
	(gr_line
		(start 232.460292 -39.05377)
		(end 232.624122 -39.086028)
		(stroke
			(width 0.06985)
			(type default)
		)
		(layer "In9.Cu")
	)
	(gr_line
		(start 232.518966 -38.767512)
		(end 232.680764 -38.799516)
		(stroke
			(width 0.06985)
			(type default)
		)
		(layer "In9.Cu")
	)
	(gr_line
		(start 232.569004 -175.636682)
		(end 232.908856 -176.159922)
		(stroke
			(width 0.06985)
			(type default)
		)
		(layer "In9.Cu")
	)
	(gr_line
		(start 232.58526 -83.402932)
		(end 232.747566 -83.509104)
		(stroke
			(width 0.06985)
			(type default)
		)
		(layer "In9.Cu")
	)
	(gr_line
		(start 232.586276 -167.693594)
		(end 232.923588 -168.210738)
		(stroke
			(width 0.06985)
			(type default)
		)
		(layer "In9.Cu")
	)
	(gr_line
		(start 232.591102 -163.869624)
		(end 232.932478 -164.39515)
		(stroke
			(width 0.06985)
			(type default)
		)
		(layer "In9.Cu")
	)
	(gr_line
		(start 232.614724 -171.940728)
		(end 232.953052 -172.461682)
		(stroke
			(width 0.06985)
			(type default)
		)
		(layer "In9.Cu")
	)
	(gr_line
		(start 232.635806 -64.5414)
		(end 232.967784 -64.797178)
		(stroke
			(width 0.06985)
			(type default)
		)
		(layer "In9.Cu")
	)
	(gr_line
		(start 232.658666 -62.442598)
		(end 233.153204 -62.823344)
		(stroke
			(width 0.06985)
			(type default)
		)
		(layer "In9.Cu")
	)
	(gr_line
		(start 232.79735 -175.446944)
		(end 232.987088 -175.48733)
		(stroke
			(width 0.06985)
			(type default)
		)
		(layer "In9.Cu")
	)
	(gr_line
		(start 232.811574 -62.18809)
		(end 233.004106 -62.163198)
		(stroke
			(width 0.06985)
			(type default)
		)
		(layer "In9.Cu")
	)
	(gr_line
		(start 232.812082 -167.501062)
		(end 233.002074 -167.541194)
		(stroke
			(width 0.06985)
			(type default)
		)
		(layer "In9.Cu")
	)
	(gr_line
		(start 232.819702 -163.680648)
		(end 233.009948 -163.721034)
		(stroke
			(width 0.06985)
			(type default)
		)
		(layer "In9.Cu")
	)
	(gr_line
		(start 232.842308 -171.750736)
		(end 233.0323 -171.791122)
		(stroke
			(width 0.06985)
			(type default)
		)
		(layer "In9.Cu")
	)
	(gr_line
		(start 232.93705 -100.858574)
		(end 232.940352 -100.84435)
		(stroke
			(width 0.06985)
			(type default)
		)
		(layer "In9.Cu")
	)
	(gr_line
		(start 232.940352 -100.84435)
		(end 232.948226 -100.832158)
		(stroke
			(width 0.06985)
			(type default)
		)
		(layer "In9.Cu")
	)
	(gr_line
		(start 232.946194 -79.621126)
		(end 233.052366 -79.45882)
		(stroke
			(width 0.06985)
			(type default)
		)
		(layer "In9.Cu")
	)
	(gr_line
		(start 232.967784 -64.797178)
		(end 232.992676 -64.98971)
		(stroke
			(width 0.06985)
			(type default)
		)
		(layer "In9.Cu")
	)
	(gr_line
		(start 232.987088 -175.48733)
		(end 233.215434 -175.838612)
		(stroke
			(width 0.06985)
			(type default)
		)
		(layer "In9.Cu")
	)
	(gr_line
		(start 233.002074 -167.541194)
		(end 233.230928 -167.892222)
		(stroke
			(width 0.06985)
			(type default)
		)
		(layer "In9.Cu")
	)
	(gr_line
		(start 233.004106 -62.163198)
		(end 233.336084 -62.418976)
		(stroke
			(width 0.06985)
			(type default)
		)
		(layer "In9.Cu")
	)
	(gr_line
		(start 233.009948 -163.721034)
		(end 233.23804 -164.072316)
		(stroke
			(width 0.06985)
			(type default)
		)
		(layer "In9.Cu")
	)
	(gr_line
		(start 233.0323 -171.791122)
		(end 233.260646 -172.142404)
		(stroke
			(width 0.06985)
			(type default)
		)
		(layer "In9.Cu")
	)
	(gr_line
		(start 233.040936 -79.902558)
		(end 233.65079 -79.774796)
		(stroke
			(width 0.06985)
			(type default)
		)
		(layer "In9.Cu")
	)
	(gr_line
		(start 233.052366 -79.45882)
		(end 233.462576 -79.372968)
		(stroke
			(width 0.06985)
			(type default)
		)
		(layer "In9.Cu")
	)
	(gr_line
		(start 233.175048 -176.028604)
		(end 233.215434 -175.838612)
		(stroke
			(width 0.06985)
			(type default)
		)
		(layer "In9.Cu")
	)
	(gr_line
		(start 233.17708 -176.57318)
		(end 233.517694 -177.097436)
		(stroke
			(width 0.06985)
			(type default)
		)
		(layer "In9.Cu")
	)
	(gr_line
		(start 233.177588 -65.503806)
		(end 233.670602 -65.883536)
		(stroke
			(width 0.06985)
			(type default)
		)
		(layer "In9.Cu")
	)
	(gr_line
		(start 233.19105 -168.08196)
		(end 233.230928 -167.892222)
		(stroke
			(width 0.06985)
			(type default)
		)
		(layer "In9.Cu")
	)
	(gr_line
		(start 233.195622 -168.628568)
		(end 233.535474 -169.149776)
		(stroke
			(width 0.06985)
			(type default)
		)
		(layer "In9.Cu")
	)
	(gr_line
		(start 233.197654 -164.262562)
		(end 233.23804 -164.072316)
		(stroke
			(width 0.06985)
			(type default)
		)
		(layer "In9.Cu")
	)
	(gr_line
		(start 233.200448 -164.807646)
		(end 233.540554 -165.331394)
		(stroke
			(width 0.06985)
			(type default)
		)
		(layer "In9.Cu")
	)
	(gr_line
		(start 233.22026 -172.332396)
		(end 233.260646 -172.142404)
		(stroke
			(width 0.06985)
			(type default)
		)
		(layer "In9.Cu")
	)
	(gr_line
		(start 233.22407 -172.879004)
		(end 233.562398 -173.399958)
		(stroke
			(width 0.06985)
			(type default)
		)
		(layer "In9.Cu")
	)
	(gr_line
		(start 233.328718 -65.248282)
		(end 233.52125 -65.22339)
		(stroke
			(width 0.06985)
			(type default)
		)
		(layer "In9.Cu")
	)
	(gr_line
		(start 233.336084 -62.418976)
		(end 233.360976 -62.611254)
		(stroke
			(width 0.06985)
			(type default)
		)
		(layer "In9.Cu")
	)
	(gr_line
		(start 233.405934 -176.384204)
		(end 233.595926 -176.42459)
		(stroke
			(width 0.06985)
			(type default)
		)
		(layer "In9.Cu")
	)
	(gr_line
		(start 233.422698 -168.437306)
		(end 233.612436 -168.477184)
		(stroke
			(width 0.06985)
			(type default)
		)
		(layer "In9.Cu")
	)
	(gr_line
		(start 233.428286 -164.617908)
		(end 233.618532 -164.658294)
		(stroke
			(width 0.06985)
			(type default)
		)
		(layer "In9.Cu")
	)
	(gr_line
		(start 233.451146 -172.687996)
		(end 233.641138 -172.728128)
		(stroke
			(width 0.06985)
			(type default)
		)
		(layer "In9.Cu")
	)
	(gr_line
		(start 233.462576 -79.372968)
		(end 233.624882 -79.478886)
		(stroke
			(width 0.06985)
			(type default)
		)
		(layer "In9.Cu")
	)
	(gr_line
		(start 233.484674 -97.07499)
		(end 233.490008 -97.066862)
		(stroke
			(width 0.06985)
			(type default)
		)
		(layer "In9.Cu")
	)
	(gr_line
		(start 233.490008 -97.066862)
		(end 233.497374 -97.06102)
		(stroke
			(width 0.06985)
			(type default)
		)
		(layer "In9.Cu")
	)
	(gr_line
		(start 233.52125 -65.22339)
		(end 233.853228 -65.479168)
		(stroke
			(width 0.06985)
			(type default)
		)
		(layer "In9.Cu")
	)
	(gr_line
		(start 233.595926 -176.42459)
		(end 233.824272 -176.775872)
		(stroke
			(width 0.06985)
			(type default)
		)
		(layer "In9.Cu")
	)
	(gr_line
		(start 233.612436 -168.477184)
		(end 233.841544 -168.828212)
		(stroke
			(width 0.06985)
			(type default)
		)
		(layer "In9.Cu")
	)
	(gr_line
		(start 233.618532 -164.658294)
		(end 233.846878 -165.00983)
		(stroke
			(width 0.06985)
			(type default)
		)
		(layer "In9.Cu")
	)
	(gr_line
		(start 233.641138 -172.728128)
		(end 233.86923 -173.079664)
		(stroke
			(width 0.06985)
			(type default)
		)
		(layer "In9.Cu")
	)
	(gr_line
		(start 233.728768 -79.758286)
		(end 234.103926 -79.6798)
		(stroke
			(width 0.06985)
			(type default)
		)
		(layer "In9.Cu")
	)
	(gr_line
		(start 233.737912 -79.457804)
		(end 234.03814 -79.395066)
		(stroke
			(width 0.06985)
			(type default)
		)
		(layer "In9.Cu")
	)
	(gr_line
		(start 233.783632 -63.308738)
		(end 233.832146 -63.346076)
		(stroke
			(width 0.06985)
			(type default)
		)
		(layer "In9.Cu")
	)
	(gr_line
		(start 233.783886 -176.965864)
		(end 233.824272 -176.775872)
		(stroke
			(width 0.06985)
			(type default)
		)
		(layer "In9.Cu")
	)
	(gr_line
		(start 233.78668 -177.511202)
		(end 234.126024 -178.03368)
		(stroke
			(width 0.06985)
			(type default)
		)
		(layer "In9.Cu")
	)
	(gr_line
		(start 233.801412 -169.018204)
		(end 233.841544 -168.828212)
		(stroke
			(width 0.06985)
			(type default)
		)
		(layer "In9.Cu")
	)
	(gr_line
		(start 233.804968 -169.563288)
		(end 234.145582 -170.085766)
		(stroke
			(width 0.06985)
			(type default)
		)
		(layer "In9.Cu")
	)
	(gr_line
		(start 233.806238 -165.199822)
		(end 233.846878 -165.00983)
		(stroke
			(width 0.06985)
			(type default)
		)
		(layer "In9.Cu")
	)
	(gr_line
		(start 233.80954 -165.745668)
		(end 234.14863 -166.267638)
		(stroke
			(width 0.06985)
			(type default)
		)
		(layer "In9.Cu")
	)
	(gr_line
		(start 233.829098 -173.26991)
		(end 233.86923 -173.079664)
		(stroke
			(width 0.06985)
			(type default)
		)
		(layer "In9.Cu")
	)
	(gr_line
		(start 233.832654 -173.816264)
		(end 234.171236 -174.337472)
		(stroke
			(width 0.06985)
			(type default)
		)
		(layer "In9.Cu")
	)
	(gr_line
		(start 233.853228 -65.479168)
		(end 233.87812 -65.6717)
		(stroke
			(width 0.06985)
			(type default)
		)
		(layer "In9.Cu")
	)
	(gr_line
		(start 234.014772 -177.321464)
		(end 234.20451 -177.36185)
		(stroke
			(width 0.06985)
			(type default)
		)
		(layer "In9.Cu")
	)
	(gr_line
		(start 234.032806 -169.373296)
		(end 234.223052 -169.413428)
		(stroke
			(width 0.06985)
			(type default)
		)
		(layer "In9.Cu")
	)
	(gr_line
		(start 234.03687 -165.555168)
		(end 234.220512 -165.59403)
		(stroke
			(width 0.06985)
			(type default)
		)
		(layer "In9.Cu")
	)
	(gr_line
		(start 234.040172 -79.392018)
		(end 234.14609 -79.229712)
		(stroke
			(width 0.06985)
			(type default)
		)
		(layer "In9.Cu")
	)
	(gr_line
		(start 234.05973 -173.625256)
		(end 234.249722 -173.665388)
		(stroke
			(width 0.06985)
			(type default)
		)
		(layer "In9.Cu")
	)
	(gr_line
		(start 234.136184 -79.672942)
		(end 234.743498 -79.545688)
		(stroke
			(width 0.06985)
			(type default)
		)
		(layer "In9.Cu")
	)
	(gr_line
		(start 234.14609 -79.229712)
		(end 234.5563 -79.143606)
		(stroke
			(width 0.06985)
			(type default)
		)
		(layer "In9.Cu")
	)
	(gr_line
		(start 234.20451 -177.36185)
		(end 234.432856 -177.713132)
		(stroke
			(width 0.06985)
			(type default)
		)
		(layer "In9.Cu")
	)
	(gr_line
		(start 234.220512 -165.59403)
		(end 234.453938 -165.953694)
		(stroke
			(width 0.06985)
			(type default)
		)
		(layer "In9.Cu")
	)
	(gr_line
		(start 234.223052 -169.413428)
		(end 234.451906 -169.764456)
		(stroke
			(width 0.06985)
			(type default)
		)
		(layer "In9.Cu")
	)
	(gr_line
		(start 234.249722 -173.665388)
		(end 234.478068 -174.016924)
		(stroke
			(width 0.06985)
			(type default)
		)
		(layer "In9.Cu")
	)
	(gr_line
		(start 234.39247 -177.903124)
		(end 234.432856 -177.713132)
		(stroke
			(width 0.06985)
			(type default)
		)
		(layer "In9.Cu")
	)
	(gr_line
		(start 234.411774 -169.954448)
		(end 234.451906 -169.764456)
		(stroke
			(width 0.06985)
			(type default)
		)
		(layer "In9.Cu")
	)
	(gr_line
		(start 234.415076 -166.137082)
		(end 234.453938 -165.953694)
		(stroke
			(width 0.06985)
			(type default)
		)
		(layer "In9.Cu")
	)
	(gr_line
		(start 234.437682 -174.206916)
		(end 234.478068 -174.016924)
		(stroke
			(width 0.06985)
			(type default)
		)
		(layer "In9.Cu")
	)
	(gr_line
		(start 234.525312 -174.88281)
		(end 234.531916 -174.893224)
		(stroke
			(width 0.06985)
			(type default)
		)
		(layer "In9.Cu")
	)
	(gr_line
		(start 234.531916 -174.893224)
		(end 234.54233 -174.901352)
		(stroke
			(width 0.06985)
			(type default)
		)
		(layer "In9.Cu")
	)
	(gr_line
		(start 234.5563 -79.143606)
		(end 234.718606 -79.249778)
		(stroke
			(width 0.06985)
			(type default)
		)
		(layer "In9.Cu")
	)
	(gr_line
		(start 234.57027 -166.91737)
		(end 234.577382 -166.928292)
		(stroke
			(width 0.06985)
			(type default)
		)
		(layer "In9.Cu")
	)
	(gr_line
		(start 234.577382 -166.928292)
		(end 234.577636 -166.928546)
		(stroke
			(width 0.06985)
			(type default)
		)
		(layer "In9.Cu")
	)
	(gr_line
		(start 234.577636 -166.928546)
		(end 234.58805 -166.936674)
		(stroke
			(width 0.06985)
			(type default)
		)
		(layer "In9.Cu")
	)
	(gr_line
		(start 234.721654 -79.25181)
		(end 234.984544 -79.196692)
		(stroke
			(width 0.06985)
			(type default)
		)
		(layer "In9.Cu")
	)
	(gr_line
		(start 234.77855 -79.538322)
		(end 235.044488 -79.482696)
		(stroke
			(width 0.06985)
			(type default)
		)
		(layer "In9.Cu")
	)
	(gr_line
		(start 234.78363 -99.984306)
		(end 234.786932 -99.969828)
		(stroke
			(width 0.06985)
			(type default)
		)
		(layer "In9.Cu")
	)
	(gr_line
		(start 234.785662 -179.04968)
		(end 234.792266 -179.059586)
		(stroke
			(width 0.06985)
			(type default)
		)
		(layer "In9.Cu")
	)
	(gr_line
		(start 234.786932 -99.969828)
		(end 234.794806 -99.957636)
		(stroke
			(width 0.06985)
			(type default)
		)
		(layer "In9.Cu")
	)
	(gr_line
		(start 234.792266 -179.059586)
		(end 234.801664 -179.066952)
		(stroke
			(width 0.06985)
			(type default)
		)
		(layer "In9.Cu")
	)
	(gr_line
		(start 234.805982 -171.098718)
		(end 234.812586 -171.108624)
		(stroke
			(width 0.06985)
			(type default)
		)
		(layer "In9.Cu")
	)
	(gr_line
		(start 234.812586 -171.108624)
		(end 234.821984 -171.11599)
		(stroke
			(width 0.06985)
			(type default)
		)
		(layer "In9.Cu")
	)
	(gr_line
		(start 235.245402 -97.295462)
		(end 235.249974 -97.288604)
		(stroke
			(width 0.06985)
			(type default)
		)
		(layer "In9.Cu")
	)
	(gr_line
		(start 235.249974 -97.288604)
		(end 235.256324 -97.283524)
		(stroke
			(width 0.06985)
			(type default)
		)
		(layer "In9.Cu")
	)
	(gr_line
		(start 235.46054 -175.608488)
		(end 235.509054 -175.645826)
		(stroke
			(width 0.06985)
			(type default)
		)
		(layer "In9.Cu")
	)
	(gr_line
		(start 235.460794 -167.608504)
		(end 235.510578 -167.646858)
		(stroke
			(width 0.06985)
			(type default)
		)
		(layer "In9.Cu")
	)
	(gr_line
		(start 235.461048 -171.608496)
		(end 235.509562 -171.645834)
		(stroke
			(width 0.06985)
			(type default)
		)
		(layer "In9.Cu")
	)
	(gr_line
		(start 235.504482 -179.60848)
		(end 235.552996 -179.645818)
		(stroke
			(width 0.06985)
			(type default)
		)
		(layer "In9.Cu")
	)
	(gr_line
		(start 235.520738 -67.30873)
		(end 235.569252 -67.346068)
		(stroke
			(width 0.06985)
			(type default)
		)
		(layer "In9.Cu")
	)
	(gr_line
		(start 235.567474 -98.7679)
		(end 235.572808 -98.759772)
		(stroke
			(width 0.06985)
			(type default)
		)
		(layer "In9.Cu")
	)
	(gr_line
		(start 235.572808 -98.759772)
		(end 235.580174 -98.75393)
		(stroke
			(width 0.06985)
			(type default)
		)
		(layer "In9.Cu")
	)
	(gr_line
		(start 240.549938 -179.499768)
		(end 241.294412 -179.872132)
		(stroke
			(width 0.06985)
			(type default)
		)
		(layer "In9.Cu")
	)
	(gr_line
		(start 240.549938 -175.499776)
		(end 241.294412 -175.87214)
		(stroke
			(width 0.06985)
			(type default)
		)
		(layer "In9.Cu")
	)
	(gr_line
		(start 240.549938 -171.499784)
		(end 241.294412 -171.872148)
		(stroke
			(width 0.06985)
			(type default)
		)
		(layer "In9.Cu")
	)
	(gr_line
		(start 240.549938 -167.499792)
		(end 241.294412 -167.872156)
		(stroke
			(width 0.06985)
			(type default)
		)
		(layer "In9.Cu")
	)
	(gr_line
		(start 240.549938 -83.199986)
		(end 241.294412 -83.57235)
		(stroke
			(width 0.06985)
			(type default)
		)
		(layer "In9.Cu")
	)
	(gr_line
		(start 240.549938 -79.199994)
		(end 241.294412 -79.572358)
		(stroke
			(width 0.06985)
			(type default)
		)
		(layer "In9.Cu")
	)
	(gr_line
		(start 240.549938 -75.200002)
		(end 241.294412 -75.572366)
		(stroke
			(width 0.06985)
			(type default)
		)
		(layer "In9.Cu")
	)
	(gr_line
		(start 240.549938 -71.20001)
		(end 241.294412 -71.572374)
		(stroke
			(width 0.06985)
			(type default)
		)
		(layer "In9.Cu")
	)
	(gr_line
		(start 240.549938 -67.200018)
		(end 241.294412 -67.572382)
		(stroke
			(width 0.06985)
			(type default)
		)
		(layer "In9.Cu")
	)
	(gr_line
		(start 240.549938 -63.200026)
		(end 241.294412 -63.57239)
		(stroke
			(width 0.06985)
			(type default)
		)
		(layer "In9.Cu")
	)
	(gr_line
		(start 240.549938 -59.200034)
		(end 241.294412 -59.572398)
		(stroke
			(width 0.06985)
			(type default)
		)
		(layer "In9.Cu")
	)
	(gr_line
		(start 240.549938 -55.200042)
		(end 241.294412 -55.572406)
		(stroke
			(width 0.06985)
			(type default)
		)
		(layer "In9.Cu")
	)
	(gr_line
		(start 240.549938 -51.20005)
		(end 241.294412 -51.572414)
		(stroke
			(width 0.06985)
			(type default)
		)
		(layer "In9.Cu")
	)
	(gr_line
		(start 240.549938 -47.200058)
		(end 241.294412 -47.572422)
		(stroke
			(width 0.06985)
			(type default)
		)
		(layer "In9.Cu")
	)
	(gr_line
		(start 240.549938 -43.200066)
		(end 241.294412 -43.57243)
		(stroke
			(width 0.06985)
			(type default)
		)
		(layer "In9.Cu")
	)
	(gr_line
		(start 240.549938 -39.200074)
		(end 241.294412 -39.572438)
		(stroke
			(width 0.06985)
			(type default)
		)
		(layer "In9.Cu")
	)
	(gr_arc
		(start 241.356896 -180.059584)
		(mid 241.364477 -179.952917)
		(end 241.294412 -179.872132)
		(stroke
			(width 0.06985)
			(type default)
		)
		(layer "In9.Cu")
	)
	(gr_arc
		(start 241.356896 -176.059592)
		(mid 241.364477 -175.952925)
		(end 241.294412 -175.87214)
		(stroke
			(width 0.06985)
			(type default)
		)
		(layer "In9.Cu")
	)
	(gr_arc
		(start 241.356896 -172.0596)
		(mid 241.364477 -171.952933)
		(end 241.294412 -171.872148)
		(stroke
			(width 0.06985)
			(type default)
		)
		(layer "In9.Cu")
	)
	(gr_arc
		(start 241.356896 -168.059608)
		(mid 241.364477 -167.952941)
		(end 241.294412 -167.872156)
		(stroke
			(width 0.06985)
			(type default)
		)
		(layer "In9.Cu")
	)
	(gr_arc
		(start 241.356896 -83.759802)
		(mid 241.364477 -83.653135)
		(end 241.294412 -83.57235)
		(stroke
			(width 0.06985)
			(type default)
		)
		(layer "In9.Cu")
	)
	(gr_arc
		(start 241.356896 -79.75981)
		(mid 241.364477 -79.653143)
		(end 241.294412 -79.572358)
		(stroke
			(width 0.06985)
			(type default)
		)
		(layer "In9.Cu")
	)
	(gr_arc
		(start 241.356896 -75.759818)
		(mid 241.364477 -75.653151)
		(end 241.294412 -75.572366)
		(stroke
			(width 0.06985)
			(type default)
		)
		(layer "In9.Cu")
	)
	(gr_arc
		(start 241.356896 -71.759826)
		(mid 241.364477 -71.653159)
		(end 241.294412 -71.572374)
		(stroke
			(width 0.06985)
			(type default)
		)
		(layer "In9.Cu")
	)
	(gr_arc
		(start 241.356896 -67.759834)
		(mid 241.364477 -67.653167)
		(end 241.294412 -67.572382)
		(stroke
			(width 0.06985)
			(type default)
		)
		(layer "In9.Cu")
	)
	(gr_arc
		(start 241.356896 -63.759842)
		(mid 241.364477 -63.653175)
		(end 241.294412 -63.57239)
		(stroke
			(width 0.06985)
			(type default)
		)
		(layer "In9.Cu")
	)
	(gr_arc
		(start 241.356896 -59.75985)
		(mid 241.364477 -59.653183)
		(end 241.294412 -59.572398)
		(stroke
			(width 0.06985)
			(type default)
		)
		(layer "In9.Cu")
	)
	(gr_arc
		(start 241.356896 -55.759858)
		(mid 241.364477 -55.653191)
		(end 241.294412 -55.572406)
		(stroke
			(width 0.06985)
			(type default)
		)
		(layer "In9.Cu")
	)
	(gr_arc
		(start 241.356896 -51.759866)
		(mid 241.364477 -51.653199)
		(end 241.294412 -51.572414)
		(stroke
			(width 0.06985)
			(type default)
		)
		(layer "In9.Cu")
	)
	(gr_arc
		(start 241.356896 -47.759874)
		(mid 241.364477 -47.653207)
		(end 241.294412 -47.572422)
		(stroke
			(width 0.06985)
			(type default)
		)
		(layer "In9.Cu")
	)
	(gr_arc
		(start 241.356896 -43.759882)
		(mid 241.364477 -43.653215)
		(end 241.294412 -43.57243)
		(stroke
			(width 0.06985)
			(type default)
		)
		(layer "In9.Cu")
	)
	(gr_arc
		(start 241.356896 -39.75989)
		(mid 241.364477 -39.653223)
		(end 241.294412 -39.572438)
		(stroke
			(width 0.06985)
			(type default)
		)
		(layer "In9.Cu")
	)
	(gr_arc
		(start 241.805714 -180.127656)
		(mid 241.699034 -180.120054)
		(end 241.618262 -180.19014)
		(stroke
			(width 0.06985)
			(type default)
		)
		(layer "In9.Cu")
	)
	(gr_line
		(start 241.805714 -180.127656)
		(end 242.549934 -180.499766)
		(stroke
			(width 0.06985)
			(type default)
		)
		(layer "In9.Cu")
	)
	(gr_arc
		(start 241.805714 -176.127664)
		(mid 241.699034 -176.120062)
		(end 241.618262 -176.190148)
		(stroke
			(width 0.06985)
			(type default)
		)
		(layer "In9.Cu")
	)
	(gr_line
		(start 241.805714 -176.127664)
		(end 242.549934 -176.499774)
		(stroke
			(width 0.06985)
			(type default)
		)
		(layer "In9.Cu")
	)
	(gr_arc
		(start 241.805714 -172.127672)
		(mid 241.699035 -172.120069)
		(end 241.618262 -172.190156)
		(stroke
			(width 0.06985)
			(type default)
		)
		(layer "In9.Cu")
	)
	(gr_line
		(start 241.805714 -172.127672)
		(end 242.549934 -172.499782)
		(stroke
			(width 0.06985)
			(type default)
		)
		(layer "In9.Cu")
	)
	(gr_arc
		(start 241.805714 -168.12768)
		(mid 241.699035 -168.120076)
		(end 241.618262 -168.190164)
		(stroke
			(width 0.06985)
			(type default)
		)
		(layer "In9.Cu")
	)
	(gr_line
		(start 241.805714 -168.12768)
		(end 242.549934 -168.49979)
		(stroke
			(width 0.06985)
			(type default)
		)
		(layer "In9.Cu")
	)
	(gr_arc
		(start 241.805714 -83.827874)
		(mid 241.699035 -83.820271)
		(end 241.618262 -83.890358)
		(stroke
			(width 0.06985)
			(type default)
		)
		(layer "In9.Cu")
	)
	(gr_line
		(start 241.805714 -83.827874)
		(end 242.549934 -84.199984)
		(stroke
			(width 0.06985)
			(type default)
		)
		(layer "In9.Cu")
	)
	(gr_arc
		(start 241.805714 -79.827882)
		(mid 241.699036 -79.820278)
		(end 241.618262 -79.890366)
		(stroke
			(width 0.06985)
			(type default)
		)
		(layer "In9.Cu")
	)
	(gr_line
		(start 241.805714 -79.827882)
		(end 242.549934 -80.199992)
		(stroke
			(width 0.06985)
			(type default)
		)
		(layer "In9.Cu")
	)
	(gr_arc
		(start 241.805714 -75.82789)
		(mid 241.699029 -75.820294)
		(end 241.618262 -75.890374)
		(stroke
			(width 0.06985)
			(type default)
		)
		(layer "In9.Cu")
	)
	(gr_line
		(start 241.805714 -75.82789)
		(end 242.549934 -76.2)
		(stroke
			(width 0.06985)
			(type default)
		)
		(layer "In9.Cu")
	)
	(gr_arc
		(start 241.805714 -71.827898)
		(mid 241.69903 -71.820301)
		(end 241.618262 -71.890382)
		(stroke
			(width 0.06985)
			(type default)
		)
		(layer "In9.Cu")
	)
	(gr_line
		(start 241.805714 -71.827898)
		(end 242.549934 -72.200008)
		(stroke
			(width 0.06985)
			(type default)
		)
		(layer "In9.Cu")
	)
	(gr_arc
		(start 241.805714 -67.827906)
		(mid 241.69903 -67.820308)
		(end 241.618262 -67.89039)
		(stroke
			(width 0.06985)
			(type default)
		)
		(layer "In9.Cu")
	)
	(gr_line
		(start 241.805714 -67.827906)
		(end 242.549934 -68.200016)
		(stroke
			(width 0.06985)
			(type default)
		)
		(layer "In9.Cu")
	)
	(gr_arc
		(start 241.805714 -63.827914)
		(mid 241.699031 -63.820316)
		(end 241.618262 -63.890398)
		(stroke
			(width 0.06985)
			(type default)
		)
		(layer "In9.Cu")
	)
	(gr_line
		(start 241.805714 -63.827914)
		(end 242.549934 -64.200024)
		(stroke
			(width 0.06985)
			(type default)
		)
		(layer "In9.Cu")
	)
	(gr_arc
		(start 241.805714 -59.827922)
		(mid 241.699031 -59.820323)
		(end 241.618262 -59.890406)
		(stroke
			(width 0.06985)
			(type default)
		)
		(layer "In9.Cu")
	)
	(gr_line
		(start 241.805714 -59.827922)
		(end 242.549934 -60.200032)
		(stroke
			(width 0.06985)
			(type default)
		)
		(layer "In9.Cu")
	)
	(gr_arc
		(start 241.805714 -55.82793)
		(mid 241.699032 -55.82033)
		(end 241.618262 -55.890414)
		(stroke
			(width 0.06985)
			(type default)
		)
		(layer "In9.Cu")
	)
	(gr_line
		(start 241.805714 -55.82793)
		(end 242.549934 -56.20004)
		(stroke
			(width 0.06985)
			(type default)
		)
		(layer "In9.Cu")
	)
	(gr_arc
		(start 241.805714 -51.827938)
		(mid 241.699032 -51.820338)
		(end 241.618262 -51.890422)
		(stroke
			(width 0.06985)
			(type default)
		)
		(layer "In9.Cu")
	)
	(gr_line
		(start 241.805714 -51.827938)
		(end 242.549934 -52.200048)
		(stroke
			(width 0.06985)
			(type default)
		)
		(layer "In9.Cu")
	)
	(gr_arc
		(start 241.805714 -47.827946)
		(mid 241.699033 -47.820345)
		(end 241.618262 -47.89043)
		(stroke
			(width 0.06985)
			(type default)
		)
		(layer "In9.Cu")
	)
	(gr_line
		(start 241.805714 -47.827946)
		(end 242.549934 -48.200056)
		(stroke
			(width 0.06985)
			(type default)
		)
		(layer "In9.Cu")
	)
	(gr_arc
		(start 241.805714 -43.827954)
		(mid 241.699034 -43.820353)
		(end 241.618262 -43.890438)
		(stroke
			(width 0.06985)
			(type default)
		)
		(layer "In9.Cu")
	)
	(gr_line
		(start 241.805714 -43.827954)
		(end 242.549934 -44.200064)
		(stroke
			(width 0.06985)
			(type default)
		)
		(layer "In9.Cu")
	)
	(gr_arc
		(start 241.805714 -39.827962)
		(mid 241.699034 -39.82036)
		(end 241.618262 -39.890446)
		(stroke
			(width 0.06985)
			(type default)
		)
		(layer "In9.Cu")
	)
	(gr_line
		(start 241.805714 -39.827962)
		(end 242.549934 -40.200072)
		(stroke
			(width 0.06985)
			(type default)
		)
		(layer "In9.Cu")
	)
	(gr_line
		(start 242.532916 -88.472772)
		(end 242.533678 -88.472264)
		(stroke
			(width 0.06985)
			(type default)
		)
		(layer "In9.Cu")
	)
	(gr_line
		(start 242.533678 -88.472264)
		(end 242.53444 -88.471248)
		(stroke
			(width 0.06985)
			(type default)
		)
		(layer "In9.Cu")
	)
	(gr_line
		(start 243.627402 -89.289636)
		(end 243.633244 -89.285064)
		(stroke
			(width 0.06985)
			(type default)
		)
		(layer "In9.Cu")
	)
	(gr_line
		(start 243.633244 -89.285064)
		(end 243.637562 -89.278714)
		(stroke
			(width 0.06985)
			(type default)
		)
		(layer "In9.Cu")
	)
	(gr_line
		(start 244.36959 -85.967062)
		(end 244.385592 -85.945218)
		(stroke
			(width 0.06985)
			(type default)
		)
		(layer "In9.Cu")
	)
	(gr_line
		(start 244.385592 -85.945218)
		(end 244.390418 -85.91931)
		(stroke
			(width 0.06985)
			(type default)
		)
		(layer "In9.Cu")
	)
	(gr_line
		(start 244.396514 -90.30843)
		(end 244.402356 -90.303858)
		(stroke
			(width 0.06985)
			(type default)
		)
		(layer "In9.Cu")
	)
	(gr_line
		(start 244.402356 -90.303858)
		(end 244.406166 -90.298016)
		(stroke
			(width 0.06985)
			(type default)
		)
		(layer "In9.Cu")
	)
	(gr_line
		(start 245.030244 -91.529408)
		(end 245.035324 -91.525344)
		(stroke
			(width 0.06985)
			(type default)
		)
		(layer "In9.Cu")
	)
	(gr_line
		(start 245.035324 -91.525344)
		(end 245.038372 -91.520518)
		(stroke
			(width 0.06985)
			(type default)
		)
		(layer "In9.Cu")
	)
	(gr_line
		(start 245.291356 -35.8013)
		(end 245.303294 -35.81908)
		(stroke
			(width 0.06985)
			(type default)
		)
		(layer "In9.Cu")
	)
	(gr_line
		(start 245.303294 -35.81908)
		(end 245.307612 -35.840924)
		(stroke
			(width 0.06985)
			(type default)
		)
		(layer "In9.Cu")
	)
	(gr_line
		(start 245.336568 -86.76894)
		(end 245.349268 -86.750144)
		(stroke
			(width 0.06985)
			(type default)
		)
		(layer "In9.Cu")
	)
	(gr_line
		(start 245.349268 -86.750144)
		(end 245.353586 -86.728046)
		(stroke
			(width 0.06985)
			(type default)
		)
		(layer "In9.Cu")
	)
	(gr_line
		(start 246.890286 -35.831526)
		(end 246.901462 -35.848544)
		(stroke
			(width 0.06985)
			(type default)
		)
		(layer "In9.Cu")
	)
	(gr_line
		(start 246.901462 -35.848544)
		(end 246.905018 -35.867848)
		(stroke
			(width 0.06985)
			(type default)
		)
		(layer "In9.Cu")
	)
	(gr_line
		(start 246.961406 -86.510114)
		(end 246.973344 -86.492334)
		(stroke
			(width 0.06985)
			(type default)
		)
		(layer "In9.Cu")
	)
	(gr_line
		(start 246.973344 -86.492334)
		(end 246.977662 -86.47049)
		(stroke
			(width 0.06985)
			(type default)
		)
		(layer "In9.Cu")
	)
	(gr_line
		(start 248.45645 -35.712654)
		(end 248.468388 -35.730434)
		(stroke
			(width 0.06985)
			(type default)
		)
		(layer "In9.Cu")
	)
	(gr_line
		(start 248.468388 -35.730434)
		(end 248.472706 -35.752278)
		(stroke
			(width 0.06985)
			(type default)
		)
		(layer "In9.Cu")
	)
	(gr_line
		(start 248.653554 -86.097872)
		(end 248.66473 -86.080854)
		(stroke
			(width 0.06985)
			(type default)
		)
		(layer "In9.Cu")
	)
	(gr_line
		(start 248.66473 -86.080854)
		(end 248.668286 -86.06155)
		(stroke
			(width 0.06985)
			(type default)
		)
		(layer "In9.Cu")
	)
	(gr_line
		(start 249.710448 -58.50128)
		(end 249.714258 -58.520838)
		(stroke
			(width 0.06985)
			(type default)
		)
		(layer "In9.Cu")
	)
	(gr_line
		(start 249.710702 -58.539634)
		(end 249.714258 -58.520838)
		(stroke
			(width 0.06985)
			(type default)
		)
		(layer "In9.Cu")
	)
	(gr_line
		(start 249.802142 -34.445956)
		(end 249.81408 -34.463736)
		(stroke
			(width 0.06985)
			(type default)
		)
		(layer "In9.Cu")
	)
	(gr_line
		(start 249.81408 -34.463736)
		(end 249.818398 -34.48558)
		(stroke
			(width 0.06985)
			(type default)
		)
		(layer "In9.Cu")
	)
	(gr_line
		(start 250.773438 -57.312814)
		(end 250.773692 -57.311798)
		(stroke
			(width 0.06985)
			(type default)
		)
		(layer "In9.Cu")
	)
	(gr_line
		(start 250.773438 -57.311798)
		(end 250.773692 -57.311798)
		(stroke
			(width 0.06985)
			(type default)
		)
		(layer "In9.Cu")
	)
	(gr_line
		(start 251.057156 -57.241694)
		(end 251.062998 -57.271666)
		(stroke
			(width 0.06985)
			(type default)
		)
		(layer "In9.Cu")
	)
	(gr_line
		(start 251.057156 -57.241694)
		(end 251.062998 -57.27065)
		(stroke
			(width 0.06985)
			(type default)
		)
		(layer "In9.Cu")
	)
	(gr_line
		(start 251.057918 -57.244234)
		(end 251.06249 -57.26811)
		(stroke
			(width 0.06985)
			(type default)
		)
		(layer "In9.Cu")
	)
	(gr_line
		(start 251.067824 -57.330594)
		(end 251.07138 -57.311798)
		(stroke
			(width 0.06985)
			(type default)
		)
		(layer "In9.Cu")
	)
	(gr_line
		(start 251.068078 -57.296812)
		(end 251.070872 -57.311798)
		(stroke
			(width 0.06985)
			(type default)
		)
		(layer "In9.Cu")
	)
	(gr_line
		(start 251.070872 -57.311798)
		(end 251.07138 -57.311798)
		(stroke
			(width 0.06985)
			(type default)
		)
		(layer "In9.Cu")
	)
	(gr_line
		(start 252.649228 -57.246012)
		(end 252.653038 -57.26557)
		(stroke
			(width 0.06985)
			(type default)
		)
		(layer "In9.Cu")
	)
	(gr_line
		(start 252.649482 -57.284366)
		(end 252.653038 -57.26557)
		(stroke
			(width 0.06985)
			(type default)
		)
		(layer "In9.Cu")
	)
	(gr_line
		(start 254.250952 -57.298844)
		(end 254.254762 -57.318402)
		(stroke
			(width 0.06985)
			(type default)
		)
		(layer "In9.Cu")
	)
	(gr_line
		(start 254.251206 -57.337198)
		(end 254.254762 -57.318402)
		(stroke
			(width 0.06985)
			(type default)
		)
		(layer "In9.Cu")
	)
	(gr_line
		(start 255.354582 -160.531048)
		(end 255.536954 -159.930338)
		(stroke
			(width 0.06985)
			(type default)
		)
		(layer "In9.Cu")
	)
	(gr_line
		(start 255.626616 -160.649412)
		(end 255.798066 -160.557972)
		(stroke
			(width 0.06985)
			(type default)
		)
		(layer "In9.Cu")
	)
	(gr_line
		(start 255.678432 -159.463486)
		(end 255.860804 -158.862522)
		(stroke
			(width 0.06985)
			(type default)
		)
		(layer "In9.Cu")
	)
	(gr_line
		(start 255.798066 -160.557972)
		(end 255.919986 -160.156906)
		(stroke
			(width 0.06985)
			(type default)
		)
		(layer "In9.Cu")
	)
	(gr_line
		(start 255.828038 -159.985202)
		(end 255.919986 -160.156906)
		(stroke
			(width 0.06985)
			(type default)
		)
		(layer "In9.Cu")
	)
	(gr_line
		(start 255.950974 -159.580326)
		(end 256.122678 -159.488378)
		(stroke
			(width 0.06985)
			(type default)
		)
		(layer "In9.Cu")
	)
	(gr_line
		(start 256.003552 -158.392114)
		(end 256.18567 -157.79242)
		(stroke
			(width 0.06985)
			(type default)
		)
		(layer "In9.Cu")
	)
	(gr_line
		(start 256.122678 -159.488378)
		(end 256.244344 -159.087312)
		(stroke
			(width 0.06985)
			(type default)
		)
		(layer "In9.Cu")
	)
	(gr_line
		(start 256.15265 -158.915862)
		(end 256.244344 -159.087312)
		(stroke
			(width 0.06985)
			(type default)
		)
		(layer "In9.Cu")
	)
	(gr_line
		(start 256.275586 -158.510478)
		(end 256.447036 -158.418784)
		(stroke
			(width 0.06985)
			(type default)
		)
		(layer "In9.Cu")
	)
	(gr_line
		(start 256.447036 -158.418784)
		(end 256.568702 -158.017972)
		(stroke
			(width 0.06985)
			(type default)
		)
		(layer "In9.Cu")
	)
	(gr_line
		(start 256.477008 -157.846268)
		(end 256.568702 -158.017972)
		(stroke
			(width 0.06985)
			(type default)
		)
		(layer "In9.Cu")
	)
	(gr_line
		(start 257.681222 -152.86355)
		(end 257.863086 -152.263602)
		(stroke
			(width 0.06985)
			(type default)
		)
		(layer "In9.Cu")
	)
	(gr_line
		(start 257.953256 -152.980898)
		(end 258.12496 -152.889458)
		(stroke
			(width 0.06985)
			(type default)
		)
		(layer "In9.Cu")
	)
	(gr_line
		(start 258.005834 -151.793194)
		(end 258.187698 -151.194008)
		(stroke
			(width 0.06985)
			(type default)
		)
		(layer "In9.Cu")
	)
	(gr_line
		(start 258.12496 -152.889458)
		(end 258.246626 -152.488392)
		(stroke
			(width 0.06985)
			(type default)
		)
		(layer "In9.Cu")
	)
	(gr_line
		(start 258.154932 -152.316942)
		(end 258.246626 -152.488392)
		(stroke
			(width 0.06985)
			(type default)
		)
		(layer "In9.Cu")
	)
	(gr_line
		(start 258.277868 -151.911558)
		(end 258.449318 -151.819864)
		(stroke
			(width 0.06985)
			(type default)
		)
		(layer "In9.Cu")
	)
	(gr_line
		(start 258.330446 -150.7236)
		(end 258.511802 -150.125938)
		(stroke
			(width 0.06985)
			(type default)
		)
		(layer "In9.Cu")
	)
	(gr_line
		(start 258.449318 -151.819864)
		(end 258.571238 -151.418798)
		(stroke
			(width 0.06985)
			(type default)
		)
		(layer "In9.Cu")
	)
	(gr_line
		(start 258.479544 -151.247348)
		(end 258.571238 -151.418798)
		(stroke
			(width 0.06985)
			(type default)
		)
		(layer "In9.Cu")
	)
	(gr_line
		(start 258.60248 -150.841964)
		(end 258.77393 -150.750524)
		(stroke
			(width 0.06985)
			(type default)
		)
		(layer "In9.Cu")
	)
	(gr_line
		(start 258.654804 -149.655022)
		(end 258.836668 -149.055836)
		(stroke
			(width 0.06985)
			(type default)
		)
		(layer "In9.Cu")
	)
	(gr_line
		(start 258.77393 -150.750524)
		(end 258.895596 -150.349458)
		(stroke
			(width 0.06985)
			(type default)
		)
		(layer "In9.Cu")
	)
	(gr_line
		(start 258.803902 -150.178008)
		(end 258.895596 -150.349458)
		(stroke
			(width 0.06985)
			(type default)
		)
		(layer "In9.Cu")
	)
	(gr_line
		(start 258.926838 -149.772624)
		(end 259.098542 -149.68093)
		(stroke
			(width 0.06985)
			(type default)
		)
		(layer "In9.Cu")
	)
	(gr_line
		(start 259.098542 -149.68093)
		(end 259.220208 -149.279864)
		(stroke
			(width 0.06985)
			(type default)
		)
		(layer "In9.Cu")
	)
	(gr_line
		(start 259.128514 -149.108414)
		(end 259.220208 -149.279864)
		(stroke
			(width 0.06985)
			(type default)
		)
		(layer "In9.Cu")
	)
	(gr_line
		(start 259.29971 -177.61204)
		(end 259.30098 -177.607976)
		(stroke
			(width 0.06985)
			(type default)
		)
		(layer "In9.Cu")
	)
	(gr_line
		(start 259.30098 -177.607976)
		(end 259.303266 -177.604674)
		(stroke
			(width 0.06985)
			(type default)
		)
		(layer "In9.Cu")
	)
	(gr_line
		(start 260.332728 -144.12468)
		(end 260.514084 -143.52651)
		(stroke
			(width 0.06985)
			(type default)
		)
		(layer "In9.Cu")
	)
	(gr_line
		(start 260.604762 -144.243044)
		(end 260.776212 -144.15135)
		(stroke
			(width 0.06985)
			(type default)
		)
		(layer "In9.Cu")
	)
	(gr_line
		(start 260.65734 -143.055086)
		(end 260.838696 -142.457424)
		(stroke
			(width 0.06985)
			(type default)
		)
		(layer "In9.Cu")
	)
	(gr_line
		(start 260.717792 -178.822858)
		(end 260.719062 -178.818794)
		(stroke
			(width 0.06985)
			(type default)
		)
		(layer "In9.Cu")
	)
	(gr_line
		(start 260.719062 -178.818794)
		(end 260.721348 -178.815492)
		(stroke
			(width 0.06985)
			(type default)
		)
		(layer "In9.Cu")
	)
	(gr_line
		(start 260.776212 -144.15135)
		(end 260.897878 -143.750284)
		(stroke
			(width 0.06985)
			(type default)
		)
		(layer "In9.Cu")
	)
	(gr_line
		(start 260.806184 -143.579088)
		(end 260.897878 -143.750284)
		(stroke
			(width 0.06985)
			(type default)
		)
		(layer "In9.Cu")
	)
	(gr_line
		(start 260.929374 -143.17345)
		(end 261.100824 -143.08201)
		(stroke
			(width 0.06985)
			(type default)
		)
		(layer "In9.Cu")
	)
	(gr_line
		(start 260.982206 -141.98473)
		(end 261.163562 -141.387322)
		(stroke
			(width 0.06985)
			(type default)
		)
		(layer "In9.Cu")
	)
	(gr_line
		(start 261.100824 -143.08201)
		(end 261.22249 -142.680944)
		(stroke
			(width 0.06985)
			(type default)
		)
		(layer "In9.Cu")
	)
	(gr_line
		(start 261.130796 -142.509494)
		(end 261.22249 -142.680944)
		(stroke
			(width 0.06985)
			(type default)
		)
		(layer "In9.Cu")
	)
	(gr_line
		(start 261.253986 -142.10411)
		(end 261.425182 -142.012416)
		(stroke
			(width 0.06985)
			(type default)
		)
		(layer "In9.Cu")
	)
	(gr_line
		(start 261.30631 -140.916406)
		(end 261.487666 -140.318744)
		(stroke
			(width 0.06985)
			(type default)
		)
		(layer "In9.Cu")
	)
	(gr_line
		(start 261.425182 -142.012416)
		(end 261.546848 -141.61135)
		(stroke
			(width 0.06985)
			(type default)
		)
		(layer "In9.Cu")
	)
	(gr_line
		(start 261.455408 -141.4399)
		(end 261.546848 -141.61135)
		(stroke
			(width 0.06985)
			(type default)
		)
		(layer "In9.Cu")
	)
	(gr_line
		(start 261.578344 -141.03477)
		(end 261.749794 -140.943076)
		(stroke
			(width 0.06985)
			(type default)
		)
		(layer "In9.Cu")
	)
	(gr_line
		(start 261.749794 -140.943076)
		(end 261.87146 -140.54201)
		(stroke
			(width 0.06985)
			(type default)
		)
		(layer "In9.Cu")
	)
	(gr_line
		(start 261.779766 -140.370814)
		(end 261.87146 -140.54201)
		(stroke
			(width 0.06985)
			(type default)
		)
		(layer "In9.Cu")
	)
	(gr_line
		(start 262.032496 -180.306726)
		(end 262.033766 -180.302662)
		(stroke
			(width 0.06985)
			(type default)
		)
		(layer "In9.Cu")
	)
	(gr_line
		(start 262.033766 -180.302662)
		(end 262.036052 -180.29936)
		(stroke
			(width 0.06985)
			(type default)
		)
		(layer "In9.Cu")
	)
	(gr_line
		(start 262.984742 -135.385556)
		(end 263.165844 -134.788148)
		(stroke
			(width 0.06985)
			(type default)
		)
		(layer "In9.Cu")
	)
	(gr_line
		(start 263.082532 -182.664354)
		(end 263.083802 -182.66029)
		(stroke
			(width 0.06985)
			(type default)
		)
		(layer "In9.Cu")
	)
	(gr_line
		(start 263.083802 -182.66029)
		(end 263.086088 -182.656988)
		(stroke
			(width 0.06985)
			(type default)
		)
		(layer "In9.Cu")
	)
	(gr_line
		(start 263.256268 -135.50519)
		(end 263.427464 -135.413496)
		(stroke
			(width 0.06985)
			(type default)
		)
		(layer "In9.Cu")
	)
	(gr_line
		(start 263.308338 -134.31774)
		(end 263.489948 -133.71957)
		(stroke
			(width 0.06985)
			(type default)
		)
		(layer "In9.Cu")
	)
	(gr_line
		(start 263.427464 -135.413496)
		(end 263.54913 -135.01243)
		(stroke
			(width 0.06985)
			(type default)
		)
		(layer "In9.Cu")
	)
	(gr_line
		(start 263.45769 -134.84098)
		(end 263.54913 -135.01243)
		(stroke
			(width 0.06985)
			(type default)
		)
		(layer "In9.Cu")
	)
	(gr_line
		(start 263.58088 -134.435596)
		(end 263.752076 -134.344156)
		(stroke
			(width 0.06985)
			(type default)
		)
		(layer "In9.Cu")
	)
	(gr_line
		(start 263.63295 -133.247892)
		(end 263.814814 -132.648706)
		(stroke
			(width 0.06985)
			(type default)
		)
		(layer "In9.Cu")
	)
	(gr_line
		(start 263.752076 -134.344156)
		(end 263.873742 -133.94309)
		(stroke
			(width 0.06985)
			(type default)
		)
		(layer "In9.Cu")
	)
	(gr_line
		(start 263.782048 -133.771894)
		(end 263.873742 -133.94309)
		(stroke
			(width 0.06985)
			(type default)
		)
		(layer "In9.Cu")
	)
	(gr_line
		(start 263.905238 -133.366002)
		(end 264.076434 -133.274562)
		(stroke
			(width 0.06985)
			(type default)
		)
		(layer "In9.Cu")
	)
	(gr_line
		(start 263.957816 -132.17779)
		(end 264.138664 -131.581906)
		(stroke
			(width 0.06985)
			(type default)
		)
		(layer "In9.Cu")
	)
	(gr_line
		(start 264.076434 -133.274562)
		(end 264.1981 -132.873496)
		(stroke
			(width 0.06985)
			(type default)
		)
		(layer "In9.Cu")
	)
	(gr_line
		(start 264.10666 -132.7023)
		(end 264.1981 -132.873496)
		(stroke
			(width 0.06985)
			(type default)
		)
		(layer "In9.Cu")
	)
	(gr_line
		(start 264.22985 -132.296662)
		(end 264.401046 -132.205222)
		(stroke
			(width 0.06985)
			(type default)
		)
		(layer "In9.Cu")
	)
	(gr_line
		(start 264.401046 -132.205222)
		(end 264.522712 -131.804156)
		(stroke
			(width 0.06985)
			(type default)
		)
		(layer "In9.Cu")
	)
	(gr_line
		(start 264.431272 -131.63296)
		(end 264.522712 -131.804156)
		(stroke
			(width 0.06985)
			(type default)
		)
		(layer "In9.Cu")
	)
	(gr_line
		(start 264.445242 -130.57251)
		(end 264.446512 -130.567684)
		(stroke
			(width 0.06985)
			(type default)
		)
		(layer "In9.Cu")
	)
	(gr_line
		(start 264.446512 -130.567684)
		(end 264.44956 -130.563112)
		(stroke
			(width 0.06985)
			(type default)
		)
		(layer "In9.Cu")
	)
	(gr_line
		(start 264.724642 -130.15214)
		(end 265.071606 -129.63398)
		(stroke
			(width 0.06985)
			(type default)
		)
		(layer "In9.Cu")
	)
	(gr_line
		(start 264.94994 -130.34518)
		(end 265.14044 -130.307588)
		(stroke
			(width 0.06985)
			(type default)
		)
		(layer "In9.Cu")
	)
	(gr_line
		(start 265.063732 -134.350506)
		(end 265.245342 -133.752082)
		(stroke
			(width 0.06985)
			(type default)
		)
		(layer "In9.Cu")
	)
	(gr_line
		(start 265.14044 -130.307588)
		(end 265.373612 -129.959354)
		(stroke
			(width 0.06985)
			(type default)
		)
		(layer "In9.Cu")
	)
	(gr_line
		(start 265.335766 -134.469378)
		(end 265.506962 -134.377938)
		(stroke
			(width 0.06985)
			(type default)
		)
		(layer "In9.Cu")
	)
	(gr_line
		(start 265.33602 -129.768854)
		(end 265.373612 -129.959354)
		(stroke
			(width 0.06985)
			(type default)
		)
		(layer "In9.Cu")
	)
	(gr_line
		(start 265.346434 -129.223516)
		(end 265.693398 -128.705356)
		(stroke
			(width 0.06985)
			(type default)
		)
		(layer "In9.Cu")
	)
	(gr_line
		(start 265.38809 -133.281674)
		(end 265.569446 -132.68452)
		(stroke
			(width 0.06985)
			(type default)
		)
		(layer "In9.Cu")
	)
	(gr_line
		(start 265.506962 -134.377938)
		(end 265.628628 -133.976872)
		(stroke
			(width 0.06985)
			(type default)
		)
		(layer "In9.Cu")
	)
	(gr_line
		(start 265.537188 -133.805422)
		(end 265.628628 -133.976872)
		(stroke
			(width 0.06985)
			(type default)
		)
		(layer "In9.Cu")
	)
	(gr_line
		(start 265.571732 -129.416556)
		(end 265.762232 -129.378964)
		(stroke
			(width 0.06985)
			(type default)
		)
		(layer "In9.Cu")
	)
	(gr_line
		(start 265.579606 -138.268456)
		(end 265.580876 -138.264392)
		(stroke
			(width 0.06985)
			(type default)
		)
		(layer "In9.Cu")
	)
	(gr_line
		(start 265.580876 -138.264392)
		(end 265.583162 -138.26109)
		(stroke
			(width 0.06985)
			(type default)
		)
		(layer "In9.Cu")
	)
	(gr_line
		(start 265.660124 -133.400038)
		(end 265.831574 -133.308344)
		(stroke
			(width 0.06985)
			(type default)
		)
		(layer "In9.Cu")
	)
	(gr_line
		(start 265.712702 -132.211572)
		(end 265.894312 -131.613148)
		(stroke
			(width 0.06985)
			(type default)
		)
		(layer "In9.Cu")
	)
	(gr_line
		(start 265.762232 -129.378964)
		(end 265.995404 -129.03073)
		(stroke
			(width 0.06985)
			(type default)
		)
		(layer "In9.Cu")
	)
	(gr_line
		(start 265.831574 -133.308344)
		(end 265.95324 -132.907278)
		(stroke
			(width 0.06985)
			(type default)
		)
		(layer "In9.Cu")
	)
	(gr_line
		(start 265.861546 -132.736082)
		(end 265.95324 -132.907278)
		(stroke
			(width 0.06985)
			(type default)
		)
		(layer "In9.Cu")
	)
	(gr_line
		(start 265.957812 -128.84023)
		(end 265.995404 -129.03073)
		(stroke
			(width 0.06985)
			(type default)
		)
		(layer "In9.Cu")
	)
	(gr_line
		(start 265.968734 -128.294384)
		(end 266.31519 -127.776732)
		(stroke
			(width 0.06985)
			(type default)
		)
		(layer "In9.Cu")
	)
	(gr_line
		(start 265.984736 -132.330444)
		(end 266.155932 -132.239004)
		(stroke
			(width 0.06985)
			(type default)
		)
		(layer "In9.Cu")
	)
	(gr_line
		(start 266.037314 -131.142232)
		(end 266.038584 -131.138168)
		(stroke
			(width 0.06985)
			(type default)
		)
		(layer "In9.Cu")
	)
	(gr_line
		(start 266.038584 -131.138168)
		(end 266.04087 -131.134866)
		(stroke
			(width 0.06985)
			(type default)
		)
		(layer "In9.Cu")
	)
	(gr_line
		(start 266.155932 -132.239004)
		(end 266.277852 -131.837938)
		(stroke
			(width 0.06985)
			(type default)
		)
		(layer "In9.Cu")
	)
	(gr_line
		(start 266.186158 -131.666488)
		(end 266.277852 -131.837938)
		(stroke
			(width 0.06985)
			(type default)
		)
		(layer "In9.Cu")
	)
	(gr_line
		(start 266.193524 -128.487932)
		(end 266.384024 -128.45034)
		(stroke
			(width 0.06985)
			(type default)
		)
		(layer "In9.Cu")
	)
	(gr_line
		(start 266.384024 -128.45034)
		(end 266.617196 -128.102106)
		(stroke
			(width 0.06985)
			(type default)
		)
		(layer "In9.Cu")
	)
	(gr_line
		(start 266.579604 -127.911606)
		(end 266.617196 -128.102106)
		(stroke
			(width 0.06985)
			(type default)
		)
		(layer "In9.Cu")
	)
	(gr_line
		(start 266.590526 -127.36576)
		(end 266.936982 -126.848108)
		(stroke
			(width 0.06985)
			(type default)
		)
		(layer "In9.Cu")
	)
	(gr_line
		(start 266.815316 -127.559308)
		(end 267.005816 -127.521716)
		(stroke
			(width 0.06985)
			(type default)
		)
		(layer "In9.Cu")
	)
	(gr_line
		(start 266.824968 -71.80453)
		(end 266.831064 -71.831708)
		(stroke
			(width 0.06985)
			(type default)
		)
		(layer "In9.Cu")
	)
	(gr_line
		(start 266.824968 -71.80453)
		(end 266.831064 -71.777352)
		(stroke
			(width 0.06985)
			(type default)
		)
		(layer "In9.Cu")
	)
	(gr_line
		(start 266.940284 -71.295514)
		(end 267.077698 -70.68693)
		(stroke
			(width 0.06985)
			(type default)
		)
		(layer "In9.Cu")
	)
	(gr_line
		(start 267.005816 -127.521716)
		(end 267.238988 -127.173482)
		(stroke
			(width 0.06985)
			(type default)
		)
		(layer "In9.Cu")
	)
	(gr_line
		(start 267.18641 -70.206362)
		(end 267.324332 -69.596508)
		(stroke
			(width 0.06985)
			(type default)
		)
		(layer "In9.Cu")
	)
	(gr_line
		(start 267.201396 -126.982982)
		(end 267.238988 -127.173482)
		(stroke
			(width 0.06985)
			(type default)
		)
		(layer "In9.Cu")
	)
	(gr_line
		(start 267.219684 -71.394828)
		(end 267.384022 -71.291196)
		(stroke
			(width 0.06985)
			(type default)
		)
		(layer "In9.Cu")
	)
	(gr_line
		(start 267.372846 -70.717918)
		(end 267.476478 -70.882256)
		(stroke
			(width 0.06985)
			(type default)
		)
		(layer "In9.Cu")
	)
	(gr_line
		(start 267.384022 -71.291196)
		(end 267.476478 -70.882256)
		(stroke
			(width 0.06985)
			(type default)
		)
		(layer "In9.Cu")
	)
	(gr_line
		(start 267.433552 -69.115432)
		(end 267.570966 -68.507102)
		(stroke
			(width 0.06985)
			(type default)
		)
		(layer "In9.Cu")
	)
	(gr_line
		(start 267.466318 -70.30466)
		(end 267.630656 -70.201028)
		(stroke
			(width 0.06985)
			(type default)
		)
		(layer "In9.Cu")
	)
	(gr_line
		(start 267.515848 -138.963146)
		(end 267.517118 -138.959082)
		(stroke
			(width 0.06985)
			(type default)
		)
		(layer "In9.Cu")
	)
	(gr_line
		(start 267.517118 -138.959082)
		(end 267.519404 -138.95578)
		(stroke
			(width 0.06985)
			(type default)
		)
		(layer "In9.Cu")
	)
	(gr_line
		(start 267.61948 -69.628004)
		(end 267.723112 -69.792342)
		(stroke
			(width 0.06985)
			(type default)
		)
		(layer "In9.Cu")
	)
	(gr_line
		(start 267.630656 -70.201028)
		(end 267.723112 -69.792342)
		(stroke
			(width 0.06985)
			(type default)
		)
		(layer "In9.Cu")
	)
	(gr_line
		(start 267.680186 -68.024502)
		(end 267.8176 -67.417442)
		(stroke
			(width 0.06985)
			(type default)
		)
		(layer "In9.Cu")
	)
	(gr_line
		(start 267.712952 -69.214746)
		(end 267.87729 -69.111114)
		(stroke
			(width 0.06985)
			(type default)
		)
		(layer "In9.Cu")
	)
	(gr_line
		(start 267.866114 -68.537836)
		(end 267.969746 -68.702174)
		(stroke
			(width 0.06985)
			(type default)
		)
		(layer "In9.Cu")
	)
	(gr_line
		(start 267.87729 -69.111114)
		(end 267.969746 -68.702174)
		(stroke
			(width 0.06985)
			(type default)
		)
		(layer "In9.Cu")
	)
	(gr_line
		(start 267.959586 -68.124578)
		(end 268.123924 -68.020946)
		(stroke
			(width 0.06985)
			(type default)
		)
		(layer "In9.Cu")
	)
	(gr_line
		(start 268.112748 -67.447922)
		(end 268.21638 -67.61226)
		(stroke
			(width 0.06985)
			(type default)
		)
		(layer "In9.Cu")
	)
	(gr_line
		(start 268.123924 -68.020946)
		(end 268.21638 -67.61226)
		(stroke
			(width 0.06985)
			(type default)
		)
		(layer "In9.Cu")
	)
	(gr_line
		(start 268.47165 -141.630908)
		(end 268.47292 -141.626844)
		(stroke
			(width 0.06985)
			(type default)
		)
		(layer "In9.Cu")
	)
	(gr_line
		(start 268.47292 -141.626844)
		(end 268.475206 -141.623542)
		(stroke
			(width 0.06985)
			(type default)
		)
		(layer "In9.Cu")
	)
	(gr_line
		(start 268.875256 -71.228712)
		(end 268.881352 -71.25589)
		(stroke
			(width 0.06985)
			(type default)
		)
		(layer "In9.Cu")
	)
	(gr_line
		(start 268.875256 -71.228712)
		(end 268.881352 -71.201534)
		(stroke
			(width 0.06985)
			(type default)
		)
		(layer "In9.Cu")
	)
	(gr_line
		(start 268.990572 -70.718934)
		(end 269.127986 -70.112128)
		(stroke
			(width 0.06985)
			(type default)
		)
		(layer "In9.Cu")
	)
	(gr_line
		(start 269.195804 -82.505296)
		(end 269.33525 -83.1342)
		(stroke
			(width 0.06985)
			(type default)
		)
		(layer "In9.Cu")
	)
	(gr_line
		(start 269.237714 -69.627496)
		(end 269.37462 -69.02323)
		(stroke
			(width 0.06985)
			(type default)
		)
		(layer "In9.Cu")
	)
	(gr_line
		(start 269.269972 -70.81901)
		(end 269.43431 -70.715378)
		(stroke
			(width 0.06985)
			(type default)
		)
		(layer "In9.Cu")
	)
	(gr_line
		(start 269.423134 -70.1421)
		(end 269.526766 -70.306438)
		(stroke
			(width 0.06985)
			(type default)
		)
		(layer "In9.Cu")
	)
	(gr_line
		(start 269.43431 -70.715378)
		(end 269.526766 -70.306438)
		(stroke
			(width 0.06985)
			(type default)
		)
		(layer "In9.Cu")
	)
	(gr_line
		(start 269.442184 -83.616546)
		(end 269.581122 -84.24418)
		(stroke
			(width 0.06985)
			(type default)
		)
		(layer "In9.Cu")
	)
	(gr_line
		(start 269.475966 -82.407506)
		(end 269.651734 -82.519774)
		(stroke
			(width 0.06985)
			(type default)
		)
		(layer "In9.Cu")
	)
	(gr_line
		(start 269.484094 -68.538344)
		(end 269.621254 -67.932554)
		(stroke
			(width 0.06985)
			(type default)
		)
		(layer "In9.Cu")
	)
	(gr_line
		(start 269.51686 -69.728842)
		(end 269.680944 -69.62521)
		(stroke
			(width 0.06985)
			(type default)
		)
		(layer "In9.Cu")
	)
	(gr_line
		(start 269.630398 -83.104736)
		(end 269.742412 -82.928968)
		(stroke
			(width 0.06985)
			(type default)
		)
		(layer "In9.Cu")
	)
	(gr_line
		(start 269.651734 -82.519774)
		(end 269.742412 -82.928968)
		(stroke
			(width 0.06985)
			(type default)
		)
		(layer "In9.Cu")
	)
	(gr_line
		(start 269.669768 -69.052186)
		(end 269.7734 -69.216524)
		(stroke
			(width 0.06985)
			(type default)
		)
		(layer "In9.Cu")
	)
	(gr_line
		(start 269.680944 -69.62521)
		(end 269.7734 -69.216524)
		(stroke
			(width 0.06985)
			(type default)
		)
		(layer "In9.Cu")
	)
	(gr_line
		(start 269.688564 -84.728558)
		(end 269.827248 -85.355176)
		(stroke
			(width 0.06985)
			(type default)
		)
		(layer "In9.Cu")
	)
	(gr_line
		(start 269.722092 -83.518502)
		(end 269.89786 -83.63077)
		(stroke
			(width 0.06985)
			(type default)
		)
		(layer "In9.Cu")
	)
	(gr_line
		(start 269.730728 -67.448176)
		(end 269.867888 -66.842132)
		(stroke
			(width 0.06985)
			(type default)
		)
		(layer "In9.Cu")
	)
	(gr_line
		(start 269.763494 -68.638928)
		(end 269.927578 -68.535296)
		(stroke
			(width 0.06985)
			(type default)
		)
		(layer "In9.Cu")
	)
	(gr_line
		(start 269.804896 -122.564906)
		(end 270.152368 -122.045984)
		(stroke
			(width 0.06985)
			(type default)
		)
		(layer "In9.Cu")
	)
	(gr_line
		(start 269.831312 -125.2982)
		(end 270.171164 -124.77496)
		(stroke
			(width 0.06985)
			(type default)
		)
		(layer "In9.Cu")
	)
	(gr_line
		(start 269.876524 -84.215732)
		(end 269.988538 -84.039964)
		(stroke
			(width 0.06985)
			(type default)
		)
		(layer "In9.Cu")
	)
	(gr_line
		(start 269.89786 -83.63077)
		(end 269.988538 -84.039964)
		(stroke
			(width 0.06985)
			(type default)
		)
		(layer "In9.Cu")
	)
	(gr_line
		(start 269.916402 -67.962272)
		(end 270.020034 -68.126356)
		(stroke
			(width 0.06985)
			(type default)
		)
		(layer "In9.Cu")
	)
	(gr_line
		(start 269.927578 -68.535296)
		(end 270.020034 -68.126356)
		(stroke
			(width 0.06985)
			(type default)
		)
		(layer "In9.Cu")
	)
	(gr_line
		(start 269.93469 -85.839808)
		(end 270.073374 -86.466426)
		(stroke
			(width 0.06985)
			(type default)
		)
		(layer "In9.Cu")
	)
	(gr_line
		(start 269.968218 -84.629498)
		(end 270.143986 -84.741766)
		(stroke
			(width 0.06985)
			(type default)
		)
		(layer "In9.Cu")
	)
	(gr_line
		(start 270.010128 -67.54876)
		(end 270.174212 -67.445128)
		(stroke
			(width 0.06985)
			(type default)
		)
		(layer "In9.Cu")
	)
	(gr_line
		(start 270.030448 -122.757692)
		(end 270.220948 -122.7201)
		(stroke
			(width 0.06985)
			(type default)
		)
		(layer "In9.Cu")
	)
	(gr_line
		(start 270.059658 -125.487684)
		(end 270.24965 -125.447298)
		(stroke
			(width 0.06985)
			(type default)
		)
		(layer "In9.Cu")
	)
	(gr_line
		(start 270.12265 -85.326728)
		(end 270.234664 -85.150706)
		(stroke
			(width 0.06985)
			(type default)
		)
		(layer "In9.Cu")
	)
	(gr_line
		(start 270.143986 -84.741766)
		(end 270.234664 -85.150706)
		(stroke
			(width 0.06985)
			(type default)
		)
		(layer "In9.Cu")
	)
	(gr_line
		(start 270.163036 -66.872358)
		(end 270.266668 -67.036442)
		(stroke
			(width 0.06985)
			(type default)
		)
		(layer "In9.Cu")
	)
	(gr_line
		(start 270.174212 -67.445128)
		(end 270.266668 -67.036442)
		(stroke
			(width 0.06985)
			(type default)
		)
		(layer "In9.Cu")
	)
	(gr_line
		(start 270.180562 -86.950042)
		(end 270.184118 -86.96579)
		(stroke
			(width 0.06985)
			(type default)
		)
		(layer "In9.Cu")
	)
	(gr_line
		(start 270.184118 -86.96579)
		(end 270.193008 -86.979252)
		(stroke
			(width 0.06985)
			(type default)
		)
		(layer "In9.Cu")
	)
	(gr_line
		(start 270.214344 -85.740494)
		(end 270.390366 -85.852508)
		(stroke
			(width 0.06985)
			(type default)
		)
		(layer "In9.Cu")
	)
	(gr_line
		(start 270.220948 -122.7201)
		(end 270.45412 -122.371866)
		(stroke
			(width 0.06985)
			(type default)
		)
		(layer "In9.Cu")
	)
	(gr_line
		(start 270.24965 -125.447298)
		(end 270.477996 -125.095762)
		(stroke
			(width 0.06985)
			(type default)
		)
		(layer "In9.Cu")
	)
	(gr_line
		(start 270.368776 -86.43747)
		(end 270.48079 -86.261702)
		(stroke
			(width 0.06985)
			(type default)
		)
		(layer "In9.Cu")
	)
	(gr_line
		(start 270.390366 -85.852508)
		(end 270.48079 -86.261702)
		(stroke
			(width 0.06985)
			(type default)
		)
		(layer "In9.Cu")
	)
	(gr_line
		(start 270.416528 -122.181366)
		(end 270.45412 -122.371866)
		(stroke
			(width 0.06985)
			(type default)
		)
		(layer "In9.Cu")
	)
	(gr_line
		(start 270.426688 -121.636282)
		(end 270.77416 -121.11736)
		(stroke
			(width 0.06985)
			(type default)
		)
		(layer "In9.Cu")
	)
	(gr_line
		(start 270.43761 -124.906024)
		(end 270.477996 -125.095762)
		(stroke
			(width 0.06985)
			(type default)
		)
		(layer "In9.Cu")
	)
	(gr_line
		(start 270.439388 -124.361702)
		(end 270.78051 -123.836684)
		(stroke
			(width 0.06985)
			(type default)
		)
		(layer "In9.Cu")
	)
	(gr_line
		(start 270.65224 -121.829068)
		(end 270.84274 -121.791476)
		(stroke
			(width 0.06985)
			(type default)
		)
		(layer "In9.Cu")
	)
	(gr_line
		(start 270.668496 -124.550424)
		(end 270.858488 -124.510038)
		(stroke
			(width 0.06985)
			(type default)
		)
		(layer "In9.Cu")
	)
	(gr_line
		(start 270.71828 -163.42106)
		(end 271.0688 -162.88131)
		(stroke
			(width 0.06985)
			(type default)
		)
		(layer "In9.Cu")
	)
	(gr_line
		(start 270.761206 -70.293992)
		(end 270.767302 -70.32117)
		(stroke
			(width 0.06985)
			(type default)
		)
		(layer "In9.Cu")
	)
	(gr_line
		(start 270.761206 -70.293992)
		(end 270.767302 -70.266814)
		(stroke
			(width 0.06985)
			(type default)
		)
		(layer "In9.Cu")
	)
	(gr_line
		(start 270.84274 -121.791476)
		(end 271.075912 -121.443242)
		(stroke
			(width 0.06985)
			(type default)
		)
		(layer "In9.Cu")
	)
	(gr_line
		(start 270.858488 -124.510038)
		(end 271.08658 -124.158502)
		(stroke
			(width 0.06985)
			(type default)
		)
		(layer "In9.Cu")
	)
	(gr_line
		(start 270.876268 -69.78523)
		(end 271.013936 -69.176646)
		(stroke
			(width 0.06985)
			(type default)
		)
		(layer "In9.Cu")
	)
	(gr_line
		(start 270.946372 -163.610798)
		(end 271.150334 -163.567618)
		(stroke
			(width 0.06985)
			(type default)
		)
		(layer "In9.Cu")
	)
	(gr_line
		(start 271.03832 -121.252742)
		(end 271.075912 -121.443242)
		(stroke
			(width 0.06985)
			(type default)
		)
		(layer "In9.Cu")
	)
	(gr_line
		(start 271.046448 -123.96851)
		(end 271.08658 -124.158502)
		(stroke
			(width 0.06985)
			(type default)
		)
		(layer "In9.Cu")
	)
	(gr_line
		(start 271.04848 -120.707658)
		(end 271.395952 -120.188736)
		(stroke
			(width 0.06985)
			(type default)
		)
		(layer "In9.Cu")
	)
	(gr_line
		(start 271.048988 -123.423426)
		(end 271.388332 -122.900948)
		(stroke
			(width 0.06985)
			(type default)
		)
		(layer "In9.Cu")
	)
	(gr_line
		(start 271.123156 -68.695316)
		(end 271.260824 -68.086224)
		(stroke
			(width 0.06985)
			(type default)
		)
		(layer "In9.Cu")
	)
	(gr_line
		(start 271.150334 -163.567618)
		(end 271.37868 -163.216082)
		(stroke
			(width 0.06985)
			(type default)
		)
		(layer "In9.Cu")
	)
	(gr_line
		(start 271.155922 -69.88429)
		(end 271.32026 -69.780658)
		(stroke
			(width 0.06985)
			(type default)
		)
		(layer "In9.Cu")
	)
	(gr_line
		(start 271.274032 -120.900444)
		(end 271.464532 -120.862852)
		(stroke
			(width 0.06985)
			(type default)
		)
		(layer "In9.Cu")
	)
	(gr_line
		(start 271.27708 -123.613164)
		(end 271.467072 -123.572778)
		(stroke
			(width 0.06985)
			(type default)
		)
		(layer "In9.Cu")
	)
	(gr_line
		(start 271.309084 -69.207634)
		(end 271.412716 -69.371718)
		(stroke
			(width 0.06985)
			(type default)
		)
		(layer "In9.Cu")
	)
	(gr_line
		(start 271.32026 -69.780658)
		(end 271.412716 -69.371718)
		(stroke
			(width 0.06985)
			(type default)
		)
		(layer "In9.Cu")
	)
	(gr_line
		(start 271.335246 -163.01212)
		(end 271.37868 -163.216082)
		(stroke
			(width 0.06985)
			(type default)
		)
		(layer "In9.Cu")
	)
	(gr_line
		(start 271.338294 -162.466528)
		(end 271.688814 -161.926524)
		(stroke
			(width 0.06985)
			(type default)
		)
		(layer "In9.Cu")
	)
	(gr_line
		(start 271.369536 -67.60591)
		(end 271.507712 -66.995294)
		(stroke
			(width 0.06985)
			(type default)
		)
		(layer "In9.Cu")
	)
	(gr_line
		(start 271.40281 -68.794122)
		(end 271.566894 -68.69049)
		(stroke
			(width 0.06985)
			(type default)
		)
		(layer "In9.Cu")
	)
	(gr_line
		(start 271.464532 -120.862852)
		(end 271.697704 -120.514618)
		(stroke
			(width 0.06985)
			(type default)
		)
		(layer "In9.Cu")
	)
	(gr_line
		(start 271.467072 -123.572778)
		(end 271.695418 -123.221242)
		(stroke
			(width 0.06985)
			(type default)
		)
		(layer "In9.Cu")
	)
	(gr_line
		(start 271.493742 -83.043522)
		(end 271.633188 -83.67268)
		(stroke
			(width 0.06985)
			(type default)
		)
		(layer "In9.Cu")
	)
	(gr_line
		(start 271.555972 -68.117466)
		(end 271.659604 -68.281804)
		(stroke
			(width 0.06985)
			(type default)
		)
		(layer "In9.Cu")
	)
	(gr_line
		(start 271.566132 -162.65652)
		(end 271.770094 -162.613086)
		(stroke
			(width 0.06985)
			(type default)
		)
		(layer "In9.Cu")
	)
	(gr_line
		(start 271.566894 -68.69049)
		(end 271.659604 -68.281804)
		(stroke
			(width 0.06985)
			(type default)
		)
		(layer "In9.Cu")
	)
	(gr_line
		(start 271.58442 -158.693358)
		(end 271.936718 -158.151068)
		(stroke
			(width 0.06985)
			(type default)
		)
		(layer "In9.Cu")
	)
	(gr_line
		(start 271.616424 -66.51498)
		(end 271.754092 -65.90665)
		(stroke
			(width 0.06985)
			(type default)
		)
		(layer "In9.Cu")
	)
	(gr_line
		(start 271.649444 -67.704208)
		(end 271.813782 -67.600576)
		(stroke
			(width 0.06985)
			(type default)
		)
		(layer "In9.Cu")
	)
	(gr_line
		(start 271.655032 -123.031504)
		(end 271.695418 -123.221242)
		(stroke
			(width 0.06985)
			(type default)
		)
		(layer "In9.Cu")
	)
	(gr_line
		(start 271.658842 -122.484642)
		(end 271.677638 -122.455686)
		(stroke
			(width 0.06985)
			(type default)
		)
		(layer "In9.Cu")
	)
	(gr_line
		(start 271.660112 -120.324118)
		(end 271.697704 -120.514618)
		(stroke
			(width 0.06985)
			(type default)
		)
		(layer "In9.Cu")
	)
	(gr_line
		(start 271.677638 -122.455686)
		(end 271.997424 -121.96318)
		(stroke
			(width 0.06985)
			(type default)
		)
		(layer "In9.Cu")
	)
	(gr_line
		(start 271.739868 -84.154264)
		(end 271.879314 -84.78266)
		(stroke
			(width 0.06985)
			(type default)
		)
		(layer "In9.Cu")
	)
	(gr_line
		(start 271.770094 -162.613086)
		(end 271.99844 -162.261804)
		(stroke
			(width 0.06985)
			(type default)
		)
		(layer "In9.Cu")
	)
	(gr_line
		(start 271.773904 -82.945732)
		(end 271.949672 -83.057746)
		(stroke
			(width 0.06985)
			(type default)
		)
		(layer "In9.Cu")
	)
	(gr_line
		(start 271.789652 -181.27091)
		(end 271.796002 -181.240938)
		(stroke
			(width 0.06985)
			(type default)
		)
		(layer "In9.Cu")
	)
	(gr_line
		(start 271.789652 -181.27091)
		(end 271.79778 -181.301136)
		(stroke
			(width 0.06985)
			(type default)
		)
		(layer "In9.Cu")
	)
	(gr_line
		(start 271.802606 -67.027552)
		(end 271.906238 -67.191636)
		(stroke
			(width 0.06985)
			(type default)
		)
		(layer "In9.Cu")
	)
	(gr_line
		(start 271.813274 -158.88208)
		(end 272.01749 -158.8389)
		(stroke
			(width 0.06985)
			(type default)
		)
		(layer "In9.Cu")
	)
	(gr_line
		(start 271.813782 -67.600576)
		(end 271.906238 -67.191636)
		(stroke
			(width 0.06985)
			(type default)
		)
		(layer "In9.Cu")
	)
	(gr_line
		(start 271.886172 -122.67565)
		(end 272.07591 -122.635518)
		(stroke
			(width 0.06985)
			(type default)
		)
		(layer "In9.Cu")
	)
	(gr_line
		(start 271.896078 -66.61404)
		(end 272.060416 -66.510408)
		(stroke
			(width 0.06985)
			(type default)
		)
		(layer "In9.Cu")
	)
	(gr_line
		(start 271.928336 -83.642708)
		(end 272.04035 -83.46694)
		(stroke
			(width 0.06985)
			(type default)
		)
		(layer "In9.Cu")
	)
	(gr_line
		(start 271.949672 -83.057746)
		(end 272.04035 -83.46694)
		(stroke
			(width 0.06985)
			(type default)
		)
		(layer "In9.Cu")
	)
	(gr_line
		(start 271.955006 -162.057842)
		(end 271.99844 -162.261804)
		(stroke
			(width 0.06985)
			(type default)
		)
		(layer "In9.Cu")
	)
	(gr_line
		(start 271.957038 -161.513266)
		(end 272.30832 -160.9725)
		(stroke
			(width 0.06985)
			(type default)
		)
		(layer "In9.Cu")
	)
	(gr_line
		(start 271.986502 -85.266784)
		(end 272.125694 -85.894672)
		(stroke
			(width 0.06985)
			(type default)
		)
		(layer "In9.Cu")
	)
	(gr_line
		(start 272.01749 -158.8389)
		(end 272.245836 -158.487364)
		(stroke
			(width 0.06985)
			(type default)
		)
		(layer "In9.Cu")
	)
	(gr_line
		(start 272.02003 -84.056474)
		(end 272.196052 -84.168742)
		(stroke
			(width 0.06985)
			(type default)
		)
		(layer "In9.Cu")
	)
	(gr_line
		(start 272.04924 -65.937384)
		(end 272.152872 -66.101722)
		(stroke
			(width 0.06985)
			(type default)
		)
		(layer "In9.Cu")
	)
	(gr_line
		(start 272.060416 -66.510408)
		(end 272.152872 -66.101722)
		(stroke
			(width 0.06985)
			(type default)
		)
		(layer "In9.Cu")
	)
	(gr_line
		(start 272.07591 -122.635518)
		(end 272.304002 -122.283982)
		(stroke
			(width 0.06985)
			(type default)
		)
		(layer "In9.Cu")
	)
	(gr_line
		(start 272.174462 -84.75345)
		(end 272.28673 -84.577936)
		(stroke
			(width 0.06985)
			(type default)
		)
		(layer "In9.Cu")
	)
	(gr_line
		(start 272.185892 -161.702242)
		(end 272.389854 -161.658808)
		(stroke
			(width 0.06985)
			(type default)
		)
		(layer "In9.Cu")
	)
	(gr_line
		(start 272.196052 -84.168742)
		(end 272.28673 -84.577936)
		(stroke
			(width 0.06985)
			(type default)
		)
		(layer "In9.Cu")
	)
	(gr_line
		(start 272.202402 -158.283402)
		(end 272.245836 -158.487364)
		(stroke
			(width 0.06985)
			(type default)
		)
		(layer "In9.Cu")
	)
	(gr_line
		(start 272.204688 -157.738572)
		(end 272.556224 -157.197298)
		(stroke
			(width 0.06985)
			(type default)
		)
		(layer "In9.Cu")
	)
	(gr_line
		(start 272.232374 -86.376256)
		(end 272.371566 -87.004398)
		(stroke
			(width 0.06985)
			(type default)
		)
		(layer "In9.Cu")
	)
	(gr_line
		(start 272.26387 -122.09399)
		(end 272.304002 -122.283982)
		(stroke
			(width 0.06985)
			(type default)
		)
		(layer "In9.Cu")
	)
	(gr_line
		(start 272.26641 -85.16747)
		(end 272.442178 -85.279738)
		(stroke
			(width 0.06985)
			(type default)
		)
		(layer "In9.Cu")
	)
	(gr_line
		(start 272.389854 -161.658808)
		(end 272.6182 -161.307272)
		(stroke
			(width 0.06985)
			(type default)
		)
		(layer "In9.Cu")
	)
	(gr_line
		(start 272.420842 -85.8647)
		(end 272.532856 -85.688932)
		(stroke
			(width 0.06985)
			(type default)
		)
		(layer "In9.Cu")
	)
	(gr_line
		(start 272.433034 -157.927802)
		(end 272.63725 -157.884368)
		(stroke
			(width 0.06985)
			(type default)
		)
		(layer "In9.Cu")
	)
	(gr_line
		(start 272.442178 -85.279738)
		(end 272.532856 -85.688932)
		(stroke
			(width 0.06985)
			(type default)
		)
		(layer "In9.Cu")
	)
	(gr_line
		(start 272.478754 -87.488014)
		(end 272.48231 -87.503762)
		(stroke
			(width 0.06985)
			(type default)
		)
		(layer "In9.Cu")
	)
	(gr_line
		(start 272.48231 -87.503762)
		(end 272.4912 -87.517224)
		(stroke
			(width 0.06985)
			(type default)
		)
		(layer "In9.Cu")
	)
	(gr_line
		(start 272.512536 -86.278466)
		(end 272.688304 -86.39048)
		(stroke
			(width 0.06985)
			(type default)
		)
		(layer "In9.Cu")
	)
	(gr_line
		(start 272.574766 -161.10331)
		(end 272.6182 -161.307272)
		(stroke
			(width 0.06985)
			(type default)
		)
		(layer "In9.Cu")
	)
	(gr_line
		(start 272.577814 -160.557464)
		(end 272.928334 -160.017968)
		(stroke
			(width 0.06985)
			(type default)
		)
		(layer "In9.Cu")
	)
	(gr_line
		(start 272.63725 -157.884368)
		(end 272.865596 -157.533086)
		(stroke
			(width 0.06985)
			(type default)
		)
		(layer "In9.Cu")
	)
	(gr_line
		(start 272.666968 -86.975696)
		(end 272.778982 -86.799674)
		(stroke
			(width 0.06985)
			(type default)
		)
		(layer "In9.Cu")
	)
	(gr_line
		(start 272.688304 -86.39048)
		(end 272.778982 -86.799674)
		(stroke
			(width 0.06985)
			(type default)
		)
		(layer "In9.Cu")
	)
	(gr_line
		(start 272.692876 -70.559168)
		(end 272.698972 -70.586346)
		(stroke
			(width 0.06985)
			(type default)
		)
		(layer "In9.Cu")
	)
	(gr_line
		(start 272.692876 -70.559168)
		(end 272.698972 -70.53199)
		(stroke
			(width 0.06985)
			(type default)
		)
		(layer "In9.Cu")
	)
	(gr_line
		(start 272.715736 -45.765974)
		(end 272.719546 -45.749464)
		(stroke
			(width 0.06985)
			(type default)
		)
		(layer "In9.Cu")
	)
	(gr_line
		(start 272.719546 -45.749464)
		(end 272.728944 -45.73524)
		(stroke
			(width 0.06985)
			(type default)
		)
		(layer "In9.Cu")
	)
	(gr_line
		(start 272.805652 -160.74771)
		(end 273.009614 -160.70453)
		(stroke
			(width 0.06985)
			(type default)
		)
		(layer "In9.Cu")
	)
	(gr_line
		(start 272.808192 -70.04939)
		(end 272.945606 -69.44233)
		(stroke
			(width 0.06985)
			(type default)
		)
		(layer "In9.Cu")
	)
	(gr_line
		(start 272.822162 -157.32887)
		(end 272.865596 -157.533086)
		(stroke
			(width 0.06985)
			(type default)
		)
		(layer "In9.Cu")
	)
	(gr_line
		(start 272.823432 -156.785564)
		(end 273.175984 -156.242766)
		(stroke
			(width 0.06985)
			(type default)
		)
		(layer "In9.Cu")
	)
	(gr_line
		(start 272.894806 -163.578032)
		(end 272.931128 -163.522152)
		(stroke
			(width 0.06985)
			(type default)
		)
		(layer "In9.Cu")
	)
	(gr_line
		(start 272.936208 -163.50996)
		(end 272.937224 -163.51123)
		(stroke
			(width 0.06985)
			(type default)
		)
		(layer "In9.Cu")
	)
	(gr_line
		(start 272.936208 -163.50996)
		(end 272.94459 -163.503356)
		(stroke
			(width 0.06985)
			(type default)
		)
		(layer "In9.Cu")
	)
	(gr_line
		(start 273.009614 -160.70453)
		(end 273.23796 -160.352994)
		(stroke
			(width 0.06985)
			(type default)
		)
		(layer "In9.Cu")
	)
	(gr_line
		(start 273.052794 -156.973524)
		(end 273.25701 -156.93009)
		(stroke
			(width 0.06985)
			(type default)
		)
		(layer "In9.Cu")
	)
	(gr_line
		(start 273.054572 -68.959984)
		(end 273.19224 -68.351908)
		(stroke
			(width 0.06985)
			(type default)
		)
		(layer "In9.Cu")
	)
	(gr_line
		(start 273.065494 -167.291258)
		(end 273.071336 -167.282368)
		(stroke
			(width 0.06985)
			(type default)
		)
		(layer "In9.Cu")
	)
	(gr_line
		(start 273.071336 -167.282368)
		(end 273.071844 -167.282876)
		(stroke
			(width 0.06985)
			(type default)
		)
		(layer "In9.Cu")
	)
	(gr_line
		(start 273.071844 -167.282876)
		(end 273.075908 -167.279574)
		(stroke
			(width 0.06985)
			(type default)
		)
		(layer "In9.Cu")
	)
	(gr_line
		(start 273.087592 -70.149466)
		(end 273.25193 -70.045834)
		(stroke
			(width 0.06985)
			(type default)
		)
		(layer "In9.Cu")
	)
	(gr_line
		(start 273.09699 -167.26281)
		(end 273.118834 -167.24503)
		(stroke
			(width 0.06985)
			(type default)
		)
		(layer "In9.Cu")
	)
	(gr_line
		(start 273.123914 -186.327542)
		(end 273.139154 -186.3852)
		(stroke
			(width 0.06985)
			(type default)
		)
		(layer "In9.Cu")
	)
	(gr_line
		(start 273.139154 -186.3852)
		(end 273.139408 -186.3852)
		(stroke
			(width 0.06985)
			(type default)
		)
		(layer "In9.Cu")
	)
	(gr_line
		(start 273.139408 -186.3852)
		(end 273.185636 -186.422538)
		(stroke
			(width 0.06985)
			(type default)
		)
		(layer "In9.Cu")
	)
	(gr_line
		(start 273.156172 -163.708334)
		(end 273.157188 -163.709858)
		(stroke
			(width 0.06985)
			(type default)
		)
		(layer "In9.Cu")
	)
	(gr_line
		(start 273.156172 -163.708334)
		(end 273.160744 -163.704778)
		(stroke
			(width 0.06985)
			(type default)
		)
		(layer "In9.Cu")
	)
	(gr_line
		(start 273.193256 -126.543054)
		(end 273.53006 -126.02464)
		(stroke
			(width 0.06985)
			(type default)
		)
		(layer "In9.Cu")
	)
	(gr_line
		(start 273.194526 -160.149032)
		(end 273.23796 -160.352994)
		(stroke
			(width 0.06985)
			(type default)
		)
		(layer "In9.Cu")
	)
	(gr_line
		(start 273.196304 -159.60471)
		(end 273.548602 -159.06242)
		(stroke
			(width 0.06985)
			(type default)
		)
		(layer "In9.Cu")
	)
	(gr_line
		(start 273.225006 -174.516796)
		(end 273.228562 -174.500286)
		(stroke
			(width 0.06985)
			(type default)
		)
		(layer "In9.Cu")
	)
	(gr_line
		(start 273.228562 -174.500286)
		(end 273.230848 -174.496984)
		(stroke
			(width 0.06985)
			(type default)
		)
		(layer "In9.Cu")
	)
	(gr_line
		(start 273.230848 -174.496984)
		(end 273.237706 -174.486316)
		(stroke
			(width 0.06985)
			(type default)
		)
		(layer "In9.Cu")
	)
	(gr_line
		(start 273.240754 -69.47281)
		(end 273.344386 -69.636894)
		(stroke
			(width 0.06985)
			(type default)
		)
		(layer "In9.Cu")
	)
	(gr_line
		(start 273.25193 -70.045834)
		(end 273.344386 -69.636894)
		(stroke
			(width 0.06985)
			(type default)
		)
		(layer "In9.Cu")
	)
	(gr_line
		(start 273.25701 -156.93009)
		(end 273.485356 -156.578554)
		(stroke
			(width 0.06985)
			(type default)
		)
		(layer "In9.Cu")
	)
	(gr_line
		(start 273.290284 -167.482012)
		(end 273.290792 -167.48125)
		(stroke
			(width 0.06985)
			(type default)
		)
		(layer "In9.Cu")
	)
	(gr_line
		(start 273.290792 -167.48125)
		(end 273.291046 -167.481504)
		(stroke
			(width 0.06985)
			(type default)
		)
		(layer "In9.Cu")
	)
	(gr_line
		(start 273.301206 -67.870832)
		(end 273.439382 -67.260724)
		(stroke
			(width 0.06985)
			(type default)
		)
		(layer "In9.Cu")
	)
	(gr_line
		(start 273.33448 -69.059298)
		(end 273.498564 -68.955666)
		(stroke
			(width 0.06985)
			(type default)
		)
		(layer "In9.Cu")
	)
	(gr_line
		(start 273.420332 -126.734062)
		(end 273.610324 -126.693422)
		(stroke
			(width 0.06985)
			(type default)
		)
		(layer "In9.Cu")
	)
	(gr_line
		(start 273.425412 -159.793432)
		(end 273.629374 -159.750252)
		(stroke
			(width 0.06985)
			(type default)
		)
		(layer "In9.Cu")
	)
	(gr_line
		(start 273.441922 -156.374592)
		(end 273.485356 -156.578554)
		(stroke
			(width 0.06985)
			(type default)
		)
		(layer "In9.Cu")
	)
	(gr_line
		(start 273.444208 -155.829762)
		(end 273.79549 -155.288996)
		(stroke
			(width 0.06985)
			(type default)
		)
		(layer "In9.Cu")
	)
	(gr_line
		(start 273.47418 -166.95928)
		(end 273.975576 -166.556436)
		(stroke
			(width 0.06985)
			(type default)
		)
		(layer "In9.Cu")
	)
	(gr_line
		(start 273.487388 -68.382896)
		(end 273.59102 -68.54698)
		(stroke
			(width 0.06985)
			(type default)
		)
		(layer "In9.Cu")
	)
	(gr_line
		(start 273.498564 -68.955666)
		(end 273.59102 -68.54698)
		(stroke
			(width 0.06985)
			(type default)
		)
		(layer "In9.Cu")
	)
	(gr_line
		(start 273.53514 -82.818732)
		(end 273.674078 -83.446112)
		(stroke
			(width 0.06985)
			(type default)
		)
		(layer "In9.Cu")
	)
	(gr_line
		(start 273.536918 -181.598316)
		(end 273.543268 -181.568598)
		(stroke
			(width 0.06985)
			(type default)
		)
		(layer "In9.Cu")
	)
	(gr_line
		(start 273.536918 -181.598316)
		(end 273.545046 -181.628542)
		(stroke
			(width 0.06985)
			(type default)
		)
		(layer "In9.Cu")
	)
	(gr_line
		(start 273.548094 -66.780156)
		(end 273.685762 -66.171826)
		(stroke
			(width 0.06985)
			(type default)
		)
		(layer "In9.Cu")
	)
	(gr_line
		(start 273.581114 -67.969384)
		(end 273.745198 -67.865752)
		(stroke
			(width 0.06985)
			(type default)
		)
		(layer "In9.Cu")
	)
	(gr_line
		(start 273.610324 -126.693422)
		(end 273.83867 -126.341886)
		(stroke
			(width 0.06985)
			(type default)
		)
		(layer "In9.Cu")
	)
	(gr_line
		(start 273.619722 -162.960304)
		(end 274.124674 -162.554412)
		(stroke
			(width 0.06985)
			(type default)
		)
		(layer "In9.Cu")
	)
	(gr_line
		(start 273.629374 -159.750252)
		(end 273.85772 -159.398716)
		(stroke
			(width 0.06985)
			(type default)
		)
		(layer "In9.Cu")
	)
	(gr_line
		(start 273.630898 -167.211248)
		(end 273.838416 -167.233854)
		(stroke
			(width 0.06985)
			(type default)
		)
		(layer "In9.Cu")
	)
	(gr_line
		(start 273.672808 -156.018992)
		(end 273.87677 -155.975812)
		(stroke
			(width 0.06985)
			(type default)
		)
		(layer "In9.Cu")
	)
	(gr_line
		(start 273.734276 -67.292728)
		(end 273.837908 -67.456812)
		(stroke
			(width 0.06985)
			(type default)
		)
		(layer "In9.Cu")
	)
	(gr_line
		(start 273.745198 -67.865752)
		(end 273.837908 -67.456812)
		(stroke
			(width 0.06985)
			(type default)
		)
		(layer "In9.Cu")
	)
	(gr_line
		(start 273.7612 -92.370656)
		(end 273.77263 -92.387928)
		(stroke
			(width 0.06985)
			(type default)
		)
		(layer "In9.Cu")
	)
	(gr_line
		(start 273.77263 -92.387928)
		(end 273.789902 -92.399358)
		(stroke
			(width 0.06985)
			(type default)
		)
		(layer "In9.Cu")
	)
	(gr_line
		(start 273.777964 -163.211256)
		(end 273.985482 -163.233862)
		(stroke
			(width 0.06985)
			(type default)
		)
		(layer "In9.Cu")
	)
	(gr_line
		(start 273.781012 -83.929474)
		(end 273.920458 -84.559394)
		(stroke
			(width 0.06985)
			(type default)
		)
		(layer "In9.Cu")
	)
	(gr_line
		(start 273.798284 -126.151894)
		(end 273.83867 -126.341886)
		(stroke
			(width 0.06985)
			(type default)
		)
		(layer "In9.Cu")
	)
	(gr_line
		(start 273.802856 -125.604524)
		(end 274.13966 -125.085856)
		(stroke
			(width 0.06985)
			(type default)
		)
		(layer "In9.Cu")
	)
	(gr_line
		(start 273.814286 -159.194754)
		(end 273.85772 -159.398716)
		(stroke
			(width 0.06985)
			(type default)
		)
		(layer "In9.Cu")
	)
	(gr_line
		(start 273.815048 -82.720688)
		(end 273.99107 -82.832702)
		(stroke
			(width 0.06985)
			(type default)
		)
		(layer "In9.Cu")
	)
	(gr_line
		(start 273.816826 -158.64967)
		(end 273.82216 -158.641542)
		(stroke
			(width 0.06985)
			(type default)
		)
		(layer "In9.Cu")
	)
	(gr_line
		(start 273.82216 -158.641542)
		(end 273.829526 -158.6357)
		(stroke
			(width 0.06985)
			(type default)
		)
		(layer "In9.Cu")
	)
	(gr_line
		(start 273.827748 -66.879216)
		(end 273.992086 -66.775584)
		(stroke
			(width 0.06985)
			(type default)
		)
		(layer "In9.Cu")
	)
	(gr_line
		(start 273.838416 -167.233854)
		(end 274.164806 -166.971218)
		(stroke
			(width 0.06985)
			(type default)
		)
		(layer "In9.Cu")
	)
	(gr_line
		(start 273.87677 -155.975812)
		(end 274.105116 -155.624276)
		(stroke
			(width 0.06985)
			(type default)
		)
		(layer "In9.Cu")
	)
	(gr_line
		(start 273.952716 -133.189472)
		(end 274.292568 -132.666232)
		(stroke
			(width 0.06985)
			(type default)
		)
		(layer "In9.Cu")
	)
	(gr_line
		(start 273.960844 -129.036826)
		(end 274.300696 -128.513586)
		(stroke
			(width 0.06985)
			(type default)
		)
		(layer "In9.Cu")
	)
	(gr_line
		(start 273.96948 -83.417918)
		(end 274.081494 -83.241896)
		(stroke
			(width 0.06985)
			(type default)
		)
		(layer "In9.Cu")
	)
	(gr_line
		(start 273.98091 -66.20256)
		(end 274.084542 -66.366898)
		(stroke
			(width 0.06985)
			(type default)
		)
		(layer "In9.Cu")
	)
	(gr_line
		(start 273.985482 -163.233862)
		(end 274.311872 -162.971226)
		(stroke
			(width 0.06985)
			(type default)
		)
		(layer "In9.Cu")
	)
	(gr_line
		(start 273.99107 -82.832702)
		(end 274.081494 -83.241896)
		(stroke
			(width 0.06985)
			(type default)
		)
		(layer "In9.Cu")
	)
	(gr_line
		(start 273.992086 -66.775584)
		(end 274.084542 -66.366898)
		(stroke
			(width 0.06985)
			(type default)
		)
		(layer "In9.Cu")
	)
	(gr_line
		(start 274.02663 -85.038946)
		(end 274.16633 -85.669374)
		(stroke
			(width 0.06985)
			(type default)
		)
		(layer "In9.Cu")
	)
	(gr_line
		(start 274.02917 -125.796294)
		(end 274.219162 -125.756162)
		(stroke
			(width 0.06985)
			(type default)
		)
		(layer "In9.Cu")
	)
	(gr_line
		(start 274.06092 -83.831684)
		(end 274.236942 -83.943698)
		(stroke
			(width 0.06985)
			(type default)
		)
		(layer "In9.Cu")
	)
	(gr_line
		(start 274.061682 -155.420314)
		(end 274.105116 -155.624276)
		(stroke
			(width 0.06985)
			(type default)
		)
		(layer "In9.Cu")
	)
	(gr_line
		(start 274.065238 -154.874214)
		(end 274.414996 -154.335226)
		(stroke
			(width 0.06985)
			(type default)
		)
		(layer "In9.Cu")
	)
	(gr_line
		(start 274.164806 -166.971218)
		(end 274.187666 -166.763954)
		(stroke
			(width 0.06985)
			(type default)
		)
		(layer "In9.Cu")
	)
	(gr_line
		(start 274.180808 -133.37921)
		(end 274.3708 -133.338824)
		(stroke
			(width 0.06985)
			(type default)
		)
		(layer "In9.Cu")
	)
	(gr_line
		(start 274.184364 -47.76597)
		(end 274.188174 -47.74946)
		(stroke
			(width 0.06985)
			(type default)
		)
		(layer "In9.Cu")
	)
	(gr_line
		(start 274.188174 -47.74946)
		(end 274.197572 -47.735236)
		(stroke
			(width 0.06985)
			(type default)
		)
		(layer "In9.Cu")
	)
	(gr_line
		(start 274.18919 -129.22631)
		(end 274.379182 -129.185924)
		(stroke
			(width 0.06985)
			(type default)
		)
		(layer "In9.Cu")
	)
	(gr_line
		(start 274.215606 -84.529168)
		(end 274.32762 -84.352892)
		(stroke
			(width 0.06985)
			(type default)
		)
		(layer "In9.Cu")
	)
	(gr_line
		(start 274.219162 -125.756162)
		(end 274.447254 -125.404626)
		(stroke
			(width 0.06985)
			(type default)
		)
		(layer "In9.Cu")
	)
	(gr_line
		(start 274.236942 -83.943698)
		(end 274.32762 -84.352892)
		(stroke
			(width 0.06985)
			(type default)
		)
		(layer "In9.Cu")
	)
	(gr_line
		(start 274.272756 -86.150704)
		(end 274.412456 -86.78164)
		(stroke
			(width 0.06985)
			(type default)
		)
		(layer "In9.Cu")
	)
	(gr_line
		(start 274.292568 -155.064714)
		(end 274.49653 -155.021534)
		(stroke
			(width 0.06985)
			(type default)
		)
		(layer "In9.Cu")
	)
	(gr_line
		(start 274.307046 -84.942426)
		(end 274.483068 -85.054694)
		(stroke
			(width 0.06985)
			(type default)
		)
		(layer "In9.Cu")
	)
	(gr_line
		(start 274.311872 -162.971226)
		(end 274.334732 -162.763708)
		(stroke
			(width 0.06985)
			(type default)
		)
		(layer "In9.Cu")
	)
	(gr_line
		(start 274.361402 -166.246048)
		(end 274.862036 -165.843712)
		(stroke
			(width 0.06985)
			(type default)
		)
		(layer "In9.Cu")
	)
	(gr_line
		(start 274.3708 -133.338824)
		(end 274.599146 -132.987288)
		(stroke
			(width 0.06985)
			(type default)
		)
		(layer "In9.Cu")
	)
	(gr_line
		(start 274.379182 -129.185924)
		(end 274.607528 -128.834388)
		(stroke
			(width 0.06985)
			(type default)
		)
		(layer "In9.Cu")
	)
	(gr_line
		(start 274.407122 -125.21438)
		(end 274.447254 -125.404626)
		(stroke
			(width 0.06985)
			(type default)
		)
		(layer "In9.Cu")
	)
	(gr_line
		(start 274.411948 -124.666756)
		(end 274.748498 -124.148342)
		(stroke
			(width 0.06985)
			(type default)
		)
		(layer "In9.Cu")
	)
	(gr_line
		(start 274.461478 -85.63991)
		(end 274.573746 -85.463888)
		(stroke
			(width 0.06985)
			(type default)
		)
		(layer "In9.Cu")
	)
	(gr_line
		(start 274.483068 -85.054694)
		(end 274.573746 -85.463888)
		(stroke
			(width 0.06985)
			(type default)
		)
		(layer "In9.Cu")
	)
	(gr_line
		(start 274.49653 -155.021534)
		(end 274.724876 -154.669998)
		(stroke
			(width 0.06985)
			(type default)
		)
		(layer "In9.Cu")
	)
	(gr_line
		(start 274.506182 -162.24758)
		(end 275.010626 -161.841942)
		(stroke
			(width 0.06985)
			(type default)
		)
		(layer "In9.Cu")
	)
	(gr_line
		(start 274.517866 -166.49827)
		(end 274.72513 -166.520876)
		(stroke
			(width 0.06985)
			(type default)
		)
		(layer "In9.Cu")
	)
	(gr_line
		(start 274.519136 -87.262208)
		(end 274.522692 -87.278972)
		(stroke
			(width 0.06985)
			(type default)
		)
		(layer "In9.Cu")
	)
	(gr_line
		(start 274.522692 -87.278972)
		(end 274.532598 -87.294212)
		(stroke
			(width 0.06985)
			(type default)
		)
		(layer "In9.Cu")
	)
	(gr_line
		(start 274.553172 -86.053676)
		(end 274.729194 -86.16569)
		(stroke
			(width 0.06985)
			(type default)
		)
		(layer "In9.Cu")
	)
	(gr_line
		(start 274.55876 -132.79755)
		(end 274.599146 -132.987288)
		(stroke
			(width 0.06985)
			(type default)
		)
		(layer "In9.Cu")
	)
	(gr_line
		(start 274.560792 -132.252974)
		(end 274.901406 -131.728718)
		(stroke
			(width 0.06985)
			(type default)
		)
		(layer "In9.Cu")
	)
	(gr_line
		(start 274.567142 -128.644396)
		(end 274.607528 -128.834388)
		(stroke
			(width 0.06985)
			(type default)
		)
		(layer "In9.Cu")
	)
	(gr_line
		(start 274.56892 -128.100328)
		(end 274.910042 -127.57531)
		(stroke
			(width 0.06985)
			(type default)
		)
		(layer "In9.Cu")
	)
	(gr_line
		(start 274.620482 -185.708544)
		(end 274.635468 -185.764932)
		(stroke
			(width 0.06985)
			(type default)
		)
		(layer "In9.Cu")
	)
	(gr_line
		(start 274.635468 -185.764932)
		(end 274.68068 -185.801508)
		(stroke
			(width 0.06985)
			(type default)
		)
		(layer "In9.Cu")
	)
	(gr_line
		(start 274.637754 -124.859034)
		(end 274.827746 -124.818902)
		(stroke
			(width 0.06985)
			(type default)
		)
		(layer "In9.Cu")
	)
	(gr_line
		(start 274.664678 -162.498278)
		(end 274.872196 -162.520884)
		(stroke
			(width 0.06985)
			(type default)
		)
		(layer "In9.Cu")
	)
	(gr_line
		(start 274.681442 -154.466036)
		(end 274.724876 -154.669998)
		(stroke
			(width 0.06985)
			(type default)
		)
		(layer "In9.Cu")
	)
	(gr_line
		(start 274.683982 -153.920952)
		(end 274.689316 -153.912824)
		(stroke
			(width 0.06985)
			(type default)
		)
		(layer "In9.Cu")
	)
	(gr_line
		(start 274.689316 -153.912824)
		(end 274.696682 -153.906982)
		(stroke
			(width 0.06985)
			(type default)
		)
		(layer "In9.Cu")
	)
	(gr_line
		(start 274.707604 -86.750906)
		(end 274.819872 -86.574884)
		(stroke
			(width 0.06985)
			(type default)
		)
		(layer "In9.Cu")
	)
	(gr_line
		(start 274.72513 -166.520876)
		(end 275.051774 -166.25824)
		(stroke
			(width 0.06985)
			(type default)
		)
		(layer "In9.Cu")
	)
	(gr_line
		(start 274.729194 -86.16569)
		(end 274.819872 -86.574884)
		(stroke
			(width 0.06985)
			(type default)
		)
		(layer "In9.Cu")
	)
	(gr_line
		(start 274.733766 -90.90533)
		(end 274.745196 -90.922602)
		(stroke
			(width 0.06985)
			(type default)
		)
		(layer "In9.Cu")
	)
	(gr_line
		(start 274.745196 -90.922602)
		(end 274.762468 -90.934032)
		(stroke
			(width 0.06985)
			(type default)
		)
		(layer "In9.Cu")
	)
	(gr_line
		(start 274.789646 -132.44195)
		(end 274.979638 -132.401564)
		(stroke
			(width 0.06985)
			(type default)
		)
		(layer "In9.Cu")
	)
	(gr_line
		(start 274.797774 -128.28905)
		(end 274.98802 -128.248664)
		(stroke
			(width 0.06985)
			(type default)
		)
		(layer "In9.Cu")
	)
	(gr_line
		(start 274.805902 -117.639084)
		(end 275.144738 -117.117114)
		(stroke
			(width 0.06985)
			(type default)
		)
		(layer "In9.Cu")
	)
	(gr_line
		(start 274.824952 -175.539654)
		(end 274.828254 -175.524414)
		(stroke
			(width 0.06985)
			(type default)
		)
		(layer "In9.Cu")
	)
	(gr_line
		(start 274.827746 -124.818902)
		(end 275.056092 -124.467366)
		(stroke
			(width 0.06985)
			(type default)
		)
		(layer "In9.Cu")
	)
	(gr_line
		(start 274.828254 -175.524414)
		(end 274.836636 -175.51146)
		(stroke
			(width 0.06985)
			(type default)
		)
		(layer "In9.Cu")
	)
	(gr_line
		(start 274.872196 -162.520884)
		(end 275.19884 -162.258248)
		(stroke
			(width 0.06985)
			(type default)
		)
		(layer "In9.Cu")
	)
	(gr_line
		(start 274.979638 -132.401564)
		(end 275.207984 -132.050028)
		(stroke
			(width 0.06985)
			(type default)
		)
		(layer "In9.Cu")
	)
	(gr_line
		(start 274.98802 -128.248664)
		(end 275.216112 -127.897128)
		(stroke
			(width 0.06985)
			(type default)
		)
		(layer "In9.Cu")
	)
	(gr_line
		(start 275.015706 -124.277374)
		(end 275.056092 -124.467366)
		(stroke
			(width 0.06985)
			(type default)
		)
		(layer "In9.Cu")
	)
	(gr_line
		(start 275.019516 -123.730766)
		(end 275.358098 -123.209558)
		(stroke
			(width 0.06985)
			(type default)
		)
		(layer "In9.Cu")
	)
	(gr_line
		(start 275.033232 -117.829584)
		(end 275.223224 -117.789198)
		(stroke
			(width 0.06985)
			(type default)
		)
		(layer "In9.Cu")
	)
	(gr_line
		(start 275.051774 -166.25824)
		(end 275.07438 -166.050976)
		(stroke
			(width 0.06985)
			(type default)
		)
		(layer "In9.Cu")
	)
	(gr_line
		(start 275.167598 -131.860036)
		(end 275.207984 -132.050028)
		(stroke
			(width 0.06985)
			(type default)
		)
		(layer "In9.Cu")
	)
	(gr_line
		(start 275.171154 -131.31419)
		(end 275.509228 -130.793236)
		(stroke
			(width 0.06985)
			(type default)
		)
		(layer "In9.Cu")
	)
	(gr_line
		(start 275.171662 -81.74736)
		(end 275.3106 -82.374486)
		(stroke
			(width 0.06985)
			(type default)
		)
		(layer "In9.Cu")
	)
	(gr_line
		(start 275.17598 -127.706882)
		(end 275.216112 -127.897128)
		(stroke
			(width 0.06985)
			(type default)
		)
		(layer "In9.Cu")
	)
	(gr_line
		(start 275.17852 -127.162052)
		(end 275.517864 -126.639574)
		(stroke
			(width 0.06985)
			(type default)
		)
		(layer "In9.Cu")
	)
	(gr_line
		(start 275.19884 -162.258248)
		(end 275.221446 -162.05073)
		(stroke
			(width 0.06985)
			(type default)
		)
		(layer "In9.Cu")
	)
	(gr_line
		(start 275.223224 -117.789198)
		(end 275.45157 -117.437916)
		(stroke
			(width 0.06985)
			(type default)
		)
		(layer "In9.Cu")
	)
	(gr_line
		(start 275.246338 -123.921774)
		(end 275.436584 -123.881388)
		(stroke
			(width 0.06985)
			(type default)
		)
		(layer "In9.Cu")
	)
	(gr_line
		(start 275.247608 -165.533578)
		(end 275.747734 -165.131496)
		(stroke
			(width 0.06985)
			(type default)
		)
		(layer "In9.Cu")
	)
	(gr_line
		(start 275.30552 -181.583838)
		(end 275.31187 -181.55412)
		(stroke
			(width 0.06985)
			(type default)
		)
		(layer "In9.Cu")
	)
	(gr_line
		(start 275.30552 -181.583838)
		(end 275.313648 -181.614064)
		(stroke
			(width 0.06985)
			(type default)
		)
		(layer "In9.Cu")
	)
	(gr_line
		(start 275.372068 -49.921414)
		(end 275.375624 -49.90592)
		(stroke
			(width 0.06985)
			(type default)
		)
		(layer "In9.Cu")
	)
	(gr_line
		(start 275.375624 -49.90592)
		(end 275.384514 -49.892458)
		(stroke
			(width 0.06985)
			(type default)
		)
		(layer "In9.Cu")
	)
	(gr_line
		(start 275.393658 -161.534094)
		(end 275.895308 -161.130996)
		(stroke
			(width 0.06985)
			(type default)
		)
		(layer "In9.Cu")
	)
	(gr_line
		(start 275.39823 -131.50469)
		(end 275.588222 -131.464304)
		(stroke
			(width 0.06985)
			(type default)
		)
		(layer "In9.Cu")
	)
	(gr_line
		(start 275.40458 -165.785292)
		(end 275.611844 -165.807898)
		(stroke
			(width 0.06985)
			(type default)
		)
		(layer "In9.Cu")
	)
	(gr_line
		(start 275.406358 -127.35179)
		(end 275.596604 -127.311404)
		(stroke
			(width 0.06985)
			(type default)
		)
		(layer "In9.Cu")
	)
	(gr_line
		(start 275.411184 -117.247924)
		(end 275.45157 -117.437916)
		(stroke
			(width 0.06985)
			(type default)
		)
		(layer "In9.Cu")
	)
	(gr_line
		(start 275.414232 -116.702332)
		(end 275.753068 -116.180362)
		(stroke
			(width 0.06985)
			(type default)
		)
		(layer "In9.Cu")
	)
	(gr_line
		(start 275.417534 -82.857848)
		(end 275.55698 -83.486752)
		(stroke
			(width 0.06985)
			(type default)
		)
		(layer "In9.Cu")
	)
	(gr_line
		(start 275.436584 -123.881388)
		(end 275.664676 -123.530106)
		(stroke
			(width 0.06985)
			(type default)
		)
		(layer "In9.Cu")
	)
	(gr_line
		(start 275.45157 -81.649062)
		(end 275.627338 -81.76133)
		(stroke
			(width 0.06985)
			(type default)
		)
		(layer "In9.Cu")
	)
	(gr_line
		(start 275.551646 -161.7853)
		(end 275.75891 -161.807906)
		(stroke
			(width 0.06985)
			(type default)
		)
		(layer "In9.Cu")
	)
	(gr_line
		(start 275.588222 -131.464304)
		(end 275.816568 -131.112768)
		(stroke
			(width 0.06985)
			(type default)
		)
		(layer "In9.Cu")
	)
	(gr_line
		(start 275.596604 -127.311404)
		(end 275.82495 -126.959868)
		(stroke
			(width 0.06985)
			(type default)
		)
		(layer "In9.Cu")
	)
	(gr_line
		(start 275.606002 -82.346292)
		(end 275.718016 -82.170524)
		(stroke
			(width 0.06985)
			(type default)
		)
		(layer "In9.Cu")
	)
	(gr_line
		(start 275.611844 -165.807898)
		(end 275.938488 -165.545262)
		(stroke
			(width 0.06985)
			(type default)
		)
		(layer "In9.Cu")
	)
	(gr_line
		(start 275.624544 -123.33986)
		(end 275.664676 -123.530106)
		(stroke
			(width 0.06985)
			(type default)
		)
		(layer "In9.Cu")
	)
	(gr_line
		(start 275.627338 -81.76133)
		(end 275.718016 -82.170524)
		(stroke
			(width 0.06985)
			(type default)
		)
		(layer "In9.Cu")
	)
	(gr_line
		(start 275.627846 -122.79376)
		(end 275.966936 -122.27179)
		(stroke
			(width 0.06985)
			(type default)
		)
		(layer "In9.Cu")
	)
	(gr_line
		(start 275.641816 -116.892324)
		(end 275.831808 -116.851938)
		(stroke
			(width 0.06985)
			(type default)
		)
		(layer "In9.Cu")
	)
	(gr_line
		(start 275.663914 -83.969098)
		(end 275.802852 -84.596732)
		(stroke
			(width 0.06985)
			(type default)
		)
		(layer "In9.Cu")
	)
	(gr_line
		(start 275.697696 -82.760058)
		(end 275.873718 -82.872326)
		(stroke
			(width 0.06985)
			(type default)
		)
		(layer "In9.Cu")
	)
	(gr_line
		(start 275.75891 -161.807906)
		(end 276.085554 -161.54527)
		(stroke
			(width 0.06985)
			(type default)
		)
		(layer "In9.Cu")
	)
	(gr_line
		(start 275.773134 -165.110922)
		(end 276.109684 -164.840412)
		(stroke
			(width 0.06985)
			(type default)
		)
		(layer "In9.Cu")
	)
	(gr_line
		(start 275.776182 -130.92303)
		(end 275.816568 -131.112768)
		(stroke
			(width 0.06985)
			(type default)
		)
		(layer "In9.Cu")
	)
	(gr_line
		(start 275.779992 -130.376422)
		(end 276.118574 -129.855214)
		(stroke
			(width 0.06985)
			(type default)
		)
		(layer "In9.Cu")
	)
	(gr_line
		(start 275.784564 -126.769876)
		(end 275.82495 -126.959868)
		(stroke
			(width 0.06985)
			(type default)
		)
		(layer "In9.Cu")
	)
	(gr_line
		(start 275.788374 -126.223268)
		(end 276.12721 -125.701552)
		(stroke
			(width 0.06985)
			(type default)
		)
		(layer "In9.Cu")
	)
	(gr_line
		(start 275.831808 -116.851938)
		(end 276.060154 -116.500656)
		(stroke
			(width 0.06985)
			(type default)
		)
		(layer "In9.Cu")
	)
	(gr_line
		(start 275.852128 -83.457288)
		(end 275.964142 -83.28152)
		(stroke
			(width 0.06985)
			(type default)
		)
		(layer "In9.Cu")
	)
	(gr_line
		(start 275.855176 -122.984514)
		(end 276.045168 -122.944128)
		(stroke
			(width 0.06985)
			(type default)
		)
		(layer "In9.Cu")
	)
	(gr_line
		(start 275.873718 -82.872326)
		(end 275.964142 -83.28152)
		(stroke
			(width 0.06985)
			(type default)
		)
		(layer "In9.Cu")
	)
	(gr_line
		(start 275.910294 -85.08111)
		(end 276.048978 -85.707728)
		(stroke
			(width 0.06985)
			(type default)
		)
		(layer "In9.Cu")
	)
	(gr_line
		(start 275.938488 -165.545262)
		(end 275.96084 -165.337998)
		(stroke
			(width 0.06985)
			(type default)
		)
		(layer "In9.Cu")
	)
	(gr_line
		(start 275.943822 -83.871054)
		(end 276.119844 -83.983322)
		(stroke
			(width 0.06985)
			(type default)
		)
		(layer "In9.Cu")
	)
	(gr_line
		(start 275.961348 -165.334442)
		(end 276.287992 -165.071806)
		(stroke
			(width 0.06985)
			(type default)
		)
		(layer "In9.Cu")
	)
	(gr_line
		(start 276.007068 -130.56743)
		(end 276.19706 -130.527044)
		(stroke
			(width 0.06985)
			(type default)
		)
		(layer "In9.Cu")
	)
	(gr_line
		(start 276.01545 -126.414276)
		(end 276.205442 -126.374144)
		(stroke
			(width 0.06985)
			(type default)
		)
		(layer "In9.Cu")
	)
	(gr_line
		(start 276.019768 -116.310664)
		(end 276.060154 -116.500656)
		(stroke
			(width 0.06985)
			(type default)
		)
		(layer "In9.Cu")
	)
	(gr_line
		(start 276.022562 -115.765326)
		(end 276.362414 -115.242086)
		(stroke
			(width 0.06985)
			(type default)
		)
		(layer "In9.Cu")
	)
	(gr_line
		(start 276.045168 -122.944128)
		(end 276.273514 -122.592592)
		(stroke
			(width 0.06985)
			(type default)
		)
		(layer "In9.Cu")
	)
	(gr_line
		(start 276.058122 -89.603072)
		(end 276.070568 -89.621868)
		(stroke
			(width 0.06985)
			(type default)
		)
		(layer "In9.Cu")
	)
	(gr_line
		(start 276.070568 -89.621868)
		(end 276.089364 -89.634314)
		(stroke
			(width 0.06985)
			(type default)
		)
		(layer "In9.Cu")
	)
	(gr_line
		(start 276.074632 -177.965862)
		(end 276.077934 -177.950622)
		(stroke
			(width 0.06985)
			(type default)
		)
		(layer "In9.Cu")
	)
	(gr_line
		(start 276.077934 -177.950622)
		(end 276.086316 -177.937668)
		(stroke
			(width 0.06985)
			(type default)
		)
		(layer "In9.Cu")
	)
	(gr_line
		(start 276.085554 -161.54527)
		(end 276.107906 -161.338006)
		(stroke
			(width 0.06985)
			(type default)
		)
		(layer "In9.Cu")
	)
	(gr_line
		(start 276.098254 -84.56803)
		(end 276.210268 -84.392262)
		(stroke
			(width 0.06985)
			(type default)
		)
		(layer "In9.Cu")
	)
	(gr_line
		(start 276.119844 -83.983322)
		(end 276.210268 -84.392262)
		(stroke
			(width 0.06985)
			(type default)
		)
		(layer "In9.Cu")
	)
	(gr_line
		(start 276.135592 -164.819584)
		(end 276.635464 -164.417756)
		(stroke
			(width 0.06985)
			(type default)
		)
		(layer "In9.Cu")
	)
	(gr_line
		(start 276.156166 -86.191598)
		(end 276.159722 -86.207346)
		(stroke
			(width 0.06985)
			(type default)
		)
		(layer "In9.Cu")
	)
	(gr_line
		(start 276.159722 -86.207346)
		(end 276.168612 -86.220808)
		(stroke
			(width 0.06985)
			(type default)
		)
		(layer "In9.Cu")
	)
	(gr_line
		(start 276.189948 -84.98205)
		(end 276.36597 -85.094064)
		(stroke
			(width 0.06985)
			(type default)
		)
		(layer "In9.Cu")
	)
	(gr_line
		(start 276.19706 -130.527044)
		(end 276.425406 -130.175508)
		(stroke
			(width 0.06985)
			(type default)
		)
		(layer "In9.Cu")
	)
	(gr_line
		(start 276.205442 -126.374144)
		(end 276.433534 -126.022608)
		(stroke
			(width 0.06985)
			(type default)
		)
		(layer "In9.Cu")
	)
	(gr_line
		(start 276.23008 -185.086498)
		(end 276.244812 -185.14314)
		(stroke
			(width 0.06985)
			(type default)
		)
		(layer "In9.Cu")
	)
	(gr_line
		(start 276.233128 -122.4026)
		(end 276.273514 -122.592592)
		(stroke
			(width 0.06985)
			(type default)
		)
		(layer "In9.Cu")
	)
	(gr_line
		(start 276.244812 -185.14314)
		(end 276.29104 -185.180224)
		(stroke
			(width 0.06985)
			(type default)
		)
		(layer "In9.Cu")
	)
	(gr_line
		(start 276.250654 -115.955064)
		(end 276.440646 -115.914678)
		(stroke
			(width 0.06985)
			(type default)
		)
		(layer "In9.Cu")
	)
	(gr_line
		(start 276.250908 -160.844992)
		(end 276.253194 -160.843214)
		(stroke
			(width 0.06985)
			(type default)
		)
		(layer "In9.Cu")
	)
	(gr_line
		(start 276.282658 -160.819592)
		(end 276.78253 -160.417764)
		(stroke
			(width 0.06985)
			(type default)
		)
		(layer "In9.Cu")
	)
	(gr_line
		(start 276.291548 -165.072314)
		(end 276.498812 -165.09492)
		(stroke
			(width 0.06985)
			(type default)
		)
		(layer "In9.Cu")
	)
	(gr_line
		(start 276.34438 -85.679026)
		(end 276.456648 -85.503258)
		(stroke
			(width 0.06985)
			(type default)
		)
		(layer "In9.Cu")
	)
	(gr_line
		(start 276.36597 -85.094064)
		(end 276.456648 -85.503258)
		(stroke
			(width 0.06985)
			(type default)
		)
		(layer "In9.Cu")
	)
	(gr_line
		(start 276.382226 -161.114232)
		(end 276.435058 -161.071814)
		(stroke
			(width 0.06985)
			(type default)
		)
		(layer "In9.Cu")
	)
	(gr_line
		(start 276.38502 -129.985516)
		(end 276.425406 -130.175508)
		(stroke
			(width 0.06985)
			(type default)
		)
		(layer "In9.Cu")
	)
	(gr_line
		(start 276.388068 -129.439924)
		(end 276.72792 -128.916938)
		(stroke
			(width 0.06985)
			(type default)
		)
		(layer "In9.Cu")
	)
	(gr_line
		(start 276.393402 -125.832362)
		(end 276.433534 -126.022608)
		(stroke
			(width 0.06985)
			(type default)
		)
		(layer "In9.Cu")
	)
	(gr_line
		(start 276.396958 -125.286008)
		(end 276.73554 -124.7648)
		(stroke
			(width 0.06985)
			(type default)
		)
		(layer "In9.Cu")
	)
	(gr_line
		(start 276.438614 -161.072322)
		(end 276.645878 -161.094928)
		(stroke
			(width 0.06985)
			(type default)
		)
		(layer "In9.Cu")
	)
	(gr_line
		(start 276.440646 -115.914678)
		(end 276.668992 -115.563396)
		(stroke
			(width 0.06985)
			(type default)
		)
		(layer "In9.Cu")
	)
	(gr_line
		(start 276.498812 -165.09492)
		(end 276.825456 -164.832284)
		(stroke
			(width 0.06985)
			(type default)
		)
		(layer "In9.Cu")
	)
	(gr_line
		(start 276.578314 -39.920672)
		(end 276.591268 -39.901114)
		(stroke
			(width 0.06985)
			(type default)
		)
		(layer "In9.Cu")
	)
	(gr_line
		(start 276.591268 -39.901114)
		(end 276.611588 -39.88816)
		(stroke
			(width 0.06985)
			(type default)
		)
		(layer "In9.Cu")
	)
	(gr_line
		(start 276.615652 -129.63017)
		(end 276.805898 -129.589784)
		(stroke
			(width 0.06985)
			(type default)
		)
		(layer "In9.Cu")
	)
	(gr_line
		(start 276.624034 -125.477016)
		(end 276.814026 -125.436884)
		(stroke
			(width 0.06985)
			(type default)
		)
		(layer "In9.Cu")
	)
	(gr_line
		(start 276.628606 -115.37315)
		(end 276.668992 -115.563396)
		(stroke
			(width 0.06985)
			(type default)
		)
		(layer "In9.Cu")
	)
	(gr_line
		(start 276.630638 -114.828828)
		(end 276.970744 -114.305334)
		(stroke
			(width 0.06985)
			(type default)
		)
		(layer "In9.Cu")
	)
	(gr_line
		(start 276.645878 -161.094928)
		(end 276.972522 -160.832292)
		(stroke
			(width 0.06985)
			(type default)
		)
		(layer "In9.Cu")
	)
	(gr_line
		(start 276.709632 -47.889922)
		(end 276.721062 -47.87265)
		(stroke
			(width 0.06985)
			(type default)
		)
		(layer "In9.Cu")
	)
	(gr_line
		(start 276.721062 -47.87265)
		(end 276.738334 -47.86122)
		(stroke
			(width 0.06985)
			(type default)
		)
		(layer "In9.Cu")
	)
	(gr_line
		(start 276.781514 -43.832272)
		(end 276.794468 -43.812714)
		(stroke
			(width 0.06985)
			(type default)
		)
		(layer "In9.Cu")
	)
	(gr_line
		(start 276.794468 -43.812714)
		(end 276.814788 -43.79976)
		(stroke
			(width 0.06985)
			(type default)
		)
		(layer "In9.Cu")
	)
	(gr_line
		(start 276.805898 -129.589784)
		(end 277.03399 -129.238248)
		(stroke
			(width 0.06985)
			(type default)
		)
		(layer "In9.Cu")
	)
	(gr_line
		(start 276.814026 -125.436884)
		(end 277.042372 -125.085348)
		(stroke
			(width 0.06985)
			(type default)
		)
		(layer "In9.Cu")
	)
	(gr_line
		(start 276.825456 -164.832284)
		(end 276.848062 -164.62502)
		(stroke
			(width 0.06985)
			(type default)
		)
		(layer "In9.Cu")
	)
	(gr_line
		(start 276.829012 -52.282344)
		(end 276.832822 -52.265834)
		(stroke
			(width 0.06985)
			(type default)
		)
		(layer "In9.Cu")
	)
	(gr_line
		(start 276.832822 -52.265834)
		(end 276.84222 -52.25161)
		(stroke
			(width 0.06985)
			(type default)
		)
		(layer "In9.Cu")
	)
	(gr_line
		(start 276.859238 -115.017804)
		(end 277.04923 -114.977418)
		(stroke
			(width 0.06985)
			(type default)
		)
		(layer "In9.Cu")
	)
	(gr_line
		(start 276.909784 -172.316394)
		(end 276.9235 -172.295312)
		(stroke
			(width 0.06985)
			(type default)
		)
		(layer "In9.Cu")
	)
	(gr_line
		(start 276.9235 -172.295312)
		(end 276.944074 -172.282104)
		(stroke
			(width 0.06985)
			(type default)
		)
		(layer "In9.Cu")
	)
	(gr_line
		(start 276.972522 -160.832292)
		(end 276.995128 -160.624774)
		(stroke
			(width 0.06985)
			(type default)
		)
		(layer "In9.Cu")
	)
	(gr_line
		(start 276.993858 -129.048256)
		(end 277.03399 -129.238248)
		(stroke
			(width 0.06985)
			(type default)
		)
		(layer "In9.Cu")
	)
	(gr_line
		(start 277.001986 -124.895356)
		(end 277.042372 -125.085348)
		(stroke
			(width 0.06985)
			(type default)
		)
		(layer "In9.Cu")
	)
	(gr_line
		(start 277.021798 -164.107114)
		(end 277.521924 -163.705032)
		(stroke
			(width 0.06985)
			(type default)
		)
		(layer "In9.Cu")
	)
	(gr_line
		(start 277.04923 -114.977418)
		(end 277.277576 -114.625882)
		(stroke
			(width 0.06985)
			(type default)
		)
		(layer "In9.Cu")
	)
	(gr_line
		(start 277.168864 -160.107122)
		(end 277.66899 -159.70504)
		(stroke
			(width 0.06985)
			(type default)
		)
		(layer "In9.Cu")
	)
	(gr_line
		(start 277.178516 -164.359082)
		(end 277.385526 -164.381688)
		(stroke
			(width 0.06985)
			(type default)
		)
		(layer "In9.Cu")
	)
	(gr_line
		(start 277.189946 -124.06503)
		(end 277.203154 -124.044456)
		(stroke
			(width 0.06985)
			(type default)
		)
		(layer "In9.Cu")
	)
	(gr_line
		(start 277.203154 -124.044456)
		(end 277.224236 -124.03074)
		(stroke
			(width 0.06985)
			(type default)
		)
		(layer "In9.Cu")
	)
	(gr_line
		(start 277.203408 -182.66791)
		(end 277.219156 -182.727346)
		(stroke
			(width 0.06985)
			(type default)
		)
		(layer "In9.Cu")
	)
	(gr_line
		(start 277.203408 -182.66791)
		(end 277.22703 -182.611522)
		(stroke
			(width 0.06985)
			(type default)
		)
		(layer "In9.Cu")
	)
	(gr_line
		(start 277.218902 -182.727092)
		(end 277.219156 -182.728108)
		(stroke
			(width 0.06985)
			(type default)
		)
		(layer "In9.Cu")
	)
	(gr_line
		(start 277.23719 -114.436144)
		(end 277.277576 -114.625882)
		(stroke
			(width 0.06985)
			(type default)
		)
		(layer "In9.Cu")
	)
	(gr_line
		(start 277.250144 -51.635914)
		(end 277.261574 -51.618642)
		(stroke
			(width 0.06985)
			(type default)
		)
		(layer "In9.Cu")
	)
	(gr_line
		(start 277.261574 -51.618642)
		(end 277.278846 -51.607212)
		(stroke
			(width 0.06985)
			(type default)
		)
		(layer "In9.Cu")
	)
	(gr_line
		(start 277.31466 -113.775998)
		(end 277.327868 -113.755424)
		(stroke
			(width 0.06985)
			(type default)
		)
		(layer "In9.Cu")
	)
	(gr_line
		(start 277.325582 -160.35909)
		(end 277.532592 -160.381696)
		(stroke
			(width 0.06985)
			(type default)
		)
		(layer "In9.Cu")
	)
	(gr_line
		(start 277.327868 -113.755424)
		(end 277.348442 -113.742216)
		(stroke
			(width 0.06985)
			(type default)
		)
		(layer "In9.Cu")
	)
	(gr_line
		(start 277.329138 -127.991108)
		(end 277.342346 -127.970534)
		(stroke
			(width 0.06985)
			(type default)
		)
		(layer "In9.Cu")
	)
	(gr_line
		(start 277.342346 -127.970534)
		(end 277.36292 -127.957326)
		(stroke
			(width 0.06985)
			(type default)
		)
		(layer "In9.Cu")
	)
	(gr_line
		(start 277.385526 -164.381688)
		(end 277.71217 -164.119052)
		(stroke
			(width 0.06985)
			(type default)
		)
		(layer "In9.Cu")
	)
	(gr_line
		(start 277.422102 -175.879506)
		(end 277.435818 -175.858424)
		(stroke
			(width 0.06985)
			(type default)
		)
		(layer "In9.Cu")
	)
	(gr_line
		(start 277.435818 -175.858424)
		(end 277.4569 -175.844708)
		(stroke
			(width 0.06985)
			(type default)
		)
		(layer "In9.Cu")
	)
	(gr_line
		(start 277.47722 -167.960548)
		(end 277.490428 -167.939974)
		(stroke
			(width 0.06985)
			(type default)
		)
		(layer "In9.Cu")
	)
	(gr_line
		(start 277.490428 -167.939974)
		(end 277.511002 -167.926766)
		(stroke
			(width 0.06985)
			(type default)
		)
		(layer "In9.Cu")
	)
	(gr_line
		(start 277.52167 -119.877586)
		(end 277.534878 -119.857012)
		(stroke
			(width 0.06985)
			(type default)
		)
		(layer "In9.Cu")
	)
	(gr_line
		(start 277.532592 -160.381696)
		(end 277.859236 -160.11906)
		(stroke
			(width 0.06985)
			(type default)
		)
		(layer "In9.Cu")
	)
	(gr_line
		(start 277.534878 -119.857012)
		(end 277.555452 -119.843804)
		(stroke
			(width 0.06985)
			(type default)
		)
		(layer "In9.Cu")
	)
	(gr_line
		(start 277.53564 -181.877716)
		(end 277.55723 -181.826408)
		(stroke
			(width 0.06985)
			(type default)
		)
		(layer "In9.Cu")
	)
	(gr_line
		(start 277.55723 -181.826408)
		(end 277.604474 -181.796944)
		(stroke
			(width 0.06985)
			(type default)
		)
		(layer "In9.Cu")
	)
	(gr_line
		(start 277.687278 -184.500774)
		(end 277.70201 -184.557416)
		(stroke
			(width 0.06985)
			(type default)
		)
		(layer "In9.Cu")
	)
	(gr_line
		(start 277.70201 -184.557416)
		(end 277.747984 -184.594246)
		(stroke
			(width 0.06985)
			(type default)
		)
		(layer "In9.Cu")
	)
	(gr_line
		(start 277.710138 -94.994222)
		(end 277.7236 -95.003112)
		(stroke
			(width 0.06985)
			(type default)
		)
		(layer "In9.Cu")
	)
	(gr_line
		(start 277.71217 -164.119052)
		(end 277.734522 -163.912042)
		(stroke
			(width 0.06985)
			(type default)
		)
		(layer "In9.Cu")
	)
	(gr_line
		(start 277.7236 -95.003112)
		(end 277.739348 -95.006668)
		(stroke
			(width 0.06985)
			(type default)
		)
		(layer "In9.Cu")
	)
	(gr_line
		(start 277.761192 -88.627204)
		(end 277.772622 -88.644476)
		(stroke
			(width 0.06985)
			(type default)
		)
		(layer "In9.Cu")
	)
	(gr_line
		(start 277.772622 -88.644476)
		(end 277.789894 -88.655906)
		(stroke
			(width 0.06985)
			(type default)
		)
		(layer "In9.Cu")
	)
	(gr_line
		(start 277.788624 -113.456466)
		(end 277.801578 -113.448084)
		(stroke
			(width 0.06985)
			(type default)
		)
		(layer "In9.Cu")
	)
	(gr_line
		(start 277.801578 -113.448084)
		(end 277.817072 -113.444782)
		(stroke
			(width 0.06985)
			(type default)
		)
		(layer "In9.Cu")
	)
	(gr_line
		(start 277.812754 -47.149258)
		(end 277.829264 -47.138336)
		(stroke
			(width 0.06985)
			(type default)
		)
		(layer "In9.Cu")
	)
	(gr_line
		(start 277.818342 -151.394414)
		(end 277.868888 -151.353774)
		(stroke
			(width 0.06985)
			(type default)
		)
		(layer "In9.Cu")
	)
	(gr_line
		(start 277.829264 -47.138336)
		(end 277.848568 -47.134272)
		(stroke
			(width 0.06985)
			(type default)
		)
		(layer "In9.Cu")
	)
	(gr_line
		(start 277.857966 -155.394406)
		(end 277.908512 -155.353766)
		(stroke
			(width 0.06985)
			(type default)
		)
		(layer "In9.Cu")
	)
	(gr_line
		(start 277.859236 -160.11906)
		(end 277.881588 -159.91205)
		(stroke
			(width 0.06985)
			(type default)
		)
		(layer "In9.Cu")
	)
	(gr_line
		(start 277.88108 -39.079424)
		(end 277.920958 -39.054024)
		(stroke
			(width 0.06985)
			(type default)
		)
		(layer "In9.Cu")
	)
	(gr_line
		(start 277.909528 -163.393628)
		(end 277.958804 -163.35375)
		(stroke
			(width 0.06985)
			(type default)
		)
		(layer "In9.Cu")
	)
	(gr_line
		(start 277.945596 -43.079416)
		(end 277.985474 -43.054016)
		(stroke
			(width 0.06985)
			(type default)
		)
		(layer "In9.Cu")
	)
	(gr_line
		(start 278.056594 -159.393636)
		(end 278.10587 -159.353758)
		(stroke
			(width 0.06985)
			(type default)
		)
		(layer "In9.Cu")
	)
	(gr_line
		(start 278.073612 -51.081432)
		(end 278.11476 -51.054)
		(stroke
			(width 0.06985)
			(type default)
		)
		(layer "In9.Cu")
	)
	(gr_line
		(start 278.12365 -190.393828)
		(end 278.136604 -190.404242)
		(stroke
			(width 0.06985)
			(type default)
		)
		(layer "In9.Cu")
	)
	(gr_line
		(start 278.136604 -190.404242)
		(end 278.152098 -190.409068)
		(stroke
			(width 0.06985)
			(type default)
		)
		(layer "In9.Cu")
	)
	(gr_line
		(start 278.173434 -175.379888)
		(end 278.21382 -175.353726)
		(stroke
			(width 0.06985)
			(type default)
		)
		(layer "In9.Cu")
	)
	(gr_line
		(start 278.226774 -123.379992)
		(end 278.26716 -123.35383)
		(stroke
			(width 0.06985)
			(type default)
		)
		(layer "In9.Cu")
	)
	(gr_line
		(start 278.23668 -345.105228)
		(end 278.634444 -345.105228)
		(stroke
			(width 0.053848)
			(type default)
		)
		(layer "In9.Cu")
	)
	(gr_line
		(start 278.23668 -341.505032)
		(end 278.634444 -341.505032)
		(stroke
			(width 0.053848)
			(type default)
		)
		(layer "In9.Cu")
	)
	(gr_line
		(start 278.23668 -337.90509)
		(end 278.634444 -337.90509)
		(stroke
			(width 0.053848)
			(type default)
		)
		(layer "In9.Cu")
	)
	(gr_line
		(start 278.23668 -323.505068)
		(end 278.634444 -323.505068)
		(stroke
			(width 0.053848)
			(type default)
		)
		(layer "In9.Cu")
	)
	(gr_line
		(start 278.23668 -319.905126)
		(end 278.634444 -319.905126)
		(stroke
			(width 0.053848)
			(type default)
		)
		(layer "In9.Cu")
	)
	(gr_line
		(start 278.23668 -316.305184)
		(end 278.634444 -316.305184)
		(stroke
			(width 0.053848)
			(type default)
		)
		(layer "In9.Cu")
	)
	(gr_line
		(start 278.23668 -301.905162)
		(end 278.634444 -301.905162)
		(stroke
			(width 0.053848)
			(type default)
		)
		(layer "In9.Cu")
	)
	(gr_line
		(start 278.23668 -298.30522)
		(end 278.634444 -298.30522)
		(stroke
			(width 0.053848)
			(type default)
		)
		(layer "In9.Cu")
	)
	(gr_line
		(start 278.251666 -127.379984)
		(end 278.292052 -127.353822)
		(stroke
			(width 0.06985)
			(type default)
		)
		(layer "In9.Cu")
	)
	(gr_line
		(start 278.269192 -119.38)
		(end 278.309578 -119.353838)
		(stroke
			(width 0.06985)
			(type default)
		)
		(layer "In9.Cu")
	)
	(gr_line
		(start 278.27605 -181.378098)
		(end 278.314404 -181.353968)
		(stroke
			(width 0.06985)
			(type default)
		)
		(layer "In9.Cu")
	)
	(gr_line
		(start 278.332946 -171.379896)
		(end 278.373332 -171.353734)
		(stroke
			(width 0.06985)
			(type default)
		)
		(layer "In9.Cu")
	)
	(gr_line
		(start 278.352504 -167.379904)
		(end 278.39289 -167.353742)
		(stroke
			(width 0.06985)
			(type default)
		)
		(layer "In9.Cu")
	)
	(gr_line
		(start 278.571452 -188.932058)
		(end 278.584406 -188.942472)
		(stroke
			(width 0.06985)
			(type default)
		)
		(layer "In9.Cu")
	)
	(gr_line
		(start 278.584406 -188.942472)
		(end 278.5999 -188.947298)
		(stroke
			(width 0.06985)
			(type default)
		)
		(layer "In9.Cu")
	)
	(gr_arc
		(start 278.724106 -345.142312)
		(mid 278.682955 -345.114879)
		(end 278.634444 -345.105228)
		(stroke
			(width 0.053848)
			(type default)
		)
		(layer "In9.Cu")
	)
	(gr_line
		(start 278.724106 -345.142312)
		(end 278.73452 -345.152726)
		(stroke
			(width 0.053848)
			(type default)
		)
		(layer "In9.Cu")
	)
	(gr_arc
		(start 278.724106 -341.542116)
		(mid 278.682959 -341.514673)
		(end 278.634444 -341.505032)
		(stroke
			(width 0.053848)
			(type default)
		)
		(layer "In9.Cu")
	)
	(gr_line
		(start 278.724106 -341.542116)
		(end 278.73452 -341.55253)
		(stroke
			(width 0.053848)
			(type default)
		)
		(layer "In9.Cu")
	)
	(gr_arc
		(start 278.724106 -337.942174)
		(mid 278.682956 -337.91474)
		(end 278.634444 -337.90509)
		(stroke
			(width 0.053848)
			(type default)
		)
		(layer "In9.Cu")
	)
	(gr_line
		(start 278.724106 -337.942174)
		(end 278.73452 -337.952588)
		(stroke
			(width 0.053848)
			(type default)
		)
		(layer "In9.Cu")
	)
	(gr_arc
		(start 278.724106 -323.542152)
		(mid 278.682955 -323.514719)
		(end 278.634444 -323.505068)
		(stroke
			(width 0.053848)
			(type default)
		)
		(layer "In9.Cu")
	)
	(gr_line
		(start 278.724106 -323.542152)
		(end 278.73452 -323.552566)
		(stroke
			(width 0.053848)
			(type default)
		)
		(layer "In9.Cu")
	)
	(gr_arc
		(start 278.724106 -319.94221)
		(mid 278.682955 -319.914777)
		(end 278.634444 -319.905126)
		(stroke
			(width 0.053848)
			(type default)
		)
		(layer "In9.Cu")
	)
	(gr_line
		(start 278.724106 -319.94221)
		(end 278.73452 -319.952624)
		(stroke
			(width 0.053848)
			(type default)
		)
		(layer "In9.Cu")
	)
	(gr_arc
		(start 278.724106 -316.342268)
		(mid 278.682956 -316.314835)
		(end 278.634444 -316.305184)
		(stroke
			(width 0.053848)
			(type default)
		)
		(layer "In9.Cu")
	)
	(gr_line
		(start 278.724106 -316.342268)
		(end 278.73452 -316.352682)
		(stroke
			(width 0.053848)
			(type default)
		)
		(layer "In9.Cu")
	)
	(gr_arc
		(start 278.724106 -301.942246)
		(mid 278.682955 -301.914813)
		(end 278.634444 -301.905162)
		(stroke
			(width 0.053848)
			(type default)
		)
		(layer "In9.Cu")
	)
	(gr_line
		(start 278.724106 -301.942246)
		(end 278.73452 -301.95266)
		(stroke
			(width 0.053848)
			(type default)
		)
		(layer "In9.Cu")
	)
	(gr_arc
		(start 278.724106 -298.342304)
		(mid 278.682955 -298.314871)
		(end 278.634444 -298.30522)
		(stroke
			(width 0.053848)
			(type default)
		)
		(layer "In9.Cu")
	)
	(gr_line
		(start 278.724106 -298.342304)
		(end 278.73452 -298.352718)
		(stroke
			(width 0.053848)
			(type default)
		)
		(layer "In9.Cu")
	)
	(gr_line
		(start 278.750014 -114.499898)
		(end 279.494488 -114.127534)
		(stroke
			(width 0.06985)
			(type default)
		)
		(layer "In9.Cu")
	)
	(gr_arc
		(start 278.771604 -345.242388)
		(mid 278.761971 -345.19387)
		(end 278.73452 -345.152726)
		(stroke
			(width 0.053848)
			(type default)
		)
		(layer "In9.Cu")
	)
	(gr_arc
		(start 278.771604 -341.642192)
		(mid 278.761942 -341.593691)
		(end 278.73452 -341.55253)
		(stroke
			(width 0.053848)
			(type default)
		)
		(layer "In9.Cu")
	)
	(gr_arc
		(start 278.771604 -338.04225)
		(mid 278.761961 -337.993737)
		(end 278.73452 -337.952588)
		(stroke
			(width 0.053848)
			(type default)
		)
		(layer "In9.Cu")
	)
	(gr_arc
		(start 278.771604 -323.642228)
		(mid 278.761971 -323.59371)
		(end 278.73452 -323.552566)
		(stroke
			(width 0.053848)
			(type default)
		)
		(layer "In9.Cu")
	)
	(gr_arc
		(start 278.771604 -320.042286)
		(mid 278.761971 -319.993768)
		(end 278.73452 -319.952624)
		(stroke
			(width 0.053848)
			(type default)
		)
		(layer "In9.Cu")
	)
	(gr_arc
		(start 278.771604 -316.442344)
		(mid 278.761959 -316.393832)
		(end 278.73452 -316.352682)
		(stroke
			(width 0.053848)
			(type default)
		)
		(layer "In9.Cu")
	)
	(gr_arc
		(start 278.771604 -302.042322)
		(mid 278.761971 -301.993804)
		(end 278.73452 -301.95266)
		(stroke
			(width 0.053848)
			(type default)
		)
		(layer "In9.Cu")
	)
	(gr_arc
		(start 278.771604 -298.44238)
		(mid 278.761971 -298.393862)
		(end 278.73452 -298.352718)
		(stroke
			(width 0.053848)
			(type default)
		)
		(layer "In9.Cu")
	)
	(gr_line
		(start 278.845772 -93.637862)
		(end 278.859488 -93.646752)
		(stroke
			(width 0.06985)
			(type default)
		)
		(layer "In9.Cu")
	)
	(gr_line
		(start 278.859488 -93.646752)
		(end 278.874474 -93.650054)
		(stroke
			(width 0.06985)
			(type default)
		)
		(layer "In9.Cu")
	)
	(gr_line
		(start 279.107392 -187.446158)
		(end 279.1206 -187.456826)
		(stroke
			(width 0.06985)
			(type default)
		)
		(layer "In9.Cu")
	)
	(gr_line
		(start 279.1206 -187.456826)
		(end 279.137618 -187.462414)
		(stroke
			(width 0.06985)
			(type default)
		)
		(layer "In9.Cu")
	)
	(gr_arc
		(start 279.138888 -345.152726)
		(mid 279.111429 -345.193871)
		(end 279.101804 -345.242388)
		(stroke
			(width 0.053848)
			(type default)
		)
		(layer "In9.Cu")
	)
	(gr_line
		(start 279.138888 -345.152726)
		(end 279.149302 -345.142312)
		(stroke
			(width 0.053848)
			(type default)
		)
		(layer "In9.Cu")
	)
	(gr_arc
		(start 279.138888 -341.55253)
		(mid 279.111455 -341.593681)
		(end 279.101804 -341.642192)
		(stroke
			(width 0.053848)
			(type default)
		)
		(layer "In9.Cu")
	)
	(gr_line
		(start 279.138888 -341.55253)
		(end 279.149302 -341.542116)
		(stroke
			(width 0.053848)
			(type default)
		)
		(layer "In9.Cu")
	)
	(gr_arc
		(start 279.138888 -337.952588)
		(mid 279.111449 -337.993737)
		(end 279.101804 -338.04225)
		(stroke
			(width 0.053848)
			(type default)
		)
		(layer "In9.Cu")
	)
	(gr_line
		(start 279.138888 -337.952588)
		(end 279.149302 -337.942174)
		(stroke
			(width 0.053848)
			(type default)
		)
		(layer "In9.Cu")
	)
	(gr_arc
		(start 279.138888 -323.552566)
		(mid 279.111442 -323.593713)
		(end 279.101804 -323.642228)
		(stroke
			(width 0.053848)
			(type default)
		)
		(layer "In9.Cu")
	)
	(gr_line
		(start 279.138888 -323.552566)
		(end 279.149302 -323.542152)
		(stroke
			(width 0.053848)
			(type default)
		)
		(layer "In9.Cu")
	)
	(gr_arc
		(start 279.138888 -319.952624)
		(mid 279.111428 -319.993769)
		(end 279.101804 -320.042286)
		(stroke
			(width 0.053848)
			(type default)
		)
		(layer "In9.Cu")
	)
	(gr_line
		(start 279.138888 -319.952624)
		(end 279.149302 -319.94221)
		(stroke
			(width 0.053848)
			(type default)
		)
		(layer "In9.Cu")
	)
	(gr_arc
		(start 279.138888 -316.352682)
		(mid 279.111447 -316.39383)
		(end 279.101804 -316.442344)
		(stroke
			(width 0.053848)
			(type default)
		)
		(layer "In9.Cu")
	)
	(gr_line
		(start 279.138888 -316.352682)
		(end 279.149302 -316.342268)
		(stroke
			(width 0.053848)
			(type default)
		)
		(layer "In9.Cu")
	)
	(gr_arc
		(start 279.138888 -301.95266)
		(mid 279.11144 -301.993807)
		(end 279.101804 -302.042322)
		(stroke
			(width 0.053848)
			(type default)
		)
		(layer "In9.Cu")
	)
	(gr_line
		(start 279.138888 -301.95266)
		(end 279.149302 -301.942246)
		(stroke
			(width 0.053848)
			(type default)
		)
		(layer "In9.Cu")
	)
	(gr_arc
		(start 279.138888 -298.352718)
		(mid 279.111426 -298.393862)
		(end 279.101804 -298.44238)
		(stroke
			(width 0.053848)
			(type default)
		)
		(layer "In9.Cu")
	)
	(gr_line
		(start 279.138888 -298.352718)
		(end 279.149302 -298.342304)
		(stroke
			(width 0.053848)
			(type default)
		)
		(layer "In9.Cu")
	)
	(gr_line
		(start 279.236678 -346.905072)
		(end 279.63876 -346.905072)
		(stroke
			(width 0.053848)
			(type default)
		)
		(layer "In9.Cu")
	)
	(gr_line
		(start 279.236678 -343.30513)
		(end 279.63876 -343.30513)
		(stroke
			(width 0.053848)
			(type default)
		)
		(layer "In9.Cu")
	)
	(gr_line
		(start 279.236678 -339.705188)
		(end 279.63876 -339.705188)
		(stroke
			(width 0.053848)
			(type default)
		)
		(layer "In9.Cu")
	)
	(gr_line
		(start 279.236678 -325.305166)
		(end 279.63876 -325.305166)
		(stroke
			(width 0.053848)
			(type default)
		)
		(layer "In9.Cu")
	)
	(gr_line
		(start 279.236678 -321.705224)
		(end 279.63876 -321.705224)
		(stroke
			(width 0.053848)
			(type default)
		)
		(layer "In9.Cu")
	)
	(gr_line
		(start 279.236678 -318.105028)
		(end 279.63876 -318.105028)
		(stroke
			(width 0.053848)
			(type default)
		)
		(layer "In9.Cu")
	)
	(gr_line
		(start 279.236678 -303.70526)
		(end 279.63876 -303.70526)
		(stroke
			(width 0.053848)
			(type default)
		)
		(layer "In9.Cu")
	)
	(gr_line
		(start 279.236678 -300.105064)
		(end 279.63876 -300.105064)
		(stroke
			(width 0.053848)
			(type default)
		)
		(layer "In9.Cu")
	)
	(gr_arc
		(start 279.238964 -345.105228)
		(mid 279.19045 -345.114868)
		(end 279.149302 -345.142312)
		(stroke
			(width 0.053848)
			(type default)
		)
		(layer "In9.Cu")
	)
	(gr_line
		(start 279.238964 -345.105228)
		(end 279.636728 -345.105228)
		(stroke
			(width 0.053848)
			(type default)
		)
		(layer "In9.Cu")
	)
	(gr_arc
		(start 279.238964 -341.505032)
		(mid 279.190446 -341.514665)
		(end 279.149302 -341.542116)
		(stroke
			(width 0.053848)
			(type default)
		)
		(layer "In9.Cu")
	)
	(gr_line
		(start 279.238964 -341.505032)
		(end 279.636728 -341.505032)
		(stroke
			(width 0.053848)
			(type default)
		)
		(layer "In9.Cu")
	)
	(gr_arc
		(start 279.238964 -337.90509)
		(mid 279.190448 -337.914728)
		(end 279.149302 -337.942174)
		(stroke
			(width 0.053848)
			(type default)
		)
		(layer "In9.Cu")
	)
	(gr_line
		(start 279.238964 -337.90509)
		(end 279.636728 -337.90509)
		(stroke
			(width 0.053848)
			(type default)
		)
		(layer "In9.Cu")
	)
	(gr_arc
		(start 279.238964 -323.505068)
		(mid 279.190446 -323.514705)
		(end 279.149302 -323.542152)
		(stroke
			(width 0.053848)
			(type default)
		)
		(layer "In9.Cu")
	)
	(gr_line
		(start 279.238964 -323.505068)
		(end 279.636728 -323.505068)
		(stroke
			(width 0.053848)
			(type default)
		)
		(layer "In9.Cu")
	)
	(gr_arc
		(start 279.238964 -319.905126)
		(mid 279.19045 -319.914766)
		(end 279.149302 -319.94221)
		(stroke
			(width 0.053848)
			(type default)
		)
		(layer "In9.Cu")
	)
	(gr_line
		(start 279.238964 -319.905126)
		(end 279.636728 -319.905126)
		(stroke
			(width 0.053848)
			(type default)
		)
		(layer "In9.Cu")
	)
	(gr_arc
		(start 279.238964 -316.305184)
		(mid 279.190447 -316.314822)
		(end 279.149302 -316.342268)
		(stroke
			(width 0.053848)
			(type default)
		)
		(layer "In9.Cu")
	)
	(gr_line
		(start 279.238964 -316.305184)
		(end 279.636728 -316.305184)
		(stroke
			(width 0.053848)
			(type default)
		)
		(layer "In9.Cu")
	)
	(gr_arc
		(start 279.238964 -301.905162)
		(mid 279.190446 -301.914799)
		(end 279.149302 -301.942246)
		(stroke
			(width 0.053848)
			(type default)
		)
		(layer "In9.Cu")
	)
	(gr_line
		(start 279.238964 -301.905162)
		(end 279.636728 -301.905162)
		(stroke
			(width 0.053848)
			(type default)
		)
		(layer "In9.Cu")
	)
	(gr_arc
		(start 279.238964 -298.30522)
		(mid 279.190449 -298.31486)
		(end 279.149302 -298.342304)
		(stroke
			(width 0.053848)
			(type default)
		)
		(layer "In9.Cu")
	)
	(gr_line
		(start 279.238964 -298.30522)
		(end 279.636728 -298.30522)
		(stroke
			(width 0.053848)
			(type default)
		)
		(layer "In9.Cu")
	)
	(gr_arc
		(start 279.494488 -114.127534)
		(mid 279.564529 -114.046751)
		(end 279.556972 -113.940082)
		(stroke
			(width 0.06985)
			(type default)
		)
		(layer "In9.Cu")
	)
	(gr_arc
		(start 279.728422 -346.942156)
		(mid 279.687271 -346.914723)
		(end 279.63876 -346.905072)
		(stroke
			(width 0.053848)
			(type default)
		)
		(layer "In9.Cu")
	)
	(gr_line
		(start 279.728422 -346.942156)
		(end 279.734518 -346.948252)
		(stroke
			(width 0.053848)
			(type default)
		)
		(layer "In9.Cu")
	)
	(gr_arc
		(start 279.728422 -343.342214)
		(mid 279.687271 -343.314781)
		(end 279.63876 -343.30513)
		(stroke
			(width 0.053848)
			(type default)
		)
		(layer "In9.Cu")
	)
	(gr_line
		(start 279.728422 -343.342214)
		(end 279.734518 -343.34831)
		(stroke
			(width 0.053848)
			(type default)
		)
		(layer "In9.Cu")
	)
	(gr_arc
		(start 279.728422 -339.742272)
		(mid 279.687273 -339.714833)
		(end 279.63876 -339.705188)
		(stroke
			(width 0.053848)
			(type default)
		)
		(layer "In9.Cu")
	)
	(gr_line
		(start 279.728422 -339.742272)
		(end 279.734518 -339.748368)
		(stroke
			(width 0.053848)
			(type default)
		)
		(layer "In9.Cu")
	)
	(gr_arc
		(start 279.728422 -325.34225)
		(mid 279.687271 -325.314817)
		(end 279.63876 -325.305166)
		(stroke
			(width 0.053848)
			(type default)
		)
		(layer "In9.Cu")
	)
	(gr_line
		(start 279.728422 -325.34225)
		(end 279.734518 -325.348346)
		(stroke
			(width 0.053848)
			(type default)
		)
		(layer "In9.Cu")
	)
	(gr_arc
		(start 279.728422 -321.742308)
		(mid 279.687275 -321.714861)
		(end 279.63876 -321.705224)
		(stroke
			(width 0.053848)
			(type default)
		)
		(layer "In9.Cu")
	)
	(gr_line
		(start 279.728422 -321.742308)
		(end 279.734518 -321.748404)
		(stroke
			(width 0.053848)
			(type default)
		)
		(layer "In9.Cu")
	)
	(gr_arc
		(start 279.728422 -318.142112)
		(mid 279.687275 -318.114665)
		(end 279.63876 -318.105028)
		(stroke
			(width 0.053848)
			(type default)
		)
		(layer "In9.Cu")
	)
	(gr_line
		(start 279.728422 -318.142112)
		(end 279.734518 -318.148208)
		(stroke
			(width 0.053848)
			(type default)
		)
		(layer "In9.Cu")
	)
	(gr_arc
		(start 279.728422 -303.742344)
		(mid 279.687277 -303.71489)
		(end 279.63876 -303.70526)
		(stroke
			(width 0.053848)
			(type default)
		)
		(layer "In9.Cu")
	)
	(gr_line
		(start 279.728422 -303.742344)
		(end 279.734518 -303.74844)
		(stroke
			(width 0.053848)
			(type default)
		)
		(layer "In9.Cu")
	)
	(gr_arc
		(start 279.728422 -300.142148)
		(mid 279.687271 -300.114715)
		(end 279.63876 -300.105064)
		(stroke
			(width 0.053848)
			(type default)
		)
		(layer "In9.Cu")
	)
	(gr_line
		(start 279.728422 -300.142148)
		(end 279.734518 -300.148244)
		(stroke
			(width 0.053848)
			(type default)
		)
		(layer "In9.Cu")
	)
	(gr_line
		(start 279.755854 -113.684304)
		(end 279.762712 -113.698274)
		(stroke
			(width 0.06985)
			(type default)
		)
		(layer "In9.Cu")
	)
	(gr_arc
		(start 279.771602 -347.037914)
		(mid 279.761969 -346.989396)
		(end 279.734518 -346.948252)
		(stroke
			(width 0.053848)
			(type default)
		)
		(layer "In9.Cu")
	)
	(gr_arc
		(start 279.771602 -343.437972)
		(mid 279.761969 -343.389454)
		(end 279.734518 -343.34831)
		(stroke
			(width 0.053848)
			(type default)
		)
		(layer "In9.Cu")
	)
	(gr_arc
		(start 279.771602 -339.83803)
		(mid 279.761952 -339.789521)
		(end 279.734518 -339.748368)
		(stroke
			(width 0.053848)
			(type default)
		)
		(layer "In9.Cu")
	)
	(gr_arc
		(start 279.771602 -325.438008)
		(mid 279.761969 -325.38949)
		(end 279.734518 -325.348346)
		(stroke
			(width 0.053848)
			(type default)
		)
		(layer "In9.Cu")
	)
	(gr_arc
		(start 279.771602 -321.838066)
		(mid 279.761964 -321.78955)
		(end 279.734518 -321.748404)
		(stroke
			(width 0.053848)
			(type default)
		)
		(layer "In9.Cu")
	)
	(gr_arc
		(start 279.771602 -318.23787)
		(mid 279.761965 -318.189353)
		(end 279.734518 -318.148208)
		(stroke
			(width 0.053848)
			(type default)
		)
		(layer "In9.Cu")
	)
	(gr_arc
		(start 279.771602 -303.838102)
		(mid 279.761943 -303.789599)
		(end 279.734518 -303.74844)
		(stroke
			(width 0.053848)
			(type default)
		)
		(layer "In9.Cu")
	)
	(gr_arc
		(start 279.771602 -300.237906)
		(mid 279.761969 -300.189388)
		(end 279.734518 -300.148244)
		(stroke
			(width 0.053848)
			(type default)
		)
		(layer "In9.Cu")
	)
	(gr_line
		(start 279.805892 -92.095066)
		(end 279.819354 -92.103956)
		(stroke
			(width 0.06985)
			(type default)
		)
		(layer "In9.Cu")
	)
	(gr_line
		(start 279.810718 -186.252358)
		(end 279.823672 -186.262772)
		(stroke
			(width 0.06985)
			(type default)
		)
		(layer "In9.Cu")
	)
	(gr_arc
		(start 279.818338 -113.809526)
		(mid 279.899123 -113.879591)
		(end 280.00579 -113.87201)
		(stroke
			(width 0.06985)
			(type default)
		)
		(layer "In9.Cu")
	)
	(gr_line
		(start 279.819354 -92.103956)
		(end 279.835102 -92.107512)
		(stroke
			(width 0.06985)
			(type default)
		)
		(layer "In9.Cu")
	)
	(gr_line
		(start 279.823672 -186.262772)
		(end 279.839928 -186.268106)
		(stroke
			(width 0.06985)
			(type default)
		)
		(layer "In9.Cu")
	)
	(gr_line
		(start 279.837134 -109.14253)
		(end 279.896062 -109.083602)
		(stroke
			(width 0.06985)
			(type default)
		)
		(layer "In9.Cu")
	)
	(gr_line
		(start 280.00579 -113.87201)
		(end 280.75001 -113.4999)
		(stroke
			(width 0.06985)
			(type default)
		)
		(layer "In9.Cu")
	)
	(gr_arc
		(start 280.138886 -346.948252)
		(mid 280.111436 -346.989399)
		(end 280.101802 -347.037914)
		(stroke
			(width 0.053848)
			(type default)
		)
		(layer "In9.Cu")
	)
	(gr_line
		(start 280.138886 -346.948252)
		(end 280.144982 -346.942156)
		(stroke
			(width 0.053848)
			(type default)
		)
		(layer "In9.Cu")
	)
	(gr_arc
		(start 280.138886 -343.34831)
		(mid 280.111455 -343.38946)
		(end 280.101802 -343.437972)
		(stroke
			(width 0.053848)
			(type default)
		)
		(layer "In9.Cu")
	)
	(gr_line
		(start 280.138886 -343.34831)
		(end 280.144982 -343.342214)
		(stroke
			(width 0.053848)
			(type default)
		)
		(layer "In9.Cu")
	)
	(gr_arc
		(start 280.138886 -339.748368)
		(mid 280.111453 -339.789519)
		(end 280.101802 -339.83803)
		(stroke
			(width 0.053848)
			(type default)
		)
		(layer "In9.Cu")
	)
	(gr_line
		(start 280.138886 -339.748368)
		(end 280.144982 -339.742272)
		(stroke
			(width 0.053848)
			(type default)
		)
		(layer "In9.Cu")
	)
	(gr_arc
		(start 280.138886 -325.348346)
		(mid 280.111434 -325.389492)
		(end 280.101802 -325.438008)
		(stroke
			(width 0.053848)
			(type default)
		)
		(layer "In9.Cu")
	)
	(gr_line
		(start 280.138886 -325.348346)
		(end 280.144982 -325.34225)
		(stroke
			(width 0.053848)
			(type default)
		)
		(layer "In9.Cu")
	)
	(gr_arc
		(start 280.138886 -321.748404)
		(mid 280.111453 -321.789555)
		(end 280.101802 -321.838066)
		(stroke
			(width 0.053848)
			(type default)
		)
		(layer "In9.Cu")
	)
	(gr_line
		(start 280.138886 -321.748404)
		(end 280.144982 -321.742308)
		(stroke
			(width 0.053848)
			(type default)
		)
		(layer "In9.Cu")
	)
	(gr_arc
		(start 280.138886 -318.148208)
		(mid 280.111453 -318.189359)
		(end 280.101802 -318.23787)
		(stroke
			(width 0.053848)
			(type default)
		)
		(layer "In9.Cu")
	)
	(gr_line
		(start 280.138886 -318.148208)
		(end 280.144982 -318.142112)
		(stroke
			(width 0.053848)
			(type default)
		)
		(layer "In9.Cu")
	)
	(gr_arc
		(start 280.138886 -303.74844)
		(mid 280.111453 -303.789591)
		(end 280.101802 -303.838102)
		(stroke
			(width 0.053848)
			(type default)
		)
		(layer "In9.Cu")
	)
	(gr_line
		(start 280.138886 -303.74844)
		(end 280.144982 -303.742344)
		(stroke
			(width 0.053848)
			(type default)
		)
		(layer "In9.Cu")
	)
	(gr_arc
		(start 280.138886 -300.148244)
		(mid 280.111433 -300.18939)
		(end 280.101802 -300.237906)
		(stroke
			(width 0.053848)
			(type default)
		)
		(layer "In9.Cu")
	)
	(gr_line
		(start 280.138886 -300.148244)
		(end 280.144982 -300.142148)
		(stroke
			(width 0.053848)
			(type default)
		)
		(layer "In9.Cu")
	)
	(gr_arc
		(start 280.234644 -346.905072)
		(mid 280.186131 -346.914716)
		(end 280.144982 -346.942156)
		(stroke
			(width 0.053848)
			(type default)
		)
		(layer "In9.Cu")
	)
	(gr_line
		(start 280.234644 -346.905072)
		(end 280.636726 -346.905072)
		(stroke
			(width 0.053848)
			(type default)
		)
		(layer "In9.Cu")
	)
	(gr_arc
		(start 280.234644 -343.30513)
		(mid 280.186134 -343.314777)
		(end 280.144982 -343.342214)
		(stroke
			(width 0.053848)
			(type default)
		)
		(layer "In9.Cu")
	)
	(gr_line
		(start 280.234644 -343.30513)
		(end 280.636726 -343.30513)
		(stroke
			(width 0.053848)
			(type default)
		)
		(layer "In9.Cu")
	)
	(gr_arc
		(start 280.234644 -339.705188)
		(mid 280.186126 -339.714821)
		(end 280.144982 -339.742272)
		(stroke
			(width 0.053848)
			(type default)
		)
		(layer "In9.Cu")
	)
	(gr_line
		(start 280.234644 -339.705188)
		(end 280.636726 -339.705188)
		(stroke
			(width 0.053848)
			(type default)
		)
		(layer "In9.Cu")
	)
	(gr_arc
		(start 280.234644 -325.305166)
		(mid 280.186131 -325.314809)
		(end 280.144982 -325.34225)
		(stroke
			(width 0.053848)
			(type default)
		)
		(layer "In9.Cu")
	)
	(gr_line
		(start 280.234644 -325.305166)
		(end 280.636726 -325.305166)
		(stroke
			(width 0.053848)
			(type default)
		)
		(layer "In9.Cu")
	)
	(gr_arc
		(start 280.234644 -321.705224)
		(mid 280.186126 -321.714857)
		(end 280.144982 -321.742308)
		(stroke
			(width 0.053848)
			(type default)
		)
		(layer "In9.Cu")
	)
	(gr_line
		(start 280.234644 -321.705224)
		(end 280.636726 -321.705224)
		(stroke
			(width 0.053848)
			(type default)
		)
		(layer "In9.Cu")
	)
	(gr_arc
		(start 280.234644 -318.105028)
		(mid 280.186126 -318.114661)
		(end 280.144982 -318.142112)
		(stroke
			(width 0.053848)
			(type default)
		)
		(layer "In9.Cu")
	)
	(gr_line
		(start 280.234644 -318.105028)
		(end 280.636726 -318.105028)
		(stroke
			(width 0.053848)
			(type default)
		)
		(layer "In9.Cu")
	)
	(gr_arc
		(start 280.234644 -303.70526)
		(mid 280.186126 -303.714893)
		(end 280.144982 -303.742344)
		(stroke
			(width 0.053848)
			(type default)
		)
		(layer "In9.Cu")
	)
	(gr_line
		(start 280.234644 -303.70526)
		(end 280.636726 -303.70526)
		(stroke
			(width 0.053848)
			(type default)
		)
		(layer "In9.Cu")
	)
	(gr_arc
		(start 280.234644 -300.105064)
		(mid 280.18613 -300.114707)
		(end 280.144982 -300.142148)
		(stroke
			(width 0.053848)
			(type default)
		)
		(layer "In9.Cu")
	)
	(gr_line
		(start 280.234644 -300.105064)
		(end 280.636726 -300.105064)
		(stroke
			(width 0.053848)
			(type default)
		)
		(layer "In9.Cu")
	)
	(gr_line
		(start 280.497534 -90.447876)
		(end 280.510996 -90.456766)
		(stroke
			(width 0.06985)
			(type default)
		)
		(layer "In9.Cu")
	)
	(gr_line
		(start 280.510996 -90.456766)
		(end 280.526744 -90.460322)
		(stroke
			(width 0.06985)
			(type default)
		)
		(layer "In9.Cu")
	)
	(gr_line
		(start 281.51582 -191.483742)
		(end 281.569414 -191.50076)
		(stroke
			(width 0.06985)
			(type default)
		)
		(layer "In9.Cu")
	)
	(gr_line
		(start 281.569414 -191.50076)
		(end 281.623262 -191.483742)
		(stroke
			(width 0.06985)
			(type default)
		)
		(layer "In9.Cu")
	)
	(gr_line
		(start 281.575256 -189.897004)
		(end 281.62885 -189.914022)
		(stroke
			(width 0.06985)
			(type default)
		)
		(layer "In9.Cu")
	)
	(gr_line
		(start 281.62885 -189.914022)
		(end 281.682444 -189.897004)
		(stroke
			(width 0.06985)
			(type default)
		)
		(layer "In9.Cu")
	)
	(gr_line
		(start 281.727148 -186.871864)
		(end 281.780488 -186.888882)
		(stroke
			(width 0.06985)
			(type default)
		)
		(layer "In9.Cu")
	)
	(gr_line
		(start 281.730958 -188.290962)
		(end 281.784298 -188.30798)
		(stroke
			(width 0.06985)
			(type default)
		)
		(layer "In9.Cu")
	)
	(gr_line
		(start 281.780488 -186.888882)
		(end 281.833828 -186.871864)
		(stroke
			(width 0.06985)
			(type default)
		)
		(layer "In9.Cu")
	)
	(gr_line
		(start 281.784298 -188.30798)
		(end 281.837892 -188.290962)
		(stroke
			(width 0.06985)
			(type default)
		)
		(layer "In9.Cu")
	)
	(gr_line
		(start 283.043122 -92.818458)
		(end 283.068268 -92.824046)
		(stroke
			(width 0.06985)
			(type default)
		)
		(layer "In9.Cu")
	)
	(gr_line
		(start 283.068268 -92.824046)
		(end 283.093922 -92.818458)
		(stroke
			(width 0.06985)
			(type default)
		)
		(layer "In9.Cu")
	)
	(gr_line
		(start 283.22651 -94.614746)
		(end 283.251656 -94.620334)
		(stroke
			(width 0.06985)
			(type default)
		)
		(layer "In9.Cu")
	)
	(gr_line
		(start 283.249878 -179.499768)
		(end 283.994352 -179.872132)
		(stroke
			(width 0.06985)
			(type default)
		)
		(layer "In9.Cu")
	)
	(gr_line
		(start 283.249878 -175.499776)
		(end 283.994352 -175.87214)
		(stroke
			(width 0.06985)
			(type default)
		)
		(layer "In9.Cu")
	)
	(gr_line
		(start 283.249878 -171.499784)
		(end 283.994352 -171.872148)
		(stroke
			(width 0.06985)
			(type default)
		)
		(layer "In9.Cu")
	)
	(gr_line
		(start 283.249878 -167.499792)
		(end 283.994352 -167.872156)
		(stroke
			(width 0.06985)
			(type default)
		)
		(layer "In9.Cu")
	)
	(gr_line
		(start 283.249878 -163.4998)
		(end 283.994352 -163.872164)
		(stroke
			(width 0.06985)
			(type default)
		)
		(layer "In9.Cu")
	)
	(gr_line
		(start 283.249878 -159.499808)
		(end 283.994352 -159.872172)
		(stroke
			(width 0.06985)
			(type default)
		)
		(layer "In9.Cu")
	)
	(gr_line
		(start 283.249878 -155.499816)
		(end 283.994352 -155.87218)
		(stroke
			(width 0.06985)
			(type default)
		)
		(layer "In9.Cu")
	)
	(gr_line
		(start 283.249878 -151.499824)
		(end 283.994352 -151.872188)
		(stroke
			(width 0.06985)
			(type default)
		)
		(layer "In9.Cu")
	)
	(gr_line
		(start 283.249878 -127.499872)
		(end 283.994352 -127.872236)
		(stroke
			(width 0.06985)
			(type default)
		)
		(layer "In9.Cu")
	)
	(gr_line
		(start 283.249878 -123.49988)
		(end 283.994352 -123.872244)
		(stroke
			(width 0.06985)
			(type default)
		)
		(layer "In9.Cu")
	)
	(gr_line
		(start 283.249878 -119.499888)
		(end 283.994352 -119.872252)
		(stroke
			(width 0.06985)
			(type default)
		)
		(layer "In9.Cu")
	)
	(gr_line
		(start 283.249878 -115.499896)
		(end 283.994098 -115.872006)
		(stroke
			(width 0.06985)
			(type default)
		)
		(layer "In9.Cu")
	)
	(gr_line
		(start 283.249878 -83.199986)
		(end 283.994098 -83.572096)
		(stroke
			(width 0.06985)
			(type default)
		)
		(layer "In9.Cu")
	)
	(gr_line
		(start 283.249878 -79.199994)
		(end 283.994098 -79.572104)
		(stroke
			(width 0.06985)
			(type default)
		)
		(layer "In9.Cu")
	)
	(gr_line
		(start 283.249878 -75.200002)
		(end 283.994098 -75.572112)
		(stroke
			(width 0.06985)
			(type default)
		)
		(layer "In9.Cu")
	)
	(gr_line
		(start 283.249878 -71.20001)
		(end 283.994098 -71.57212)
		(stroke
			(width 0.06985)
			(type default)
		)
		(layer "In9.Cu")
	)
	(gr_line
		(start 283.249878 -67.200018)
		(end 283.994098 -67.572128)
		(stroke
			(width 0.06985)
			(type default)
		)
		(layer "In9.Cu")
	)
	(gr_line
		(start 283.249878 -63.200026)
		(end 283.994098 -63.572136)
		(stroke
			(width 0.06985)
			(type default)
		)
		(layer "In9.Cu")
	)
	(gr_line
		(start 283.249878 -59.200034)
		(end 283.994098 -59.572144)
		(stroke
			(width 0.06985)
			(type default)
		)
		(layer "In9.Cu")
	)
	(gr_line
		(start 283.249878 -55.200042)
		(end 283.994098 -55.572152)
		(stroke
			(width 0.06985)
			(type default)
		)
		(layer "In9.Cu")
	)
	(gr_line
		(start 283.249878 -51.20005)
		(end 283.994352 -51.572414)
		(stroke
			(width 0.06985)
			(type default)
		)
		(layer "In9.Cu")
	)
	(gr_line
		(start 283.249878 -47.200058)
		(end 283.994352 -47.572422)
		(stroke
			(width 0.06985)
			(type default)
		)
		(layer "In9.Cu")
	)
	(gr_line
		(start 283.249878 -43.200066)
		(end 283.994352 -43.57243)
		(stroke
			(width 0.06985)
			(type default)
		)
		(layer "In9.Cu")
	)
	(gr_line
		(start 283.249878 -39.200074)
		(end 283.994352 -39.572438)
		(stroke
			(width 0.06985)
			(type default)
		)
		(layer "In9.Cu")
	)
	(gr_line
		(start 283.251656 -94.620334)
		(end 283.277564 -94.614746)
		(stroke
			(width 0.06985)
			(type default)
		)
		(layer "In9.Cu")
	)
	(gr_line
		(start 283.420566 -91.101672)
		(end 283.445712 -91.10726)
		(stroke
			(width 0.06985)
			(type default)
		)
		(layer "In9.Cu")
	)
	(gr_line
		(start 283.431488 -96.26854)
		(end 283.456634 -96.274128)
		(stroke
			(width 0.06985)
			(type default)
		)
		(layer "In9.Cu")
	)
	(gr_line
		(start 283.445712 -91.10726)
		(end 283.47162 -91.101672)
		(stroke
			(width 0.06985)
			(type default)
		)
		(layer "In9.Cu")
	)
	(gr_line
		(start 283.456634 -96.274128)
		(end 283.482542 -96.26854)
		(stroke
			(width 0.06985)
			(type default)
		)
		(layer "In9.Cu")
	)
	(gr_line
		(start 283.575252 -186.314842)
		(end 283.591508 -186.309508)
		(stroke
			(width 0.06985)
			(type default)
		)
		(layer "In9.Cu")
	)
	(gr_line
		(start 283.591508 -186.309508)
		(end 283.604462 -186.299094)
		(stroke
			(width 0.06985)
			(type default)
		)
		(layer "In9.Cu")
	)
	(gr_arc
		(start 283.994098 -83.572096)
		(mid 284.100765 -83.579677)
		(end 284.18155 -83.509612)
		(stroke
			(width 0.06985)
			(type default)
		)
		(layer "In9.Cu")
	)
	(gr_arc
		(start 283.994098 -79.572104)
		(mid 284.100765 -79.579685)
		(end 284.18155 -79.50962)
		(stroke
			(width 0.06985)
			(type default)
		)
		(layer "In9.Cu")
	)
	(gr_arc
		(start 283.994098 -75.572112)
		(mid 284.100765 -75.579693)
		(end 284.18155 -75.509628)
		(stroke
			(width 0.06985)
			(type default)
		)
		(layer "In9.Cu")
	)
	(gr_arc
		(start 283.994098 -71.57212)
		(mid 284.100765 -71.579701)
		(end 284.18155 -71.509636)
		(stroke
			(width 0.06985)
			(type default)
		)
		(layer "In9.Cu")
	)
	(gr_arc
		(start 283.994098 -67.572128)
		(mid 284.100771 -67.579723)
		(end 284.18155 -67.509644)
		(stroke
			(width 0.06985)
			(type default)
		)
		(layer "In9.Cu")
	)
	(gr_arc
		(start 283.994098 -63.572136)
		(mid 284.100772 -63.579731)
		(end 284.18155 -63.509652)
		(stroke
			(width 0.06985)
			(type default)
		)
		(layer "In9.Cu")
	)
	(gr_arc
		(start 283.994098 -59.572144)
		(mid 284.100772 -59.579738)
		(end 284.18155 -59.50966)
		(stroke
			(width 0.06985)
			(type default)
		)
		(layer "In9.Cu")
	)
	(gr_arc
		(start 283.994098 -55.572152)
		(mid 284.100773 -55.579745)
		(end 284.18155 -55.509668)
		(stroke
			(width 0.06985)
			(type default)
		)
		(layer "In9.Cu")
	)
	(gr_arc
		(start 284.056582 -116.059458)
		(mid 284.064163 -115.952791)
		(end 283.994098 -115.872006)
		(stroke
			(width 0.06985)
			(type default)
		)
		(layer "In9.Cu")
	)
	(gr_arc
		(start 284.056836 -180.059584)
		(mid 284.064417 -179.952917)
		(end 283.994352 -179.872132)
		(stroke
			(width 0.06985)
			(type default)
		)
		(layer "In9.Cu")
	)
	(gr_arc
		(start 284.056836 -176.059592)
		(mid 284.064417 -175.952925)
		(end 283.994352 -175.87214)
		(stroke
			(width 0.06985)
			(type default)
		)
		(layer "In9.Cu")
	)
	(gr_arc
		(start 284.056836 -172.0596)
		(mid 284.064417 -171.952933)
		(end 283.994352 -171.872148)
		(stroke
			(width 0.06985)
			(type default)
		)
		(layer "In9.Cu")
	)
	(gr_arc
		(start 284.056836 -168.059608)
		(mid 284.064417 -167.952941)
		(end 283.994352 -167.872156)
		(stroke
			(width 0.06985)
			(type default)
		)
		(layer "In9.Cu")
	)
	(gr_arc
		(start 284.056836 -164.059616)
		(mid 284.064417 -163.952949)
		(end 283.994352 -163.872164)
		(stroke
			(width 0.06985)
			(type default)
		)
		(layer "In9.Cu")
	)
	(gr_arc
		(start 284.056836 -160.059624)
		(mid 284.064417 -159.952957)
		(end 283.994352 -159.872172)
		(stroke
			(width 0.06985)
			(type default)
		)
		(layer "In9.Cu")
	)
	(gr_arc
		(start 284.056836 -156.059632)
		(mid 284.064417 -155.952965)
		(end 283.994352 -155.87218)
		(stroke
			(width 0.06985)
			(type default)
		)
		(layer "In9.Cu")
	)
	(gr_arc
		(start 284.056836 -152.05964)
		(mid 284.064417 -151.952973)
		(end 283.994352 -151.872188)
		(stroke
			(width 0.06985)
			(type default)
		)
		(layer "In9.Cu")
	)
	(gr_arc
		(start 284.056836 -128.059688)
		(mid 284.064417 -127.953021)
		(end 283.994352 -127.872236)
		(stroke
			(width 0.06985)
			(type default)
		)
		(layer "In9.Cu")
	)
	(gr_arc
		(start 284.056836 -124.059696)
		(mid 284.064417 -123.953029)
		(end 283.994352 -123.872244)
		(stroke
			(width 0.06985)
			(type default)
		)
		(layer "In9.Cu")
	)
	(gr_arc
		(start 284.056836 -120.059704)
		(mid 284.064417 -119.953037)
		(end 283.994352 -119.872252)
		(stroke
			(width 0.06985)
			(type default)
		)
		(layer "In9.Cu")
	)
	(gr_arc
		(start 284.056836 -51.759866)
		(mid 284.064408 -51.65321)
		(end 283.994352 -51.572414)
		(stroke
			(width 0.06985)
			(type default)
		)
		(layer "In9.Cu")
	)
	(gr_arc
		(start 284.056836 -47.759874)
		(mid 284.064413 -47.653214)
		(end 283.994352 -47.572422)
		(stroke
			(width 0.06985)
			(type default)
		)
		(layer "In9.Cu")
	)
	(gr_arc
		(start 284.056836 -43.759882)
		(mid 284.064418 -43.653218)
		(end 283.994352 -43.57243)
		(stroke
			(width 0.06985)
			(type default)
		)
		(layer "In9.Cu")
	)
	(gr_arc
		(start 284.056836 -39.75989)
		(mid 284.064423 -39.653222)
		(end 283.994352 -39.572438)
		(stroke
			(width 0.06985)
			(type default)
		)
		(layer "In9.Cu")
	)
	(gr_line
		(start 284.06344 -94.14002)
		(end 284.168088 -93.976444)
		(stroke
			(width 0.06985)
			(type default)
		)
		(layer "In9.Cu")
	)
	(gr_line
		(start 284.12186 -187.561982)
		(end 284.137354 -187.557156)
		(stroke
			(width 0.06985)
			(type default)
		)
		(layer "In9.Cu")
	)
	(gr_line
		(start 284.137354 -187.557156)
		(end 284.150308 -187.546742)
		(stroke
			(width 0.06985)
			(type default)
		)
		(layer "In9.Cu")
	)
	(gr_line
		(start 284.162246 -94.419674)
		(end 284.767528 -94.286324)
		(stroke
			(width 0.06985)
			(type default)
		)
		(layer "In9.Cu")
	)
	(gr_line
		(start 284.168088 -93.976444)
		(end 284.577536 -93.886274)
		(stroke
			(width 0.06985)
			(type default)
		)
		(layer "In9.Cu")
	)
	(gr_line
		(start 284.240478 -95.800418)
		(end 284.345126 -95.637096)
		(stroke
			(width 0.06985)
			(type default)
		)
		(layer "In9.Cu")
	)
	(gr_line
		(start 284.25521 -116.315236)
		(end 284.255464 -116.314982)
		(stroke
			(width 0.06985)
			(type default)
		)
		(layer "In9.Cu")
	)
	(gr_line
		(start 284.261306 -79.350362)
		(end 284.263338 -79.346552)
		(stroke
			(width 0.06985)
			(type default)
		)
		(layer "In9.Cu")
	)
	(gr_line
		(start 284.338268 -96.080834)
		(end 284.946598 -95.947484)
		(stroke
			(width 0.06985)
			(type default)
		)
		(layer "In9.Cu")
	)
	(gr_line
		(start 284.345126 -95.637096)
		(end 284.754574 -95.54718)
		(stroke
			(width 0.06985)
			(type default)
		)
		(layer "In9.Cu")
	)
	(gr_line
		(start 284.429962 -92.222066)
		(end 284.53461 -92.058744)
		(stroke
			(width 0.06985)
			(type default)
		)
		(layer "In9.Cu")
	)
	(gr_arc
		(start 284.442916 -83.640168)
		(mid 284.435306 -83.74686)
		(end 284.5054 -83.82762)
		(stroke
			(width 0.06985)
			(type default)
		)
		(layer "In9.Cu")
	)
	(gr_arc
		(start 284.442916 -79.640176)
		(mid 284.435311 -79.746864)
		(end 284.5054 -79.827628)
		(stroke
			(width 0.06985)
			(type default)
		)
		(layer "In9.Cu")
	)
	(gr_arc
		(start 284.442916 -75.640184)
		(mid 284.435316 -75.746868)
		(end 284.5054 -75.827636)
		(stroke
			(width 0.06985)
			(type default)
		)
		(layer "In9.Cu")
	)
	(gr_arc
		(start 284.442916 -71.640192)
		(mid 284.435321 -71.746872)
		(end 284.5054 -71.827644)
		(stroke
			(width 0.06985)
			(type default)
		)
		(layer "In9.Cu")
	)
	(gr_arc
		(start 284.442916 -67.6402)
		(mid 284.435335 -67.746867)
		(end 284.5054 -67.827652)
		(stroke
			(width 0.06985)
			(type default)
		)
		(layer "In9.Cu")
	)
	(gr_arc
		(start 284.442916 -63.640208)
		(mid 284.435335 -63.746875)
		(end 284.5054 -63.82766)
		(stroke
			(width 0.06985)
			(type default)
		)
		(layer "In9.Cu")
	)
	(gr_arc
		(start 284.442916 -59.640216)
		(mid 284.435335 -59.746883)
		(end 284.5054 -59.827668)
		(stroke
			(width 0.06985)
			(type default)
		)
		(layer "In9.Cu")
	)
	(gr_arc
		(start 284.442916 -55.640224)
		(mid 284.435335 -55.746891)
		(end 284.5054 -55.827676)
		(stroke
			(width 0.06985)
			(type default)
		)
		(layer "In9.Cu")
	)
	(gr_arc
		(start 284.5054 -116.12753)
		(mid 284.398725 -116.119939)
		(end 284.317948 -116.190014)
		(stroke
			(width 0.06985)
			(type default)
		)
		(layer "In9.Cu")
	)
	(gr_line
		(start 284.5054 -116.12753)
		(end 285.249874 -116.499894)
		(stroke
			(width 0.06985)
			(type default)
		)
		(layer "In9.Cu")
	)
	(gr_line
		(start 284.5054 -83.82762)
		(end 285.249874 -84.199984)
		(stroke
			(width 0.06985)
			(type default)
		)
		(layer "In9.Cu")
	)
	(gr_line
		(start 284.5054 -79.827628)
		(end 285.249874 -80.199992)
		(stroke
			(width 0.06985)
			(type default)
		)
		(layer "In9.Cu")
	)
	(gr_line
		(start 284.5054 -75.827636)
		(end 285.249874 -76.2)
		(stroke
			(width 0.06985)
			(type default)
		)
		(layer "In9.Cu")
	)
	(gr_line
		(start 284.5054 -71.827644)
		(end 285.249874 -72.200008)
		(stroke
			(width 0.06985)
			(type default)
		)
		(layer "In9.Cu")
	)
	(gr_line
		(start 284.5054 -67.827652)
		(end 285.249874 -68.200016)
		(stroke
			(width 0.06985)
			(type default)
		)
		(layer "In9.Cu")
	)
	(gr_line
		(start 284.5054 -63.82766)
		(end 285.249874 -64.200024)
		(stroke
			(width 0.06985)
			(type default)
		)
		(layer "In9.Cu")
	)
	(gr_line
		(start 284.5054 -59.827668)
		(end 285.249874 -60.200032)
		(stroke
			(width 0.06985)
			(type default)
		)
		(layer "In9.Cu")
	)
	(gr_line
		(start 284.5054 -55.827676)
		(end 285.249874 -56.20004)
		(stroke
			(width 0.06985)
			(type default)
		)
		(layer "In9.Cu")
	)
	(gr_arc
		(start 284.505654 -180.127656)
		(mid 284.399004 -180.120093)
		(end 284.318202 -180.19014)
		(stroke
			(width 0.06985)
			(type default)
		)
		(layer "In9.Cu")
	)
	(gr_line
		(start 284.505654 -180.127656)
		(end 285.249874 -180.499766)
		(stroke
			(width 0.06985)
			(type default)
		)
		(layer "In9.Cu")
	)
	(gr_arc
		(start 284.505654 -176.127664)
		(mid 284.399005 -176.1201)
		(end 284.318202 -176.190148)
		(stroke
			(width 0.06985)
			(type default)
		)
		(layer "In9.Cu")
	)
	(gr_line
		(start 284.505654 -176.127664)
		(end 285.249874 -176.499774)
		(stroke
			(width 0.06985)
			(type default)
		)
		(layer "In9.Cu")
	)
	(gr_arc
		(start 284.505654 -172.127672)
		(mid 284.399005 -172.120107)
		(end 284.318202 -172.190156)
		(stroke
			(width 0.06985)
			(type default)
		)
		(layer "In9.Cu")
	)
	(gr_line
		(start 284.505654 -172.127672)
		(end 285.249874 -172.499782)
		(stroke
			(width 0.06985)
			(type default)
		)
		(layer "In9.Cu")
	)
	(gr_arc
		(start 284.505654 -168.12768)
		(mid 284.399006 -168.120115)
		(end 284.318202 -168.190164)
		(stroke
			(width 0.06985)
			(type default)
		)
		(layer "In9.Cu")
	)
	(gr_line
		(start 284.505654 -168.12768)
		(end 285.249874 -168.49979)
		(stroke
			(width 0.06985)
			(type default)
		)
		(layer "In9.Cu")
	)
	(gr_arc
		(start 284.505654 -164.127688)
		(mid 284.398999 -164.12013)
		(end 284.318202 -164.190172)
		(stroke
			(width 0.06985)
			(type default)
		)
		(layer "In9.Cu")
	)
	(gr_line
		(start 284.505654 -164.127688)
		(end 285.249874 -164.499798)
		(stroke
			(width 0.06985)
			(type default)
		)
		(layer "In9.Cu")
	)
	(gr_arc
		(start 284.505654 -160.127696)
		(mid 284.399 -160.120137)
		(end 284.318202 -160.19018)
		(stroke
			(width 0.06985)
			(type default)
		)
		(layer "In9.Cu")
	)
	(gr_line
		(start 284.505654 -160.127696)
		(end 285.249874 -160.499806)
		(stroke
			(width 0.06985)
			(type default)
		)
		(layer "In9.Cu")
	)
	(gr_arc
		(start 284.505654 -156.127704)
		(mid 284.399 -156.120145)
		(end 284.318202 -156.190188)
		(stroke
			(width 0.06985)
			(type default)
		)
		(layer "In9.Cu")
	)
	(gr_line
		(start 284.505654 -156.127704)
		(end 285.249874 -156.499814)
		(stroke
			(width 0.06985)
			(type default)
		)
		(layer "In9.Cu")
	)
	(gr_arc
		(start 284.505654 -152.127712)
		(mid 284.399001 -152.120152)
		(end 284.318202 -152.190196)
		(stroke
			(width 0.06985)
			(type default)
		)
		(layer "In9.Cu")
	)
	(gr_line
		(start 284.505654 -152.127712)
		(end 285.249874 -152.499822)
		(stroke
			(width 0.06985)
			(type default)
		)
		(layer "In9.Cu")
	)
	(gr_arc
		(start 284.505654 -128.12776)
		(mid 284.399004 -128.120196)
		(end 284.318202 -128.190244)
		(stroke
			(width 0.06985)
			(type default)
		)
		(layer "In9.Cu")
	)
	(gr_line
		(start 284.505654 -128.12776)
		(end 285.249874 -128.49987)
		(stroke
			(width 0.06985)
			(type default)
		)
		(layer "In9.Cu")
	)
	(gr_arc
		(start 284.505654 -124.127768)
		(mid 284.399005 -124.120204)
		(end 284.318202 -124.190252)
		(stroke
			(width 0.06985)
			(type default)
		)
		(layer "In9.Cu")
	)
	(gr_line
		(start 284.505654 -124.127768)
		(end 285.249874 -124.499878)
		(stroke
			(width 0.06985)
			(type default)
		)
		(layer "In9.Cu")
	)
	(gr_arc
		(start 284.505654 -120.127776)
		(mid 284.399005 -120.120211)
		(end 284.318202 -120.19026)
		(stroke
			(width 0.06985)
			(type default)
		)
		(layer "In9.Cu")
	)
	(gr_line
		(start 284.505654 -120.127776)
		(end 285.249874 -120.499886)
		(stroke
			(width 0.06985)
			(type default)
		)
		(layer "In9.Cu")
	)
	(gr_arc
		(start 284.505654 -51.827938)
		(mid 284.398987 -51.820357)
		(end 284.318202 -51.890422)
		(stroke
			(width 0.06985)
			(type default)
		)
		(layer "In9.Cu")
	)
	(gr_line
		(start 284.505654 -51.827938)
		(end 285.249874 -52.200048)
		(stroke
			(width 0.06985)
			(type default)
		)
		(layer "In9.Cu")
	)
	(gr_arc
		(start 284.505654 -47.827946)
		(mid 284.398987 -47.820365)
		(end 284.318202 -47.89043)
		(stroke
			(width 0.06985)
			(type default)
		)
		(layer "In9.Cu")
	)
	(gr_line
		(start 284.505654 -47.827946)
		(end 285.249874 -48.200056)
		(stroke
			(width 0.06985)
			(type default)
		)
		(layer "In9.Cu")
	)
	(gr_arc
		(start 284.505654 -43.827954)
		(mid 284.398987 -43.820373)
		(end 284.318202 -43.890438)
		(stroke
			(width 0.06985)
			(type default)
		)
		(layer "In9.Cu")
	)
	(gr_line
		(start 284.505654 -43.827954)
		(end 285.249874 -44.200064)
		(stroke
			(width 0.06985)
			(type default)
		)
		(layer "In9.Cu")
	)
	(gr_arc
		(start 284.505654 -39.827962)
		(mid 284.399004 -39.820398)
		(end 284.318202 -39.890446)
		(stroke
			(width 0.06985)
			(type default)
		)
		(layer "In9.Cu")
	)
	(gr_line
		(start 284.505654 -39.827962)
		(end 285.249874 -40.200072)
		(stroke
			(width 0.06985)
			(type default)
		)
		(layer "In9.Cu")
	)
	(gr_line
		(start 284.527752 -92.502482)
		(end 285.137352 -92.368116)
		(stroke
			(width 0.06985)
			(type default)
		)
		(layer "In9.Cu")
	)
	(gr_line
		(start 284.53461 -92.058744)
		(end 284.943804 -91.968574)
		(stroke
			(width 0.06985)
			(type default)
		)
		(layer "In9.Cu")
	)
	(gr_line
		(start 284.577536 -93.886274)
		(end 284.740858 -93.990668)
		(stroke
			(width 0.06985)
			(type default)
		)
		(layer "In9.Cu")
	)
	(gr_line
		(start 284.754574 -95.54718)
		(end 284.917896 -95.651828)
		(stroke
			(width 0.06985)
			(type default)
		)
		(layer "In9.Cu")
	)
	(gr_line
		(start 284.943804 -91.968574)
		(end 285.10738 -92.072968)
		(stroke
			(width 0.06985)
			(type default)
		)
		(layer "In9.Cu")
	)
	(gr_line
		(start 284.945836 -188.855858)
		(end 284.964886 -188.849762)
		(stroke
			(width 0.06985)
			(type default)
		)
		(layer "In9.Cu")
	)
	(gr_line
		(start 284.94863 -90.4748)
		(end 285.053024 -90.311224)
		(stroke
			(width 0.06985)
			(type default)
		)
		(layer "In9.Cu")
	)
	(gr_line
		(start 284.964886 -188.849762)
		(end 284.980126 -188.837062)
		(stroke
			(width 0.06985)
			(type default)
		)
		(layer "In9.Cu")
	)
	(gr_line
		(start 285.047436 -90.754454)
		(end 285.653226 -90.621104)
		(stroke
			(width 0.06985)
			(type default)
		)
		(layer "In9.Cu")
	)
	(gr_line
		(start 285.053024 -90.311224)
		(end 285.462472 -90.221054)
		(stroke
			(width 0.06985)
			(type default)
		)
		(layer "In9.Cu")
	)
	(gr_line
		(start 285.154878 -93.899736)
		(end 285.259526 -93.73616)
		(stroke
			(width 0.06985)
			(type default)
		)
		(layer "In9.Cu")
	)
	(gr_line
		(start 285.254192 -94.17939)
		(end 285.859982 -94.04604)
		(stroke
			(width 0.06985)
			(type default)
		)
		(layer "In9.Cu")
	)
	(gr_line
		(start 285.259526 -93.73616)
		(end 285.668974 -93.64599)
		(stroke
			(width 0.06985)
			(type default)
		)
		(layer "In9.Cu")
	)
	(gr_line
		(start 285.331916 -95.56115)
		(end 285.436818 -95.397574)
		(stroke
			(width 0.06985)
			(type default)
		)
		(layer "In9.Cu")
	)
	(gr_line
		(start 285.428182 -95.84182)
		(end 286.038798 -95.707708)
		(stroke
			(width 0.06985)
			(type default)
		)
		(layer "In9.Cu")
	)
	(gr_line
		(start 285.436818 -95.397574)
		(end 285.846012 -95.307658)
		(stroke
			(width 0.06985)
			(type default)
		)
		(layer "In9.Cu")
	)
	(gr_line
		(start 285.462472 -90.221054)
		(end 285.625794 -90.325702)
		(stroke
			(width 0.06985)
			(type default)
		)
		(layer "In9.Cu")
	)
	(gr_line
		(start 285.5214 -91.981528)
		(end 285.625794 -91.818206)
		(stroke
			(width 0.06985)
			(type default)
		)
		(layer "In9.Cu")
	)
	(gr_line
		(start 285.613602 -55.346092)
		(end 285.641034 -55.332122)
		(stroke
			(width 0.06985)
			(type default)
		)
		(layer "In9.Cu")
	)
	(gr_line
		(start 285.619444 -92.26169)
		(end 286.227266 -92.127832)
		(stroke
			(width 0.06985)
			(type default)
		)
		(layer "In9.Cu")
	)
	(gr_line
		(start 285.625794 -91.818206)
		(end 286.035242 -91.727782)
		(stroke
			(width 0.06985)
			(type default)
		)
		(layer "In9.Cu")
	)
	(gr_line
		(start 285.668974 -93.64599)
		(end 285.832296 -93.750638)
		(stroke
			(width 0.06985)
			(type default)
		)
		(layer "In9.Cu")
	)
	(gr_line
		(start 285.735776 -67.346068)
		(end 285.776924 -67.318636)
		(stroke
			(width 0.06985)
			(type default)
		)
		(layer "In9.Cu")
	)
	(gr_line
		(start 285.846012 -95.307658)
		(end 286.009588 -95.41256)
		(stroke
			(width 0.06985)
			(type default)
		)
		(layer "In9.Cu")
	)
	(gr_line
		(start 285.96463 -184.401714)
		(end 285.968186 -184.398666)
		(stroke
			(width 0.06985)
			(type default)
		)
		(layer "In9.Cu")
	)
	(gr_line
		(start 285.968186 -184.398666)
		(end 285.97098 -184.394856)
		(stroke
			(width 0.06985)
			(type default)
		)
		(layer "In9.Cu")
	)
	(gr_line
		(start 286.005778 -190.086234)
		(end 286.024828 -190.080138)
		(stroke
			(width 0.06985)
			(type default)
		)
		(layer "In9.Cu")
	)
	(gr_line
		(start 286.024828 -190.080138)
		(end 286.040068 -190.067438)
		(stroke
			(width 0.06985)
			(type default)
		)
		(layer "In9.Cu")
	)
	(gr_line
		(start 286.035242 -91.727782)
		(end 286.198818 -91.83243)
		(stroke
			(width 0.06985)
			(type default)
		)
		(layer "In9.Cu")
	)
	(gr_line
		(start 286.040068 -90.234516)
		(end 286.144462 -90.07094)
		(stroke
			(width 0.06985)
			(type default)
		)
		(layer "In9.Cu")
	)
	(gr_line
		(start 286.13989 -90.513916)
		(end 286.744156 -90.38082)
		(stroke
			(width 0.06985)
			(type default)
		)
		(layer "In9.Cu")
	)
	(gr_line
		(start 286.144462 -90.07094)
		(end 286.55391 -89.98077)
		(stroke
			(width 0.06985)
			(type default)
		)
		(layer "In9.Cu")
	)
	(gr_line
		(start 286.246316 -93.659452)
		(end 286.350964 -93.495876)
		(stroke
			(width 0.06985)
			(type default)
		)
		(layer "In9.Cu")
	)
	(gr_line
		(start 286.344614 -93.93936)
		(end 286.951674 -93.805756)
		(stroke
			(width 0.06985)
			(type default)
		)
		(layer "In9.Cu")
	)
	(gr_line
		(start 286.350964 -93.495876)
		(end 286.760412 -93.405706)
		(stroke
			(width 0.06985)
			(type default)
		)
		(layer "In9.Cu")
	)
	(gr_line
		(start 286.423608 -95.321628)
		(end 286.52851 -95.158052)
		(stroke
			(width 0.06985)
			(type default)
		)
		(layer "In9.Cu")
	)
	(gr_line
		(start 286.511746 -75.155552)
		(end 286.53105 -75.151488)
		(stroke
			(width 0.06985)
			(type default)
		)
		(layer "In9.Cu")
	)
	(gr_line
		(start 286.519112 -95.602552)
		(end 287.13176 -95.468186)
		(stroke
			(width 0.06985)
			(type default)
		)
		(layer "In9.Cu")
	)
	(gr_line
		(start 286.52851 -95.158052)
		(end 286.937704 -95.06839)
		(stroke
			(width 0.06985)
			(type default)
		)
		(layer "In9.Cu")
	)
	(gr_line
		(start 286.53105 -75.151488)
		(end 286.54756 -75.140566)
		(stroke
			(width 0.06985)
			(type default)
		)
		(layer "In9.Cu")
	)
	(gr_line
		(start 286.55391 -89.98077)
		(end 286.717232 -90.085418)
		(stroke
			(width 0.06985)
			(type default)
		)
		(layer "In9.Cu")
	)
	(gr_line
		(start 286.610298 -71.203058)
		(end 286.629856 -71.198994)
		(stroke
			(width 0.06985)
			(type default)
		)
		(layer "In9.Cu")
	)
	(gr_line
		(start 286.613092 -91.74099)
		(end 286.717232 -91.577668)
		(stroke
			(width 0.06985)
			(type default)
		)
		(layer "In9.Cu")
	)
	(gr_line
		(start 286.629856 -71.198994)
		(end 286.646366 -71.188072)
		(stroke
			(width 0.06985)
			(type default)
		)
		(layer "In9.Cu")
	)
	(gr_line
		(start 286.712152 -92.020898)
		(end 287.318958 -91.887294)
		(stroke
			(width 0.06985)
			(type default)
		)
		(layer "In9.Cu")
	)
	(gr_line
		(start 286.717232 -91.577668)
		(end 287.12668 -91.487244)
		(stroke
			(width 0.06985)
			(type default)
		)
		(layer "In9.Cu")
	)
	(gr_line
		(start 286.760412 -93.405706)
		(end 286.923734 -93.510354)
		(stroke
			(width 0.06985)
			(type default)
		)
		(layer "In9.Cu")
	)
	(gr_line
		(start 286.850328 -63.081662)
		(end 286.869886 -63.077598)
		(stroke
			(width 0.06985)
			(type default)
		)
		(layer "In9.Cu")
	)
	(gr_line
		(start 286.869886 -63.077598)
		(end 286.886396 -63.066676)
		(stroke
			(width 0.06985)
			(type default)
		)
		(layer "In9.Cu")
	)
	(gr_line
		(start 286.912812 -59.039506)
		(end 286.931608 -59.035696)
		(stroke
			(width 0.06985)
			(type default)
		)
		(layer "In9.Cu")
	)
	(gr_line
		(start 286.931608 -59.035696)
		(end 286.94761 -59.025282)
		(stroke
			(width 0.06985)
			(type default)
		)
		(layer "In9.Cu")
	)
	(gr_line
		(start 286.937704 -95.06839)
		(end 287.10128 -95.173038)
		(stroke
			(width 0.06985)
			(type default)
		)
		(layer "In9.Cu")
	)
	(gr_line
		(start 287.12668 -91.487244)
		(end 287.290002 -91.591892)
		(stroke
			(width 0.06985)
			(type default)
		)
		(layer "In9.Cu")
	)
	(gr_line
		(start 287.131506 -89.994232)
		(end 287.236154 -89.830656)
		(stroke
			(width 0.06985)
			(type default)
		)
		(layer "In9.Cu")
	)
	(gr_line
		(start 287.231328 -90.273632)
		(end 287.835594 -90.140536)
		(stroke
			(width 0.06985)
			(type default)
		)
		(layer "In9.Cu")
	)
	(gr_line
		(start 287.236154 -89.830656)
		(end 287.645348 -89.740486)
		(stroke
			(width 0.06985)
			(type default)
		)
		(layer "In9.Cu")
	)
	(gr_line
		(start 287.315402 -185.001154)
		(end 287.318958 -184.998106)
		(stroke
			(width 0.06985)
			(type default)
		)
		(layer "In9.Cu")
	)
	(gr_line
		(start 287.318958 -184.998106)
		(end 287.320228 -184.998106)
		(stroke
			(width 0.06985)
			(type default)
		)
		(layer "In9.Cu")
	)
	(gr_line
		(start 287.320228 -184.998106)
		(end 287.327086 -184.9882)
		(stroke
			(width 0.06985)
			(type default)
		)
		(layer "In9.Cu")
	)
	(gr_line
		(start 287.645348 -89.740486)
		(end 287.808924 -89.845134)
		(stroke
			(width 0.06985)
			(type default)
		)
		(layer "In9.Cu")
	)
	(gr_line
		(start 287.87725 -65.769998)
		(end 288.41192 -65.499234)
		(stroke
			(width 0.06985)
			(type default)
		)
		(layer "In9.Cu")
	)
	(gr_line
		(start 287.902904 -183.387492)
		(end 287.938464 -183.57977)
		(stroke
			(width 0.06985)
			(type default)
		)
		(layer "In9.Cu")
	)
	(gr_line
		(start 287.902904 -183.387492)
		(end 288.140648 -183.042306)
		(stroke
			(width 0.06985)
			(type default)
		)
		(layer "In9.Cu")
	)
	(gr_arc
		(start 287.946592 -299.370242)
		(mid 287.958346 -299.369614)
		(end 287.96996 -299.367702)
		(stroke
			(width 0.053848)
			(type default)
		)
		(layer "In9.Cu")
	)
	(gr_line
		(start 287.977834 -66.049144)
		(end 288.148776 -66.105024)
		(stroke
			(width 0.06985)
			(type default)
		)
		(layer "In9.Cu")
	)
	(gr_line
		(start 287.986724 -69.95033)
		(end 288.489644 -69.61759)
		(stroke
			(width 0.06985)
			(type default)
		)
		(layer "In9.Cu")
	)
	(gr_line
		(start 288.11982 -70.21576)
		(end 288.295842 -70.251574)
		(stroke
			(width 0.06985)
			(type default)
		)
		(layer "In9.Cu")
	)
	(gr_line
		(start 288.140648 -183.042306)
		(end 288.332926 -183.006492)
		(stroke
			(width 0.06985)
			(type default)
		)
		(layer "In9.Cu")
	)
	(gr_line
		(start 288.148776 -66.105024)
		(end 288.522664 -65.915794)
		(stroke
			(width 0.06985)
			(type default)
		)
		(layer "In9.Cu")
	)
	(gr_line
		(start 288.196528 -183.725058)
		(end 288.56178 -183.194452)
		(stroke
			(width 0.06985)
			(type default)
		)
		(layer "In9.Cu")
	)
	(gr_line
		(start 288.295842 -70.251574)
		(end 288.645346 -70.02018)
		(stroke
			(width 0.06985)
			(type default)
		)
		(layer "In9.Cu")
	)
	(gr_arc
		(start 288.315146 -347.970094)
		(mid 288.3269 -347.969472)
		(end 288.338514 -347.967554)
		(stroke
			(width 0.053848)
			(type default)
		)
		(layer "In9.Cu")
	)
	(gr_line
		(start 288.388806 -180.11521)
		(end 288.424366 -180.306218)
		(stroke
			(width 0.06985)
			(type default)
		)
		(layer "In9.Cu")
	)
	(gr_line
		(start 288.388806 -180.11521)
		(end 288.626296 -179.770024)
		(stroke
			(width 0.06985)
			(type default)
		)
		(layer "In9.Cu")
	)
	(gr_line
		(start 288.417254 -338.781644)
		(end 288.434272 -338.778088)
		(stroke
			(width 0.053848)
			(type default)
		)
		(layer "In9.Cu")
	)
	(gr_line
		(start 288.434272 -338.778088)
		(end 288.44875 -338.76869)
		(stroke
			(width 0.053848)
			(type default)
		)
		(layer "In9.Cu")
	)
	(gr_line
		(start 288.43986 -65.48501)
		(end 288.673286 -65.366646)
		(stroke
			(width 0.06985)
			(type default)
		)
		(layer "In9.Cu")
	)
	(gr_arc
		(start 288.482786 -301.170086)
		(mid 288.49454 -301.169459)
		(end 288.506154 -301.167546)
		(stroke
			(width 0.053848)
			(type default)
		)
		(layer "In9.Cu")
	)
	(gr_line
		(start 288.485834 -317.151766)
		(end 288.502852 -317.14821)
		(stroke
			(width 0.053848)
			(type default)
		)
		(layer "In9.Cu")
	)
	(gr_line
		(start 288.502852 -317.14821)
		(end 288.51733 -317.138812)
		(stroke
			(width 0.053848)
			(type default)
		)
		(layer "In9.Cu")
	)
	(gr_line
		(start 288.522664 -65.915794)
		(end 288.57829 -65.745106)
		(stroke
			(width 0.06985)
			(type default)
		)
		(layer "In9.Cu")
	)
	(gr_line
		(start 288.536634 -182.466742)
		(end 288.572194 -182.65902)
		(stroke
			(width 0.06985)
			(type default)
		)
		(layer "In9.Cu")
	)
	(gr_line
		(start 288.536634 -182.466742)
		(end 288.774124 -182.121556)
		(stroke
			(width 0.06985)
			(type default)
		)
		(layer "In9.Cu")
	)
	(gr_line
		(start 288.57956 -65.74155)
		(end 288.766758 -65.646808)
		(stroke
			(width 0.06985)
			(type default)
		)
		(layer "In9.Cu")
	)
	(gr_line
		(start 288.626296 -179.770024)
		(end 288.81705 -179.734718)
		(stroke
			(width 0.06985)
			(type default)
		)
		(layer "In9.Cu")
	)
	(gr_line
		(start 288.637726 -53.486812)
		(end 289.191954 -53.206142)
		(stroke
			(width 0.06985)
			(type default)
		)
		(layer "In9.Cu")
	)
	(gr_line
		(start 288.645346 -70.02018)
		(end 288.68116 -69.843904)
		(stroke
			(width 0.06985)
			(type default)
		)
		(layer "In9.Cu")
	)
	(gr_line
		(start 288.687002 -180.44414)
		(end 289.040062 -179.930552)
		(stroke
			(width 0.06985)
			(type default)
		)
		(layer "In9.Cu")
	)
	(gr_line
		(start 288.73831 -53.765958)
		(end 288.922714 -53.82641)
		(stroke
			(width 0.06985)
			(type default)
		)
		(layer "In9.Cu")
	)
	(gr_line
		(start 288.752534 -61.4807)
		(end 289.257232 -61.146436)
		(stroke
			(width 0.06985)
			(type default)
		)
		(layer "In9.Cu")
	)
	(gr_line
		(start 288.774124 -182.121556)
		(end 288.966402 -182.085996)
		(stroke
			(width 0.06985)
			(type default)
		)
		(layer "In9.Cu")
	)
	(gr_line
		(start 288.82975 -182.804562)
		(end 289.193732 -182.275734)
		(stroke
			(width 0.06985)
			(type default)
		)
		(layer "In9.Cu")
	)
	(gr_line
		(start 288.856166 -65.27419)
		(end 289.390836 -65.003426)
		(stroke
			(width 0.06985)
			(type default)
		)
		(layer "In9.Cu")
	)
	(gr_line
		(start 288.873946 -344.039952)
		(end 288.8742 -344.039952)
		(stroke
			(width 0.053848)
			(type default)
		)
		(layer "In9.Cu")
	)
	(gr_line
		(start 288.88563 -61.74613)
		(end 289.061906 -61.781944)
		(stroke
			(width 0.06985)
			(type default)
		)
		(layer "In9.Cu")
	)
	(gr_line
		(start 288.900362 -69.345556)
		(end 289.404298 -69.012054)
		(stroke
			(width 0.06985)
			(type default)
		)
		(layer "In9.Cu")
	)
	(gr_line
		(start 288.922714 -53.82641)
		(end 289.296602 -53.63718)
		(stroke
			(width 0.06985)
			(type default)
		)
		(layer "In9.Cu")
	)
	(gr_line
		(start 288.9377 -344.370152)
		(end 288.942272 -344.36558)
		(stroke
			(width 0.053848)
			(type default)
		)
		(layer "In9.Cu")
	)
	(gr_line
		(start 288.945574 -344.362278)
		(end 288.954464 -344.360246)
		(stroke
			(width 0.053848)
			(type default)
		)
		(layer "In9.Cu")
	)
	(gr_line
		(start 288.95675 -65.553336)
		(end 289.127692 -65.609216)
		(stroke
			(width 0.06985)
			(type default)
		)
		(layer "In9.Cu")
	)
	(gr_line
		(start 289.022028 -179.19446)
		(end 289.057334 -179.38496)
		(stroke
			(width 0.06985)
			(type default)
		)
		(layer "In9.Cu")
	)
	(gr_line
		(start 289.022028 -179.19446)
		(end 289.259518 -178.84902)
		(stroke
			(width 0.06985)
			(type default)
		)
		(layer "In9.Cu")
	)
	(gr_line
		(start 289.034728 -69.610224)
		(end 289.211004 -69.646038)
		(stroke
			(width 0.06985)
			(type default)
		)
		(layer "In9.Cu")
	)
	(gr_line
		(start 289.03803 -324.428358)
		(end 289.055048 -324.424802)
		(stroke
			(width 0.053848)
			(type default)
		)
		(layer "In9.Cu")
	)
	(gr_line
		(start 289.055048 -324.424802)
		(end 289.069526 -324.415404)
		(stroke
			(width 0.053848)
			(type default)
		)
		(layer "In9.Cu")
	)
	(gr_line
		(start 289.061906 -61.781944)
		(end 289.41141 -61.550804)
		(stroke
			(width 0.06985)
			(type default)
		)
		(layer "In9.Cu")
	)
	(gr_line
		(start 289.10788 -320.668142)
		(end 289.124898 -320.664586)
		(stroke
			(width 0.053848)
			(type default)
		)
		(layer "In9.Cu")
	)
	(gr_line
		(start 289.124898 -320.664586)
		(end 289.139376 -320.655188)
		(stroke
			(width 0.053848)
			(type default)
		)
		(layer "In9.Cu")
	)
	(gr_line
		(start 289.127692 -65.609216)
		(end 289.501326 -65.419986)
		(stroke
			(width 0.06985)
			(type default)
		)
		(layer "In9.Cu")
	)
	(gr_line
		(start 289.138106 -73.075292)
		(end 289.642296 -72.741536)
		(stroke
			(width 0.06985)
			(type default)
		)
		(layer "In9.Cu")
	)
	(gr_line
		(start 289.17011 -181.546246)
		(end 289.20567 -181.738524)
		(stroke
			(width 0.06985)
			(type default)
		)
		(layer "In9.Cu")
	)
	(gr_line
		(start 289.17011 -181.546246)
		(end 289.4076 -181.200806)
		(stroke
			(width 0.06985)
			(type default)
		)
		(layer "In9.Cu")
	)
	(gr_line
		(start 289.211004 -69.646038)
		(end 289.560508 -69.414644)
		(stroke
			(width 0.06985)
			(type default)
		)
		(layer "In9.Cu")
	)
	(gr_line
		(start 289.259518 -178.84902)
		(end 289.450272 -178.813714)
		(stroke
			(width 0.06985)
			(type default)
		)
		(layer "In9.Cu")
	)
	(gr_line
		(start 289.267138 -185.267346)
		(end 289.268154 -185.266584)
		(stroke
			(width 0.06985)
			(type default)
		)
		(layer "In9.Cu")
	)
	(gr_line
		(start 289.268154 -185.266584)
		(end 289.26917 -185.265314)
		(stroke
			(width 0.06985)
			(type default)
		)
		(layer "In9.Cu")
	)
	(gr_line
		(start 289.271964 -73.340214)
		(end 289.44824 -73.376028)
		(stroke
			(width 0.06985)
			(type default)
		)
		(layer "In9.Cu")
	)
	(gr_line
		(start 289.288728 -318.937894)
		(end 289.305746 -318.934338)
		(stroke
			(width 0.053848)
			(type default)
		)
		(layer "In9.Cu")
	)
	(gr_line
		(start 289.296602 -53.63718)
		(end 289.357054 -53.452522)
		(stroke
			(width 0.06985)
			(type default)
		)
		(layer "In9.Cu")
	)
	(gr_line
		(start 289.296856 -322.543678)
		(end 289.313874 -322.540122)
		(stroke
			(width 0.053848)
			(type default)
		)
		(layer "In9.Cu")
	)
	(gr_line
		(start 289.305746 -318.934338)
		(end 289.320224 -318.92494)
		(stroke
			(width 0.053848)
			(type default)
		)
		(layer "In9.Cu")
	)
	(gr_line
		(start 289.313874 -322.540122)
		(end 289.328352 -322.530724)
		(stroke
			(width 0.053848)
			(type default)
		)
		(layer "In9.Cu")
	)
	(gr_line
		(start 289.320224 -179.522882)
		(end 289.672776 -179.01031)
		(stroke
			(width 0.06985)
			(type default)
		)
		(layer "In9.Cu")
	)
	(gr_line
		(start 289.4076 -181.200806)
		(end 289.599878 -181.165246)
		(stroke
			(width 0.06985)
			(type default)
		)
		(layer "In9.Cu")
	)
	(gr_line
		(start 289.41141 -61.550804)
		(end 289.447478 -61.374274)
		(stroke
			(width 0.06985)
			(type default)
		)
		(layer "In9.Cu")
	)
	(gr_line
		(start 289.44824 -73.376028)
		(end 289.797744 -73.144634)
		(stroke
			(width 0.06985)
			(type default)
		)
		(layer "In9.Cu")
	)
	(gr_line
		(start 289.46348 -181.883558)
		(end 289.827716 -181.354476)
		(stroke
			(width 0.06985)
			(type default)
		)
		(layer "In9.Cu")
	)
	(gr_line
		(start 289.501326 -65.419986)
		(end 289.55746 -65.249298)
		(stroke
			(width 0.06985)
			(type default)
		)
		(layer "In9.Cu")
	)
	(gr_line
		(start 289.558476 -65.245742)
		(end 289.644582 -65.202054)
		(stroke
			(width 0.06985)
			(type default)
		)
		(layer "In9.Cu")
	)
	(gr_line
		(start 289.560508 -69.414644)
		(end 289.596068 -69.238368)
		(stroke
			(width 0.06985)
			(type default)
		)
		(layer "In9.Cu")
	)
	(gr_line
		(start 289.634676 -52.98186)
		(end 290.188142 -52.701444)
		(stroke
			(width 0.06985)
			(type default)
		)
		(layer "In9.Cu")
	)
	(gr_line
		(start 289.65525 -178.273456)
		(end 289.690556 -178.464464)
		(stroke
			(width 0.06985)
			(type default)
		)
		(layer "In9.Cu")
	)
	(gr_line
		(start 289.65525 -178.273456)
		(end 289.892486 -177.928016)
		(stroke
			(width 0.06985)
			(type default)
		)
		(layer "In9.Cu")
	)
	(gr_line
		(start 289.666934 -60.875672)
		(end 290.169854 -60.542932)
		(stroke
			(width 0.06985)
			(type default)
		)
		(layer "In9.Cu")
	)
	(gr_line
		(start 289.673792 -326.081644)
		(end 289.69208 -326.07758)
		(stroke
			(width 0.053848)
			(type default)
		)
		(layer "In9.Cu")
	)
	(gr_line
		(start 289.674554 -183.918098)
		(end 289.709606 -184.109106)
		(stroke
			(width 0.06985)
			(type default)
		)
		(layer "In9.Cu")
	)
	(gr_line
		(start 289.674554 -183.918098)
		(end 289.912806 -183.573166)
		(stroke
			(width 0.06985)
			(type default)
		)
		(layer "In9.Cu")
	)
	(gr_line
		(start 289.69208 -326.07758)
		(end 289.707066 -326.067928)
		(stroke
			(width 0.053848)
			(type default)
		)
		(layer "In9.Cu")
	)
	(gr_line
		(start 289.73526 -53.261006)
		(end 289.919664 -53.321458)
		(stroke
			(width 0.06985)
			(type default)
		)
		(layer "In9.Cu")
	)
	(gr_line
		(start 289.736784 -340.47557)
		(end 289.753802 -340.472014)
		(stroke
			(width 0.053848)
			(type default)
		)
		(layer "In9.Cu")
	)
	(gr_line
		(start 289.753802 -340.472014)
		(end 289.76828 -340.462616)
		(stroke
			(width 0.053848)
			(type default)
		)
		(layer "In9.Cu")
	)
	(gr_line
		(start 289.797744 -73.144634)
		(end 289.833558 -72.968358)
		(stroke
			(width 0.06985)
			(type default)
		)
		(layer "In9.Cu")
	)
	(gr_line
		(start 289.800538 -61.140594)
		(end 289.976814 -61.176408)
		(stroke
			(width 0.06985)
			(type default)
		)
		(layer "In9.Cu")
	)
	(gr_line
		(start 289.803586 -180.625496)
		(end 289.839146 -180.818028)
		(stroke
			(width 0.06985)
			(type default)
		)
		(layer "In9.Cu")
	)
	(gr_line
		(start 289.803586 -180.625496)
		(end 290.041076 -180.28031)
		(stroke
			(width 0.06985)
			(type default)
		)
		(layer "In9.Cu")
	)
	(gr_line
		(start 289.815778 -68.739766)
		(end 290.319968 -68.40601)
		(stroke
			(width 0.06985)
			(type default)
		)
		(layer "In9.Cu")
	)
	(gr_line
		(start 289.835082 -64.778382)
		(end 290.369752 -64.507618)
		(stroke
			(width 0.06985)
			(type default)
		)
		(layer "In9.Cu")
	)
	(gr_line
		(start 289.839146 -56.761888)
		(end 290.341812 -56.429402)
		(stroke
			(width 0.06985)
			(type default)
		)
		(layer "In9.Cu")
	)
	(gr_line
		(start 289.883596 -344.154252)
		(end 289.900614 -344.150696)
		(stroke
			(width 0.053848)
			(type default)
		)
		(layer "In9.Cu")
	)
	(gr_line
		(start 289.892486 -177.928016)
		(end 290.083494 -177.892456)
		(stroke
			(width 0.06985)
			(type default)
		)
		(layer "In9.Cu")
	)
	(gr_line
		(start 289.893248 -298.94149)
		(end 289.910266 -298.937934)
		(stroke
			(width 0.053848)
			(type default)
		)
		(layer "In9.Cu")
	)
	(gr_line
		(start 289.900614 -344.150696)
		(end 289.915092 -344.141298)
		(stroke
			(width 0.053848)
			(type default)
		)
		(layer "In9.Cu")
	)
	(gr_line
		(start 289.910266 -298.937934)
		(end 289.924744 -298.928536)
		(stroke
			(width 0.053848)
			(type default)
		)
		(layer "In9.Cu")
	)
	(gr_line
		(start 289.912806 -183.573166)
		(end 290.103814 -183.538114)
		(stroke
			(width 0.06985)
			(type default)
		)
		(layer "In9.Cu")
	)
	(gr_line
		(start 289.919664 -53.321458)
		(end 290.293552 -53.132228)
		(stroke
			(width 0.06985)
			(type default)
		)
		(layer "In9.Cu")
	)
	(gr_line
		(start 289.935666 -65.057528)
		(end 290.106354 -65.113408)
		(stroke
			(width 0.06985)
			(type default)
		)
		(layer "In9.Cu")
	)
	(gr_line
		(start 289.949636 -69.004688)
		(end 290.125912 -69.040248)
		(stroke
			(width 0.06985)
			(type default)
		)
		(layer "In9.Cu")
	)
	(gr_line
		(start 289.953446 -178.601878)
		(end 290.30676 -178.088036)
		(stroke
			(width 0.06985)
			(type default)
		)
		(layer "In9.Cu")
	)
	(gr_line
		(start 289.972242 -57.027318)
		(end 290.148264 -57.063132)
		(stroke
			(width 0.06985)
			(type default)
		)
		(layer "In9.Cu")
	)
	(gr_line
		(start 289.972496 -184.246266)
		(end 290.324794 -183.736234)
		(stroke
			(width 0.06985)
			(type default)
		)
		(layer "In9.Cu")
	)
	(gr_line
		(start 289.976814 -61.176408)
		(end 290.326318 -60.945014)
		(stroke
			(width 0.06985)
			(type default)
		)
		(layer "In9.Cu")
	)
	(gr_line
		(start 290.041076 -180.28031)
		(end 290.233608 -180.244496)
		(stroke
			(width 0.06985)
			(type default)
		)
		(layer "In9.Cu")
	)
	(gr_line
		(start 290.051744 -72.470518)
		(end 290.55695 -72.136254)
		(stroke
			(width 0.06985)
			(type default)
		)
		(layer "In9.Cu")
	)
	(gr_line
		(start 290.096702 -180.963316)
		(end 290.4617 -180.432964)
		(stroke
			(width 0.06985)
			(type default)
		)
		(layer "In9.Cu")
	)
	(gr_line
		(start 290.106354 -65.113408)
		(end 290.480242 -64.924178)
		(stroke
			(width 0.06985)
			(type default)
		)
		(layer "In9.Cu")
	)
	(gr_line
		(start 290.125912 -69.040248)
		(end 290.475416 -68.809108)
		(stroke
			(width 0.06985)
			(type default)
		)
		(layer "In9.Cu")
	)
	(gr_line
		(start 290.142676 -342.103202)
		(end 290.159694 -342.099646)
		(stroke
			(width 0.053848)
			(type default)
		)
		(layer "In9.Cu")
	)
	(gr_line
		(start 290.148264 -57.063132)
		(end 290.497768 -56.831992)
		(stroke
			(width 0.06985)
			(type default)
		)
		(layer "In9.Cu")
	)
	(gr_line
		(start 290.159694 -342.099646)
		(end 290.174172 -342.090248)
		(stroke
			(width 0.053848)
			(type default)
		)
		(layer "In9.Cu")
	)
	(gr_line
		(start 290.186872 -72.734424)
		(end 290.363148 -72.770492)
		(stroke
			(width 0.06985)
			(type default)
		)
		(layer "In9.Cu")
	)
	(gr_line
		(start 290.288218 -177.352452)
		(end 290.323524 -177.543206)
		(stroke
			(width 0.06985)
			(type default)
		)
		(layer "In9.Cu")
	)
	(gr_line
		(start 290.288218 -177.352452)
		(end 290.525708 -177.007012)
		(stroke
			(width 0.06985)
			(type default)
		)
		(layer "In9.Cu")
	)
	(gr_line
		(start 290.293552 -53.132228)
		(end 290.354004 -52.94757)
		(stroke
			(width 0.06985)
			(type default)
		)
		(layer "In9.Cu")
	)
	(gr_line
		(start 290.309808 -182.998364)
		(end 290.34486 -183.189118)
		(stroke
			(width 0.06985)
			(type default)
		)
		(layer "In9.Cu")
	)
	(gr_line
		(start 290.309808 -182.998364)
		(end 290.547806 -182.653686)
		(stroke
			(width 0.06985)
			(type default)
		)
		(layer "In9.Cu")
	)
	(gr_line
		(start 290.326318 -60.945014)
		(end 290.362132 -60.768738)
		(stroke
			(width 0.06985)
			(type default)
		)
		(layer "In9.Cu")
	)
	(gr_line
		(start 290.363148 -72.770492)
		(end 290.712652 -72.539098)
		(stroke
			(width 0.06985)
			(type default)
		)
		(layer "In9.Cu")
	)
	(gr_line
		(start 290.475416 -68.809108)
		(end 290.51123 -68.632578)
		(stroke
			(width 0.06985)
			(type default)
		)
		(layer "In9.Cu")
	)
	(gr_line
		(start 290.480242 -64.924178)
		(end 290.536376 -64.753236)
		(stroke
			(width 0.06985)
			(type default)
		)
		(layer "In9.Cu")
	)
	(gr_line
		(start 290.497768 -56.831992)
		(end 290.533582 -56.655716)
		(stroke
			(width 0.06985)
			(type default)
		)
		(layer "In9.Cu")
	)
	(gr_line
		(start 290.525708 -177.007012)
		(end 290.716462 -176.97196)
		(stroke
			(width 0.06985)
			(type default)
		)
		(layer "In9.Cu")
	)
	(gr_line
		(start 290.547806 -182.653686)
		(end 290.738814 -182.618634)
		(stroke
			(width 0.06985)
			(type default)
		)
		(layer "In9.Cu")
	)
	(gr_line
		(start 290.582604 -60.269628)
		(end 291.084762 -59.937396)
		(stroke
			(width 0.06985)
			(type default)
		)
		(layer "In9.Cu")
	)
	(gr_line
		(start 290.586668 -177.68062)
		(end 290.938458 -177.169064)
		(stroke
			(width 0.06985)
			(type default)
		)
		(layer "In9.Cu")
	)
	(gr_line
		(start 290.608258 -183.32577)
		(end 290.960048 -182.8165)
		(stroke
			(width 0.06985)
			(type default)
		)
		(layer "In9.Cu")
	)
	(gr_line
		(start 290.630864 -52.477162)
		(end 291.185854 -52.195984)
		(stroke
			(width 0.06985)
			(type default)
		)
		(layer "In9.Cu")
	)
	(gr_line
		(start 290.712652 -72.539098)
		(end 290.748466 -72.362568)
		(stroke
			(width 0.06985)
			(type default)
		)
		(layer "In9.Cu")
	)
	(gr_line
		(start 290.715446 -60.534804)
		(end 290.891976 -60.570618)
		(stroke
			(width 0.06985)
			(type default)
		)
		(layer "In9.Cu")
	)
	(gr_line
		(start 290.73221 -52.756054)
		(end 290.916614 -52.816506)
		(stroke
			(width 0.06985)
			(type default)
		)
		(layer "In9.Cu")
	)
	(gr_line
		(start 290.753292 -56.157114)
		(end 291.256466 -55.82412)
		(stroke
			(width 0.06985)
			(type default)
		)
		(layer "In9.Cu")
	)
	(gr_arc
		(start 290.861242 -300.645068)
		(mid 290.87913 -300.639451)
		(end 290.895786 -300.630844)
		(stroke
			(width 0.053848)
			(type default)
		)
		(layer "In9.Cu")
	)
	(gr_line
		(start 290.88715 -56.422036)
		(end 291.063426 -56.457596)
		(stroke
			(width 0.06985)
			(type default)
		)
		(layer "In9.Cu")
	)
	(gr_line
		(start 290.891976 -60.570618)
		(end 291.24148 -60.339478)
		(stroke
			(width 0.06985)
			(type default)
		)
		(layer "In9.Cu")
	)
	(gr_line
		(start 290.903406 -302.49749)
		(end 290.920424 -302.493934)
		(stroke
			(width 0.053848)
			(type default)
		)
		(layer "In9.Cu")
	)
	(gr_line
		(start 290.916614 -52.816506)
		(end 291.290502 -52.627022)
		(stroke
			(width 0.06985)
			(type default)
		)
		(layer "In9.Cu")
	)
	(gr_line
		(start 290.920424 -302.493934)
		(end 290.934902 -302.484536)
		(stroke
			(width 0.053848)
			(type default)
		)
		(layer "In9.Cu")
	)
	(gr_line
		(start 290.944808 -182.078884)
		(end 290.97986 -182.269638)
		(stroke
			(width 0.06985)
			(type default)
		)
		(layer "In9.Cu")
	)
	(gr_line
		(start 290.944808 -182.078884)
		(end 291.18306 -181.733952)
		(stroke
			(width 0.06985)
			(type default)
		)
		(layer "In9.Cu")
	)
	(gr_line
		(start 290.967668 -71.86422)
		(end 291.472874 -71.529956)
		(stroke
			(width 0.06985)
			(type default)
		)
		(layer "In9.Cu")
	)
	(gr_line
		(start 291.063426 -56.457596)
		(end 291.41293 -56.226456)
		(stroke
			(width 0.06985)
			(type default)
		)
		(layer "In9.Cu")
	)
	(gr_line
		(start 291.102034 -72.128888)
		(end 291.27831 -72.164702)
		(stroke
			(width 0.06985)
			(type default)
		)
		(layer "In9.Cu")
	)
	(gr_line
		(start 291.147246 -304.265838)
		(end 291.165534 -304.261774)
		(stroke
			(width 0.053848)
			(type default)
		)
		(layer "In9.Cu")
	)
	(gr_line
		(start 291.165534 -304.261774)
		(end 291.18052 -304.252122)
		(stroke
			(width 0.053848)
			(type default)
		)
		(layer "In9.Cu")
	)
	(gr_line
		(start 291.18306 -181.733952)
		(end 291.373814 -181.699154)
		(stroke
			(width 0.06985)
			(type default)
		)
		(layer "In9.Cu")
	)
	(gr_line
		(start 291.24148 -60.339478)
		(end 291.27704 -60.163202)
		(stroke
			(width 0.06985)
			(type default)
		)
		(layer "In9.Cu")
	)
	(gr_line
		(start 291.243512 -182.405782)
		(end 291.59454 -181.897528)
		(stroke
			(width 0.06985)
			(type default)
		)
		(layer "In9.Cu")
	)
	(gr_line
		(start 291.27831 -72.164702)
		(end 291.627814 -71.933308)
		(stroke
			(width 0.06985)
			(type default)
		)
		(layer "In9.Cu")
	)
	(gr_line
		(start 291.28466 -55.805832)
		(end 291.399214 -55.729886)
		(stroke
			(width 0.06985)
			(type default)
		)
		(layer "In9.Cu")
	)
	(gr_line
		(start 291.290502 -52.627022)
		(end 291.350954 -52.442618)
		(stroke
			(width 0.06985)
			(type default)
		)
		(layer "In9.Cu")
	)
	(gr_line
		(start 291.41293 -56.226456)
		(end 291.448744 -56.050434)
		(stroke
			(width 0.06985)
			(type default)
		)
		(layer "In9.Cu")
	)
	(gr_line
		(start 291.449506 -56.046878)
		(end 291.514784 -56.003698)
		(stroke
			(width 0.06985)
			(type default)
		)
		(layer "In9.Cu")
	)
	(gr_line
		(start 291.579808 -181.15915)
		(end 291.61486 -181.350158)
		(stroke
			(width 0.06985)
			(type default)
		)
		(layer "In9.Cu")
	)
	(gr_line
		(start 291.579808 -181.15915)
		(end 291.81806 -180.814472)
		(stroke
			(width 0.06985)
			(type default)
		)
		(layer "In9.Cu")
	)
	(gr_line
		(start 291.627814 -71.933308)
		(end 291.663628 -71.757032)
		(stroke
			(width 0.06985)
			(type default)
		)
		(layer "In9.Cu")
	)
	(gr_line
		(start 291.668962 -55.551324)
		(end 292.17239 -55.21833)
		(stroke
			(width 0.06985)
			(type default)
		)
		(layer "In9.Cu")
	)
	(gr_line
		(start 291.717222 -184.57164)
		(end 291.755068 -184.776872)
		(stroke
			(width 0.06985)
			(type default)
		)
		(layer "In9.Cu")
	)
	(gr_line
		(start 291.717222 -184.57164)
		(end 291.954712 -184.226454)
		(stroke
			(width 0.06985)
			(type default)
		)
		(layer "In9.Cu")
	)
	(gr_line
		(start 291.733732 -185.326274)
		(end 291.736018 -185.324242)
		(stroke
			(width 0.06985)
			(type default)
		)
		(layer "In9.Cu")
	)
	(gr_line
		(start 291.736018 -185.324242)
		(end 291.737796 -185.321702)
		(stroke
			(width 0.06985)
			(type default)
		)
		(layer "In9.Cu")
	)
	(gr_line
		(start 291.802566 -55.8165)
		(end 291.978588 -55.852314)
		(stroke
			(width 0.06985)
			(type default)
		)
		(layer "In9.Cu")
	)
	(gr_line
		(start 291.81806 -180.814472)
		(end 292.008814 -180.779674)
		(stroke
			(width 0.06985)
			(type default)
		)
		(layer "In9.Cu")
	)
	(gr_line
		(start 291.878004 -181.48681)
		(end 292.228524 -180.979064)
		(stroke
			(width 0.06985)
			(type default)
		)
		(layer "In9.Cu")
	)
	(gr_line
		(start 291.954712 -184.226454)
		(end 292.159944 -184.188354)
		(stroke
			(width 0.06985)
			(type default)
		)
		(layer "In9.Cu")
	)
	(gr_line
		(start 291.978588 -55.852314)
		(end 292.328092 -55.621174)
		(stroke
			(width 0.06985)
			(type default)
		)
		(layer "In9.Cu")
	)
	(gr_line
		(start 292.017704 -184.914794)
		(end 292.382448 -184.38495)
		(stroke
			(width 0.06985)
			(type default)
		)
		(layer "In9.Cu")
	)
	(gr_line
		(start 292.135052 -314.834778)
		(end 292.164516 -314.815982)
		(stroke
			(width 0.053848)
			(type default)
		)
		(layer "In9.Cu")
	)
	(gr_line
		(start 292.164516 -314.815982)
		(end 292.183312 -314.786518)
		(stroke
			(width 0.053848)
			(type default)
		)
		(layer "In9.Cu")
	)
	(gr_line
		(start 292.328092 -55.621174)
		(end 292.363906 -55.444898)
		(stroke
			(width 0.06985)
			(type default)
		)
		(layer "In9.Cu")
	)
	(gr_line
		(start 292.362128 -183.63438)
		(end 292.400228 -183.839358)
		(stroke
			(width 0.06985)
			(type default)
		)
		(layer "In9.Cu")
	)
	(gr_line
		(start 292.362128 -183.63438)
		(end 292.599872 -183.28894)
		(stroke
			(width 0.06985)
			(type default)
		)
		(layer "In9.Cu")
	)
	(gr_line
		(start 292.52164 -336.174334)
		(end 292.549834 -336.1563)
		(stroke
			(width 0.053848)
			(type default)
		)
		(layer "In9.Cu")
	)
	(gr_line
		(start 292.549834 -336.1563)
		(end 292.567868 -336.128106)
		(stroke
			(width 0.053848)
			(type default)
		)
		(layer "In9.Cu")
	)
	(gr_line
		(start 292.599872 -183.28894)
		(end 292.80485 -183.251094)
		(stroke
			(width 0.06985)
			(type default)
		)
		(layer "In9.Cu")
	)
	(gr_line
		(start 292.66261 -183.977788)
		(end 293.027608 -183.447182)
		(stroke
			(width 0.06985)
			(type default)
		)
		(layer "In9.Cu")
	)
	(gr_line
		(start 292.809422 -315.818774)
		(end 292.872668 -316.104778)
		(stroke
			(width 0.053848)
			(type default)
		)
		(layer "In9.Cu")
	)
	(gr_line
		(start 292.809422 -315.818774)
		(end 292.983412 -315.54547)
		(stroke
			(width 0.053848)
			(type default)
		)
		(layer "In9.Cu")
	)
	(gr_line
		(start 292.910514 -316.638432)
		(end 292.938708 -316.620398)
		(stroke
			(width 0.053848)
			(type default)
		)
		(layer "In9.Cu")
	)
	(gr_line
		(start 292.938708 -316.620398)
		(end 292.956234 -316.592712)
		(stroke
			(width 0.053848)
			(type default)
		)
		(layer "In9.Cu")
	)
	(gr_line
		(start 292.971982 -296.111676)
		(end 293.030402 -296.398696)
		(stroke
			(width 0.053848)
			(type default)
		)
		(layer "In9.Cu")
	)
	(gr_line
		(start 292.971982 -296.111676)
		(end 293.150798 -295.841674)
		(stroke
			(width 0.053848)
			(type default)
		)
		(layer "In9.Cu")
	)
	(gr_line
		(start 292.983412 -315.54547)
		(end 293.269416 -315.482224)
		(stroke
			(width 0.053848)
			(type default)
		)
		(layer "In9.Cu")
	)
	(gr_line
		(start 293.007288 -182.696866)
		(end 293.045388 -182.901844)
		(stroke
			(width 0.06985)
			(type default)
		)
		(layer "In9.Cu")
	)
	(gr_line
		(start 293.007288 -182.696866)
		(end 293.244778 -182.35168)
		(stroke
			(width 0.06985)
			(type default)
		)
		(layer "In9.Cu")
	)
	(gr_line
		(start 293.06393 -296.929048)
		(end 293.089076 -296.913046)
		(stroke
			(width 0.053848)
			(type default)
		)
		(layer "In9.Cu")
	)
	(gr_line
		(start 293.089076 -296.913046)
		(end 293.105586 -296.888154)
		(stroke
			(width 0.053848)
			(type default)
		)
		(layer "In9.Cu")
	)
	(gr_line
		(start 293.133018 -334.23606)
		(end 293.196518 -334.52181)
		(stroke
			(width 0.053848)
			(type default)
		)
		(layer "In9.Cu")
	)
	(gr_line
		(start 293.133018 -334.23606)
		(end 293.307008 -333.962756)
		(stroke
			(width 0.053848)
			(type default)
		)
		(layer "In9.Cu")
	)
	(gr_line
		(start 293.150798 -295.841674)
		(end 293.437818 -295.783508)
		(stroke
			(width 0.053848)
			(type default)
		)
		(layer "In9.Cu")
	)
	(gr_line
		(start 293.17315 -316.252606)
		(end 293.530274 -315.692282)
		(stroke
			(width 0.053848)
			(type default)
		)
		(layer "In9.Cu")
	)
	(gr_line
		(start 293.205662 -312.173366)
		(end 293.269416 -312.45937)
		(stroke
			(width 0.053848)
			(type default)
		)
		(layer "In9.Cu")
	)
	(gr_line
		(start 293.205662 -312.173366)
		(end 293.379652 -311.900062)
		(stroke
			(width 0.053848)
			(type default)
		)
		(layer "In9.Cu")
	)
	(gr_line
		(start 293.244778 -182.35168)
		(end 293.45001 -182.31358)
		(stroke
			(width 0.06985)
			(type default)
		)
		(layer "In9.Cu")
	)
	(gr_line
		(start 293.307008 -333.962756)
		(end 293.593012 -333.89951)
		(stroke
			(width 0.053848)
			(type default)
		)
		(layer "In9.Cu")
	)
	(gr_line
		(start 293.307516 -183.040528)
		(end 293.673022 -182.509414)
		(stroke
			(width 0.06985)
			(type default)
		)
		(layer "In9.Cu")
	)
	(gr_line
		(start 293.329106 -296.550588)
		(end 293.694612 -295.998392)
		(stroke
			(width 0.053848)
			(type default)
		)
		(layer "In9.Cu")
	)
	(gr_line
		(start 293.379652 -311.900062)
		(end 293.665656 -311.836562)
		(stroke
			(width 0.053848)
			(type default)
		)
		(layer "In9.Cu")
	)
	(gr_line
		(start 293.3827 -314.919106)
		(end 293.445946 -315.20511)
		(stroke
			(width 0.053848)
			(type default)
		)
		(layer "In9.Cu")
	)
	(gr_line
		(start 293.3827 -314.919106)
		(end 293.55669 -314.645802)
		(stroke
			(width 0.053848)
			(type default)
		)
		(layer "In9.Cu")
	)
	(gr_line
		(start 293.497762 -334.668114)
		(end 293.853108 -334.11033)
		(stroke
			(width 0.053848)
			(type default)
		)
		(layer "In9.Cu")
	)
	(gr_line
		(start 293.55669 -314.645802)
		(end 293.842694 -314.582556)
		(stroke
			(width 0.053848)
			(type default)
		)
		(layer "In9.Cu")
	)
	(gr_line
		(start 293.560754 -295.222168)
		(end 293.619174 -295.509188)
		(stroke
			(width 0.053848)
			(type default)
		)
		(layer "In9.Cu")
	)
	(gr_line
		(start 293.560754 -295.222168)
		(end 293.73957 -294.952166)
		(stroke
			(width 0.053848)
			(type default)
		)
		(layer "In9.Cu")
	)
	(gr_line
		(start 293.57066 -312.605674)
		(end 293.92626 -312.046874)
		(stroke
			(width 0.053848)
			(type default)
		)
		(layer "In9.Cu")
	)
	(gr_line
		(start 293.706296 -333.336138)
		(end 293.769542 -333.622396)
		(stroke
			(width 0.053848)
			(type default)
		)
		(layer "In9.Cu")
	)
	(gr_line
		(start 293.706296 -333.336138)
		(end 293.880286 -333.063088)
		(stroke
			(width 0.053848)
			(type default)
		)
		(layer "In9.Cu")
	)
	(gr_line
		(start 293.73957 -294.952166)
		(end 294.02659 -294.893746)
		(stroke
			(width 0.053848)
			(type default)
		)
		(layer "In9.Cu")
	)
	(gr_line
		(start 293.746682 -315.35243)
		(end 294.103552 -314.79236)
		(stroke
			(width 0.053848)
			(type default)
		)
		(layer "In9.Cu")
	)
	(gr_line
		(start 293.778432 -311.27319)
		(end 293.841932 -311.559448)
		(stroke
			(width 0.053848)
			(type default)
		)
		(layer "In9.Cu")
	)
	(gr_line
		(start 293.778432 -311.27319)
		(end 293.952168 -310.999886)
		(stroke
			(width 0.053848)
			(type default)
		)
		(layer "In9.Cu")
	)
	(gr_line
		(start 293.880286 -333.063088)
		(end 294.16629 -332.999588)
		(stroke
			(width 0.053848)
			(type default)
		)
		(layer "In9.Cu")
	)
	(gr_line
		(start 293.917116 -295.66235)
		(end 294.2844 -295.10736)
		(stroke
			(width 0.053848)
			(type default)
		)
		(layer "In9.Cu")
	)
	(gr_line
		(start 293.952168 -310.999886)
		(end 294.238426 -310.936386)
		(stroke
			(width 0.053848)
			(type default)
		)
		(layer "In9.Cu")
	)
	(gr_line
		(start 293.955724 -314.019184)
		(end 294.019224 -314.305442)
		(stroke
			(width 0.053848)
			(type default)
		)
		(layer "In9.Cu")
	)
	(gr_line
		(start 293.955724 -314.019184)
		(end 294.129968 -313.746134)
		(stroke
			(width 0.053848)
			(type default)
		)
		(layer "In9.Cu")
	)
	(gr_line
		(start 293.963598 -297.732958)
		(end 294.022018 -298.019978)
		(stroke
			(width 0.053848)
			(type default)
		)
		(layer "In9.Cu")
	)
	(gr_line
		(start 293.963598 -297.732958)
		(end 294.142414 -297.462956)
		(stroke
			(width 0.053848)
			(type default)
		)
		(layer "In9.Cu")
	)
	(gr_line
		(start 293.977568 -298.667932)
		(end 294.002968 -298.651676)
		(stroke
			(width 0.053848)
			(type default)
		)
		(layer "In9.Cu")
	)
	(gr_line
		(start 294.002968 -298.651676)
		(end 294.019478 -298.626784)
		(stroke
			(width 0.053848)
			(type default)
		)
		(layer "In9.Cu")
	)
	(gr_line
		(start 294.070532 -333.768954)
		(end 294.426386 -333.210662)
		(stroke
			(width 0.053848)
			(type default)
		)
		(layer "In9.Cu")
	)
	(gr_line
		(start 294.129968 -313.746134)
		(end 294.415718 -313.682888)
		(stroke
			(width 0.053848)
			(type default)
		)
		(layer "In9.Cu")
	)
	(gr_line
		(start 294.142414 -311.707022)
		(end 294.498776 -311.146444)
		(stroke
			(width 0.053848)
			(type default)
		)
		(layer "In9.Cu")
	)
	(gr_line
		(start 294.142414 -297.462956)
		(end 294.429434 -297.404536)
		(stroke
			(width 0.053848)
			(type default)
		)
		(layer "In9.Cu")
	)
	(gr_line
		(start 294.149526 -294.33266)
		(end 294.207946 -294.61968)
		(stroke
			(width 0.053848)
			(type default)
		)
		(layer "In9.Cu")
	)
	(gr_line
		(start 294.149526 -294.33266)
		(end 294.328342 -294.062658)
		(stroke
			(width 0.053848)
			(type default)
		)
		(layer "In9.Cu")
	)
	(gr_line
		(start 294.279574 -332.43647)
		(end 294.34282 -332.722474)
		(stroke
			(width 0.053848)
			(type default)
		)
		(layer "In9.Cu")
	)
	(gr_line
		(start 294.279574 -332.43647)
		(end 294.453564 -332.16342)
		(stroke
			(width 0.053848)
			(type default)
		)
		(layer "In9.Cu")
	)
	(gr_line
		(start 294.320214 -314.452254)
		(end 294.676068 -313.893962)
		(stroke
			(width 0.053848)
			(type default)
		)
		(layer "In9.Cu")
	)
	(gr_line
		(start 294.320976 -298.1706)
		(end 294.68572 -297.619928)
		(stroke
			(width 0.053848)
			(type default)
		)
		(layer "In9.Cu")
	)
	(gr_line
		(start 294.328342 -294.062658)
		(end 294.615362 -294.004238)
		(stroke
			(width 0.053848)
			(type default)
		)
		(layer "In9.Cu")
	)
	(gr_line
		(start 294.351202 -310.373268)
		(end 294.414702 -310.659272)
		(stroke
			(width 0.053848)
			(type default)
		)
		(layer "In9.Cu")
	)
	(gr_line
		(start 294.351202 -310.373268)
		(end 294.524938 -310.099964)
		(stroke
			(width 0.053848)
			(type default)
		)
		(layer "In9.Cu")
	)
	(gr_line
		(start 294.453564 -332.16342)
		(end 294.739568 -332.09992)
		(stroke
			(width 0.053848)
			(type default)
		)
		(layer "In9.Cu")
	)
	(gr_line
		(start 294.50665 -294.771318)
		(end 294.87241 -294.218868)
		(stroke
			(width 0.053848)
			(type default)
		)
		(layer "In9.Cu")
	)
	(gr_line
		(start 294.524938 -310.099964)
		(end 294.810942 -310.036464)
		(stroke
			(width 0.053848)
			(type default)
		)
		(layer "In9.Cu")
	)
	(gr_line
		(start 294.55237 -296.84345)
		(end 294.61079 -297.13047)
		(stroke
			(width 0.053848)
			(type default)
		)
		(layer "In9.Cu")
	)
	(gr_line
		(start 294.55237 -296.84345)
		(end 294.731186 -296.573194)
		(stroke
			(width 0.053848)
			(type default)
		)
		(layer "In9.Cu")
	)
	(gr_line
		(start 294.565832 -316.253114)
		(end 294.629078 -316.539118)
		(stroke
			(width 0.053848)
			(type default)
		)
		(layer "In9.Cu")
	)
	(gr_line
		(start 294.565832 -316.253114)
		(end 294.739822 -315.97981)
		(stroke
			(width 0.053848)
			(type default)
		)
		(layer "In9.Cu")
	)
	(gr_line
		(start 294.6019 -317.17488)
		(end 294.630094 -317.156846)
		(stroke
			(width 0.053848)
			(type default)
		)
		(layer "In9.Cu")
	)
	(gr_line
		(start 294.630094 -317.156846)
		(end 294.648128 -317.128652)
		(stroke
			(width 0.053848)
			(type default)
		)
		(layer "In9.Cu")
	)
	(gr_line
		(start 294.643556 -332.869794)
		(end 294.999918 -332.310486)
		(stroke
			(width 0.053848)
			(type default)
		)
		(layer "In9.Cu")
	)
	(gr_line
		(start 294.68699 -88.330786)
		(end 294.791638 -88.16721)
		(stroke
			(width 0.06985)
			(type default)
		)
		(layer "In9.Cu")
	)
	(gr_line
		(start 294.715692 -310.80583)
		(end 295.071038 -310.247284)
		(stroke
			(width 0.053848)
			(type default)
		)
		(layer "In9.Cu")
	)
	(gr_line
		(start 294.731186 -296.573194)
		(end 295.018206 -296.515028)
		(stroke
			(width 0.053848)
			(type default)
		)
		(layer "In9.Cu")
	)
	(gr_line
		(start 294.739822 -315.97981)
		(end 295.025826 -315.916564)
		(stroke
			(width 0.053848)
			(type default)
		)
		(layer "In9.Cu")
	)
	(gr_line
		(start 294.785796 -88.61044)
		(end 295.391078 -88.47709)
		(stroke
			(width 0.06985)
			(type default)
		)
		(layer "In9.Cu")
	)
	(gr_line
		(start 294.791638 -88.16721)
		(end 295.200832 -88.07704)
		(stroke
			(width 0.06985)
			(type default)
		)
		(layer "In9.Cu")
	)
	(gr_line
		(start 294.909494 -297.282108)
		(end 295.274746 -296.730166)
		(stroke
			(width 0.053848)
			(type default)
		)
		(layer "In9.Cu")
	)
	(gr_line
		(start 294.930068 -316.68593)
		(end 295.28643 -316.126876)
		(stroke
			(width 0.053848)
			(type default)
		)
		(layer "In9.Cu")
	)
	(gr_line
		(start 295.13911 -315.353446)
		(end 295.202356 -315.63945)
		(stroke
			(width 0.053848)
			(type default)
		)
		(layer "In9.Cu")
	)
	(gr_line
		(start 295.13911 -315.353446)
		(end 295.3131 -315.080142)
		(stroke
			(width 0.053848)
			(type default)
		)
		(layer "In9.Cu")
	)
	(gr_line
		(start 295.141396 -295.953688)
		(end 295.199562 -296.240962)
		(stroke
			(width 0.053848)
			(type default)
		)
		(layer "In9.Cu")
	)
	(gr_line
		(start 295.141396 -295.953688)
		(end 295.319958 -295.683686)
		(stroke
			(width 0.053848)
			(type default)
		)
		(layer "In9.Cu")
	)
	(gr_line
		(start 295.200832 -88.07704)
		(end 295.364662 -88.181688)
		(stroke
			(width 0.06985)
			(type default)
		)
		(layer "In9.Cu")
	)
	(gr_line
		(start 295.3131 -315.080142)
		(end 295.599104 -315.016896)
		(stroke
			(width 0.053848)
			(type default)
		)
		(layer "In9.Cu")
	)
	(gr_line
		(start 295.319958 -295.683686)
		(end 295.607232 -295.625266)
		(stroke
			(width 0.053848)
			(type default)
		)
		(layer "In9.Cu")
	)
	(gr_line
		(start 295.401746 -93.352112)
		(end 295.506394 -93.188536)
		(stroke
			(width 0.06985)
			(type default)
		)
		(layer "In9.Cu")
	)
	(gr_line
		(start 295.434004 -89.796874)
		(end 295.538652 -89.633298)
		(stroke
			(width 0.06985)
			(type default)
		)
		(layer "In9.Cu")
	)
	(gr_line
		(start 295.465246 -91.629992)
		(end 295.569894 -91.466416)
		(stroke
			(width 0.06985)
			(type default)
		)
		(layer "In9.Cu")
	)
	(gr_line
		(start 295.498266 -93.632782)
		(end 296.109644 -93.49867)
		(stroke
			(width 0.06985)
			(type default)
		)
		(layer "In9.Cu")
	)
	(gr_line
		(start 295.498774 -296.391584)
		(end 295.862756 -295.84142)
		(stroke
			(width 0.053848)
			(type default)
		)
		(layer "In9.Cu")
	)
	(gr_line
		(start 295.502838 -315.787278)
		(end 295.859708 -315.227208)
		(stroke
			(width 0.053848)
			(type default)
		)
		(layer "In9.Cu")
	)
	(gr_line
		(start 295.506394 -93.188536)
		(end 295.915842 -93.098874)
		(stroke
			(width 0.06985)
			(type default)
		)
		(layer "In9.Cu")
	)
	(gr_line
		(start 295.532048 -90.077036)
		(end 296.141648 -89.94267)
		(stroke
			(width 0.06985)
			(type default)
		)
		(layer "In9.Cu")
	)
	(gr_line
		(start 295.538652 -89.633298)
		(end 295.947846 -89.542874)
		(stroke
			(width 0.06985)
			(type default)
		)
		(layer "In9.Cu")
	)
	(gr_line
		(start 295.55186 -298.6659)
		(end 295.61028 -298.95292)
		(stroke
			(width 0.053848)
			(type default)
		)
		(layer "In9.Cu")
	)
	(gr_line
		(start 295.55186 -298.6659)
		(end 295.730676 -298.395898)
		(stroke
			(width 0.053848)
			(type default)
		)
		(layer "In9.Cu")
	)
	(gr_line
		(start 295.563544 -91.9099)
		(end 296.170604 -91.776296)
		(stroke
			(width 0.06985)
			(type default)
		)
		(layer "In9.Cu")
	)
	(gr_line
		(start 295.569894 -91.466416)
		(end 295.979088 -91.376246)
		(stroke
			(width 0.06985)
			(type default)
		)
		(layer "In9.Cu")
	)
	(gr_line
		(start 295.643808 -299.483272)
		(end 295.668954 -299.46727)
		(stroke
			(width 0.053848)
			(type default)
		)
		(layer "In9.Cu")
	)
	(gr_line
		(start 295.668954 -299.46727)
		(end 295.685464 -299.442378)
		(stroke
			(width 0.053848)
			(type default)
		)
		(layer "In9.Cu")
	)
	(gr_line
		(start 295.705022 -317.584328)
		(end 295.768268 -317.870332)
		(stroke
			(width 0.053848)
			(type default)
		)
		(layer "In9.Cu")
	)
	(gr_line
		(start 295.705022 -317.584328)
		(end 295.879012 -317.311024)
		(stroke
			(width 0.053848)
			(type default)
		)
		(layer "In9.Cu")
	)
	(gr_line
		(start 295.712388 -314.453778)
		(end 295.775634 -314.739782)
		(stroke
			(width 0.053848)
			(type default)
		)
		(layer "In9.Cu")
	)
	(gr_line
		(start 295.712388 -314.453778)
		(end 295.886378 -314.180474)
		(stroke
			(width 0.053848)
			(type default)
		)
		(layer "In9.Cu")
	)
	(gr_line
		(start 295.730676 -298.395898)
		(end 296.017696 -298.337732)
		(stroke
			(width 0.053848)
			(type default)
		)
		(layer "In9.Cu")
	)
	(gr_line
		(start 295.778428 -88.090502)
		(end 295.883076 -87.926926)
		(stroke
			(width 0.06985)
			(type default)
		)
		(layer "In9.Cu")
	)
	(gr_line
		(start 295.806114 -318.403986)
		(end 295.834308 -318.385952)
		(stroke
			(width 0.053848)
			(type default)
		)
		(layer "In9.Cu")
	)
	(gr_line
		(start 295.834308 -318.385952)
		(end 295.852342 -318.357758)
		(stroke
			(width 0.053848)
			(type default)
		)
		(layer "In9.Cu")
	)
	(gr_line
		(start 295.845484 -169.251376)
		(end 295.883584 -169.456354)
		(stroke
			(width 0.06985)
			(type default)
		)
		(layer "In9.Cu")
	)
	(gr_line
		(start 295.845484 -169.251376)
		(end 296.08272 -168.905936)
		(stroke
			(width 0.06985)
			(type default)
		)
		(layer "In9.Cu")
	)
	(gr_line
		(start 295.877742 -88.370156)
		(end 296.483786 -88.236806)
		(stroke
			(width 0.06985)
			(type default)
		)
		(layer "In9.Cu")
	)
	(gr_line
		(start 295.879012 -317.311024)
		(end 296.165016 -317.247778)
		(stroke
			(width 0.053848)
			(type default)
		)
		(layer "In9.Cu")
	)
	(gr_line
		(start 295.883076 -87.926926)
		(end 296.29227 -87.836756)
		(stroke
			(width 0.06985)
			(type default)
		)
		(layer "In9.Cu")
	)
	(gr_line
		(start 295.886378 -314.180474)
		(end 296.172382 -314.117228)
		(stroke
			(width 0.053848)
			(type default)
		)
		(layer "In9.Cu")
	)
	(gr_line
		(start 295.908984 -299.104812)
		(end 296.27449 -298.552616)
		(stroke
			(width 0.053848)
			(type default)
		)
		(layer "In9.Cu")
	)
	(gr_line
		(start 295.915842 -93.098874)
		(end 296.079418 -93.203522)
		(stroke
			(width 0.06985)
			(type default)
		)
		(layer "In9.Cu")
	)
	(gr_line
		(start 295.947846 -89.542874)
		(end 296.111422 -89.647522)
		(stroke
			(width 0.06985)
			(type default)
		)
		(layer "In9.Cu")
	)
	(gr_line
		(start 295.979088 -91.376246)
		(end 296.142664 -91.480894)
		(stroke
			(width 0.06985)
			(type default)
		)
		(layer "In9.Cu")
	)
	(gr_line
		(start 296.069004 -318.017652)
		(end 296.425366 -317.458344)
		(stroke
			(width 0.053848)
			(type default)
		)
		(layer "In9.Cu")
	)
	(gr_line
		(start 296.076116 -314.88761)
		(end 296.432986 -314.32754)
		(stroke
			(width 0.053848)
			(type default)
		)
		(layer "In9.Cu")
	)
	(gr_line
		(start 296.08272 -168.905936)
		(end 296.287952 -168.867836)
		(stroke
			(width 0.06985)
			(type default)
		)
		(layer "In9.Cu")
	)
	(gr_line
		(start 296.140632 -297.776392)
		(end 296.199052 -298.063412)
		(stroke
			(width 0.053848)
			(type default)
		)
		(layer "In9.Cu")
	)
	(gr_line
		(start 296.140632 -297.776392)
		(end 296.319448 -297.50639)
		(stroke
			(width 0.053848)
			(type default)
		)
		(layer "In9.Cu")
	)
	(gr_line
		(start 296.146728 -169.59326)
		(end 296.510456 -169.064432)
		(stroke
			(width 0.06985)
			(type default)
		)
		(layer "In9.Cu")
	)
	(gr_line
		(start 296.278046 -316.684406)
		(end 296.341546 -316.97041)
		(stroke
			(width 0.053848)
			(type default)
		)
		(layer "In9.Cu")
	)
	(gr_line
		(start 296.278046 -316.684406)
		(end 296.452036 -316.411356)
		(stroke
			(width 0.053848)
			(type default)
		)
		(layer "In9.Cu")
	)
	(gr_line
		(start 296.29227 -87.836756)
		(end 296.4561 -87.941404)
		(stroke
			(width 0.06985)
			(type default)
		)
		(layer "In9.Cu")
	)
	(gr_line
		(start 296.319448 -297.50639)
		(end 296.606468 -297.44797)
		(stroke
			(width 0.053848)
			(type default)
		)
		(layer "In9.Cu")
	)
	(gr_line
		(start 296.452036 -316.411356)
		(end 296.73804 -316.34811)
		(stroke
			(width 0.053848)
			(type default)
		)
		(layer "In9.Cu")
	)
	(gr_line
		(start 296.490136 -168.313608)
		(end 296.528236 -168.518586)
		(stroke
			(width 0.06985)
			(type default)
		)
		(layer "In9.Cu")
	)
	(gr_line
		(start 296.490136 -168.313608)
		(end 296.727372 -167.968168)
		(stroke
			(width 0.06985)
			(type default)
		)
		(layer "In9.Cu")
	)
	(gr_line
		(start 296.493438 -93.11259)
		(end 296.598086 -92.949014)
		(stroke
			(width 0.06985)
			(type default)
		)
		(layer "In9.Cu")
	)
	(gr_line
		(start 296.497756 -298.21505)
		(end 296.864024 -297.661838)
		(stroke
			(width 0.053848)
			(type default)
		)
		(layer "In9.Cu")
	)
	(gr_line
		(start 296.525442 -89.556336)
		(end 296.629836 -89.39276)
		(stroke
			(width 0.06985)
			(type default)
		)
		(layer "In9.Cu")
	)
	(gr_line
		(start 296.556684 -91.389708)
		(end 296.661332 -91.226132)
		(stroke
			(width 0.06985)
			(type default)
		)
		(layer "In9.Cu")
	)
	(gr_line
		(start 296.589196 -93.393514)
		(end 297.202098 -93.259148)
		(stroke
			(width 0.06985)
			(type default)
		)
		(layer "In9.Cu")
	)
	(gr_line
		(start 296.598086 -92.949014)
		(end 297.007534 -92.859352)
		(stroke
			(width 0.06985)
			(type default)
		)
		(layer "In9.Cu")
	)
	(gr_line
		(start 296.624248 -89.83599)
		(end 297.2308 -89.702386)
		(stroke
			(width 0.06985)
			(type default)
		)
		(layer "In9.Cu")
	)
	(gr_line
		(start 296.629836 -89.39276)
		(end 297.039284 -89.302336)
		(stroke
			(width 0.06985)
			(type default)
		)
		(layer "In9.Cu")
	)
	(gr_line
		(start 296.64279 -317.116714)
		(end 296.99839 -316.558676)
		(stroke
			(width 0.053848)
			(type default)
		)
		(layer "In9.Cu")
	)
	(gr_line
		(start 296.655998 -91.669362)
		(end 297.261788 -91.536012)
		(stroke
			(width 0.06985)
			(type default)
		)
		(layer "In9.Cu")
	)
	(gr_line
		(start 296.661332 -91.226132)
		(end 297.07078 -91.135962)
		(stroke
			(width 0.06985)
			(type default)
		)
		(layer "In9.Cu")
	)
	(gr_line
		(start 296.727372 -167.968168)
		(end 296.932604 -167.930068)
		(stroke
			(width 0.06985)
			(type default)
		)
		(layer "In9.Cu")
	)
	(gr_line
		(start 296.729404 -296.886884)
		(end 296.787824 -297.173904)
		(stroke
			(width 0.053848)
			(type default)
		)
		(layer "In9.Cu")
	)
	(gr_line
		(start 296.729404 -296.886884)
		(end 296.90822 -296.616882)
		(stroke
			(width 0.053848)
			(type default)
		)
		(layer "In9.Cu")
	)
	(gr_line
		(start 296.791126 -168.656254)
		(end 297.155616 -168.125902)
		(stroke
			(width 0.06985)
			(type default)
		)
		(layer "In9.Cu")
	)
	(gr_line
		(start 296.851324 -315.784738)
		(end 296.914824 -316.070742)
		(stroke
			(width 0.053848)
			(type default)
		)
		(layer "In9.Cu")
	)
	(gr_line
		(start 296.851324 -315.784738)
		(end 297.025314 -315.511688)
		(stroke
			(width 0.053848)
			(type default)
		)
		(layer "In9.Cu")
	)
	(gr_line
		(start 296.90822 -296.616882)
		(end 297.19524 -296.558462)
		(stroke
			(width 0.053848)
			(type default)
		)
		(layer "In9.Cu")
	)
	(gr_line
		(start 297.007534 -92.859352)
		(end 297.17111 -92.964)
		(stroke
			(width 0.06985)
			(type default)
		)
		(layer "In9.Cu")
	)
	(gr_line
		(start 297.025314 -315.511688)
		(end 297.311572 -315.448188)
		(stroke
			(width 0.053848)
			(type default)
		)
		(layer "In9.Cu")
	)
	(gr_line
		(start 297.031918 -299.647864)
		(end 297.090338 -299.934884)
		(stroke
			(width 0.053848)
			(type default)
		)
		(layer "In9.Cu")
	)
	(gr_line
		(start 297.031918 -299.647864)
		(end 297.210734 -299.377862)
		(stroke
			(width 0.053848)
			(type default)
		)
		(layer "In9.Cu")
	)
	(gr_line
		(start 297.039284 -89.302336)
		(end 297.20286 -89.406984)
		(stroke
			(width 0.06985)
			(type default)
		)
		(layer "In9.Cu")
	)
	(gr_line
		(start 297.07078 -91.135962)
		(end 297.234356 -91.24061)
		(stroke
			(width 0.06985)
			(type default)
		)
		(layer "In9.Cu")
	)
	(gr_line
		(start 297.086274 -297.32605)
		(end 297.452034 -296.773346)
		(stroke
			(width 0.053848)
			(type default)
		)
		(layer "In9.Cu")
	)
	(gr_line
		(start 297.09364 -170.013376)
		(end 297.131994 -170.219878)
		(stroke
			(width 0.06985)
			(type default)
		)
		(layer "In9.Cu")
	)
	(gr_line
		(start 297.09364 -170.013376)
		(end 297.331384 -169.66819)
		(stroke
			(width 0.06985)
			(type default)
		)
		(layer "In9.Cu")
	)
	(gr_line
		(start 297.115738 -318.404494)
		(end 297.179238 -318.690498)
		(stroke
			(width 0.053848)
			(type default)
		)
		(layer "In9.Cu")
	)
	(gr_line
		(start 297.115738 -318.404494)
		(end 297.289728 -318.13119)
		(stroke
			(width 0.053848)
			(type default)
		)
		(layer "In9.Cu")
	)
	(gr_line
		(start 297.123866 -300.465236)
		(end 297.149012 -300.449234)
		(stroke
			(width 0.053848)
			(type default)
		)
		(layer "In9.Cu")
	)
	(gr_line
		(start 297.134788 -167.37584)
		(end 297.172634 -167.580818)
		(stroke
			(width 0.06985)
			(type default)
		)
		(layer "In9.Cu")
	)
	(gr_line
		(start 297.134788 -167.37584)
		(end 297.372278 -167.030654)
		(stroke
			(width 0.06985)
			(type default)
		)
		(layer "In9.Cu")
	)
	(gr_line
		(start 297.149012 -300.449234)
		(end 297.165522 -300.424342)
		(stroke
			(width 0.053848)
			(type default)
		)
		(layer "In9.Cu")
	)
	(gr_line
		(start 297.210734 -299.377862)
		(end 297.497754 -299.319696)
		(stroke
			(width 0.053848)
			(type default)
		)
		(layer "In9.Cu")
	)
	(gr_line
		(start 297.216068 -316.217046)
		(end 297.572176 -315.657992)
		(stroke
			(width 0.053848)
			(type default)
		)
		(layer "In9.Cu")
	)
	(gr_line
		(start 297.217084 -319.224152)
		(end 297.245278 -319.206118)
		(stroke
			(width 0.053848)
			(type default)
		)
		(layer "In9.Cu")
	)
	(gr_line
		(start 297.245278 -319.206118)
		(end 297.263312 -319.177924)
		(stroke
			(width 0.053848)
			(type default)
		)
		(layer "In9.Cu")
	)
	(gr_line
		(start 297.289728 -318.13119)
		(end 297.575732 -318.067944)
		(stroke
			(width 0.053848)
			(type default)
		)
		(layer "In9.Cu")
	)
	(gr_line
		(start 297.331384 -169.66819)
		(end 297.537632 -169.63009)
		(stroke
			(width 0.06985)
			(type default)
		)
		(layer "In9.Cu")
	)
	(gr_line
		(start 297.372278 -167.030654)
		(end 297.577256 -166.992554)
		(stroke
			(width 0.06985)
			(type default)
		)
		(layer "In9.Cu")
	)
	(gr_line
		(start 297.388788 -300.087284)
		(end 297.754802 -299.534072)
		(stroke
			(width 0.053848)
			(type default)
		)
		(layer "In9.Cu")
	)
	(gr_line
		(start 297.390566 -170.363896)
		(end 297.76547 -169.81932)
		(stroke
			(width 0.06985)
			(type default)
		)
		(layer "In9.Cu")
	)
	(gr_line
		(start 297.435524 -167.71874)
		(end 297.79976 -167.18915)
		(stroke
			(width 0.06985)
			(type default)
		)
		(layer "In9.Cu")
	)
	(gr_line
		(start 297.480482 -318.836802)
		(end 297.836336 -318.278256)
		(stroke
			(width 0.053848)
			(type default)
		)
		(layer "In9.Cu")
	)
	(gr_line
		(start 297.555666 -335.501488)
		(end 297.58386 -335.483454)
		(stroke
			(width 0.053848)
			(type default)
		)
		(layer "In9.Cu")
	)
	(gr_line
		(start 297.58386 -335.483454)
		(end 297.601894 -335.45526)
		(stroke
			(width 0.053848)
			(type default)
		)
		(layer "In9.Cu")
	)
	(gr_line
		(start 297.62069 -298.758356)
		(end 297.67911 -299.045376)
		(stroke
			(width 0.053848)
			(type default)
		)
		(layer "In9.Cu")
	)
	(gr_line
		(start 297.62069 -298.758356)
		(end 297.799506 -298.488354)
		(stroke
			(width 0.053848)
			(type default)
		)
		(layer "In9.Cu")
	)
	(gr_line
		(start 297.689016 -317.504572)
		(end 297.752262 -317.79083)
		(stroke
			(width 0.053848)
			(type default)
		)
		(layer "In9.Cu")
	)
	(gr_line
		(start 297.689016 -317.504572)
		(end 297.863006 -317.231522)
		(stroke
			(width 0.053848)
			(type default)
		)
		(layer "In9.Cu")
	)
	(gr_line
		(start 297.7388 -169.076116)
		(end 297.777154 -169.282364)
		(stroke
			(width 0.06985)
			(type default)
		)
		(layer "In9.Cu")
	)
	(gr_line
		(start 297.7388 -169.076116)
		(end 297.97629 -168.73093)
		(stroke
			(width 0.06985)
			(type default)
		)
		(layer "In9.Cu")
	)
	(gr_line
		(start 297.77944 -166.438072)
		(end 297.81754 -166.643304)
		(stroke
			(width 0.06985)
			(type default)
		)
		(layer "In9.Cu")
	)
	(gr_line
		(start 297.77944 -166.438072)
		(end 298.01693 -166.092886)
		(stroke
			(width 0.06985)
			(type default)
		)
		(layer "In9.Cu")
	)
	(gr_line
		(start 297.799506 -298.488354)
		(end 298.086526 -298.429934)
		(stroke
			(width 0.053848)
			(type default)
		)
		(layer "In9.Cu")
	)
	(gr_line
		(start 297.863006 -317.231522)
		(end 298.14901 -317.168022)
		(stroke
			(width 0.053848)
			(type default)
		)
		(layer "In9.Cu")
	)
	(gr_line
		(start 297.866308 -334.035146)
		(end 297.929808 -334.32115)
		(stroke
			(width 0.053848)
			(type default)
		)
		(layer "In9.Cu")
	)
	(gr_line
		(start 297.866308 -334.035146)
		(end 298.040298 -333.762096)
		(stroke
			(width 0.053848)
			(type default)
		)
		(layer "In9.Cu")
	)
	(gr_line
		(start 297.97629 -168.73093)
		(end 298.182792 -168.692576)
		(stroke
			(width 0.06985)
			(type default)
		)
		(layer "In9.Cu")
	)
	(gr_line
		(start 297.977306 -299.19803)
		(end 298.344336 -298.643548)
		(stroke
			(width 0.053848)
			(type default)
		)
		(layer "In9.Cu")
	)
	(gr_line
		(start 298.01693 -166.092886)
		(end 298.221908 -166.054786)
		(stroke
			(width 0.06985)
			(type default)
		)
		(layer "In9.Cu")
	)
	(gr_line
		(start 298.035472 -169.426636)
		(end 298.410122 -168.882314)
		(stroke
			(width 0.06985)
			(type default)
		)
		(layer "In9.Cu")
	)
	(gr_line
		(start 298.040298 -333.762096)
		(end 298.326302 -333.698596)
		(stroke
			(width 0.053848)
			(type default)
		)
		(layer "In9.Cu")
	)
	(gr_line
		(start 298.052744 -317.938658)
		(end 298.409868 -317.377826)
		(stroke
			(width 0.053848)
			(type default)
		)
		(layer "In9.Cu")
	)
	(gr_line
		(start 298.08043 -166.780972)
		(end 298.44492 -166.25062)
		(stroke
			(width 0.06985)
			(type default)
		)
		(layer "In9.Cu")
	)
	(gr_line
		(start 298.209462 -297.868848)
		(end 298.267882 -298.155868)
		(stroke
			(width 0.053848)
			(type default)
		)
		(layer "In9.Cu")
	)
	(gr_line
		(start 298.209462 -297.868848)
		(end 298.388278 -297.598846)
		(stroke
			(width 0.053848)
			(type default)
		)
		(layer "In9.Cu")
	)
	(gr_line
		(start 298.231052 -334.467454)
		(end 298.58716 -333.908654)
		(stroke
			(width 0.053848)
			(type default)
		)
		(layer "In9.Cu")
	)
	(gr_line
		(start 298.26204 -316.604904)
		(end 298.32554 -316.890908)
		(stroke
			(width 0.053848)
			(type default)
		)
		(layer "In9.Cu")
	)
	(gr_line
		(start 298.26204 -316.604904)
		(end 298.43603 -316.3316)
		(stroke
			(width 0.053848)
			(type default)
		)
		(layer "In9.Cu")
	)
	(gr_line
		(start 298.38396 -168.138602)
		(end 298.42206 -168.345104)
		(stroke
			(width 0.06985)
			(type default)
		)
		(layer "In9.Cu")
	)
	(gr_line
		(start 298.38396 -168.138602)
		(end 298.62145 -167.793416)
		(stroke
			(width 0.06985)
			(type default)
		)
		(layer "In9.Cu")
	)
	(gr_line
		(start 298.388278 -297.598846)
		(end 298.675298 -297.540426)
		(stroke
			(width 0.053848)
			(type default)
		)
		(layer "In9.Cu")
	)
	(gr_line
		(start 298.43603 -316.3316)
		(end 298.722034 -316.268354)
		(stroke
			(width 0.053848)
			(type default)
		)
		(layer "In9.Cu")
	)
	(gr_line
		(start 298.439586 -333.135478)
		(end 298.502832 -333.421482)
		(stroke
			(width 0.053848)
			(type default)
		)
		(layer "In9.Cu")
	)
	(gr_line
		(start 298.439586 -333.135478)
		(end 298.613576 -332.862428)
		(stroke
			(width 0.053848)
			(type default)
		)
		(layer "In9.Cu")
	)
	(gr_line
		(start 298.566332 -298.308014)
		(end 298.932346 -297.754802)
		(stroke
			(width 0.053848)
			(type default)
		)
		(layer "In9.Cu")
	)
	(gr_line
		(start 298.613576 -332.862428)
		(end 298.89958 -332.798928)
		(stroke
			(width 0.053848)
			(type default)
		)
		(layer "In9.Cu")
	)
	(gr_line
		(start 298.62145 -167.793416)
		(end 298.827952 -167.755062)
		(stroke
			(width 0.06985)
			(type default)
		)
		(layer "In9.Cu")
	)
	(gr_line
		(start 298.625768 -317.039498)
		(end 298.98467 -316.476126)
		(stroke
			(width 0.053848)
			(type default)
		)
		(layer "In9.Cu")
	)
	(gr_line
		(start 298.642024 -170.915076)
		(end 298.67987 -171.120054)
		(stroke
			(width 0.06985)
			(type default)
		)
		(layer "In9.Cu")
	)
	(gr_line
		(start 298.642024 -170.915076)
		(end 298.880276 -170.570398)
		(stroke
			(width 0.06985)
			(type default)
		)
		(layer "In9.Cu")
	)
	(gr_line
		(start 298.680378 -168.489376)
		(end 299.056044 -167.94353)
		(stroke
			(width 0.06985)
			(type default)
		)
		(layer "In9.Cu")
	)
	(gr_line
		(start 298.708572 -319.449704)
		(end 298.772072 -319.735708)
		(stroke
			(width 0.053848)
			(type default)
		)
		(layer "In9.Cu")
	)
	(gr_line
		(start 298.708572 -319.449704)
		(end 298.882816 -319.1764)
		(stroke
			(width 0.053848)
			(type default)
		)
		(layer "In9.Cu")
	)
	(gr_line
		(start 298.770294 -76.590652)
		(end 299.364146 -76.475082)
		(stroke
			(width 0.06985)
			(type default)
		)
		(layer "In9.Cu")
	)
	(gr_line
		(start 298.792138 -76.886562)
		(end 298.941236 -76.9874)
		(stroke
			(width 0.06985)
			(type default)
		)
		(layer "In9.Cu")
	)
	(gr_line
		(start 298.803568 -333.568802)
		(end 299.15993 -333.009494)
		(stroke
			(width 0.053848)
			(type default)
		)
		(layer "In9.Cu")
	)
	(gr_line
		(start 298.809918 -320.269362)
		(end 298.838112 -320.251328)
		(stroke
			(width 0.053848)
			(type default)
		)
		(layer "In9.Cu")
	)
	(gr_line
		(start 298.838112 -320.251328)
		(end 298.856146 -320.223134)
		(stroke
			(width 0.053848)
			(type default)
		)
		(layer "In9.Cu")
	)
	(gr_line
		(start 298.880276 -170.570398)
		(end 299.085254 -170.53306)
		(stroke
			(width 0.06985)
			(type default)
		)
		(layer "In9.Cu")
	)
	(gr_line
		(start 298.882816 -319.1764)
		(end 299.168566 -319.113154)
		(stroke
			(width 0.053848)
			(type default)
		)
		(layer "In9.Cu")
	)
	(gr_line
		(start 298.941236 -76.9874)
		(end 299.352462 -76.90739)
		(stroke
			(width 0.06985)
			(type default)
		)
		(layer "In9.Cu")
	)
	(gr_line
		(start 298.943776 -171.25569)
		(end 299.305472 -170.731942)
		(stroke
			(width 0.06985)
			(type default)
		)
		(layer "In9.Cu")
	)
	(gr_line
		(start 298.964096 -80.609186)
		(end 299.554392 -80.494378)
		(stroke
			(width 0.06985)
			(type default)
		)
		(layer "In9.Cu")
	)
	(gr_line
		(start 298.985178 -80.905096)
		(end 299.134276 -81.00568)
		(stroke
			(width 0.06985)
			(type default)
		)
		(layer "In9.Cu")
	)
	(gr_line
		(start 299.01261 -332.23581)
		(end 299.07611 -332.521814)
		(stroke
			(width 0.053848)
			(type default)
		)
		(layer "In9.Cu")
	)
	(gr_line
		(start 299.01261 -332.23581)
		(end 299.1866 -331.962506)
		(stroke
			(width 0.053848)
			(type default)
		)
		(layer "In9.Cu")
	)
	(gr_line
		(start 299.022516 -336.45348)
		(end 299.05071 -336.435446)
		(stroke
			(width 0.053848)
			(type default)
		)
		(layer "In9.Cu")
	)
	(gr_line
		(start 299.028866 -167.201342)
		(end 299.06722 -167.40759)
		(stroke
			(width 0.06985)
			(type default)
		)
		(layer "In9.Cu")
	)
	(gr_line
		(start 299.028866 -167.201342)
		(end 299.26661 -166.855902)
		(stroke
			(width 0.06985)
			(type default)
		)
		(layer "In9.Cu")
	)
	(gr_line
		(start 299.05071 -336.435446)
		(end 299.068744 -336.407252)
		(stroke
			(width 0.053848)
			(type default)
		)
		(layer "In9.Cu")
	)
	(gr_line
		(start 299.073062 -319.88252)
		(end 299.428154 -319.32499)
		(stroke
			(width 0.053848)
			(type default)
		)
		(layer "In9.Cu")
	)
	(gr_line
		(start 299.134276 -81.00568)
		(end 299.545502 -80.92567)
		(stroke
			(width 0.06985)
			(type default)
		)
		(layer "In9.Cu")
	)
	(gr_line
		(start 299.1866 -331.962506)
		(end 299.472604 -331.89926)
		(stroke
			(width 0.053848)
			(type default)
		)
		(layer "In9.Cu")
	)
	(gr_line
		(start 299.248576 -335.11998)
		(end 299.311822 -335.406238)
		(stroke
			(width 0.053848)
			(type default)
		)
		(layer "In9.Cu")
	)
	(gr_line
		(start 299.248576 -335.11998)
		(end 299.422566 -334.84693)
		(stroke
			(width 0.053848)
			(type default)
		)
		(layer "In9.Cu")
	)
	(gr_line
		(start 299.26661 -166.855902)
		(end 299.472858 -166.817802)
		(stroke
			(width 0.06985)
			(type default)
		)
		(layer "In9.Cu")
	)
	(gr_line
		(start 299.28185 -318.549782)
		(end 299.34535 -318.835786)
		(stroke
			(width 0.053848)
			(type default)
		)
		(layer "In9.Cu")
	)
	(gr_line
		(start 299.28185 -318.549782)
		(end 299.45584 -318.276732)
		(stroke
			(width 0.053848)
			(type default)
		)
		(layer "In9.Cu")
	)
	(gr_line
		(start 299.288708 -169.978832)
		(end 299.3263 -170.184064)
		(stroke
			(width 0.06985)
			(type default)
		)
		(layer "In9.Cu")
	)
	(gr_line
		(start 299.288708 -169.978832)
		(end 299.52696 -169.6339)
		(stroke
			(width 0.06985)
			(type default)
		)
		(layer "In9.Cu")
	)
	(gr_line
		(start 299.326046 -167.550846)
		(end 299.698918 -167.00881)
		(stroke
			(width 0.06985)
			(type default)
		)
		(layer "In9.Cu")
	)
	(gr_line
		(start 299.352462 -76.90739)
		(end 299.4533 -76.758292)
		(stroke
			(width 0.06985)
			(type default)
		)
		(layer "In9.Cu")
	)
	(gr_line
		(start 299.3771 -332.668626)
		(end 299.732446 -332.110588)
		(stroke
			(width 0.053848)
			(type default)
		)
		(layer "In9.Cu")
	)
	(gr_line
		(start 299.422566 -334.84693)
		(end 299.70857 -334.783684)
		(stroke
			(width 0.053848)
			(type default)
		)
		(layer "In9.Cu")
	)
	(gr_line
		(start 299.45584 -318.276732)
		(end 299.742098 -318.213232)
		(stroke
			(width 0.053848)
			(type default)
		)
		(layer "In9.Cu")
	)
	(gr_line
		(start 299.52696 -169.6339)
		(end 299.731938 -169.596308)
		(stroke
			(width 0.06985)
			(type default)
		)
		(layer "In9.Cu")
	)
	(gr_line
		(start 299.545502 -80.92567)
		(end 299.646086 -80.776572)
		(stroke
			(width 0.06985)
			(type default)
		)
		(layer "In9.Cu")
	)
	(gr_line
		(start 299.59046 -170.319192)
		(end 299.952156 -169.795444)
		(stroke
			(width 0.06985)
			(type default)
		)
		(layer "In9.Cu")
	)
	(gr_line
		(start 299.612812 -335.55305)
		(end 299.968666 -334.994504)
		(stroke
			(width 0.053848)
			(type default)
		)
		(layer "In9.Cu")
	)
	(gr_line
		(start 299.646086 -318.98336)
		(end 300.003718 -318.421766)
		(stroke
			(width 0.053848)
			(type default)
		)
		(layer "In9.Cu")
	)
	(gr_line
		(start 299.789342 -172.859446)
		(end 299.824648 -173.0502)
		(stroke
			(width 0.06985)
			(type default)
		)
		(layer "In9.Cu")
	)
	(gr_line
		(start 299.789342 -172.859446)
		(end 300.027086 -172.51426)
		(stroke
			(width 0.06985)
			(type default)
		)
		(layer "In9.Cu")
	)
	(gr_line
		(start 299.821854 -334.220312)
		(end 299.8851 -334.506316)
		(stroke
			(width 0.053848)
			(type default)
		)
		(layer "In9.Cu")
	)
	(gr_line
		(start 299.821854 -334.220312)
		(end 299.995844 -333.947262)
		(stroke
			(width 0.053848)
			(type default)
		)
		(layer "In9.Cu")
	)
	(gr_line
		(start 299.846746 -76.38161)
		(end 300.439836 -76.266294)
		(stroke
			(width 0.06985)
			(type default)
		)
		(layer "In9.Cu")
	)
	(gr_line
		(start 299.855128 -317.650114)
		(end 299.918374 -317.936118)
		(stroke
			(width 0.053848)
			(type default)
		)
		(layer "In9.Cu")
	)
	(gr_line
		(start 299.855128 -317.650114)
		(end 300.029118 -317.377064)
		(stroke
			(width 0.053848)
			(type default)
		)
		(layer "In9.Cu")
	)
	(gr_line
		(start 299.869098 -76.677266)
		(end 300.018196 -76.77785)
		(stroke
			(width 0.06985)
			(type default)
		)
		(layer "In9.Cu")
	)
	(gr_line
		(start 299.935392 -169.042588)
		(end 299.972984 -169.24782)
		(stroke
			(width 0.06985)
			(type default)
		)
		(layer "In9.Cu")
	)
	(gr_line
		(start 299.935392 -169.042588)
		(end 300.173644 -168.697656)
		(stroke
			(width 0.06985)
			(type default)
		)
		(layer "In9.Cu")
	)
	(gr_line
		(start 299.995844 -333.947262)
		(end 300.281848 -333.883762)
		(stroke
			(width 0.053848)
			(type default)
		)
		(layer "In9.Cu")
	)
	(gr_line
		(start 300.018196 -76.77785)
		(end 300.429676 -76.698094)
		(stroke
			(width 0.06985)
			(type default)
		)
		(layer "In9.Cu")
	)
	(gr_line
		(start 300.027086 -172.51426)
		(end 300.218094 -172.478954)
		(stroke
			(width 0.06985)
			(type default)
		)
		(layer "In9.Cu")
	)
	(gr_line
		(start 300.029118 -317.377064)
		(end 300.315122 -317.313564)
		(stroke
			(width 0.053848)
			(type default)
		)
		(layer "In9.Cu")
	)
	(gr_line
		(start 300.041056 -80.39989)
		(end 300.631352 -80.285082)
		(stroke
			(width 0.06985)
			(type default)
		)
		(layer "In9.Cu")
	)
	(gr_line
		(start 300.062138 -80.6958)
		(end 300.211236 -80.796384)
		(stroke
			(width 0.06985)
			(type default)
		)
		(layer "In9.Cu")
	)
	(gr_line
		(start 300.088046 -173.187106)
		(end 300.439836 -172.676058)
		(stroke
			(width 0.06985)
			(type default)
		)
		(layer "In9.Cu")
	)
	(gr_line
		(start 300.173644 -168.697656)
		(end 300.378622 -168.660064)
		(stroke
			(width 0.06985)
			(type default)
		)
		(layer "In9.Cu")
	)
	(gr_line
		(start 300.18609 -334.653128)
		(end 300.541944 -334.094582)
		(stroke
			(width 0.053848)
			(type default)
		)
		(layer "In9.Cu")
	)
	(gr_line
		(start 300.211236 -80.796384)
		(end 300.622716 -80.716374)
		(stroke
			(width 0.06985)
			(type default)
		)
		(layer "In9.Cu")
	)
	(gr_line
		(start 300.218602 -318.084454)
		(end 300.575726 -317.523876)
		(stroke
			(width 0.053848)
			(type default)
		)
		(layer "In9.Cu")
	)
	(gr_line
		(start 300.237144 -169.382694)
		(end 300.59884 -168.858946)
		(stroke
			(width 0.06985)
			(type default)
		)
		(layer "In9.Cu")
	)
	(gr_line
		(start 300.394878 -333.320644)
		(end 300.458378 -333.606648)
		(stroke
			(width 0.053848)
			(type default)
		)
		(layer "In9.Cu")
	)
	(gr_line
		(start 300.394878 -333.320644)
		(end 300.568868 -333.047594)
		(stroke
			(width 0.053848)
			(type default)
		)
		(layer "In9.Cu")
	)
	(gr_line
		(start 300.422818 -171.938696)
		(end 300.458378 -172.129704)
		(stroke
			(width 0.06985)
			(type default)
		)
		(layer "In9.Cu")
	)
	(gr_line
		(start 300.422818 -171.938696)
		(end 300.660562 -171.59351)
		(stroke
			(width 0.06985)
			(type default)
		)
		(layer "In9.Cu")
	)
	(gr_line
		(start 300.429676 -76.698094)
		(end 300.53026 -76.548742)
		(stroke
			(width 0.06985)
			(type default)
		)
		(layer "In9.Cu")
	)
	(gr_line
		(start 300.568868 -333.047594)
		(end 300.855126 -332.984094)
		(stroke
			(width 0.053848)
			(type default)
		)
		(layer "In9.Cu")
	)
	(gr_line
		(start 300.582076 -168.10609)
		(end 300.619668 -168.311322)
		(stroke
			(width 0.06985)
			(type default)
		)
		(layer "In9.Cu")
	)
	(gr_line
		(start 300.582076 -168.10609)
		(end 300.820074 -167.761412)
		(stroke
			(width 0.06985)
			(type default)
		)
		(layer "In9.Cu")
	)
	(gr_line
		(start 300.622716 -80.716374)
		(end 300.723046 -80.567276)
		(stroke
			(width 0.06985)
			(type default)
		)
		(layer "In9.Cu")
	)
	(gr_line
		(start 300.660562 -171.59351)
		(end 300.85157 -171.55795)
		(stroke
			(width 0.06985)
			(type default)
		)
		(layer "In9.Cu")
	)
	(gr_line
		(start 300.721776 -172.266102)
		(end 301.073312 -171.755054)
		(stroke
			(width 0.06985)
			(type default)
		)
		(layer "In9.Cu")
	)
	(gr_line
		(start 300.759876 -333.752444)
		(end 301.115476 -333.194406)
		(stroke
			(width 0.053848)
			(type default)
		)
		(layer "In9.Cu")
	)
	(gr_line
		(start 300.820074 -167.761412)
		(end 301.025306 -167.72382)
		(stroke
			(width 0.06985)
			(type default)
		)
		(layer "In9.Cu")
	)
	(gr_line
		(start 300.867572 -204.28585)
		(end 300.874684 -204.317854)
		(stroke
			(width 0.053848)
			(type default)
		)
		(layer "In9.Cu")
	)
	(gr_line
		(start 300.867572 -204.28585)
		(end 300.874938 -204.252576)
		(stroke
			(width 0.053848)
			(type default)
		)
		(layer "In9.Cu")
	)
	(gr_line
		(start 300.883574 -168.446958)
		(end 301.246032 -167.922194)
		(stroke
			(width 0.06985)
			(type default)
		)
		(layer "In9.Cu")
	)
	(gr_line
		(start 300.924976 -76.17206)
		(end 301.515526 -76.057252)
		(stroke
			(width 0.06985)
			(type default)
		)
		(layer "In9.Cu")
	)
	(gr_line
		(start 300.946312 -76.46797)
		(end 301.09541 -76.568554)
		(stroke
			(width 0.06985)
			(type default)
		)
		(layer "In9.Cu")
	)
	(gr_line
		(start 301.017432 -336.184748)
		(end 301.080932 -336.470752)
		(stroke
			(width 0.053848)
			(type default)
		)
		(layer "In9.Cu")
	)
	(gr_line
		(start 301.017432 -336.184748)
		(end 301.191676 -335.911444)
		(stroke
			(width 0.053848)
			(type default)
		)
		(layer "In9.Cu")
	)
	(gr_line
		(start 301.056548 -171.017946)
		(end 301.091854 -171.208954)
		(stroke
			(width 0.06985)
			(type default)
		)
		(layer "In9.Cu")
	)
	(gr_line
		(start 301.056548 -171.017946)
		(end 301.294038 -170.67276)
		(stroke
			(width 0.06985)
			(type default)
		)
		(layer "In9.Cu")
	)
	(gr_line
		(start 301.09541 -76.568554)
		(end 301.50689 -76.488544)
		(stroke
			(width 0.06985)
			(type default)
		)
		(layer "In9.Cu")
	)
	(gr_line
		(start 301.118778 -337.004406)
		(end 301.146972 -336.986372)
		(stroke
			(width 0.053848)
			(type default)
		)
		(layer "In9.Cu")
	)
	(gr_line
		(start 301.118778 -80.19034)
		(end 301.709074 -80.075786)
		(stroke
			(width 0.06985)
			(type default)
		)
		(layer "In9.Cu")
	)
	(gr_line
		(start 301.139352 -80.486504)
		(end 301.28845 -80.587088)
		(stroke
			(width 0.06985)
			(type default)
		)
		(layer "In9.Cu")
	)
	(gr_line
		(start 301.146972 -336.986372)
		(end 301.165006 -336.958178)
		(stroke
			(width 0.053848)
			(type default)
		)
		(layer "In9.Cu")
	)
	(gr_line
		(start 301.191676 -335.911444)
		(end 301.477426 -335.848198)
		(stroke
			(width 0.053848)
			(type default)
		)
		(layer "In9.Cu")
	)
	(gr_line
		(start 301.28845 -80.587088)
		(end 301.69993 -80.507078)
		(stroke
			(width 0.06985)
			(type default)
		)
		(layer "In9.Cu")
	)
	(gr_line
		(start 301.294038 -170.67276)
		(end 301.485046 -170.637454)
		(stroke
			(width 0.06985)
			(type default)
		)
		(layer "In9.Cu")
	)
	(gr_line
		(start 301.306738 -284.496764)
		(end 301.318168 -284.48)
		(stroke
			(width 0.053848)
			(type default)
		)
		(layer "In9.Cu")
	)
	(gr_line
		(start 301.318168 -284.48)
		(end 301.32274 -284.459172)
		(stroke
			(width 0.053848)
			(type default)
		)
		(layer "In9.Cu")
	)
	(gr_line
		(start 301.354236 -171.347384)
		(end 301.708058 -170.833288)
		(stroke
			(width 0.06985)
			(type default)
		)
		(layer "In9.Cu")
	)
	(gr_line
		(start 301.381668 -336.618072)
		(end 301.73803 -336.058764)
		(stroke
			(width 0.053848)
			(type default)
		)
		(layer "In9.Cu")
	)
	(gr_line
		(start 301.50689 -76.488544)
		(end 301.607474 -76.339446)
		(stroke
			(width 0.06985)
			(type default)
		)
		(layer "In9.Cu")
	)
	(gr_line
		(start 301.59071 -335.284826)
		(end 301.65421 -335.57083)
		(stroke
			(width 0.053848)
			(type default)
		)
		(layer "In9.Cu")
	)
	(gr_line
		(start 301.59071 -335.284826)
		(end 301.7647 -335.011776)
		(stroke
			(width 0.053848)
			(type default)
		)
		(layer "In9.Cu")
	)
	(gr_line
		(start 301.69993 -80.507078)
		(end 301.800514 -80.35798)
		(stroke
			(width 0.06985)
			(type default)
		)
		(layer "In9.Cu")
	)
	(gr_line
		(start 301.7647 -335.011776)
		(end 302.050958 -334.948276)
		(stroke
			(width 0.053848)
			(type default)
		)
		(layer "In9.Cu")
	)
	(gr_line
		(start 301.954946 -335.71815)
		(end 302.311562 -335.158334)
		(stroke
			(width 0.053848)
			(type default)
		)
		(layer "In9.Cu")
	)
	(gr_line
		(start 302.118268 -286.390842)
		(end 302.129444 -286.373824)
		(stroke
			(width 0.053848)
			(type default)
		)
		(layer "In9.Cu")
	)
	(gr_line
		(start 302.129444 -286.373824)
		(end 302.133762 -286.35452)
		(stroke
			(width 0.053848)
			(type default)
		)
		(layer "In9.Cu")
	)
	(gr_line
		(start 302.163988 -334.385158)
		(end 302.227234 -334.671162)
		(stroke
			(width 0.053848)
			(type default)
		)
		(layer "In9.Cu")
	)
	(gr_line
		(start 302.163988 -334.385158)
		(end 302.337978 -334.112108)
		(stroke
			(width 0.053848)
			(type default)
		)
		(layer "In9.Cu")
	)
	(gr_line
		(start 302.337978 -334.112108)
		(end 302.623982 -334.048608)
		(stroke
			(width 0.053848)
			(type default)
		)
		(layer "In9.Cu")
	)
	(gr_line
		(start 302.377348 -206.124556)
		(end 302.38446 -206.15656)
		(stroke
			(width 0.053848)
			(type default)
		)
		(layer "In9.Cu")
	)
	(gr_line
		(start 302.377348 -206.124556)
		(end 302.38446 -206.092298)
		(stroke
			(width 0.053848)
			(type default)
		)
		(layer "In9.Cu")
	)
	(gr_line
		(start 302.38446 -206.156814)
		(end 302.38446 -206.157068)
		(stroke
			(width 0.053848)
			(type default)
		)
		(layer "In9.Cu")
	)
	(gr_line
		(start 302.527716 -334.81899)
		(end 302.884332 -334.259174)
		(stroke
			(width 0.053848)
			(type default)
		)
		(layer "In9.Cu")
	)
	(gr_line
		(start 303.321974 -287.904936)
		(end 303.33315 -287.887918)
		(stroke
			(width 0.053848)
			(type default)
		)
		(layer "In9.Cu")
	)
	(gr_line
		(start 303.33315 -287.887918)
		(end 303.337468 -287.868614)
		(stroke
			(width 0.053848)
			(type default)
		)
		(layer "In9.Cu")
	)
	(gr_line
		(start 303.93513 -157.502098)
		(end 303.97069 -157.693106)
		(stroke
			(width 0.06985)
			(type default)
		)
		(layer "In9.Cu")
	)
	(gr_line
		(start 303.93513 -157.502098)
		(end 304.17262 -157.156912)
		(stroke
			(width 0.06985)
			(type default)
		)
		(layer "In9.Cu")
	)
	(gr_line
		(start 304.11166 -206.82966)
		(end 304.118772 -206.861664)
		(stroke
			(width 0.053848)
			(type default)
		)
		(layer "In9.Cu")
	)
	(gr_line
		(start 304.11166 -206.82966)
		(end 304.118772 -206.797402)
		(stroke
			(width 0.053848)
			(type default)
		)
		(layer "In9.Cu")
	)
	(gr_line
		(start 304.118772 -206.861918)
		(end 304.118772 -206.862172)
		(stroke
			(width 0.053848)
			(type default)
		)
		(layer "In9.Cu")
	)
	(gr_line
		(start 304.17262 -157.156912)
		(end 304.363628 -157.121352)
		(stroke
			(width 0.06985)
			(type default)
		)
		(layer "In9.Cu")
	)
	(gr_line
		(start 304.232818 -157.83179)
		(end 304.58664 -157.317186)
		(stroke
			(width 0.06985)
			(type default)
		)
		(layer "In9.Cu")
	)
	(gr_line
		(start 304.568352 -156.581348)
		(end 304.603658 -156.772356)
		(stroke
			(width 0.06985)
			(type default)
		)
		(layer "In9.Cu")
	)
	(gr_line
		(start 304.568352 -156.581348)
		(end 304.805588 -156.235908)
		(stroke
			(width 0.06985)
			(type default)
		)
		(layer "In9.Cu")
	)
	(gr_line
		(start 304.805588 -156.235908)
		(end 304.99685 -156.200348)
		(stroke
			(width 0.06985)
			(type default)
		)
		(layer "In9.Cu")
	)
	(gr_line
		(start 304.823114 -288.85515)
		(end 304.83429 -288.838132)
		(stroke
			(width 0.053848)
			(type default)
		)
		(layer "In9.Cu")
	)
	(gr_line
		(start 304.83429 -288.838132)
		(end 304.838608 -288.818828)
		(stroke
			(width 0.053848)
			(type default)
		)
		(layer "In9.Cu")
	)
	(gr_line
		(start 304.865532 -156.911548)
		(end 305.22037 -156.39542)
		(stroke
			(width 0.06985)
			(type default)
		)
		(layer "In9.Cu")
	)
	(gr_line
		(start 305.006756 -87.988648)
		(end 305.021488 -87.985346)
		(stroke
			(width 0.06985)
			(type default)
		)
		(layer "In9.Cu")
	)
	(gr_line
		(start 305.021488 -87.985346)
		(end 305.033934 -87.977472)
		(stroke
			(width 0.06985)
			(type default)
		)
		(layer "In9.Cu")
	)
	(gr_line
		(start 305.096926 -158.401258)
		(end 305.132486 -158.593282)
		(stroke
			(width 0.06985)
			(type default)
		)
		(layer "In9.Cu")
	)
	(gr_line
		(start 305.096926 -158.401258)
		(end 305.33467 -158.056072)
		(stroke
			(width 0.06985)
			(type default)
		)
		(layer "In9.Cu")
	)
	(gr_line
		(start 305.20132 -155.660344)
		(end 305.23688 -155.851352)
		(stroke
			(width 0.06985)
			(type default)
		)
		(layer "In9.Cu")
	)
	(gr_line
		(start 305.20132 -155.660344)
		(end 305.43881 -155.314904)
		(stroke
			(width 0.06985)
			(type default)
		)
		(layer "In9.Cu")
	)
	(gr_line
		(start 305.33467 -158.056072)
		(end 305.526694 -158.020512)
		(stroke
			(width 0.06985)
			(type default)
		)
		(layer "In9.Cu")
	)
	(gr_line
		(start 305.34229 -86.286848)
		(end 305.357022 -86.283546)
		(stroke
			(width 0.06985)
			(type default)
		)
		(layer "In9.Cu")
	)
	(gr_line
		(start 305.357022 -86.283546)
		(end 305.369468 -86.275672)
		(stroke
			(width 0.06985)
			(type default)
		)
		(layer "In9.Cu")
	)
	(gr_line
		(start 305.392836 -158.734506)
		(end 305.751992 -158.212536)
		(stroke
			(width 0.06985)
			(type default)
		)
		(layer "In9.Cu")
	)
	(gr_line
		(start 305.43881 -155.314904)
		(end 305.629818 -155.279344)
		(stroke
			(width 0.06985)
			(type default)
		)
		(layer "In9.Cu")
	)
	(gr_line
		(start 305.491642 -293.868856)
		(end 305.501294 -293.853616)
		(stroke
			(width 0.053848)
			(type default)
		)
		(layer "In9.Cu")
	)
	(gr_line
		(start 305.499262 -155.989782)
		(end 305.853592 -155.474416)
		(stroke
			(width 0.06985)
			(type default)
		)
		(layer "In9.Cu")
	)
	(gr_line
		(start 305.501294 -293.853616)
		(end 305.50485 -293.836598)
		(stroke
			(width 0.053848)
			(type default)
		)
		(layer "In9.Cu")
	)
	(gr_line
		(start 305.730656 -157.480508)
		(end 305.765962 -157.672532)
		(stroke
			(width 0.06985)
			(type default)
		)
		(layer "In9.Cu")
	)
	(gr_line
		(start 305.730656 -157.480508)
		(end 305.968146 -157.135322)
		(stroke
			(width 0.06985)
			(type default)
		)
		(layer "In9.Cu")
	)
	(gr_line
		(start 305.968146 -157.135322)
		(end 306.16017 -157.100016)
		(stroke
			(width 0.06985)
			(type default)
		)
		(layer "In9.Cu")
	)
	(gr_line
		(start 306.025804 -157.814772)
		(end 306.385722 -157.29204)
		(stroke
			(width 0.06985)
			(type default)
		)
		(layer "In9.Cu")
	)
	(gr_line
		(start 306.166774 -205.204314)
		(end 306.173886 -205.236572)
		(stroke
			(width 0.053848)
			(type default)
		)
		(layer "In9.Cu")
	)
	(gr_line
		(start 306.166774 -205.204314)
		(end 306.173886 -205.17231)
		(stroke
			(width 0.053848)
			(type default)
		)
		(layer "In9.Cu")
	)
	(gr_line
		(start 306.173886 -205.171802)
		(end 306.173886 -205.172056)
		(stroke
			(width 0.053848)
			(type default)
		)
		(layer "In9.Cu")
	)
	(gr_line
		(start 306.332128 -324.391274)
		(end 306.350162 -324.36308)
		(stroke
			(width 0.053848)
			(type default)
		)
		(layer "In9.Cu")
	)
	(gr_line
		(start 306.350162 -324.36308)
		(end 306.378102 -324.344792)
		(stroke
			(width 0.053848)
			(type default)
		)
		(layer "In9.Cu")
	)
	(gr_line
		(start 306.364132 -156.559758)
		(end 306.399438 -156.752036)
		(stroke
			(width 0.06985)
			(type default)
		)
		(layer "In9.Cu")
	)
	(gr_line
		(start 306.364132 -156.559758)
		(end 306.601876 -156.214572)
		(stroke
			(width 0.06985)
			(type default)
		)
		(layer "In9.Cu")
	)
	(gr_line
		(start 306.554886 -295.250108)
		(end 306.564284 -295.23563)
		(stroke
			(width 0.053848)
			(type default)
		)
		(layer "In9.Cu")
	)
	(gr_line
		(start 306.564284 -295.23563)
		(end 306.56784 -295.218612)
		(stroke
			(width 0.053848)
			(type default)
		)
		(layer "In9.Cu")
	)
	(gr_line
		(start 306.601876 -156.214572)
		(end 306.793646 -156.179266)
		(stroke
			(width 0.06985)
			(type default)
		)
		(layer "In9.Cu")
	)
	(gr_line
		(start 306.612544 -327.791826)
		(end 306.630578 -327.763632)
		(stroke
			(width 0.053848)
			(type default)
		)
		(layer "In9.Cu")
	)
	(gr_line
		(start 306.630578 -327.763632)
		(end 306.658772 -327.745598)
		(stroke
			(width 0.053848)
			(type default)
		)
		(layer "In9.Cu")
	)
	(gr_line
		(start 306.659026 -156.89453)
		(end 307.01869 -156.371544)
		(stroke
			(width 0.06985)
			(type default)
		)
		(layer "In9.Cu")
	)
	(gr_line
		(start 306.77866 -159.151066)
		(end 306.813712 -159.342328)
		(stroke
			(width 0.06985)
			(type default)
		)
		(layer "In9.Cu")
	)
	(gr_line
		(start 306.77866 -159.151066)
		(end 307.016912 -158.806134)
		(stroke
			(width 0.06985)
			(type default)
		)
		(layer "In9.Cu")
	)
	(gr_line
		(start 307.016912 -158.806134)
		(end 307.208174 -158.771082)
		(stroke
			(width 0.06985)
			(type default)
		)
		(layer "In9.Cu")
	)
	(gr_line
		(start 307.076094 -159.48025)
		(end 307.429662 -158.96844)
		(stroke
			(width 0.06985)
			(type default)
		)
		(layer "In9.Cu")
	)
	(gr_line
		(start 307.41366 -158.231332)
		(end 307.448712 -158.422848)
		(stroke
			(width 0.06985)
			(type default)
		)
		(layer "In9.Cu")
	)
	(gr_line
		(start 307.41366 -158.231332)
		(end 307.651912 -157.886654)
		(stroke
			(width 0.06985)
			(type default)
		)
		(layer "In9.Cu")
	)
	(gr_line
		(start 307.651912 -157.886654)
		(end 307.843174 -157.851602)
		(stroke
			(width 0.06985)
			(type default)
		)
		(layer "In9.Cu")
	)
	(gr_line
		(start 307.71084 -158.561278)
		(end 308.064662 -158.048706)
		(stroke
			(width 0.06985)
			(type default)
		)
		(layer "In9.Cu")
	)
	(gr_line
		(start 307.756306 -296.55643)
		(end 307.765704 -296.541952)
		(stroke
			(width 0.053848)
			(type default)
		)
		(layer "In9.Cu")
	)
	(gr_line
		(start 307.765704 -296.541952)
		(end 307.76926 -296.524934)
		(stroke
			(width 0.053848)
			(type default)
		)
		(layer "In9.Cu")
	)
	(gr_line
		(start 307.91023 -205.610714)
		(end 307.917342 -205.642972)
		(stroke
			(width 0.053848)
			(type default)
		)
		(layer "In9.Cu")
	)
	(gr_line
		(start 307.91023 -205.610714)
		(end 307.917342 -205.57871)
		(stroke
			(width 0.053848)
			(type default)
		)
		(layer "In9.Cu")
	)
	(gr_line
		(start 307.917342 -205.578202)
		(end 307.917342 -205.578456)
		(stroke
			(width 0.053848)
			(type default)
		)
		(layer "In9.Cu")
	)
	(gr_line
		(start 308.048914 -157.311852)
		(end 308.083966 -157.503114)
		(stroke
			(width 0.06985)
			(type default)
		)
		(layer "In9.Cu")
	)
	(gr_line
		(start 308.048914 -157.311852)
		(end 308.286912 -156.96692)
		(stroke
			(width 0.06985)
			(type default)
		)
		(layer "In9.Cu")
	)
	(gr_line
		(start 308.286912 -156.96692)
		(end 308.478428 -156.931868)
		(stroke
			(width 0.06985)
			(type default)
		)
		(layer "In9.Cu")
	)
	(gr_line
		(start 308.346602 -157.640782)
		(end 308.70017 -157.128464)
		(stroke
			(width 0.06985)
			(type default)
		)
		(layer "In9.Cu")
	)
	(gr_line
		(start 309.108856 -297.549824)
		(end 309.118254 -297.535346)
		(stroke
			(width 0.053848)
			(type default)
		)
		(layer "In9.Cu")
	)
	(gr_line
		(start 309.118254 -297.535346)
		(end 309.12181 -297.518328)
		(stroke
			(width 0.053848)
			(type default)
		)
		(layer "In9.Cu")
	)
	(gr_line
		(start 310.110124 -244.52199)
		(end 310.117236 -244.489478)
		(stroke
			(width 0.053848)
			(type default)
		)
		(layer "In9.Cu")
	)
	(gr_line
		(start 310.110124 -244.456966)
		(end 310.117236 -244.489478)
		(stroke
			(width 0.053848)
			(type default)
		)
		(layer "In9.Cu")
	)
	(gr_line
		(start 310.225186 -298.828714)
		(end 310.234584 -298.814236)
		(stroke
			(width 0.053848)
			(type default)
		)
		(layer "In9.Cu")
	)
	(gr_line
		(start 310.234584 -298.814236)
		(end 310.23814 -298.797218)
		(stroke
			(width 0.053848)
			(type default)
		)
		(layer "In9.Cu")
	)
	(gr_line
		(start 310.744362 -159.723582)
		(end 310.749696 -159.699452)
		(stroke
			(width 0.053848)
			(type default)
		)
		(layer "In9.Cu")
	)
	(gr_line
		(start 310.749696 -159.699452)
		(end 310.763666 -159.679386)
		(stroke
			(width 0.053848)
			(type default)
		)
		(layer "In9.Cu")
	)
	(gr_line
		(start 311.313322 -244.963188)
		(end 311.313322 -244.963442)
		(stroke
			(width 0.053848)
			(type default)
		)
		(layer "In9.Cu")
	)
	(gr_line
		(start 311.313322 -244.962934)
		(end 311.320434 -244.93093)
		(stroke
			(width 0.053848)
			(type default)
		)
		(layer "In9.Cu")
	)
	(gr_line
		(start 311.313322 -244.898672)
		(end 311.320434 -244.93093)
		(stroke
			(width 0.053848)
			(type default)
		)
		(layer "In9.Cu")
	)
	(gr_line
		(start 311.596278 -146.35861)
		(end 311.631584 -146.549872)
		(stroke
			(width 0.06985)
			(type default)
		)
		(layer "In9.Cu")
	)
	(gr_line
		(start 311.596278 -146.35861)
		(end 311.833514 -146.01317)
		(stroke
			(width 0.06985)
			(type default)
		)
		(layer "In9.Cu")
	)
	(gr_line
		(start 311.833514 -146.01317)
		(end 312.024776 -145.97761)
		(stroke
			(width 0.06985)
			(type default)
		)
		(layer "In9.Cu")
	)
	(gr_line
		(start 311.893204 -146.689572)
		(end 312.249312 -146.171412)
		(stroke
			(width 0.06985)
			(type default)
		)
		(layer "In9.Cu")
	)
	(gr_line
		(start 312.229246 -145.437606)
		(end 312.264806 -145.628868)
		(stroke
			(width 0.06985)
			(type default)
		)
		(layer "In9.Cu")
	)
	(gr_line
		(start 312.229246 -145.437606)
		(end 312.466736 -145.092166)
		(stroke
			(width 0.06985)
			(type default)
		)
		(layer "In9.Cu")
	)
	(gr_line
		(start 312.44286 -298.895262)
		(end 312.452258 -298.880784)
		(stroke
			(width 0.053848)
			(type default)
		)
		(layer "In9.Cu")
	)
	(gr_line
		(start 312.452258 -298.880784)
		(end 312.455814 -298.863766)
		(stroke
			(width 0.053848)
			(type default)
		)
		(layer "In9.Cu")
	)
	(gr_line
		(start 312.466736 -145.092166)
		(end 312.657744 -145.05686)
		(stroke
			(width 0.06985)
			(type default)
		)
		(layer "In9.Cu")
	)
	(gr_line
		(start 312.482484 -304.868072)
		(end 312.491882 -304.853594)
		(stroke
			(width 0.053848)
			(type default)
		)
		(layer "In9.Cu")
	)
	(gr_line
		(start 312.491882 -304.853594)
		(end 312.495438 -304.836576)
		(stroke
			(width 0.053848)
			(type default)
		)
		(layer "In9.Cu")
	)
	(gr_line
		(start 312.526426 -145.768568)
		(end 312.88228 -145.25117)
		(stroke
			(width 0.06985)
			(type default)
		)
		(layer "In9.Cu")
	)
	(gr_line
		(start 312.776108 -159.21482)
		(end 312.78195 -159.188658)
		(stroke
			(width 0.053848)
			(type default)
		)
		(layer "In9.Cu")
	)
	(gr_line
		(start 312.78195 -159.188658)
		(end 312.796428 -159.167322)
		(stroke
			(width 0.053848)
			(type default)
		)
		(layer "In9.Cu")
	)
	(gr_line
		(start 312.870088 -244.877844)
		(end 312.870088 -244.878098)
		(stroke
			(width 0.053848)
			(type default)
		)
		(layer "In9.Cu")
	)
	(gr_line
		(start 312.870088 -244.87759)
		(end 312.8772 -244.845586)
		(stroke
			(width 0.053848)
			(type default)
		)
		(layer "In9.Cu")
	)
	(gr_line
		(start 312.870088 -244.813328)
		(end 312.8772 -244.845586)
		(stroke
			(width 0.053848)
			(type default)
		)
		(layer "In9.Cu")
	)
	(gr_line
		(start 312.89244 -88.095074)
		(end 312.911744 -88.09101)
		(stroke
			(width 0.06985)
			(type default)
		)
		(layer "In9.Cu")
	)
	(gr_line
		(start 312.911744 -88.09101)
		(end 312.928508 -88.079326)
		(stroke
			(width 0.06985)
			(type default)
		)
		(layer "In9.Cu")
	)
	(gr_line
		(start 312.913014 -147.043394)
		(end 312.94832 -147.235164)
		(stroke
			(width 0.06985)
			(type default)
		)
		(layer "In9.Cu")
	)
	(gr_line
		(start 312.913014 -147.043394)
		(end 313.150504 -146.697954)
		(stroke
			(width 0.06985)
			(type default)
		)
		(layer "In9.Cu")
	)
	(gr_line
		(start 313.150504 -146.697954)
		(end 313.342274 -146.662648)
		(stroke
			(width 0.06985)
			(type default)
		)
		(layer "In9.Cu")
	)
	(gr_line
		(start 313.20867 -147.376642)
		(end 313.567826 -146.854672)
		(stroke
			(width 0.06985)
			(type default)
		)
		(layer "In9.Cu")
	)
	(gr_line
		(start 313.54649 -146.122644)
		(end 313.581796 -146.314414)
		(stroke
			(width 0.06985)
			(type default)
		)
		(layer "In9.Cu")
	)
	(gr_line
		(start 313.54649 -146.122644)
		(end 313.784234 -145.777458)
		(stroke
			(width 0.06985)
			(type default)
		)
		(layer "In9.Cu")
	)
	(gr_line
		(start 313.645296 -268.486636)
		(end 313.64936 -268.468602)
		(stroke
			(width 0.053848)
			(type default)
		)
		(layer "In9.Cu")
	)
	(gr_line
		(start 313.64936 -268.468602)
		(end 313.659012 -268.452854)
		(stroke
			(width 0.053848)
			(type default)
		)
		(layer "In9.Cu")
	)
	(gr_line
		(start 313.784234 -145.777458)
		(end 313.976004 -145.741898)
		(stroke
			(width 0.06985)
			(type default)
		)
		(layer "In9.Cu")
	)
	(gr_line
		(start 313.804046 -78.022196)
		(end 313.82208 -78.01864)
		(stroke
			(width 0.06985)
			(type default)
		)
		(layer "In9.Cu")
	)
	(gr_line
		(start 313.82208 -78.01864)
		(end 313.837574 -78.008734)
		(stroke
			(width 0.06985)
			(type default)
		)
		(layer "In9.Cu")
	)
	(gr_line
		(start 313.841638 -146.456908)
		(end 314.20181 -145.93316)
		(stroke
			(width 0.06985)
			(type default)
		)
		(layer "In9.Cu")
	)
	(gr_line
		(start 314.22086 -89.525348)
		(end 314.240164 -89.521284)
		(stroke
			(width 0.06985)
			(type default)
		)
		(layer "In9.Cu")
	)
	(gr_line
		(start 314.240164 -89.521284)
		(end 314.256928 -89.5096)
		(stroke
			(width 0.06985)
			(type default)
		)
		(layer "In9.Cu")
	)
	(gr_line
		(start 314.513214 -257.860546)
		(end 314.51677 -257.843528)
		(stroke
			(width 0.053848)
			(type default)
		)
		(layer "In9.Cu")
	)
	(gr_line
		(start 314.51677 -257.843528)
		(end 314.526168 -257.82905)
		(stroke
			(width 0.053848)
			(type default)
		)
		(layer "In9.Cu")
	)
	(gr_line
		(start 314.519818 -271.648682)
		(end 314.523374 -271.631664)
		(stroke
			(width 0.053848)
			(type default)
		)
		(layer "In9.Cu")
	)
	(gr_line
		(start 314.523374 -271.631664)
		(end 314.532772 -271.617186)
		(stroke
			(width 0.053848)
			(type default)
		)
		(layer "In9.Cu")
	)
	(gr_line
		(start 314.53201 -147.923758)
		(end 314.567062 -148.115528)
		(stroke
			(width 0.06985)
			(type default)
		)
		(layer "In9.Cu")
	)
	(gr_line
		(start 314.53201 -147.923758)
		(end 314.770262 -147.578826)
		(stroke
			(width 0.06985)
			(type default)
		)
		(layer "In9.Cu")
	)
	(gr_line
		(start 314.690506 -159.114744)
		(end 314.69584 -159.090614)
		(stroke
			(width 0.053848)
			(type default)
		)
		(layer "In9.Cu")
	)
	(gr_line
		(start 314.69584 -159.090614)
		(end 314.70981 -159.07004)
		(stroke
			(width 0.053848)
			(type default)
		)
		(layer "In9.Cu")
	)
	(gr_line
		(start 314.770262 -147.578826)
		(end 314.961778 -147.543774)
		(stroke
			(width 0.06985)
			(type default)
		)
		(layer "In9.Cu")
	)
	(gr_line
		(start 314.82792 -148.25599)
		(end 315.185298 -147.738338)
		(stroke
			(width 0.06985)
			(type default)
		)
		(layer "In9.Cu")
	)
	(gr_line
		(start 314.93206 -243.289074)
		(end 314.939172 -243.256816)
		(stroke
			(width 0.053848)
			(type default)
		)
		(layer "In9.Cu")
	)
	(gr_line
		(start 314.93206 -243.224812)
		(end 314.939172 -243.256816)
		(stroke
			(width 0.053848)
			(type default)
		)
		(layer "In9.Cu")
	)
	(gr_line
		(start 314.93206 -243.224304)
		(end 314.93206 -243.224558)
		(stroke
			(width 0.053848)
			(type default)
		)
		(layer "In9.Cu")
	)
	(gr_line
		(start 315.167264 -147.004024)
		(end 315.202316 -147.19554)
		(stroke
			(width 0.06985)
			(type default)
		)
		(layer "In9.Cu")
	)
	(gr_line
		(start 315.167264 -147.004024)
		(end 315.405262 -146.659346)
		(stroke
			(width 0.06985)
			(type default)
		)
		(layer "In9.Cu")
	)
	(gr_line
		(start 315.405262 -146.659346)
		(end 315.596778 -146.624294)
		(stroke
			(width 0.06985)
			(type default)
		)
		(layer "In9.Cu")
	)
	(gr_line
		(start 315.463174 -147.33651)
		(end 315.821822 -146.817334)
		(stroke
			(width 0.06985)
			(type default)
		)
		(layer "In9.Cu")
	)
	(gr_line
		(start 315.700918 -272.619724)
		(end 315.704474 -272.602706)
		(stroke
			(width 0.053848)
			(type default)
		)
		(layer "In9.Cu")
	)
	(gr_line
		(start 315.704474 -272.602706)
		(end 315.713872 -272.588228)
		(stroke
			(width 0.053848)
			(type default)
		)
		(layer "In9.Cu")
	)
	(gr_line
		(start 316.161674 -160.11652)
		(end 316.167008 -160.09239)
		(stroke
			(width 0.053848)
			(type default)
		)
		(layer "In9.Cu")
	)
	(gr_line
		(start 316.167008 -160.09239)
		(end 316.180978 -160.072324)
		(stroke
			(width 0.053848)
			(type default)
		)
		(layer "In9.Cu")
	)
	(gr_line
		(start 316.585092 -73.425812)
		(end 316.603126 -73.422256)
		(stroke
			(width 0.06985)
			(type default)
		)
		(layer "In9.Cu")
	)
	(gr_line
		(start 316.603126 -73.422256)
		(end 316.61862 -73.41235)
		(stroke
			(width 0.06985)
			(type default)
		)
		(layer "In9.Cu")
	)
	(gr_line
		(start 316.65926 -243.609368)
		(end 316.666372 -243.57711)
		(stroke
			(width 0.053848)
			(type default)
		)
		(layer "In9.Cu")
	)
	(gr_line
		(start 316.65926 -243.545106)
		(end 316.666372 -243.57711)
		(stroke
			(width 0.053848)
			(type default)
		)
		(layer "In9.Cu")
	)
	(gr_line
		(start 316.65926 -243.544598)
		(end 316.65926 -243.544852)
		(stroke
			(width 0.053848)
			(type default)
		)
		(layer "In9.Cu")
	)
	(gr_line
		(start 317.780924 -273.32051)
		(end 317.78448 -273.303492)
		(stroke
			(width 0.053848)
			(type default)
		)
		(layer "In9.Cu")
	)
	(gr_line
		(start 317.78448 -273.303492)
		(end 317.793624 -273.289268)
		(stroke
			(width 0.053848)
			(type default)
		)
		(layer "In9.Cu")
	)
	(gr_line
		(start 317.970408 -160.23463)
		(end 317.974472 -160.216596)
		(stroke
			(width 0.053848)
			(type default)
		)
		(layer "In9.Cu")
	)
	(gr_line
		(start 317.974472 -160.216596)
		(end 317.984124 -160.20161)
		(stroke
			(width 0.053848)
			(type default)
		)
		(layer "In9.Cu")
	)
	(gr_line
		(start 318.967866 -274.115784)
		(end 318.984122 -274.041616)
		(stroke
			(width 0.053848)
			(type default)
		)
		(layer "In9.Cu")
	)
	(gr_line
		(start 318.984122 -274.041616)
		(end 319.043558 -273.994118)
		(stroke
			(width 0.053848)
			(type default)
		)
		(layer "In9.Cu")
	)
	(gr_line
		(start 318.989964 -158.842964)
		(end 319.058036 -158.774892)
		(stroke
			(width 0.053848)
			(type default)
		)
		(layer "In9.Cu")
	)
	(gr_line
		(start 319.257934 -273.821906)
		(end 319.287144 -273.798538)
		(stroke
			(width 0.053848)
			(type default)
		)
		(layer "In9.Cu")
	)
	(gr_arc
		(start 319.354454 -273.774916)
		(mid 319.318787 -273.780994)
		(end 319.287144 -273.798538)
		(stroke
			(width 0.053848)
			(type default)
		)
		(layer "In9.Cu")
	)
	(gr_line
		(start 319.786 -270.162274)
		(end 319.804034 -270.13408)
		(stroke
			(width 0.053848)
			(type default)
		)
		(layer "In9.Cu")
	)
	(gr_line
		(start 319.804034 -270.13408)
		(end 319.832228 -270.116046)
		(stroke
			(width 0.053848)
			(type default)
		)
		(layer "In9.Cu")
	)
	(gr_arc
		(start 319.820798 -158.774892)
		(mid 319.939874 -158.725568)
		(end 319.9892 -158.60649)
		(stroke
			(width 0.053848)
			(type default)
		)
		(layer "In9.Cu")
	)
	(gr_arc
		(start 319.891918 -273.774916)
		(mid 319.928995 -273.767593)
		(end 319.960498 -273.746722)
		(stroke
			(width 0.053848)
			(type default)
		)
		(layer "In9.Cu")
	)
	(gr_arc
		(start 319.952878 -274.141438)
		(mid 319.912679 -274.114555)
		(end 319.865248 -274.105116)
		(stroke
			(width 0.053848)
			(type default)
		)
		(layer "In9.Cu")
	)
	(gr_line
		(start 319.960498 -273.746722)
		(end 319.960752 -273.746468)
		(stroke
			(width 0.053848)
			(type default)
		)
		(layer "In9.Cu")
	)
	(gr_arc
		(start 319.960752 -273.746468)
		(mid 319.981868 -273.714759)
		(end 319.9892 -273.67738)
		(stroke
			(width 0.053848)
			(type default)
		)
		(layer "In9.Cu")
	)
	(gr_arc
		(start 319.9892 -274.229068)
		(mid 319.97973 -274.181653)
		(end 319.952878 -274.141438)
		(stroke
			(width 0.053848)
			(type default)
		)
		(layer "In9.Cu")
	)
	(gr_line
		(start 319.9892 -274.229068)
		(end 319.9892 -274.511516)
		(stroke
			(width 0.053848)
			(type default)
		)
		(layer "In9.Cu")
	)
	(gr_line
		(start 319.9892 -273.368516)
		(end 319.9892 -273.67738)
		(stroke
			(width 0.053848)
			(type default)
		)
		(layer "In9.Cu")
	)
	(gr_arc
		(start 319.9892 -159.273494)
		(mid 319.939874 -159.15442)
		(end 319.820798 -159.105092)
		(stroke
			(width 0.053848)
			(type default)
		)
		(layer "In9.Cu")
	)
	(gr_line
		(start 319.9892 -159.273494)
		(end 319.9892 -159.511492)
		(stroke
			(width 0.053848)
			(type default)
		)
		(layer "In9.Cu")
	)
	(gr_line
		(start 319.9892 -158.368492)
		(end 319.9892 -158.60649)
		(stroke
			(width 0.053848)
			(type default)
		)
		(layer "In9.Cu")
	)
	(gr_line
		(start 324.306946 -313.076844)
		(end 324.329044 -313.06262)
		(stroke
			(width 0.053848)
			(type default)
		)
		(layer "In9.Cu")
	)
	(gr_line
		(start 324.329044 -313.06262)
		(end 324.344284 -313.040522)
		(stroke
			(width 0.053848)
			(type default)
		)
		(layer "In9.Cu")
	)
	(gr_line
		(start 326.480932 -34.644838)
		(end 326.510904 -34.629598)
		(stroke
			(width 0.06985)
			(type default)
		)
		(layer "In9.Cu")
	)
	(gr_line
		(start 326.510904 -34.629598)
		(end 326.530716 -34.60242)
		(stroke
			(width 0.06985)
			(type default)
		)
		(layer "In9.Cu")
	)
	(gr_line
		(start 328.464926 -306.469034)
		(end 328.480166 -306.446682)
		(stroke
			(width 0.053848)
			(type default)
		)
		(layer "In9.Cu")
	)
	(gr_line
		(start 328.480166 -306.446682)
		(end 328.50328 -306.43195)
		(stroke
			(width 0.053848)
			(type default)
		)
		(layer "In9.Cu")
	)
	(gr_line
		(start 329.509882 -284.753812)
		(end 329.521566 -284.735016)
		(stroke
			(width 0.053848)
			(type default)
		)
		(layer "In9.Cu")
	)
	(gr_line
		(start 329.521566 -284.735016)
		(end 329.540362 -284.721046)
		(stroke
			(width 0.053848)
			(type default)
		)
		(layer "In9.Cu")
	)
	(gr_line
		(start 332.177136 -26.33091)
		(end 332.205584 -26.291794)
		(stroke
			(width 0.06985)
			(type default)
		)
		(layer "In9.Cu")
	)
	(gr_line
		(start 332.205584 -26.291794)
		(end 332.250542 -26.274268)
		(stroke
			(width 0.06985)
			(type default)
		)
		(layer "In9.Cu")
	)
	(gr_line
		(start 335.1022 -309.625492)
		(end 335.116678 -309.616094)
		(stroke
			(width 0.053848)
			(type default)
		)
		(layer "In9.Cu")
	)
	(gr_line
		(start 335.116678 -309.616094)
		(end 335.133696 -309.612538)
		(stroke
			(width 0.053848)
			(type default)
		)
		(layer "In9.Cu")
	)
	(gr_line
		(start 336.954114 -279.260046)
		(end 336.954876 -279.259538)
		(stroke
			(width 0.053848)
			(type default)
		)
		(layer "In9.Cu")
	)
	(gr_line
		(start 336.954876 -279.259538)
		(end 336.955384 -279.259284)
		(stroke
			(width 0.053848)
			(type default)
		)
		(layer "In9.Cu")
	)
	(gr_line
		(start 337.811872 -221.890844)
		(end 337.820762 -221.876874)
		(stroke
			(width 0.053848)
			(type default)
		)
		(layer "In9.Cu")
	)
	(gr_line
		(start 337.820762 -221.876874)
		(end 337.824572 -221.860618)
		(stroke
			(width 0.053848)
			(type default)
		)
		(layer "In9.Cu")
	)
	(gr_line
		(start 341.699596 -166.549324)
		(end 341.705946 -166.51986)
		(stroke
			(width 0.053848)
			(type default)
		)
		(layer "In9.Cu")
	)
	(gr_line
		(start 341.699596 -166.549324)
		(end 341.7062 -166.580058)
		(stroke
			(width 0.053848)
			(type default)
		)
		(layer "In9.Cu")
	)
	(gr_line
		(start 342.579452 -162.407092)
		(end 342.584024 -162.385756)
		(stroke
			(width 0.053848)
			(type default)
		)
		(layer "In9.Cu")
	)
	(gr_line
		(start 342.584024 -162.385756)
		(end 342.595962 -162.367722)
		(stroke
			(width 0.053848)
			(type default)
		)
		(layer "In9.Cu")
	)
	(gr_line
		(start 343.469722 -161.025078)
		(end 343.486994 -160.998662)
		(stroke
			(width 0.053848)
			(type default)
		)
		(layer "In9.Cu")
	)
	(gr_line
		(start 343.486994 -160.998662)
		(end 343.51341 -160.98139)
		(stroke
			(width 0.053848)
			(type default)
		)
		(layer "In9.Cu")
	)
	(gr_line
		(start 346.051378 -159.332676)
		(end 346.06992 -159.320738)
		(stroke
			(width 0.053848)
			(type default)
		)
		(layer "In9.Cu")
	)
	(gr_line
		(start 346.06992 -159.320738)
		(end 346.091256 -159.316166)
		(stroke
			(width 0.053848)
			(type default)
		)
		(layer "In9.Cu")
	)
	(gr_line
		(start 346.12072 -185.835036)
		(end 346.12834 -185.80227)
		(stroke
			(width 0.053848)
			(type default)
		)
		(layer "In9.Cu")
	)
	(gr_line
		(start 346.121482 -185.769758)
		(end 346.12834 -185.80227)
		(stroke
			(width 0.053848)
			(type default)
		)
		(layer "In9.Cu")
	)
	(gr_line
		(start 348.731586 -52.953412)
		(end 348.753684 -52.939188)
		(stroke
			(width 0.06985)
			(type default)
		)
		(layer "In9.Cu")
	)
	(gr_line
		(start 348.753684 -52.939188)
		(end 348.767908 -52.91709)
		(stroke
			(width 0.06985)
			(type default)
		)
		(layer "In9.Cu")
	)
	(gr_line
		(start 349.532956 -108.491274)
		(end 349.547688 -108.469938)
		(stroke
			(width 0.053848)
			(type default)
		)
		(layer "In9.Cu")
	)
	(gr_line
		(start 349.547688 -108.469938)
		(end 349.569024 -108.456222)
		(stroke
			(width 0.053848)
			(type default)
		)
		(layer "In9.Cu")
	)
	(gr_line
		(start 349.742252 -158.538926)
		(end 349.772732 -158.532576)
		(stroke
			(width 0.053848)
			(type default)
		)
		(layer "In9.Cu")
	)
	(gr_line
		(start 349.772732 -158.532576)
		(end 349.803212 -158.538926)
		(stroke
			(width 0.053848)
			(type default)
		)
		(layer "In9.Cu")
	)
	(gr_line
		(start 349.924116 -273.785076)
		(end 349.948246 -273.774916)
		(stroke
			(width 0.053848)
			(type default)
		)
		(layer "In9.Cu")
	)
	(gr_line
		(start 350.305624 -110.451646)
		(end 350.320102 -110.430564)
		(stroke
			(width 0.053848)
			(type default)
		)
		(layer "In9.Cu")
	)
	(gr_line
		(start 350.320102 -110.430564)
		(end 350.341438 -110.416848)
		(stroke
			(width 0.053848)
			(type default)
		)
		(layer "In9.Cu")
	)
	(gr_arc
		(start 351.419668 -273.774916)
		(mid 351.46545 -273.765809)
		(end 351.50425 -273.739864)
		(stroke
			(width 0.053848)
			(type default)
		)
		(layer "In9.Cu")
	)
	(gr_arc
		(start 351.419668 -158.774892)
		(mid 351.46545 -158.765785)
		(end 351.50425 -158.73984)
		(stroke
			(width 0.053848)
			(type default)
		)
		(layer "In9.Cu")
	)
	(gr_arc
		(start 351.50425 -274.140168)
		(mid 351.46545 -274.114217)
		(end 351.419668 -274.105116)
		(stroke
			(width 0.053848)
			(type default)
		)
		(layer "In9.Cu")
	)
	(gr_arc
		(start 351.50425 -273.739864)
		(mid 351.53018 -273.701057)
		(end 351.539302 -273.655282)
		(stroke
			(width 0.053848)
			(type default)
		)
		(layer "In9.Cu")
	)
	(gr_arc
		(start 351.50425 -159.140144)
		(mid 351.465449 -159.114198)
		(end 351.419668 -159.105092)
		(stroke
			(width 0.053848)
			(type default)
		)
		(layer "In9.Cu")
	)
	(gr_arc
		(start 351.50425 -158.73984)
		(mid 351.53018 -158.701033)
		(end 351.539302 -158.655258)
		(stroke
			(width 0.053848)
			(type default)
		)
		(layer "In9.Cu")
	)
	(gr_arc
		(start 351.539302 -274.22475)
		(mid 351.530183 -274.178975)
		(end 351.50425 -274.140168)
		(stroke
			(width 0.053848)
			(type default)
		)
		(layer "In9.Cu")
	)
	(gr_line
		(start 351.539302 -274.22475)
		(end 351.539302 -274.511516)
		(stroke
			(width 0.053848)
			(type default)
		)
		(layer "In9.Cu")
	)
	(gr_line
		(start 351.539302 -273.368516)
		(end 351.539302 -273.655282)
		(stroke
			(width 0.053848)
			(type default)
		)
		(layer "In9.Cu")
	)
	(gr_arc
		(start 351.539302 -159.224726)
		(mid 351.530175 -159.178956)
		(end 351.50425 -159.140144)
		(stroke
			(width 0.053848)
			(type default)
		)
		(layer "In9.Cu")
	)
	(gr_line
		(start 351.539302 -159.224726)
		(end 351.539302 -159.511492)
		(stroke
			(width 0.053848)
			(type default)
		)
		(layer "In9.Cu")
	)
	(gr_line
		(start 351.539302 -158.368492)
		(end 351.539302 -158.655258)
		(stroke
			(width 0.053848)
			(type default)
		)
		(layer "In9.Cu")
	)
	(gr_line
		(start 352.183954 -33.846516)
		(end 352.202496 -33.842198)
		(stroke
			(width 0.06985)
			(type default)
		)
		(layer "In9.Cu")
	)
	(gr_line
		(start 352.191828 -36.909502)
		(end 352.203512 -36.906962)
		(stroke
			(width 0.06985)
			(type default)
		)
		(layer "In9.Cu")
	)
	(gr_line
		(start 352.202496 -33.842198)
		(end 352.217736 -33.83153)
		(stroke
			(width 0.06985)
			(type default)
		)
		(layer "In9.Cu")
	)
	(gr_line
		(start 352.203512 -36.906962)
		(end 352.214434 -36.900104)
		(stroke
			(width 0.06985)
			(type default)
		)
		(layer "In9.Cu")
	)
	(gr_line
		(start 352.316288 -46.803818)
		(end 352.327464 -46.786292)
		(stroke
			(width 0.06985)
			(type default)
		)
		(layer "In9.Cu")
	)
	(gr_line
		(start 352.327464 -46.786292)
		(end 352.344736 -46.7741)
		(stroke
			(width 0.06985)
			(type default)
		)
		(layer "In9.Cu")
	)
	(gr_line
		(start 352.720402 -34.716974)
		(end 352.720402 -34.717228)
		(stroke
			(width 0.06985)
			(type default)
		)
		(layer "In9.Cu")
	)
	(gr_line
		(start 352.822764 -34.99358)
		(end 352.835718 -34.990532)
		(stroke
			(width 0.06985)
			(type default)
		)
		(layer "In9.Cu")
	)
	(gr_line
		(start 352.835464 -34.990532)
		(end 352.835718 -34.990532)
		(stroke
			(width 0.06985)
			(type default)
		)
		(layer "In9.Cu")
	)
	(gr_line
		(start 352.835464 -34.990278)
		(end 352.835464 -34.990532)
		(stroke
			(width 0.06985)
			(type default)
		)
		(layer "In9.Cu")
	)
	(gr_line
		(start 352.835464 -34.990278)
		(end 352.844354 -34.98469)
		(stroke
			(width 0.06985)
			(type default)
		)
		(layer "In9.Cu")
	)
	(gr_line
		(start 353.802188 -17.91081)
		(end 353.817428 -17.904968)
		(stroke
			(width 0.06985)
			(type default)
		)
		(layer "In9.Cu")
	)
	(gr_arc
		(start 354.965762 -17.904968)
		(mid 355.014271 -17.895319)
		(end 355.055424 -17.867884)
		(stroke
			(width 0.06985)
			(type default)
		)
		(layer "In9.Cu")
	)
	(gr_arc
		(start 355.053392 -18.234152)
		(mid 355.012241 -18.206719)
		(end 354.96373 -18.197068)
		(stroke
			(width 0.06985)
			(type default)
		)
		(layer "In9.Cu")
	)
	(gr_line
		(start 355.053392 -18.234152)
		(end 355.112828 -18.293588)
		(stroke
			(width 0.06985)
			(type default)
		)
		(layer "In9.Cu")
	)
	(gr_line
		(start 355.055424 -17.867884)
		(end 355.112828 -17.81048)
		(stroke
			(width 0.06985)
			(type default)
		)
		(layer "In9.Cu")
	)
	(gr_arc
		(start 355.112828 -17.81048)
		(mid 355.140286 -17.769335)
		(end 355.149912 -17.720818)
		(stroke
			(width 0.06985)
			(type default)
		)
		(layer "In9.Cu")
	)
	(gr_line
		(start 355.149658 -332.8162)
		(end 355.307138 -332.569058)
		(stroke
			(width 0.053848)
			(type default)
		)
		(layer "In9.Cu")
	)
	(gr_arc
		(start 355.149912 -18.38325)
		(mid 355.140279 -18.334732)
		(end 355.112828 -18.293588)
		(stroke
			(width 0.06985)
			(type default)
		)
		(layer "In9.Cu")
	)
	(gr_line
		(start 355.149912 -18.38325)
		(end 355.149912 -18.750026)
		(stroke
			(width 0.06985)
			(type default)
		)
		(layer "In9.Cu")
	)
	(gr_line
		(start 355.149912 -17.349978)
		(end 355.149912 -17.720818)
		(stroke
			(width 0.06985)
			(type default)
		)
		(layer "In9.Cu")
	)
	(gr_line
		(start 355.258116 -333.132938)
		(end 355.905562 -332.989428)
		(stroke
			(width 0.053848)
			(type default)
		)
		(layer "In9.Cu")
	)
	(gr_line
		(start 355.307138 -332.569058)
		(end 355.623368 -332.498954)
		(stroke
			(width 0.053848)
			(type default)
		)
		(layer "In9.Cu")
	)
	(gr_line
		(start 355.438202 -210.232244)
		(end 355.456236 -210.20405)
		(stroke
			(width 0.053848)
			(type default)
		)
		(layer "In9.Cu")
	)
	(gr_line
		(start 355.456236 -210.20405)
		(end 355.48443 -210.186016)
		(stroke
			(width 0.053848)
			(type default)
		)
		(layer "In9.Cu")
	)
	(gr_line
		(start 355.623368 -332.498954)
		(end 355.87051 -332.656434)
		(stroke
			(width 0.053848)
			(type default)
		)
		(layer "In9.Cu")
	)
	(gr_line
		(start 355.81971 -331.129132)
		(end 355.976936 -330.88199)
		(stroke
			(width 0.053848)
			(type default)
		)
		(layer "In9.Cu")
	)
	(gr_line
		(start 355.929184 -331.445362)
		(end 356.575106 -331.30236)
		(stroke
			(width 0.053848)
			(type default)
		)
		(layer "In9.Cu")
	)
	(gr_line
		(start 355.956362 -31.20898)
		(end 355.980238 -31.192216)
		(stroke
			(width 0.06985)
			(type default)
		)
		(layer "In9.Cu")
	)
	(gr_line
		(start 355.976936 -330.88199)
		(end 356.293166 -330.811886)
		(stroke
			(width 0.053848)
			(type default)
		)
		(layer "In9.Cu")
	)
	(gr_line
		(start 355.980238 -31.192216)
		(end 355.994208 -31.166816)
		(stroke
			(width 0.06985)
			(type default)
		)
		(layer "In9.Cu")
	)
	(gr_line
		(start 356.161086 -51.051968)
		(end 356.181406 -51.039014)
		(stroke
			(width 0.06985)
			(type default)
		)
		(layer "In9.Cu")
	)
	(gr_line
		(start 356.17785 -30.837124)
		(end 356.196138 -30.804104)
		(stroke
			(width 0.06985)
			(type default)
		)
		(layer "In9.Cu")
	)
	(gr_line
		(start 356.181406 -51.039014)
		(end 356.19436 -51.019456)
		(stroke
			(width 0.06985)
			(type default)
		)
		(layer "In9.Cu")
	)
	(gr_line
		(start 356.191058 -332.585314)
		(end 356.348538 -332.338172)
		(stroke
			(width 0.053848)
			(type default)
		)
		(layer "In9.Cu")
	)
	(gr_line
		(start 356.293166 -330.811886)
		(end 356.540308 -330.969366)
		(stroke
			(width 0.053848)
			(type default)
		)
		(layer "In9.Cu")
	)
	(gr_line
		(start 356.299008 -332.902306)
		(end 356.947216 -332.758542)
		(stroke
			(width 0.053848)
			(type default)
		)
		(layer "In9.Cu")
	)
	(gr_line
		(start 356.348538 -332.338172)
		(end 356.664768 -332.268068)
		(stroke
			(width 0.053848)
			(type default)
		)
		(layer "In9.Cu")
	)
	(gr_line
		(start 356.664768 -332.268068)
		(end 356.91191 -332.425548)
		(stroke
			(width 0.053848)
			(type default)
		)
		(layer "In9.Cu")
	)
	(gr_arc
		(start 356.807516 -18.90395)
		(mid 356.856018 -18.894288)
		(end 356.897178 -18.866866)
		(stroke
			(width 0.06985)
			(type default)
		)
		(layer "In9.Cu")
	)
	(gr_line
		(start 356.86111 -330.898246)
		(end 357.01859 -330.651104)
		(stroke
			(width 0.053848)
			(type default)
		)
		(layer "In9.Cu")
	)
	(gr_arc
		(start 356.897178 -19.233388)
		(mid 356.856027 -19.205955)
		(end 356.807516 -19.196304)
		(stroke
			(width 0.06985)
			(type default)
		)
		(layer "In9.Cu")
	)
	(gr_line
		(start 356.897178 -19.233388)
		(end 356.912926 -19.249136)
		(stroke
			(width 0.06985)
			(type default)
		)
		(layer "In9.Cu")
	)
	(gr_line
		(start 356.897178 -18.866866)
		(end 356.912926 -18.851118)
		(stroke
			(width 0.06985)
			(type default)
		)
		(layer "In9.Cu")
	)
	(gr_arc
		(start 356.912926 -18.851118)
		(mid 356.940364 -18.809969)
		(end 356.95001 -18.761456)
		(stroke
			(width 0.06985)
			(type default)
		)
		(layer "In9.Cu")
	)
	(gr_arc
		(start 356.95001 -19.338798)
		(mid 356.940377 -19.29028)
		(end 356.912926 -19.249136)
		(stroke
			(width 0.06985)
			(type default)
		)
		(layer "In9.Cu")
	)
	(gr_line
		(start 356.95001 -19.338798)
		(end 356.95001 -19.750024)
		(stroke
			(width 0.06985)
			(type default)
		)
		(layer "In9.Cu")
	)
	(gr_line
		(start 356.95001 -18.35023)
		(end 356.95001 -18.761456)
		(stroke
			(width 0.06985)
			(type default)
		)
		(layer "In9.Cu")
	)
	(gr_line
		(start 356.969822 -331.214984)
		(end 357.61676 -331.071474)
		(stroke
			(width 0.053848)
			(type default)
		)
		(layer "In9.Cu")
	)
	(gr_line
		(start 357.01859 -330.651104)
		(end 357.33482 -330.581)
		(stroke
			(width 0.053848)
			(type default)
		)
		(layer "In9.Cu")
	)
	(gr_line
		(start 357.232712 -332.354428)
		(end 357.390192 -332.107286)
		(stroke
			(width 0.053848)
			(type default)
		)
		(layer "In9.Cu")
	)
	(gr_line
		(start 357.33482 -330.581)
		(end 357.581962 -330.73848)
		(stroke
			(width 0.053848)
			(type default)
		)
		(layer "In9.Cu")
	)
	(gr_line
		(start 357.342186 -332.670658)
		(end 357.988108 -332.527656)
		(stroke
			(width 0.053848)
			(type default)
		)
		(layer "In9.Cu")
	)
	(gr_line
		(start 357.390192 -332.107286)
		(end 357.706422 -332.037182)
		(stroke
			(width 0.053848)
			(type default)
		)
		(layer "In9.Cu")
	)
	(gr_line
		(start 357.517192 -53.05298)
		(end 357.537766 -53.039772)
		(stroke
			(width 0.06985)
			(type default)
		)
		(layer "In9.Cu")
	)
	(gr_line
		(start 357.537766 -53.039772)
		(end 357.55072 -53.020214)
		(stroke
			(width 0.06985)
			(type default)
		)
		(layer "In9.Cu")
	)
	(gr_line
		(start 357.629714 -31.935674)
		(end 357.660702 -31.915862)
		(stroke
			(width 0.06985)
			(type default)
		)
		(layer "In9.Cu")
	)
	(gr_line
		(start 357.660702 -31.915862)
		(end 357.678736 -31.883604)
		(stroke
			(width 0.06985)
			(type default)
		)
		(layer "In9.Cu")
	)
	(gr_line
		(start 357.706422 -332.037182)
		(end 357.95331 -332.194662)
		(stroke
			(width 0.053848)
			(type default)
		)
		(layer "In9.Cu")
	)
	(gr_line
		(start 357.90251 -330.66736)
		(end 358.05999 -330.420218)
		(stroke
			(width 0.053848)
			(type default)
		)
		(layer "In9.Cu")
	)
	(gr_line
		(start 357.977948 -31.345886)
		(end 357.996236 -31.312866)
		(stroke
			(width 0.06985)
			(type default)
		)
		(layer "In9.Cu")
	)
	(gr_line
		(start 358.010968 -330.984098)
		(end 358.65943 -330.840334)
		(stroke
			(width 0.053848)
			(type default)
		)
		(layer "In9.Cu")
	)
	(gr_line
		(start 358.05999 -330.420218)
		(end 358.37622 -330.350114)
		(stroke
			(width 0.053848)
			(type default)
		)
		(layer "In9.Cu")
	)
	(gr_line
		(start 358.37622 -330.350114)
		(end 358.623362 -330.507594)
		(stroke
			(width 0.053848)
			(type default)
		)
		(layer "In9.Cu")
	)
	(gr_arc
		(start 358.607614 -17.903952)
		(mid 358.656116 -17.894291)
		(end 358.697276 -17.866868)
		(stroke
			(width 0.06985)
			(type default)
		)
		(layer "In9.Cu")
	)
	(gr_arc
		(start 358.697276 -18.23339)
		(mid 358.656125 -18.205957)
		(end 358.607614 -18.196306)
		(stroke
			(width 0.06985)
			(type default)
		)
		(layer "In9.Cu")
	)
	(gr_line
		(start 358.697276 -18.23339)
		(end 358.713024 -18.249138)
		(stroke
			(width 0.06985)
			(type default)
		)
		(layer "In9.Cu")
	)
	(gr_line
		(start 358.697276 -17.866868)
		(end 358.723692 -17.840452)
		(stroke
			(width 0.06985)
			(type default)
		)
		(layer "In9.Cu")
	)
	(gr_arc
		(start 358.723692 -17.840452)
		(mid 358.743249 -17.811205)
		(end 358.750108 -17.776698)
		(stroke
			(width 0.06985)
			(type default)
		)
		(layer "In9.Cu")
	)
	(gr_arc
		(start 358.750108 -18.3388)
		(mid 358.740475 -18.290282)
		(end 358.713024 -18.249138)
		(stroke
			(width 0.06985)
			(type default)
		)
		(layer "In9.Cu")
	)
	(gr_line
		(start 358.750108 -18.3388)
		(end 358.750108 -18.750026)
		(stroke
			(width 0.06985)
			(type default)
		)
		(layer "In9.Cu")
	)
	(gr_line
		(start 358.750108 -17.349978)
		(end 358.750108 -17.776698)
		(stroke
			(width 0.06985)
			(type default)
		)
		(layer "In9.Cu")
	)
	(gr_line
		(start 358.83596 -32.680656)
		(end 358.866948 -32.660844)
		(stroke
			(width 0.06985)
			(type default)
		)
		(layer "In9.Cu")
	)
	(gr_line
		(start 358.866948 -32.660844)
		(end 358.884728 -32.62884)
		(stroke
			(width 0.06985)
			(type default)
		)
		(layer "In9.Cu")
	)
	(gr_line
		(start 359.002838 -42.460418)
		(end 359.026714 -42.443654)
		(stroke
			(width 0.06985)
			(type default)
		)
		(layer "In9.Cu")
	)
	(gr_line
		(start 359.026714 -42.443654)
		(end 359.040684 -42.418254)
		(stroke
			(width 0.06985)
			(type default)
		)
		(layer "In9.Cu")
	)
	(gr_line
		(start 359.77703 -332.130908)
		(end 359.782364 -332.129892)
		(stroke
			(width 0.053848)
			(type default)
		)
		(layer "In9.Cu")
	)
	(gr_line
		(start 359.777792 -31.022036)
		(end 359.79608 -30.989016)
		(stroke
			(width 0.06985)
			(type default)
		)
		(layer "In9.Cu")
	)
	(gr_line
		(start 359.782364 -332.129892)
		(end 359.787952 -332.126844)
		(stroke
			(width 0.053848)
			(type default)
		)
		(layer "In9.Cu")
	)
	(gr_arc
		(start 360.407458 -18.90395)
		(mid 360.455972 -18.894307)
		(end 360.49712 -18.866866)
		(stroke
			(width 0.06985)
			(type default)
		)
		(layer "In9.Cu")
	)
	(gr_arc
		(start 360.49712 -19.233388)
		(mid 360.455969 -19.205955)
		(end 360.407458 -19.196304)
		(stroke
			(width 0.06985)
			(type default)
		)
		(layer "In9.Cu")
	)
	(gr_line
		(start 360.49712 -19.233388)
		(end 360.512868 -19.249136)
		(stroke
			(width 0.06985)
			(type default)
		)
		(layer "In9.Cu")
	)
	(gr_line
		(start 360.49712 -18.866866)
		(end 360.512868 -18.851118)
		(stroke
			(width 0.06985)
			(type default)
		)
		(layer "In9.Cu")
	)
	(gr_arc
		(start 360.512868 -18.851118)
		(mid 360.540318 -18.809972)
		(end 360.549952 -18.761456)
		(stroke
			(width 0.06985)
			(type default)
		)
		(layer "In9.Cu")
	)
	(gr_arc
		(start 360.549952 -19.338798)
		(mid 360.540319 -19.29028)
		(end 360.512868 -19.249136)
		(stroke
			(width 0.06985)
			(type default)
		)
		(layer "In9.Cu")
	)
	(gr_line
		(start 360.549952 -19.338798)
		(end 360.549952 -19.750024)
		(stroke
			(width 0.06985)
			(type default)
		)
		(layer "In9.Cu")
	)
	(gr_line
		(start 360.549952 -18.35023)
		(end 360.549952 -18.761456)
		(stroke
			(width 0.06985)
			(type default)
		)
		(layer "In9.Cu")
	)
	(gr_line
		(start 360.650028 -330.398882)
		(end 360.677206 -330.39304)
		(stroke
			(width 0.053848)
			(type default)
		)
		(layer "In9.Cu")
	)
	(gr_line
		(start 360.677206 -330.39304)
		(end 360.699812 -330.376784)
		(stroke
			(width 0.053848)
			(type default)
		)
		(layer "In9.Cu")
	)
	(gr_line
		(start 360.97718 -32.888174)
		(end 361.008168 -32.868362)
		(stroke
			(width 0.06985)
			(type default)
		)
		(layer "In9.Cu")
	)
	(gr_line
		(start 361.008168 -32.868362)
		(end 361.025948 -32.836358)
		(stroke
			(width 0.06985)
			(type default)
		)
		(layer "In9.Cu")
	)
	(gr_line
		(start 361.422442 -34.613088)
		(end 361.453684 -34.593022)
		(stroke
			(width 0.06985)
			(type default)
		)
		(layer "In9.Cu")
	)
	(gr_line
		(start 361.453684 -34.593022)
		(end 361.471718 -34.560764)
		(stroke
			(width 0.06985)
			(type default)
		)
		(layer "In9.Cu")
	)
	(gr_line
		(start 361.57789 -31.843472)
		(end 361.596178 -31.810452)
		(stroke
			(width 0.06985)
			(type default)
		)
		(layer "In9.Cu")
	)
	(gr_line
		(start 361.741974 -82.83194)
		(end 361.777534 -83.022948)
		(stroke
			(width 0.06985)
			(type default)
		)
		(layer "In9.Cu")
	)
	(gr_line
		(start 361.741974 -82.83194)
		(end 361.979718 -82.486754)
		(stroke
			(width 0.06985)
			(type default)
		)
		(layer "In9.Cu")
	)
	(gr_line
		(start 361.979718 -82.486754)
		(end 362.170726 -82.451194)
		(stroke
			(width 0.06985)
			(type default)
		)
		(layer "In9.Cu")
	)
	(gr_line
		(start 362.040424 -83.160108)
		(end 362.392468 -82.648298)
		(stroke
			(width 0.06985)
			(type default)
		)
		(layer "In9.Cu")
	)
	(gr_arc
		(start 362.207556 -17.903952)
		(mid 362.256074 -17.894319)
		(end 362.297218 -17.866868)
		(stroke
			(width 0.06985)
			(type default)
		)
		(layer "In9.Cu")
	)
	(gr_arc
		(start 362.297218 -18.23339)
		(mid 362.25607 -18.205949)
		(end 362.207556 -18.196306)
		(stroke
			(width 0.06985)
			(type default)
		)
		(layer "In9.Cu")
	)
	(gr_line
		(start 362.297218 -18.23339)
		(end 362.312966 -18.249138)
		(stroke
			(width 0.06985)
			(type default)
		)
		(layer "In9.Cu")
	)
	(gr_line
		(start 362.297218 -17.866868)
		(end 362.323634 -17.840452)
		(stroke
			(width 0.06985)
			(type default)
		)
		(layer "In9.Cu")
	)
	(gr_arc
		(start 362.323634 -17.840452)
		(mid 362.343179 -17.811201)
		(end 362.35005 -17.776698)
		(stroke
			(width 0.06985)
			(type default)
		)
		(layer "In9.Cu")
	)
	(gr_arc
		(start 362.35005 -18.3388)
		(mid 362.340393 -18.290295)
		(end 362.312966 -18.249138)
		(stroke
			(width 0.06985)
			(type default)
		)
		(layer "In9.Cu")
	)
	(gr_line
		(start 362.35005 -18.3388)
		(end 362.35005 -18.750026)
		(stroke
			(width 0.06985)
			(type default)
		)
		(layer "In9.Cu")
	)
	(gr_line
		(start 362.35005 -17.349978)
		(end 362.35005 -17.776698)
		(stroke
			(width 0.06985)
			(type default)
		)
		(layer "In9.Cu")
	)
	(gr_line
		(start 362.37545 -81.91119)
		(end 362.41101 -82.102198)
		(stroke
			(width 0.06985)
			(type default)
		)
		(layer "In9.Cu")
	)
	(gr_line
		(start 362.37545 -81.91119)
		(end 362.613194 -81.566004)
		(stroke
			(width 0.06985)
			(type default)
		)
		(layer "In9.Cu")
	)
	(gr_line
		(start 362.613194 -81.566004)
		(end 362.804202 -81.530698)
		(stroke
			(width 0.06985)
			(type default)
		)
		(layer "In9.Cu")
	)
	(gr_line
		(start 362.674154 -82.239104)
		(end 363.025944 -81.728056)
		(stroke
			(width 0.06985)
			(type default)
		)
		(layer "In9.Cu")
	)
	(gr_line
		(start 363.00918 -80.990694)
		(end 363.044486 -81.181702)
		(stroke
			(width 0.06985)
			(type default)
		)
		(layer "In9.Cu")
	)
	(gr_line
		(start 363.00918 -80.990694)
		(end 363.24667 -80.645254)
		(stroke
			(width 0.06985)
			(type default)
		)
		(layer "In9.Cu")
	)
	(gr_line
		(start 363.24667 -80.645254)
		(end 363.437678 -80.609948)
		(stroke
			(width 0.06985)
			(type default)
		)
		(layer "In9.Cu")
	)
	(gr_line
		(start 363.26826 -43.852338)
		(end 363.278674 -43.83659)
		(stroke
			(width 0.06985)
			(type default)
		)
		(layer "In9.Cu")
	)
	(gr_line
		(start 363.278674 -43.83659)
		(end 363.294676 -43.825668)
		(stroke
			(width 0.06985)
			(type default)
		)
		(layer "In9.Cu")
	)
	(gr_line
		(start 363.307884 -81.3181)
		(end 363.65942 -80.807052)
		(stroke
			(width 0.06985)
			(type default)
		)
		(layer "In9.Cu")
	)
	(gr_line
		(start 363.377734 -31.134304)
		(end 363.396022 -31.101284)
		(stroke
			(width 0.06985)
			(type default)
		)
		(layer "In9.Cu")
	)
	(gr_line
		(start 363.642656 -80.069944)
		(end 363.677962 -80.261206)
		(stroke
			(width 0.06985)
			(type default)
		)
		(layer "In9.Cu")
	)
	(gr_line
		(start 363.642656 -80.069944)
		(end 363.880146 -79.724758)
		(stroke
			(width 0.06985)
			(type default)
		)
		(layer "In9.Cu")
	)
	(gr_line
		(start 363.880146 -79.724758)
		(end 364.071408 -79.689198)
		(stroke
			(width 0.06985)
			(type default)
		)
		(layer "In9.Cu")
	)
	(gr_line
		(start 363.941106 -80.397858)
		(end 364.293658 -79.885794)
		(stroke
			(width 0.06985)
			(type default)
		)
		(layer "In9.Cu")
	)
	(gr_arc
		(start 364.0074 -18.90395)
		(mid 364.055918 -18.894317)
		(end 364.097062 -18.866866)
		(stroke
			(width 0.06985)
			(type default)
		)
		(layer "In9.Cu")
	)
	(gr_arc
		(start 364.097062 -19.233388)
		(mid 364.055916 -19.205933)
		(end 364.0074 -19.196304)
		(stroke
			(width 0.06985)
			(type default)
		)
		(layer "In9.Cu")
	)
	(gr_line
		(start 364.097062 -19.233388)
		(end 364.11281 -19.249136)
		(stroke
			(width 0.06985)
			(type default)
		)
		(layer "In9.Cu")
	)
	(gr_line
		(start 364.097062 -18.866866)
		(end 364.11281 -18.851118)
		(stroke
			(width 0.06985)
			(type default)
		)
		(layer "In9.Cu")
	)
	(gr_arc
		(start 364.11281 -18.851118)
		(mid 364.140243 -18.809967)
		(end 364.149894 -18.761456)
		(stroke
			(width 0.06985)
			(type default)
		)
		(layer "In9.Cu")
	)
	(gr_arc
		(start 364.149894 -19.338798)
		(mid 364.140233 -19.290296)
		(end 364.11281 -19.249136)
		(stroke
			(width 0.06985)
			(type default)
		)
		(layer "In9.Cu")
	)
	(gr_line
		(start 364.149894 -19.338798)
		(end 364.149894 -19.750024)
		(stroke
			(width 0.06985)
			(type default)
		)
		(layer "In9.Cu")
	)
	(gr_line
		(start 364.149894 -18.35023)
		(end 364.149894 -18.761456)
		(stroke
			(width 0.06985)
			(type default)
		)
		(layer "In9.Cu")
	)
	(gr_line
		(start 365.177832 -31.383478)
		(end 365.19612 -31.350458)
		(stroke
			(width 0.06985)
			(type default)
		)
		(layer "In9.Cu")
	)
	(gr_arc
		(start 365.807498 -17.903952)
		(mid 365.856016 -17.894319)
		(end 365.89716 -17.866868)
		(stroke
			(width 0.06985)
			(type default)
		)
		(layer "In9.Cu")
	)
	(gr_arc
		(start 365.89716 -18.23339)
		(mid 365.856014 -18.205935)
		(end 365.807498 -18.196306)
		(stroke
			(width 0.06985)
			(type default)
		)
		(layer "In9.Cu")
	)
	(gr_line
		(start 365.89716 -18.23339)
		(end 365.912908 -18.249138)
		(stroke
			(width 0.06985)
			(type default)
		)
		(layer "In9.Cu")
	)
	(gr_line
		(start 365.89716 -17.866868)
		(end 365.923576 -17.840452)
		(stroke
			(width 0.06985)
			(type default)
		)
		(layer "In9.Cu")
	)
	(gr_arc
		(start 365.923576 -17.840452)
		(mid 365.943121 -17.811201)
		(end 365.949992 -17.776698)
		(stroke
			(width 0.06985)
			(type default)
		)
		(layer "In9.Cu")
	)
	(gr_arc
		(start 365.949992 -18.3388)
		(mid 365.940332 -18.290298)
		(end 365.912908 -18.249138)
		(stroke
			(width 0.06985)
			(type default)
		)
		(layer "In9.Cu")
	)
	(gr_line
		(start 365.949992 -18.3388)
		(end 365.949992 -18.750026)
		(stroke
			(width 0.06985)
			(type default)
		)
		(layer "In9.Cu")
	)
	(gr_line
		(start 365.949992 -17.349978)
		(end 365.949992 -17.776698)
		(stroke
			(width 0.06985)
			(type default)
		)
		(layer "In9.Cu")
	)
	(gr_line
		(start 366.968786 -34.76752)
		(end 366.996218 -34.726118)
		(stroke
			(width 0.06985)
			(type default)
		)
		(layer "In9.Cu")
	)
	(gr_arc
		(start 367.607596 -18.90395)
		(mid 367.656114 -18.894317)
		(end 367.697258 -18.866866)
		(stroke
			(width 0.06985)
			(type default)
		)
		(layer "In9.Cu")
	)
	(gr_arc
		(start 367.697258 -19.233388)
		(mid 367.656112 -19.205934)
		(end 367.607596 -19.196304)
		(stroke
			(width 0.06985)
			(type default)
		)
		(layer "In9.Cu")
	)
	(gr_line
		(start 367.697258 -19.233388)
		(end 367.713006 -19.249136)
		(stroke
			(width 0.06985)
			(type default)
		)
		(layer "In9.Cu")
	)
	(gr_line
		(start 367.697258 -18.866866)
		(end 367.713006 -18.851118)
		(stroke
			(width 0.06985)
			(type default)
		)
		(layer "In9.Cu")
	)
	(gr_arc
		(start 367.713006 -18.851118)
		(mid 367.740439 -18.809967)
		(end 367.75009 -18.761456)
		(stroke
			(width 0.06985)
			(type default)
		)
		(layer "In9.Cu")
	)
	(gr_arc
		(start 367.75009 -19.338798)
		(mid 367.740429 -19.290297)
		(end 367.713006 -19.249136)
		(stroke
			(width 0.06985)
			(type default)
		)
		(layer "In9.Cu")
	)
	(gr_line
		(start 367.75009 -19.338798)
		(end 367.75009 -19.750024)
		(stroke
			(width 0.06985)
			(type default)
		)
		(layer "In9.Cu")
	)
	(gr_line
		(start 367.75009 -18.35023)
		(end 367.75009 -18.761456)
		(stroke
			(width 0.06985)
			(type default)
		)
		(layer "In9.Cu")
	)
	(gr_line
		(start 368.710464 -72.705722)
		(end 368.74577 -72.89673)
		(stroke
			(width 0.06985)
			(type default)
		)
		(layer "In9.Cu")
	)
	(gr_line
		(start 368.710464 -72.705722)
		(end 368.947954 -72.360536)
		(stroke
			(width 0.06985)
			(type default)
		)
		(layer "In9.Cu")
	)
	(gr_line
		(start 368.947954 -72.360536)
		(end 369.138962 -72.32523)
		(stroke
			(width 0.06985)
			(type default)
		)
		(layer "In9.Cu")
	)
	(gr_line
		(start 369.008406 -73.034652)
		(end 369.361466 -72.521826)
		(stroke
			(width 0.06985)
			(type default)
		)
		(layer "In9.Cu")
	)
	(gr_line
		(start 369.34394 -71.784972)
		(end 369.379246 -71.976234)
		(stroke
			(width 0.06985)
			(type default)
		)
		(layer "In9.Cu")
	)
	(gr_line
		(start 369.34394 -71.784972)
		(end 369.58143 -71.439786)
		(stroke
			(width 0.06985)
			(type default)
		)
		(layer "In9.Cu")
	)
	(gr_line
		(start 369.58143 -71.439786)
		(end 369.772692 -71.40448)
		(stroke
			(width 0.06985)
			(type default)
		)
		(layer "In9.Cu")
	)
	(gr_line
		(start 369.641628 -72.114156)
		(end 369.994942 -71.601076)
		(stroke
			(width 0.06985)
			(type default)
		)
		(layer "In9.Cu")
	)
	(gr_line
		(start 369.977416 -70.864476)
		(end 370.012976 -71.055484)
		(stroke
			(width 0.06985)
			(type default)
		)
		(layer "In9.Cu")
	)
	(gr_line
		(start 369.977416 -70.864476)
		(end 370.21516 -70.51929)
		(stroke
			(width 0.06985)
			(type default)
		)
		(layer "In9.Cu")
	)
	(gr_line
		(start 370.21516 -70.51929)
		(end 370.406168 -70.48373)
		(stroke
			(width 0.06985)
			(type default)
		)
		(layer "In9.Cu")
	)
	(gr_line
		(start 370.276374 -71.191882)
		(end 370.628672 -70.680326)
		(stroke
			(width 0.06985)
			(type default)
		)
		(layer "In9.Cu")
	)
	(gr_line
		(start 370.954046 -302.009048)
		(end 370.975382 -302.004222)
		(stroke
			(width 0.053848)
			(type default)
		)
		(layer "In9.Cu")
	)
	(gr_line
		(start 370.975382 -302.004222)
		(end 370.993162 -301.99203)
		(stroke
			(width 0.053848)
			(type default)
		)
		(layer "In9.Cu")
	)
	(gr_line
		(start 371.004084 -45.94987)
		(end 371.026436 -45.935646)
		(stroke
			(width 0.06985)
			(type default)
		)
		(layer "In9.Cu")
	)
	(gr_line
		(start 371.026436 -45.935646)
		(end 371.04066 -45.913548)
		(stroke
			(width 0.06985)
			(type default)
		)
		(layer "In9.Cu")
	)
	(gr_line
		(start 371.058694 -45.884846)
		(end 371.065552 -45.874178)
		(stroke
			(width 0.06985)
			(type default)
		)
		(layer "In9.Cu")
	)
	(gr_line
		(start 371.917976 -181.610508)
		(end 371.93601 -181.582314)
		(stroke
			(width 0.053848)
			(type default)
		)
		(layer "In9.Cu")
	)
	(gr_line
		(start 371.93601 -181.582314)
		(end 371.964204 -181.56428)
		(stroke
			(width 0.053848)
			(type default)
		)
		(layer "In9.Cu")
	)
	(gr_line
		(start 372.767098 -236.391958)
		(end 372.78564 -236.38002)
		(stroke
			(width 0.053848)
			(type default)
		)
		(layer "In9.Cu")
	)
	(gr_line
		(start 372.767606 -46.103032)
		(end 372.783862 -46.091602)
		(stroke
			(width 0.06985)
			(type default)
		)
		(layer "In9.Cu")
	)
	(gr_line
		(start 372.783862 -46.091602)
		(end 372.79453 -46.075092)
		(stroke
			(width 0.06985)
			(type default)
		)
		(layer "In9.Cu")
	)
	(gr_line
		(start 372.78564 -236.38002)
		(end 372.807992 -236.375448)
		(stroke
			(width 0.053848)
			(type default)
		)
		(layer "In9.Cu")
	)
	(gr_line
		(start 373.14251 -71.414386)
		(end 373.147082 -71.407528)
		(stroke
			(width 0.053848)
			(type default)
		)
		(layer "In9.Cu")
	)
	(gr_line
		(start 373.147082 -71.407528)
		(end 373.154194 -71.401686)
		(stroke
			(width 0.053848)
			(type default)
		)
		(layer "In9.Cu")
	)
	(gr_line
		(start 373.539258 -47.923704)
		(end 373.555514 -47.912274)
		(stroke
			(width 0.06985)
			(type default)
		)
		(layer "In9.Cu")
	)
	(gr_line
		(start 373.555514 -47.912274)
		(end 373.566182 -47.895764)
		(stroke
			(width 0.06985)
			(type default)
		)
		(layer "In9.Cu")
	)
	(gr_line
		(start 373.886476 -36.637214)
		(end 373.88673 -36.637214)
		(stroke
			(width 0.06985)
			(type default)
		)
		(layer "In9.Cu")
	)
	(gr_line
		(start 374.08104 -36.858702)
		(end 374.10009 -36.845748)
		(stroke
			(width 0.06985)
			(type default)
		)
		(layer "In9.Cu")
	)
	(gr_line
		(start 374.10009 -36.845748)
		(end 374.111266 -36.827968)
		(stroke
			(width 0.06985)
			(type default)
		)
		(layer "In9.Cu")
	)
	(gr_line
		(start 374.128538 -36.801044)
		(end 374.13692 -36.78809)
		(stroke
			(width 0.06985)
			(type default)
		)
		(layer "In9.Cu")
	)
	(gr_line
		(start 376.750072 -18.3388)
		(end 376.750072 -18.750026)
		(stroke
			(width 0.06985)
			(type default)
		)
		(layer "In9.Cu")
	)
	(gr_arc
		(start 376.750072 -17.761458)
		(mid 376.759716 -17.809971)
		(end 376.787156 -17.85112)
		(stroke
			(width 0.06985)
			(type default)
		)
		(layer "In9.Cu")
	)
	(gr_line
		(start 376.750072 -17.349978)
		(end 376.750072 -17.761458)
		(stroke
			(width 0.06985)
			(type default)
		)
		(layer "In9.Cu")
	)
	(gr_arc
		(start 376.787156 -18.249138)
		(mid 376.759723 -18.290289)
		(end 376.750072 -18.3388)
		(stroke
			(width 0.06985)
			(type default)
		)
		(layer "In9.Cu")
	)
	(gr_line
		(start 376.787156 -18.249138)
		(end 376.802904 -18.23339)
		(stroke
			(width 0.06985)
			(type default)
		)
		(layer "In9.Cu")
	)
	(gr_line
		(start 376.787156 -17.85112)
		(end 376.802904 -17.866868)
		(stroke
			(width 0.06985)
			(type default)
		)
		(layer "In9.Cu")
	)
	(gr_arc
		(start 376.802904 -17.866868)
		(mid 376.844051 -17.894311)
		(end 376.892566 -17.903952)
		(stroke
			(width 0.06985)
			(type default)
		)
		(layer "In9.Cu")
	)
	(gr_arc
		(start 376.892566 -18.196306)
		(mid 376.844048 -18.205939)
		(end 376.802904 -18.23339)
		(stroke
			(width 0.06985)
			(type default)
		)
		(layer "In9.Cu")
	)
	(gr_line
		(start 377.771152 -31.087568)
		(end 377.796044 -31.048706)
		(stroke
			(width 0.06985)
			(type default)
		)
		(layer "In9.Cu")
	)
	(gr_line
		(start 378.549916 -19.338798)
		(end 378.549916 -19.750024)
		(stroke
			(width 0.06985)
			(type default)
		)
		(layer "In9.Cu")
	)
	(gr_arc
		(start 378.549916 -18.761456)
		(mid 378.559562 -18.809967)
		(end 378.587 -18.851118)
		(stroke
			(width 0.06985)
			(type default)
		)
		(layer "In9.Cu")
	)
	(gr_line
		(start 378.549916 -18.35023)
		(end 378.549916 -18.761456)
		(stroke
			(width 0.06985)
			(type default)
		)
		(layer "In9.Cu")
	)
	(gr_line
		(start 378.57938 -274.530312)
		(end 378.594366 -274.52066)
		(stroke
			(width 0.053848)
			(type default)
		)
		(layer "In9.Cu")
	)
	(gr_arc
		(start 378.587 -19.249136)
		(mid 378.559567 -19.290287)
		(end 378.549916 -19.338798)
		(stroke
			(width 0.06985)
			(type default)
		)
		(layer "In9.Cu")
	)
	(gr_line
		(start 378.587 -19.249136)
		(end 378.602748 -19.233388)
		(stroke
			(width 0.06985)
			(type default)
		)
		(layer "In9.Cu")
	)
	(gr_line
		(start 378.587 -18.851118)
		(end 378.602748 -18.866866)
		(stroke
			(width 0.06985)
			(type default)
		)
		(layer "In9.Cu")
	)
	(gr_line
		(start 378.594366 -274.52066)
		(end 378.612654 -274.516596)
		(stroke
			(width 0.053848)
			(type default)
		)
		(layer "In9.Cu")
	)
	(gr_arc
		(start 378.602748 -18.866866)
		(mid 378.643892 -18.894328)
		(end 378.69241 -18.90395)
		(stroke
			(width 0.06985)
			(type default)
		)
		(layer "In9.Cu")
	)
	(gr_arc
		(start 378.69241 -19.196304)
		(mid 378.643892 -19.205937)
		(end 378.602748 -19.233388)
		(stroke
			(width 0.06985)
			(type default)
		)
		(layer "In9.Cu")
	)
	(gr_line
		(start 379.570996 -32.535368)
		(end 379.595888 -32.496506)
		(stroke
			(width 0.06985)
			(type default)
		)
		(layer "In9.Cu")
	)
	(gr_line
		(start 380.350014 -18.3388)
		(end 380.350014 -18.750026)
		(stroke
			(width 0.06985)
			(type default)
		)
		(layer "In9.Cu")
	)
	(gr_arc
		(start 380.350014 -17.761458)
		(mid 380.359661 -17.809968)
		(end 380.387098 -17.85112)
		(stroke
			(width 0.06985)
			(type default)
		)
		(layer "In9.Cu")
	)
	(gr_line
		(start 380.350014 -17.349978)
		(end 380.350014 -17.761458)
		(stroke
			(width 0.06985)
			(type default)
		)
		(layer "In9.Cu")
	)
	(gr_arc
		(start 380.387098 -18.249138)
		(mid 380.359665 -18.290289)
		(end 380.350014 -18.3388)
		(stroke
			(width 0.06985)
			(type default)
		)
		(layer "In9.Cu")
	)
	(gr_line
		(start 380.387098 -18.249138)
		(end 380.402846 -18.23339)
		(stroke
			(width 0.06985)
			(type default)
		)
		(layer "In9.Cu")
	)
	(gr_line
		(start 380.387098 -17.85112)
		(end 380.402846 -17.866868)
		(stroke
			(width 0.06985)
			(type default)
		)
		(layer "In9.Cu")
	)
	(gr_arc
		(start 380.402846 -17.866868)
		(mid 380.44399 -17.89433)
		(end 380.492508 -17.903952)
		(stroke
			(width 0.06985)
			(type default)
		)
		(layer "In9.Cu")
	)
	(gr_arc
		(start 380.492508 -18.196306)
		(mid 380.44399 -18.205939)
		(end 380.402846 -18.23339)
		(stroke
			(width 0.06985)
			(type default)
		)
		(layer "In9.Cu")
	)
	(gr_line
		(start 381.099568 -45.683932)
		(end 381.1016 -45.679106)
		(stroke
			(width 0.06985)
			(type default)
		)
		(layer "In9.Cu")
	)
	(gr_line
		(start 381.1016 -45.679106)
		(end 381.104902 -45.67428)
		(stroke
			(width 0.06985)
			(type default)
		)
		(layer "In9.Cu")
	)
	(gr_arc
		(start 381.366776 -45.809408)
		(mid 381.359287 -45.821376)
		(end 381.35306 -45.834046)
		(stroke
			(width 0.06985)
			(type default)
		)
		(layer "In9.Cu")
	)
	(gr_line
		(start 381.371094 -32.622236)
		(end 381.395986 -32.583374)
		(stroke
			(width 0.06985)
			(type default)
		)
		(layer "In9.Cu")
	)
	(gr_line
		(start 382.034034 -159.029654)
		(end 382.053846 -158.998158)
		(stroke
			(width 0.053848)
			(type default)
		)
		(layer "In9.Cu")
	)
	(gr_line
		(start 382.053846 -158.998158)
		(end 382.085342 -158.978346)
		(stroke
			(width 0.053848)
			(type default)
		)
		(layer "In9.Cu")
	)
	(gr_line
		(start 382.150112 -19.338798)
		(end 382.150112 -19.750024)
		(stroke
			(width 0.06985)
			(type default)
		)
		(layer "In9.Cu")
	)
	(gr_arc
		(start 382.150112 -18.761456)
		(mid 382.159758 -18.809967)
		(end 382.187196 -18.851118)
		(stroke
			(width 0.06985)
			(type default)
		)
		(layer "In9.Cu")
	)
	(gr_line
		(start 382.150112 -18.35023)
		(end 382.150112 -18.761456)
		(stroke
			(width 0.06985)
			(type default)
		)
		(layer "In9.Cu")
	)
	(gr_arc
		(start 382.187196 -19.249136)
		(mid 382.159738 -19.290281)
		(end 382.150112 -19.338798)
		(stroke
			(width 0.06985)
			(type default)
		)
		(layer "In9.Cu")
	)
	(gr_line
		(start 382.187196 -19.249136)
		(end 382.202944 -19.233388)
		(stroke
			(width 0.06985)
			(type default)
		)
		(layer "In9.Cu")
	)
	(gr_line
		(start 382.187196 -18.851118)
		(end 382.202944 -18.866866)
		(stroke
			(width 0.06985)
			(type default)
		)
		(layer "In9.Cu")
	)
	(gr_arc
		(start 382.202944 -18.866866)
		(mid 382.244087 -18.894329)
		(end 382.292606 -18.90395)
		(stroke
			(width 0.06985)
			(type default)
		)
		(layer "In9.Cu")
	)
	(gr_arc
		(start 382.292606 -19.196304)
		(mid 382.244103 -19.205962)
		(end 382.202944 -19.233388)
		(stroke
			(width 0.06985)
			(type default)
		)
		(layer "In9.Cu")
	)
	(gr_line
		(start 382.363472 -158.803848)
		(end 382.4097 -158.774892)
		(stroke
			(width 0.053848)
			(type default)
		)
		(layer "In9.Cu")
	)
	(gr_line
		(start 382.7653 -46.1518)
		(end 383.06502 -46.1518)
		(stroke
			(width 0.053848)
			(type default)
		)
		(layer "In9.Cu")
	)
	(gr_arc
		(start 382.969516 -273.774916)
		(mid 383.015298 -273.765809)
		(end 383.054098 -273.739864)
		(stroke
			(width 0.053848)
			(type default)
		)
		(layer "In9.Cu")
	)
	(gr_arc
		(start 382.969516 -158.774892)
		(mid 383.015298 -158.765784)
		(end 383.054098 -158.73984)
		(stroke
			(width 0.053848)
			(type default)
		)
		(layer "In9.Cu")
	)
	(gr_arc
		(start 383.054098 -274.140168)
		(mid 383.015301 -274.114201)
		(end 382.969516 -274.105116)
		(stroke
			(width 0.053848)
			(type default)
		)
		(layer "In9.Cu")
	)
	(gr_arc
		(start 383.054098 -273.739864)
		(mid 383.080028 -273.701057)
		(end 383.08915 -273.655282)
		(stroke
			(width 0.053848)
			(type default)
		)
		(layer "In9.Cu")
	)
	(gr_arc
		(start 383.054098 -159.140144)
		(mid 383.015291 -159.114214)
		(end 382.969516 -159.105092)
		(stroke
			(width 0.053848)
			(type default)
		)
		(layer "In9.Cu")
	)
	(gr_arc
		(start 383.054098 -158.73984)
		(mid 383.080032 -158.701036)
		(end 383.08915 -158.655258)
		(stroke
			(width 0.053848)
			(type default)
		)
		(layer "In9.Cu")
	)
	(gr_arc
		(start 383.08915 -274.22475)
		(mid 383.080034 -274.178972)
		(end 383.054098 -274.140168)
		(stroke
			(width 0.053848)
			(type default)
		)
		(layer "In9.Cu")
	)
	(gr_line
		(start 383.08915 -274.22475)
		(end 383.08915 -274.511516)
		(stroke
			(width 0.053848)
			(type default)
		)
		(layer "In9.Cu")
	)
	(gr_line
		(start 383.08915 -273.368516)
		(end 383.08915 -273.655282)
		(stroke
			(width 0.053848)
			(type default)
		)
		(layer "In9.Cu")
	)
	(gr_arc
		(start 383.08915 -159.224726)
		(mid 383.080043 -159.178944)
		(end 383.054098 -159.140144)
		(stroke
			(width 0.053848)
			(type default)
		)
		(layer "In9.Cu")
	)
	(gr_line
		(start 383.08915 -159.224726)
		(end 383.08915 -159.511492)
		(stroke
			(width 0.053848)
			(type default)
		)
		(layer "In9.Cu")
	)
	(gr_line
		(start 383.08915 -158.368492)
		(end 383.08915 -158.655258)
		(stroke
			(width 0.053848)
			(type default)
		)
		(layer "In9.Cu")
	)
	(gr_arc
		(start 383.154682 -46.188884)
		(mid 383.113537 -46.161423)
		(end 383.06502 -46.1518)
		(stroke
			(width 0.053848)
			(type default)
		)
		(layer "In9.Cu")
	)
	(gr_line
		(start 383.154682 -46.188884)
		(end 383.156968 -46.19117)
		(stroke
			(width 0.053848)
			(type default)
		)
		(layer "In9.Cu")
	)
	(gr_line
		(start 383.171192 -32.832294)
		(end 383.196084 -32.793432)
		(stroke
			(width 0.06985)
			(type default)
		)
		(layer "In9.Cu")
	)
	(gr_arc
		(start 383.194052 -46.280832)
		(mid 383.184406 -46.23232)
		(end 383.156968 -46.19117)
		(stroke
			(width 0.053848)
			(type default)
		)
		(layer "In9.Cu")
	)
	(gr_line
		(start 383.513584 -46.8757)
		(end 383.524252 -46.850808)
		(stroke
			(width 0.053848)
			(type default)
		)
		(layer "In9.Cu")
	)
	(gr_arc
		(start 383.561336 -46.204378)
		(mid 383.533903 -46.245529)
		(end 383.524252 -46.29404)
		(stroke
			(width 0.053848)
			(type default)
		)
		(layer "In9.Cu")
	)
	(gr_line
		(start 383.561336 -46.204378)
		(end 383.57683 -46.188884)
		(stroke
			(width 0.053848)
			(type default)
		)
		(layer "In9.Cu")
	)
	(gr_arc
		(start 383.666492 -46.1518)
		(mid 383.617974 -46.161433)
		(end 383.57683 -46.188884)
		(stroke
			(width 0.053848)
			(type default)
		)
		(layer "In9.Cu")
	)
	(gr_line
		(start 383.666492 -46.1518)
		(end 383.9083 -46.1518)
		(stroke
			(width 0.053848)
			(type default)
		)
		(layer "In9.Cu")
	)
	(gr_line
		(start 383.949956 -18.3388)
		(end 383.949956 -18.750026)
		(stroke
			(width 0.06985)
			(type default)
		)
		(layer "In9.Cu")
	)
	(gr_arc
		(start 383.949956 -17.761458)
		(mid 383.959589 -17.809976)
		(end 383.98704 -17.85112)
		(stroke
			(width 0.06985)
			(type default)
		)
		(layer "In9.Cu")
	)
	(gr_line
		(start 383.949956 -17.349978)
		(end 383.949956 -17.761458)
		(stroke
			(width 0.06985)
			(type default)
		)
		(layer "In9.Cu")
	)
	(gr_arc
		(start 383.98704 -18.249138)
		(mid 383.959574 -18.290281)
		(end 383.949956 -18.3388)
		(stroke
			(width 0.06985)
			(type default)
		)
		(layer "In9.Cu")
	)
	(gr_line
		(start 383.98704 -18.249138)
		(end 384.002788 -18.23339)
		(stroke
			(width 0.06985)
			(type default)
		)
		(layer "In9.Cu")
	)
	(gr_line
		(start 383.98704 -17.85112)
		(end 384.002788 -17.866868)
		(stroke
			(width 0.06985)
			(type default)
		)
		(layer "In9.Cu")
	)
	(gr_arc
		(start 384.002788 -17.866868)
		(mid 384.043939 -17.894301)
		(end 384.09245 -17.903952)
		(stroke
			(width 0.06985)
			(type default)
		)
		(layer "In9.Cu")
	)
	(gr_arc
		(start 384.09245 -18.196306)
		(mid 384.043937 -18.20595)
		(end 384.002788 -18.23339)
		(stroke
			(width 0.06985)
			(type default)
		)
		(layer "In9.Cu")
	)
	(gr_line
		(start 384.965702 -33.43021)
		(end 384.995928 -33.386776)
		(stroke
			(width 0.06985)
			(type default)
		)
		(layer "In9.Cu")
	)
	(gr_line
		(start 385.750054 -19.338798)
		(end 385.750054 -19.750024)
		(stroke
			(width 0.06985)
			(type default)
		)
		(layer "In9.Cu")
	)
	(gr_arc
		(start 385.750054 -18.761456)
		(mid 385.759687 -18.809974)
		(end 385.787138 -18.851118)
		(stroke
			(width 0.06985)
			(type default)
		)
		(layer "In9.Cu")
	)
	(gr_line
		(start 385.750054 -18.35023)
		(end 385.750054 -18.761456)
		(stroke
			(width 0.06985)
			(type default)
		)
		(layer "In9.Cu")
	)
	(gr_arc
		(start 385.787138 -19.249136)
		(mid 385.759671 -19.290279)
		(end 385.750054 -19.338798)
		(stroke
			(width 0.06985)
			(type default)
		)
		(layer "In9.Cu")
	)
	(gr_line
		(start 385.787138 -19.249136)
		(end 385.802886 -19.233388)
		(stroke
			(width 0.06985)
			(type default)
		)
		(layer "In9.Cu")
	)
	(gr_line
		(start 385.787138 -18.851118)
		(end 385.802886 -18.866866)
		(stroke
			(width 0.06985)
			(type default)
		)
		(layer "In9.Cu")
	)
	(gr_arc
		(start 385.802886 -18.866866)
		(mid 385.844037 -18.894299)
		(end 385.892548 -18.90395)
		(stroke
			(width 0.06985)
			(type default)
		)
		(layer "In9.Cu")
	)
	(gr_arc
		(start 385.892548 -19.196304)
		(mid 385.844036 -19.205948)
		(end 385.802886 -19.233388)
		(stroke
			(width 0.06985)
			(type default)
		)
		(layer "In9.Cu")
	)
	(gr_line
		(start 386.7658 -33.400492)
		(end 386.796026 -33.357058)
		(stroke
			(width 0.06985)
			(type default)
		)
		(layer "In9.Cu")
	)
	(gr_line
		(start 387.549898 -18.3388)
		(end 387.549898 -18.750026)
		(stroke
			(width 0.06985)
			(type default)
		)
		(layer "In9.Cu")
	)
	(gr_arc
		(start 387.549898 -17.761458)
		(mid 387.559531 -17.809976)
		(end 387.586982 -17.85112)
		(stroke
			(width 0.06985)
			(type default)
		)
		(layer "In9.Cu")
	)
	(gr_line
		(start 387.549898 -17.349978)
		(end 387.549898 -17.761458)
		(stroke
			(width 0.06985)
			(type default)
		)
		(layer "In9.Cu")
	)
	(gr_arc
		(start 387.586982 -18.249138)
		(mid 387.559528 -18.290284)
		(end 387.549898 -18.3388)
		(stroke
			(width 0.06985)
			(type default)
		)
		(layer "In9.Cu")
	)
	(gr_line
		(start 387.586982 -18.249138)
		(end 387.60273 -18.23339)
		(stroke
			(width 0.06985)
			(type default)
		)
		(layer "In9.Cu")
	)
	(gr_line
		(start 387.586982 -17.85112)
		(end 387.60273 -17.866868)
		(stroke
			(width 0.06985)
			(type default)
		)
		(layer "In9.Cu")
	)
	(gr_arc
		(start 387.60273 -17.866868)
		(mid 387.643881 -17.894301)
		(end 387.692392 -17.903952)
		(stroke
			(width 0.06985)
			(type default)
		)
		(layer "In9.Cu")
	)
	(gr_arc
		(start 387.692392 -18.196306)
		(mid 387.643892 -18.205969)
		(end 387.60273 -18.23339)
		(stroke
			(width 0.06985)
			(type default)
		)
		(layer "In9.Cu")
	)
	(gr_line
		(start 388.565644 -33.311592)
		(end 388.59587 -33.267904)
		(stroke
			(width 0.06985)
			(type default)
		)
		(layer "In9.Cu")
	)
	(gr_line
		(start 389.349996 -19.338798)
		(end 389.349996 -19.750024)
		(stroke
			(width 0.06985)
			(type default)
		)
		(layer "In9.Cu")
	)
	(gr_arc
		(start 389.349996 -18.761456)
		(mid 389.359629 -18.809974)
		(end 389.38708 -18.851118)
		(stroke
			(width 0.06985)
			(type default)
		)
		(layer "In9.Cu")
	)
	(gr_line
		(start 389.349996 -18.35023)
		(end 389.349996 -18.761456)
		(stroke
			(width 0.06985)
			(type default)
		)
		(layer "In9.Cu")
	)
	(gr_arc
		(start 389.38708 -19.249136)
		(mid 389.359626 -19.290282)
		(end 389.349996 -19.338798)
		(stroke
			(width 0.06985)
			(type default)
		)
		(layer "In9.Cu")
	)
	(gr_line
		(start 389.38708 -19.249136)
		(end 389.402828 -19.233388)
		(stroke
			(width 0.06985)
			(type default)
		)
		(layer "In9.Cu")
	)
	(gr_line
		(start 389.38708 -18.851118)
		(end 389.402828 -18.866866)
		(stroke
			(width 0.06985)
			(type default)
		)
		(layer "In9.Cu")
	)
	(gr_arc
		(start 389.402828 -18.866866)
		(mid 389.443979 -18.894299)
		(end 389.49249 -18.90395)
		(stroke
			(width 0.06985)
			(type default)
		)
		(layer "In9.Cu")
	)
	(gr_arc
		(start 389.49249 -19.196304)
		(mid 389.44399 -19.205967)
		(end 389.402828 -19.233388)
		(stroke
			(width 0.06985)
			(type default)
		)
		(layer "In9.Cu")
	)
	(gr_line
		(start 390.365996 -32.803846)
		(end 390.371076 -32.796226)
		(stroke
			(width 0.06985)
			(type default)
		)
		(layer "In9.Cu")
	)
	(gr_arc
		(start 390.371076 -32.796226)
		(mid 390.389611 -32.75838)
		(end 390.395968 -32.716724)
		(stroke
			(width 0.06985)
			(type default)
		)
		(layer "In9.Cu")
	)
	(gr_line
		(start 397.462756 -79.813658)
		(end 397.46682 -79.811118)
		(stroke
			(width 0.053848)
			(type default)
		)
		(layer "In9.Cu")
	)
	(gr_line
		(start 397.46682 -79.811118)
		(end 397.471392 -79.809594)
		(stroke
			(width 0.053848)
			(type default)
		)
		(layer "In9.Cu")
	)
	(gr_line
		(start 403.235414 -47.198026)
		(end 403.250908 -47.18558)
		(stroke
			(width 0.053848)
			(type default)
		)
		(layer "In9.Cu")
	)
	(gr_line
		(start 403.250908 -47.18558)
		(end 403.26945 -47.179484)
		(stroke
			(width 0.053848)
			(type default)
		)
		(layer "In9.Cu")
	)
	(gr_line
		(start 405.40432 -160.260538)
		(end 405.418798 -160.25114)
		(stroke
			(width 0.053848)
			(type default)
		)
		(layer "In9.Cu")
	)
	(gr_line
		(start 405.418798 -160.25114)
		(end 405.435816 -160.247584)
		(stroke
			(width 0.053848)
			(type default)
		)
		(layer "In9.Cu")
	)
	(gr_line
		(start 413.690054 -43.778424)
		(end 413.700976 -43.774868)
		(stroke
			(width 0.053848)
			(type default)
		)
		(layer "In9.Cu")
	)
	(gr_line
		(start 413.867346 -273.782028)
		(end 413.885888 -273.774916)
		(stroke
			(width 0.053848)
			(type default)
		)
		(layer "In9.Cu")
	)
	(gr_arc
		(start 414.519618 -273.774916)
		(mid 414.565401 -273.765808)
		(end 414.6042 -273.739864)
		(stroke
			(width 0.053848)
			(type default)
		)
		(layer "In9.Cu")
	)
	(gr_arc
		(start 414.519618 -158.774892)
		(mid 414.5654 -158.765785)
		(end 414.6042 -158.73984)
		(stroke
			(width 0.053848)
			(type default)
		)
		(layer "In9.Cu")
	)
	(gr_arc
		(start 414.519618 -43.774868)
		(mid 414.565404 -43.765763)
		(end 414.6042 -43.739816)
		(stroke
			(width 0.053848)
			(type default)
		)
		(layer "In9.Cu")
	)
	(gr_arc
		(start 414.6042 -274.140168)
		(mid 414.565393 -274.114238)
		(end 414.519618 -274.105116)
		(stroke
			(width 0.053848)
			(type default)
		)
		(layer "In9.Cu")
	)
	(gr_arc
		(start 414.6042 -273.739864)
		(mid 414.630141 -273.701061)
		(end 414.639252 -273.655282)
		(stroke
			(width 0.053848)
			(type default)
		)
		(layer "In9.Cu")
	)
	(gr_arc
		(start 414.6042 -159.140144)
		(mid 414.565402 -159.114182)
		(end 414.519618 -159.105092)
		(stroke
			(width 0.053848)
			(type default)
		)
		(layer "In9.Cu")
	)
	(gr_arc
		(start 414.6042 -158.73984)
		(mid 414.63013 -158.701033)
		(end 414.639252 -158.655258)
		(stroke
			(width 0.053848)
			(type default)
		)
		(layer "In9.Cu")
	)
	(gr_arc
		(start 414.6042 -44.14012)
		(mid 414.565393 -44.11419)
		(end 414.519618 -44.105068)
		(stroke
			(width 0.053848)
			(type default)
		)
		(layer "In9.Cu")
	)
	(gr_arc
		(start 414.6042 -43.739816)
		(mid 414.630125 -43.70101)
		(end 414.639252 -43.655234)
		(stroke
			(width 0.053848)
			(type default)
		)
		(layer "In9.Cu")
	)
	(gr_arc
		(start 414.639252 -274.22475)
		(mid 414.630145 -274.178968)
		(end 414.6042 -274.140168)
		(stroke
			(width 0.053848)
			(type default)
		)
		(layer "In9.Cu")
	)
	(gr_line
		(start 414.639252 -274.22475)
		(end 414.639252 -274.511516)
		(stroke
			(width 0.053848)
			(type default)
		)
		(layer "In9.Cu")
	)
	(gr_line
		(start 414.639252 -273.368516)
		(end 414.639252 -273.655282)
		(stroke
			(width 0.053848)
			(type default)
		)
		(layer "In9.Cu")
	)
	(gr_arc
		(start 414.639252 -159.224726)
		(mid 414.630128 -159.178953)
		(end 414.6042 -159.140144)
		(stroke
			(width 0.053848)
			(type default)
		)
		(layer "In9.Cu")
	)
	(gr_line
		(start 414.639252 -159.224726)
		(end 414.639252 -159.511492)
		(stroke
			(width 0.053848)
			(type default)
		)
		(layer "In9.Cu")
	)
	(gr_line
		(start 414.639252 -158.368492)
		(end 414.639252 -158.655258)
		(stroke
			(width 0.053848)
			(type default)
		)
		(layer "In9.Cu")
	)
	(gr_arc
		(start 414.639252 -44.224702)
		(mid 414.630145 -44.17892)
		(end 414.6042 -44.14012)
		(stroke
			(width 0.053848)
			(type default)
		)
		(layer "In9.Cu")
	)
	(gr_line
		(start 414.639252 -44.224702)
		(end 414.639252 -44.511468)
		(stroke
			(width 0.053848)
			(type default)
		)
		(layer "In9.Cu")
	)
	(gr_line
		(start 414.639252 -43.368468)
		(end 414.639252 -43.655234)
		(stroke
			(width 0.053848)
			(type default)
		)
		(layer "In9.Cu")
	)
	(gr_line
		(start 429.947578 -225.090228)
		(end 429.970692 -225.085402)
		(stroke
			(width 0.053848)
			(type default)
		)
		(layer "In9.Cu")
	)
	(gr_line
		(start 429.970692 -225.085402)
		(end 429.989488 -225.072956)
		(stroke
			(width 0.053848)
			(type default)
		)
		(layer "In9.Cu")
	)
	(gr_line
		(start 433.110894 -47.676054)
		(end 433.126388 -47.663608)
		(stroke
			(width 0.053848)
			(type default)
		)
		(layer "In9.Cu")
	)
	(gr_line
		(start 433.126388 -47.663608)
		(end 433.14493 -47.657512)
		(stroke
			(width 0.053848)
			(type default)
		)
		(layer "In9.Cu")
	)
	(gr_line
		(start 437.998108 -219.90177)
		(end 438.031382 -219.88018)
		(stroke
			(width 0.053848)
			(type default)
		)
		(layer "In9.Cu")
	)
	(gr_line
		(start 438.031382 -219.88018)
		(end 438.050686 -219.846906)
		(stroke
			(width 0.053848)
			(type default)
		)
		(layer "In9.Cu")
	)
	(gr_line
		(start 438.324244 -158.78556)
		(end 438.348882 -158.774892)
		(stroke
			(width 0.053848)
			(type default)
		)
		(layer "In9.Cu")
	)
	(gr_arc
		(start 439.719466 -158.774892)
		(mid 439.765237 -158.765767)
		(end 439.804048 -158.73984)
		(stroke
			(width 0.053848)
			(type default)
		)
		(layer "In9.Cu")
	)
	(gr_arc
		(start 439.804048 -159.140144)
		(mid 439.765241 -159.114214)
		(end 439.719466 -159.105092)
		(stroke
			(width 0.053848)
			(type default)
		)
		(layer "In9.Cu")
	)
	(gr_arc
		(start 439.804048 -158.73984)
		(mid 439.829992 -158.701038)
		(end 439.8391 -158.655258)
		(stroke
			(width 0.053848)
			(type default)
		)
		(layer "In9.Cu")
	)
	(gr_arc
		(start 439.8391 -159.224726)
		(mid 439.829993 -159.178944)
		(end 439.804048 -159.140144)
		(stroke
			(width 0.053848)
			(type default)
		)
		(layer "In9.Cu")
	)
	(gr_line
		(start 439.8391 -159.224726)
		(end 439.8391 -159.511492)
		(stroke
			(width 0.053848)
			(type default)
		)
		(layer "In9.Cu")
	)
	(gr_line
		(start 439.8391 -158.368492)
		(end 439.8391 -158.655258)
		(stroke
			(width 0.053848)
			(type default)
		)
		(layer "In9.Cu")
	)
	(gr_line
		(start 443.529974 -65.12433)
		(end 443.548516 -65.118234)
		(stroke
			(width 0.053848)
			(type default)
		)
		(layer "In9.Cu")
	)
	(gr_line
		(start 443.548516 -65.118234)
		(end 443.56401 -65.105788)
		(stroke
			(width 0.053848)
			(type default)
		)
		(layer "In9.Cu")
	)
	(gr_line
		(start 444.506858 -273.7866)
		(end 444.532766 -273.774916)
		(stroke
			(width 0.053848)
			(type default)
		)
		(layer "In9.Cu")
	)
	(gr_line
		(start 445.029336 -43.778424)
		(end 445.040258 -43.774868)
		(stroke
			(width 0.053848)
			(type default)
		)
		(layer "In9.Cu")
	)
	(gr_arc
		(start 446.069466 -273.774916)
		(mid 446.115239 -273.765793)
		(end 446.154048 -273.739864)
		(stroke
			(width 0.053848)
			(type default)
		)
		(layer "In9.Cu")
	)
	(gr_arc
		(start 446.069466 -43.774868)
		(mid 446.115242 -43.765748)
		(end 446.154048 -43.739816)
		(stroke
			(width 0.053848)
			(type default)
		)
		(layer "In9.Cu")
	)
	(gr_arc
		(start 446.154048 -274.140168)
		(mid 446.115241 -274.114238)
		(end 446.069466 -274.105116)
		(stroke
			(width 0.053848)
			(type default)
		)
		(layer "In9.Cu")
	)
	(gr_arc
		(start 446.154048 -273.739864)
		(mid 446.18 -273.701064)
		(end 446.1891 -273.655282)
		(stroke
			(width 0.053848)
			(type default)
		)
		(layer "In9.Cu")
	)
	(gr_arc
		(start 446.154048 -44.14012)
		(mid 446.115241 -44.11419)
		(end 446.069466 -44.105068)
		(stroke
			(width 0.053848)
			(type default)
		)
		(layer "In9.Cu")
	)
	(gr_arc
		(start 446.154048 -43.739816)
		(mid 446.179984 -43.701013)
		(end 446.1891 -43.655234)
		(stroke
			(width 0.053848)
			(type default)
		)
		(layer "In9.Cu")
	)
	(gr_arc
		(start 446.1891 -274.22475)
		(mid 446.179993 -274.178968)
		(end 446.154048 -274.140168)
		(stroke
			(width 0.053848)
			(type default)
		)
		(layer "In9.Cu")
	)
	(gr_line
		(start 446.1891 -274.22475)
		(end 446.1891 -274.511516)
		(stroke
			(width 0.053848)
			(type default)
		)
		(layer "In9.Cu")
	)
	(gr_line
		(start 446.1891 -273.368516)
		(end 446.1891 -273.655282)
		(stroke
			(width 0.053848)
			(type default)
		)
		(layer "In9.Cu")
	)
	(gr_arc
		(start 446.1891 -44.224702)
		(mid 446.179993 -44.17892)
		(end 446.154048 -44.14012)
		(stroke
			(width 0.053848)
			(type default)
		)
		(layer "In9.Cu")
	)
	(gr_line
		(start 446.1891 -44.224702)
		(end 446.1891 -44.511468)
		(stroke
			(width 0.053848)
			(type default)
		)
		(layer "In9.Cu")
	)
	(gr_line
		(start 446.1891 -43.368468)
		(end 446.1891 -43.655234)
		(stroke
			(width 0.053848)
			(type default)
		)
		(layer "In9.Cu")
	)
	(gr_line
		(start 452.952104 -194.271646)
		(end 452.955152 -194.266312)
		(stroke
			(width 0.053848)
			(type default)
		)
		(layer "In9.Cu")
	)
	(gr_line
		(start 452.955152 -194.266312)
		(end 452.956676 -194.260216)
		(stroke
			(width 0.053848)
			(type default)
		)
		(layer "In9.Cu")
	)
	(gr_line
		(start 458.112876 -172.49521)
		(end 458.113638 -172.492416)
		(stroke
			(width 0.053848)
			(type default)
		)
		(layer "In9.Cu")
	)
	(gr_line
		(start 458.113638 -172.492416)
		(end 458.114908 -172.489876)
		(stroke
			(width 0.053848)
			(type default)
		)
		(layer "In9.Cu")
	)
	(gr_line
		(start 458.371194 -277.657814)
		(end 458.376782 -277.654766)
		(stroke
			(width 0.053848)
			(type default)
		)
		(layer "In9.Cu")
	)
	(gr_line
		(start 458.376782 -277.654766)
		(end 458.382116 -277.65375)
		(stroke
			(width 0.053848)
			(type default)
		)
		(layer "In9.Cu")
	)
	(gr_line
		(start 462.271618 -164.95268)
		(end 462.284318 -164.92982)
		(stroke
			(width 0.053848)
			(type default)
		)
		(layer "In9.Cu")
	)
	(gr_line
		(start 462.284318 -164.92982)
		(end 462.304638 -164.91331)
		(stroke
			(width 0.053848)
			(type default)
		)
		(layer "In9.Cu")
	)
	(gr_line
		(start 463.053684 -49.000664)
		(end 463.06359 -48.99279)
		(stroke
			(width 0.053848)
			(type default)
		)
		(layer "In9.Cu")
	)
	(gr_line
		(start 463.06359 -48.99279)
		(end 463.075274 -48.988218)
		(stroke
			(width 0.053848)
			(type default)
		)
		(layer "In9.Cu")
	)
	(gr_line
		(start 467.44636 -160.761426)
		(end 467.473538 -160.739582)
		(stroke
			(width 0.053848)
			(type default)
		)
		(layer "In9.Cu")
	)
	(gr_line
		(start 467.473538 -160.739582)
		(end 467.507066 -160.731708)
		(stroke
			(width 0.053848)
			(type default)
		)
		(layer "In9.Cu")
	)
	(gr_line
		(start 476.828612 -43.781726)
		(end 476.8469 -43.774868)
		(stroke
			(width 0.053848)
			(type default)
		)
		(layer "In9.Cu")
	)
	(gr_arc
		(start 477.619568 -273.774916)
		(mid 477.66534 -273.765792)
		(end 477.70415 -273.739864)
		(stroke
			(width 0.053848)
			(type default)
		)
		(layer "In9.Cu")
	)
	(gr_arc
		(start 477.619568 -158.774892)
		(mid 477.665339 -158.765767)
		(end 477.70415 -158.73984)
		(stroke
			(width 0.053848)
			(type default)
		)
		(layer "In9.Cu")
	)
	(gr_arc
		(start 477.619568 -43.774868)
		(mid 477.66535 -43.765761)
		(end 477.70415 -43.739816)
		(stroke
			(width 0.053848)
			(type default)
		)
		(layer "In9.Cu")
	)
	(gr_arc
		(start 477.70415 -274.140168)
		(mid 477.665343 -274.114238)
		(end 477.619568 -274.105116)
		(stroke
			(width 0.053848)
			(type default)
		)
		(layer "In9.Cu")
	)
	(gr_arc
		(start 477.70415 -273.739864)
		(mid 477.730102 -273.701064)
		(end 477.739202 -273.655282)
		(stroke
			(width 0.053848)
			(type default)
		)
		(layer "In9.Cu")
	)
	(gr_arc
		(start 477.70415 -159.140144)
		(mid 477.665343 -159.114214)
		(end 477.619568 -159.105092)
		(stroke
			(width 0.053848)
			(type default)
		)
		(layer "In9.Cu")
	)
	(gr_arc
		(start 477.70415 -158.73984)
		(mid 477.730094 -158.701038)
		(end 477.739202 -158.655258)
		(stroke
			(width 0.053848)
			(type default)
		)
		(layer "In9.Cu")
	)
	(gr_arc
		(start 477.70415 -44.14012)
		(mid 477.665347 -44.114179)
		(end 477.619568 -44.105068)
		(stroke
			(width 0.053848)
			(type default)
		)
		(layer "In9.Cu")
	)
	(gr_arc
		(start 477.70415 -43.739816)
		(mid 477.73008 -43.701009)
		(end 477.739202 -43.655234)
		(stroke
			(width 0.053848)
			(type default)
		)
		(layer "In9.Cu")
	)
	(gr_arc
		(start 477.739202 -274.22475)
		(mid 477.730095 -274.178968)
		(end 477.70415 -274.140168)
		(stroke
			(width 0.053848)
			(type default)
		)
		(layer "In9.Cu")
	)
	(gr_line
		(start 477.739202 -274.22475)
		(end 477.739202 -274.511516)
		(stroke
			(width 0.053848)
			(type default)
		)
		(layer "In9.Cu")
	)
	(gr_line
		(start 477.739202 -273.368516)
		(end 477.739202 -273.655282)
		(stroke
			(width 0.053848)
			(type default)
		)
		(layer "In9.Cu")
	)
	(gr_arc
		(start 477.739202 -159.224726)
		(mid 477.730095 -159.178944)
		(end 477.70415 -159.140144)
		(stroke
			(width 0.053848)
			(type default)
		)
		(layer "In9.Cu")
	)
	(gr_line
		(start 477.739202 -159.224726)
		(end 477.739202 -159.511492)
		(stroke
			(width 0.053848)
			(type default)
		)
		(layer "In9.Cu")
	)
	(gr_line
		(start 477.739202 -158.368492)
		(end 477.739202 -158.655258)
		(stroke
			(width 0.053848)
			(type default)
		)
		(layer "In9.Cu")
	)
	(gr_arc
		(start 477.739202 -44.224702)
		(mid 477.730067 -44.178937)
		(end 477.70415 -44.14012)
		(stroke
			(width 0.053848)
			(type default)
		)
		(layer "In9.Cu")
	)
	(gr_line
		(start 477.739202 -44.224702)
		(end 477.739202 -44.511468)
		(stroke
			(width 0.053848)
			(type default)
		)
		(layer "In9.Cu")
	)
	(gr_line
		(start 477.739202 -43.368468)
		(end 477.739202 -43.655234)
		(stroke
			(width 0.053848)
			(type default)
		)
		(layer "In9.Cu")
	)
	(gr_line
		(start 0 -348.199964)
		(end 0 -0.999998)
		(stroke
			(width 1.524)
			(type default)
		)
		(layer "In10.Cu")
	)
	(gr_arc
		(start 0 -348.199964)
		(mid 0.292894 -348.907067)
		(end 0.999998 -349.199962)
		(stroke
			(width 1.524)
			(type default)
		)
		(layer "In10.Cu")
	)
	(gr_arc
		(start 0.999998 0)
		(mid 0.292893 -0.292893)
		(end 0 -0.999998)
		(stroke
			(width 1.524)
			(type default)
		)
		(layer "In10.Cu")
	)
	(gr_line
		(start 0.999998 0)
		(end 101.000052 0)
		(stroke
			(width 1.524)
			(type default)
		)
		(layer "In10.Cu")
	)
	(gr_arc
		(start 32.127952 -278.321516)
		(mid 32.508952 -278.702516)
		(end 32.889952 -278.321516)
		(stroke
			(width 0.2)
			(type default)
		)
		(layer "In10.Cu")
	)
	(gr_line
		(start 32.127952 -277.178516)
		(end 32.127952 -278.321516)
		(stroke
			(width 0.2)
			(type default)
		)
		(layer "In10.Cu")
	)
	(gr_arc
		(start 32.127952 -163.321492)
		(mid 32.508952 -163.702492)
		(end 32.889952 -163.321492)
		(stroke
			(width 0.2)
			(type default)
		)
		(layer "In10.Cu")
	)
	(gr_line
		(start 32.127952 -162.178492)
		(end 32.127952 -163.321492)
		(stroke
			(width 0.2)
			(type default)
		)
		(layer "In10.Cu")
	)
	(gr_arc
		(start 32.127952 -48.321468)
		(mid 32.508952 -48.702468)
		(end 32.889952 -48.321468)
		(stroke
			(width 0.2)
			(type default)
		)
		(layer "In10.Cu")
	)
	(gr_line
		(start 32.127952 -47.178468)
		(end 32.127952 -48.321468)
		(stroke
			(width 0.2)
			(type default)
		)
		(layer "In10.Cu")
	)
	(gr_line
		(start 32.889952 -278.321516)
		(end 32.889952 -277.17877)
		(stroke
			(width 0.2)
			(type default)
		)
		(layer "In10.Cu")
	)
	(gr_arc
		(start 32.889952 -277.17877)
		(mid 32.509079 -276.797516)
		(end 32.127952 -277.178516)
		(stroke
			(width 0.2)
			(type default)
		)
		(layer "In10.Cu")
	)
	(gr_line
		(start 32.889952 -163.321492)
		(end 32.889952 -162.178746)
		(stroke
			(width 0.2)
			(type default)
		)
		(layer "In10.Cu")
	)
	(gr_arc
		(start 32.889952 -162.178746)
		(mid 32.509079 -161.797492)
		(end 32.127952 -162.178492)
		(stroke
			(width 0.2)
			(type default)
		)
		(layer "In10.Cu")
	)
	(gr_line
		(start 32.889952 -48.321468)
		(end 32.889952 -47.178722)
		(stroke
			(width 0.2)
			(type default)
		)
		(layer "In10.Cu")
	)
	(gr_arc
		(start 32.889952 -47.178722)
		(mid 32.509079 -46.797468)
		(end 32.127952 -47.178468)
		(stroke
			(width 0.2)
			(type default)
		)
		(layer "In10.Cu")
	)
	(gr_arc
		(start 63.6778 -278.321516)
		(mid 64.0588 -278.702516)
		(end 64.4398 -278.321516)
		(stroke
			(width 0.2)
			(type default)
		)
		(layer "In10.Cu")
	)
	(gr_line
		(start 63.6778 -277.178516)
		(end 63.6778 -278.321516)
		(stroke
			(width 0.2)
			(type default)
		)
		(layer "In10.Cu")
	)
	(gr_arc
		(start 63.6778 -163.321492)
		(mid 64.0588 -163.702492)
		(end 64.4398 -163.321492)
		(stroke
			(width 0.2)
			(type default)
		)
		(layer "In10.Cu")
	)
	(gr_line
		(start 63.6778 -162.178492)
		(end 63.6778 -163.321492)
		(stroke
			(width 0.2)
			(type default)
		)
		(layer "In10.Cu")
	)
	(gr_arc
		(start 63.6778 -48.321468)
		(mid 64.0588 -48.702468)
		(end 64.4398 -48.321468)
		(stroke
			(width 0.2)
			(type default)
		)
		(layer "In10.Cu")
	)
	(gr_line
		(start 63.6778 -47.178468)
		(end 63.6778 -48.321468)
		(stroke
			(width 0.2)
			(type default)
		)
		(layer "In10.Cu")
	)
	(gr_line
		(start 64.4398 -278.321516)
		(end 64.4398 -277.17877)
		(stroke
			(width 0.2)
			(type default)
		)
		(layer "In10.Cu")
	)
	(gr_arc
		(start 64.4398 -277.17877)
		(mid 64.058927 -276.797516)
		(end 63.6778 -277.178516)
		(stroke
			(width 0.2)
			(type default)
		)
		(layer "In10.Cu")
	)
	(gr_line
		(start 64.4398 -163.321492)
		(end 64.4398 -162.178746)
		(stroke
			(width 0.2)
			(type default)
		)
		(layer "In10.Cu")
	)
	(gr_arc
		(start 64.4398 -162.178746)
		(mid 64.058927 -161.797492)
		(end 63.6778 -162.178492)
		(stroke
			(width 0.2)
			(type default)
		)
		(layer "In10.Cu")
	)
	(gr_line
		(start 64.4398 -48.321468)
		(end 64.4398 -47.178722)
		(stroke
			(width 0.2)
			(type default)
		)
		(layer "In10.Cu")
	)
	(gr_arc
		(start 64.4398 -47.178722)
		(mid 64.058927 -46.797468)
		(end 63.6778 -47.178468)
		(stroke
			(width 0.2)
			(type default)
		)
		(layer "In10.Cu")
	)
	(gr_arc
		(start 95.227902 -278.321516)
		(mid 95.608902 -278.702516)
		(end 95.989902 -278.321516)
		(stroke
			(width 0.2)
			(type default)
		)
		(layer "In10.Cu")
	)
	(gr_line
		(start 95.227902 -277.178516)
		(end 95.227902 -278.321516)
		(stroke
			(width 0.2)
			(type default)
		)
		(layer "In10.Cu")
	)
	(gr_arc
		(start 95.227902 -163.321492)
		(mid 95.608902 -163.702492)
		(end 95.989902 -163.321492)
		(stroke
			(width 0.2)
			(type default)
		)
		(layer "In10.Cu")
	)
	(gr_line
		(start 95.227902 -162.178492)
		(end 95.227902 -163.321492)
		(stroke
			(width 0.2)
			(type default)
		)
		(layer "In10.Cu")
	)
	(gr_arc
		(start 95.227902 -48.321468)
		(mid 95.608902 -48.702468)
		(end 95.989902 -48.321468)
		(stroke
			(width 0.2)
			(type default)
		)
		(layer "In10.Cu")
	)
	(gr_line
		(start 95.227902 -47.178468)
		(end 95.227902 -48.321468)
		(stroke
			(width 0.2)
			(type default)
		)
		(layer "In10.Cu")
	)
	(gr_line
		(start 95.989902 -278.321516)
		(end 95.989902 -277.17877)
		(stroke
			(width 0.2)
			(type default)
		)
		(layer "In10.Cu")
	)
	(gr_arc
		(start 95.989902 -277.17877)
		(mid 95.609029 -276.797516)
		(end 95.227902 -277.178516)
		(stroke
			(width 0.2)
			(type default)
		)
		(layer "In10.Cu")
	)
	(gr_line
		(start 95.989902 -163.321492)
		(end 95.989902 -162.178746)
		(stroke
			(width 0.2)
			(type default)
		)
		(layer "In10.Cu")
	)
	(gr_arc
		(start 95.989902 -162.178746)
		(mid 95.609029 -161.797492)
		(end 95.227902 -162.178492)
		(stroke
			(width 0.2)
			(type default)
		)
		(layer "In10.Cu")
	)
	(gr_line
		(start 95.989902 -48.321468)
		(end 95.989902 -47.178722)
		(stroke
			(width 0.2)
			(type default)
		)
		(layer "In10.Cu")
	)
	(gr_arc
		(start 95.989902 -47.178722)
		(mid 95.609029 -46.797468)
		(end 95.227902 -47.178468)
		(stroke
			(width 0.2)
			(type default)
		)
		(layer "In10.Cu")
	)
	(gr_arc
		(start 102.00005 -13.999972)
		(mid 102.292943 -14.707077)
		(end 103.000048 -14.99997)
		(stroke
			(width 1.524)
			(type default)
		)
		(layer "In10.Cu")
	)
	(gr_arc
		(start 102.00005 -0.999998)
		(mid 101.707154 -0.292911)
		(end 101.000052 0)
		(stroke
			(width 1.524)
			(type default)
		)
		(layer "In10.Cu")
	)
	(gr_line
		(start 102.00005 -0.999998)
		(end 102.00005 -13.999972)
		(stroke
			(width 1.524)
			(type default)
		)
		(layer "In10.Cu")
	)
	(gr_line
		(start 103.000048 -14.99997)
		(end 148.999956 -14.99997)
		(stroke
			(width 1.524)
			(type default)
		)
		(layer "In10.Cu")
	)
	(gr_arc
		(start 108.601256 -22.350222)
		(mid 109.149896 -22.898862)
		(end 109.698536 -22.350222)
		(stroke
			(width 0.2)
			(type default)
		)
		(layer "In10.Cu")
	)
	(gr_line
		(start 108.601256 -20.950174)
		(end 108.601256 -22.350222)
		(stroke
			(width 0.2)
			(type default)
		)
		(layer "In10.Cu")
	)
	(gr_arc
		(start 108.601256 -18.750026)
		(mid 109.149896 -19.298666)
		(end 109.698536 -18.750026)
		(stroke
			(width 0.2)
			(type default)
		)
		(layer "In10.Cu")
	)
	(gr_line
		(start 108.601256 -17.349978)
		(end 108.601256 -18.750026)
		(stroke
			(width 0.2)
			(type default)
		)
		(layer "In10.Cu")
	)
	(gr_line
		(start 109.698536 -22.350222)
		(end 109.698536 -20.950428)
		(stroke
			(width 0.2)
			(type default)
		)
		(layer "In10.Cu")
	)
	(gr_arc
		(start 109.698536 -20.950428)
		(mid 109.150023 -20.401534)
		(end 108.601256 -20.950174)
		(stroke
			(width 0.2)
			(type default)
		)
		(layer "In10.Cu")
	)
	(gr_line
		(start 109.698536 -18.750026)
		(end 109.698536 -17.350232)
		(stroke
			(width 0.2)
			(type default)
		)
		(layer "In10.Cu")
	)
	(gr_arc
		(start 109.698536 -17.350232)
		(mid 109.150023 -16.801338)
		(end 108.601256 -17.349978)
		(stroke
			(width 0.2)
			(type default)
		)
		(layer "In10.Cu")
	)
	(gr_arc
		(start 110.401354 -23.35022)
		(mid 110.949994 -23.89886)
		(end 111.498634 -23.35022)
		(stroke
			(width 0.2)
			(type default)
		)
		(layer "In10.Cu")
	)
	(gr_line
		(start 110.401354 -21.950172)
		(end 110.401354 -23.35022)
		(stroke
			(width 0.2)
			(type default)
		)
		(layer "In10.Cu")
	)
	(gr_arc
		(start 110.401354 -19.750024)
		(mid 110.949994 -20.298664)
		(end 111.498634 -19.750024)
		(stroke
			(width 0.2)
			(type default)
		)
		(layer "In10.Cu")
	)
	(gr_line
		(start 110.401354 -18.35023)
		(end 110.401354 -19.750024)
		(stroke
			(width 0.2)
			(type default)
		)
		(layer "In10.Cu")
	)
	(gr_line
		(start 111.498634 -23.35022)
		(end 111.498634 -21.950426)
		(stroke
			(width 0.2)
			(type default)
		)
		(layer "In10.Cu")
	)
	(gr_arc
		(start 111.498634 -21.950426)
		(mid 110.950121 -21.401532)
		(end 110.401354 -21.950172)
		(stroke
			(width 0.2)
			(type default)
		)
		(layer "In10.Cu")
	)
	(gr_line
		(start 111.498634 -19.750024)
		(end 111.498634 -18.350484)
		(stroke
			(width 0.2)
			(type default)
		)
		(layer "In10.Cu")
	)
	(gr_arc
		(start 111.498634 -18.350484)
		(mid 110.950121 -17.80159)
		(end 110.401354 -18.35023)
		(stroke
			(width 0.2)
			(type default)
		)
		(layer "In10.Cu")
	)
	(gr_arc
		(start 112.201452 -22.350222)
		(mid 112.750092 -22.898862)
		(end 113.298732 -22.350222)
		(stroke
			(width 0.2)
			(type default)
		)
		(layer "In10.Cu")
	)
	(gr_line
		(start 112.201452 -20.950174)
		(end 112.201452 -22.350222)
		(stroke
			(width 0.2)
			(type default)
		)
		(layer "In10.Cu")
	)
	(gr_arc
		(start 112.201452 -18.750026)
		(mid 112.750092 -19.298666)
		(end 113.298732 -18.750026)
		(stroke
			(width 0.2)
			(type default)
		)
		(layer "In10.Cu")
	)
	(gr_line
		(start 112.201452 -17.349978)
		(end 112.201452 -18.750026)
		(stroke
			(width 0.2)
			(type default)
		)
		(layer "In10.Cu")
	)
	(gr_line
		(start 113.298732 -22.350222)
		(end 113.298732 -20.950428)
		(stroke
			(width 0.2)
			(type default)
		)
		(layer "In10.Cu")
	)
	(gr_arc
		(start 113.298732 -20.950428)
		(mid 112.750219 -20.401534)
		(end 112.201452 -20.950174)
		(stroke
			(width 0.2)
			(type default)
		)
		(layer "In10.Cu")
	)
	(gr_line
		(start 113.298732 -18.750026)
		(end 113.298732 -17.350232)
		(stroke
			(width 0.2)
			(type default)
		)
		(layer "In10.Cu")
	)
	(gr_arc
		(start 113.298732 -17.350232)
		(mid 112.750219 -16.801338)
		(end 112.201452 -17.349978)
		(stroke
			(width 0.2)
			(type default)
		)
		(layer "In10.Cu")
	)
	(gr_arc
		(start 114.001296 -23.35022)
		(mid 114.549936 -23.89886)
		(end 115.098576 -23.35022)
		(stroke
			(width 0.2)
			(type default)
		)
		(layer "In10.Cu")
	)
	(gr_line
		(start 114.001296 -21.950172)
		(end 114.001296 -23.35022)
		(stroke
			(width 0.2)
			(type default)
		)
		(layer "In10.Cu")
	)
	(gr_arc
		(start 114.001296 -19.750024)
		(mid 114.549936 -20.298664)
		(end 115.098576 -19.750024)
		(stroke
			(width 0.2)
			(type default)
		)
		(layer "In10.Cu")
	)
	(gr_line
		(start 114.001296 -18.35023)
		(end 114.001296 -19.750024)
		(stroke
			(width 0.2)
			(type default)
		)
		(layer "In10.Cu")
	)
	(gr_line
		(start 115.098576 -23.35022)
		(end 115.098576 -21.950426)
		(stroke
			(width 0.2)
			(type default)
		)
		(layer "In10.Cu")
	)
	(gr_arc
		(start 115.098576 -21.950426)
		(mid 114.550063 -21.401532)
		(end 114.001296 -21.950172)
		(stroke
			(width 0.2)
			(type default)
		)
		(layer "In10.Cu")
	)
	(gr_line
		(start 115.098576 -19.750024)
		(end 115.098576 -18.350484)
		(stroke
			(width 0.2)
			(type default)
		)
		(layer "In10.Cu")
	)
	(gr_arc
		(start 115.098576 -18.350484)
		(mid 114.550063 -17.80159)
		(end 114.001296 -18.35023)
		(stroke
			(width 0.2)
			(type default)
		)
		(layer "In10.Cu")
	)
	(gr_arc
		(start 115.801394 -29.550106)
		(mid 116.350034 -30.098746)
		(end 116.898674 -29.550106)
		(stroke
			(width 0.2)
			(type default)
		)
		(layer "In10.Cu")
	)
	(gr_line
		(start 115.801394 -28.150058)
		(end 115.801394 -29.550106)
		(stroke
			(width 0.2)
			(type default)
		)
		(layer "In10.Cu")
	)
	(gr_arc
		(start 115.801394 -22.350222)
		(mid 116.350034 -22.898862)
		(end 116.898674 -22.350222)
		(stroke
			(width 0.2)
			(type default)
		)
		(layer "In10.Cu")
	)
	(gr_line
		(start 115.801394 -20.950174)
		(end 115.801394 -22.350222)
		(stroke
			(width 0.2)
			(type default)
		)
		(layer "In10.Cu")
	)
	(gr_arc
		(start 115.801394 -18.750026)
		(mid 116.350034 -19.298666)
		(end 116.898674 -18.750026)
		(stroke
			(width 0.2)
			(type default)
		)
		(layer "In10.Cu")
	)
	(gr_line
		(start 115.801394 -17.349978)
		(end 115.801394 -18.750026)
		(stroke
			(width 0.2)
			(type default)
		)
		(layer "In10.Cu")
	)
	(gr_line
		(start 116.898674 -29.550106)
		(end 116.898674 -28.150312)
		(stroke
			(width 0.2)
			(type default)
		)
		(layer "In10.Cu")
	)
	(gr_arc
		(start 116.898674 -28.150312)
		(mid 116.350161 -27.601418)
		(end 115.801394 -28.150058)
		(stroke
			(width 0.2)
			(type default)
		)
		(layer "In10.Cu")
	)
	(gr_line
		(start 116.898674 -22.350222)
		(end 116.898674 -20.950428)
		(stroke
			(width 0.2)
			(type default)
		)
		(layer "In10.Cu")
	)
	(gr_arc
		(start 116.898674 -20.950428)
		(mid 116.350161 -20.401534)
		(end 115.801394 -20.950174)
		(stroke
			(width 0.2)
			(type default)
		)
		(layer "In10.Cu")
	)
	(gr_line
		(start 116.898674 -18.750026)
		(end 116.898674 -17.350232)
		(stroke
			(width 0.2)
			(type default)
		)
		(layer "In10.Cu")
	)
	(gr_arc
		(start 116.898674 -17.350232)
		(mid 116.350161 -16.801338)
		(end 115.801394 -17.349978)
		(stroke
			(width 0.2)
			(type default)
		)
		(layer "In10.Cu")
	)
	(gr_arc
		(start 117.601238 -23.35022)
		(mid 118.149878 -23.89886)
		(end 118.698518 -23.35022)
		(stroke
			(width 0.2)
			(type default)
		)
		(layer "In10.Cu")
	)
	(gr_line
		(start 117.601238 -21.950172)
		(end 117.601238 -23.35022)
		(stroke
			(width 0.2)
			(type default)
		)
		(layer "In10.Cu")
	)
	(gr_arc
		(start 117.601238 -19.750024)
		(mid 118.149878 -20.298664)
		(end 118.698518 -19.750024)
		(stroke
			(width 0.2)
			(type default)
		)
		(layer "In10.Cu")
	)
	(gr_line
		(start 117.601238 -18.35023)
		(end 117.601238 -19.750024)
		(stroke
			(width 0.2)
			(type default)
		)
		(layer "In10.Cu")
	)
	(gr_line
		(start 118.698518 -23.35022)
		(end 118.698518 -21.950426)
		(stroke
			(width 0.2)
			(type default)
		)
		(layer "In10.Cu")
	)
	(gr_arc
		(start 118.698518 -21.950426)
		(mid 118.150005 -21.401532)
		(end 117.601238 -21.950172)
		(stroke
			(width 0.2)
			(type default)
		)
		(layer "In10.Cu")
	)
	(gr_line
		(start 118.698518 -19.750024)
		(end 118.698518 -18.350484)
		(stroke
			(width 0.2)
			(type default)
		)
		(layer "In10.Cu")
	)
	(gr_arc
		(start 118.698518 -18.350484)
		(mid 118.150005 -17.80159)
		(end 117.601238 -18.35023)
		(stroke
			(width 0.2)
			(type default)
		)
		(layer "In10.Cu")
	)
	(gr_arc
		(start 119.401336 -22.350222)
		(mid 119.949976 -22.898862)
		(end 120.498616 -22.350222)
		(stroke
			(width 0.2)
			(type default)
		)
		(layer "In10.Cu")
	)
	(gr_line
		(start 119.401336 -20.950174)
		(end 119.401336 -22.350222)
		(stroke
			(width 0.2)
			(type default)
		)
		(layer "In10.Cu")
	)
	(gr_arc
		(start 119.401336 -18.750026)
		(mid 119.949976 -19.298666)
		(end 120.498616 -18.750026)
		(stroke
			(width 0.2)
			(type default)
		)
		(layer "In10.Cu")
	)
	(gr_line
		(start 119.401336 -17.349978)
		(end 119.401336 -18.750026)
		(stroke
			(width 0.2)
			(type default)
		)
		(layer "In10.Cu")
	)
	(gr_line
		(start 120.498616 -22.350222)
		(end 120.498616 -20.950428)
		(stroke
			(width 0.2)
			(type default)
		)
		(layer "In10.Cu")
	)
	(gr_arc
		(start 120.498616 -20.950428)
		(mid 119.950103 -20.401534)
		(end 119.401336 -20.950174)
		(stroke
			(width 0.2)
			(type default)
		)
		(layer "In10.Cu")
	)
	(gr_line
		(start 120.498616 -18.750026)
		(end 120.498616 -17.350232)
		(stroke
			(width 0.2)
			(type default)
		)
		(layer "In10.Cu")
	)
	(gr_arc
		(start 120.498616 -17.350232)
		(mid 119.950103 -16.801338)
		(end 119.401336 -17.349978)
		(stroke
			(width 0.2)
			(type default)
		)
		(layer "In10.Cu")
	)
	(gr_arc
		(start 121.198894 -30.54985)
		(mid 121.749947 -31.101284)
		(end 122.301254 -30.550104)
		(stroke
			(width 0.2)
			(type default)
		)
		(layer "In10.Cu")
	)
	(gr_line
		(start 121.198894 -29.150056)
		(end 121.198894 -30.54985)
		(stroke
			(width 0.2)
			(type default)
		)
		(layer "In10.Cu")
	)
	(gr_arc
		(start 121.201434 -23.35022)
		(mid 121.750074 -23.89886)
		(end 122.298714 -23.35022)
		(stroke
			(width 0.2)
			(type default)
		)
		(layer "In10.Cu")
	)
	(gr_line
		(start 121.201434 -21.950172)
		(end 121.201434 -23.35022)
		(stroke
			(width 0.2)
			(type default)
		)
		(layer "In10.Cu")
	)
	(gr_arc
		(start 121.201434 -19.750024)
		(mid 121.750074 -20.298664)
		(end 122.298714 -19.750024)
		(stroke
			(width 0.2)
			(type default)
		)
		(layer "In10.Cu")
	)
	(gr_line
		(start 121.201434 -18.35023)
		(end 121.201434 -19.750024)
		(stroke
			(width 0.2)
			(type default)
		)
		(layer "In10.Cu")
	)
	(gr_line
		(start 122.298714 -23.35022)
		(end 122.298714 -21.950426)
		(stroke
			(width 0.2)
			(type default)
		)
		(layer "In10.Cu")
	)
	(gr_arc
		(start 122.298714 -21.950426)
		(mid 121.750201 -21.401532)
		(end 121.201434 -21.950172)
		(stroke
			(width 0.2)
			(type default)
		)
		(layer "In10.Cu")
	)
	(gr_line
		(start 122.298714 -19.750024)
		(end 122.298714 -18.350484)
		(stroke
			(width 0.2)
			(type default)
		)
		(layer "In10.Cu")
	)
	(gr_arc
		(start 122.298714 -18.350484)
		(mid 121.750201 -17.80159)
		(end 121.201434 -18.35023)
		(stroke
			(width 0.2)
			(type default)
		)
		(layer "In10.Cu")
	)
	(gr_line
		(start 122.301254 -30.550104)
		(end 122.301254 -29.150056)
		(stroke
			(width 0.2)
			(type default)
		)
		(layer "In10.Cu")
	)
	(gr_arc
		(start 122.301254 -29.150056)
		(mid 121.750074 -28.598876)
		(end 121.198894 -29.150056)
		(stroke
			(width 0.2)
			(type default)
		)
		(layer "In10.Cu")
	)
	(gr_arc
		(start 126.77775 -278.321516)
		(mid 127.15875 -278.702516)
		(end 127.53975 -278.321516)
		(stroke
			(width 0.2)
			(type default)
		)
		(layer "In10.Cu")
	)
	(gr_line
		(start 126.77775 -277.178516)
		(end 126.77775 -278.321516)
		(stroke
			(width 0.2)
			(type default)
		)
		(layer "In10.Cu")
	)
	(gr_arc
		(start 126.77775 -163.321492)
		(mid 127.15875 -163.702492)
		(end 127.53975 -163.321492)
		(stroke
			(width 0.2)
			(type default)
		)
		(layer "In10.Cu")
	)
	(gr_line
		(start 126.77775 -162.178492)
		(end 126.77775 -163.321492)
		(stroke
			(width 0.2)
			(type default)
		)
		(layer "In10.Cu")
	)
	(gr_arc
		(start 126.77775 -48.321468)
		(mid 127.15875 -48.702468)
		(end 127.53975 -48.321468)
		(stroke
			(width 0.2)
			(type default)
		)
		(layer "In10.Cu")
	)
	(gr_line
		(start 126.77775 -47.178468)
		(end 126.77775 -48.321468)
		(stroke
			(width 0.2)
			(type default)
		)
		(layer "In10.Cu")
	)
	(gr_line
		(start 127.53975 -278.321516)
		(end 127.53975 -277.17877)
		(stroke
			(width 0.2)
			(type default)
		)
		(layer "In10.Cu")
	)
	(gr_arc
		(start 127.53975 -277.17877)
		(mid 127.158877 -276.797516)
		(end 126.77775 -277.178516)
		(stroke
			(width 0.2)
			(type default)
		)
		(layer "In10.Cu")
	)
	(gr_line
		(start 127.53975 -163.321492)
		(end 127.53975 -162.178746)
		(stroke
			(width 0.2)
			(type default)
		)
		(layer "In10.Cu")
	)
	(gr_arc
		(start 127.53975 -162.178746)
		(mid 127.158877 -161.797492)
		(end 126.77775 -162.178492)
		(stroke
			(width 0.2)
			(type default)
		)
		(layer "In10.Cu")
	)
	(gr_line
		(start 127.53975 -48.321468)
		(end 127.53975 -47.178722)
		(stroke
			(width 0.2)
			(type default)
		)
		(layer "In10.Cu")
	)
	(gr_arc
		(start 127.53975 -47.178722)
		(mid 127.158877 -46.797468)
		(end 126.77775 -47.178468)
		(stroke
			(width 0.2)
			(type default)
		)
		(layer "In10.Cu")
	)
	(gr_arc
		(start 130.201416 -22.350222)
		(mid 130.750056 -22.898862)
		(end 131.298696 -22.350222)
		(stroke
			(width 0.2)
			(type default)
		)
		(layer "In10.Cu")
	)
	(gr_line
		(start 130.201416 -20.950174)
		(end 130.201416 -22.350222)
		(stroke
			(width 0.2)
			(type default)
		)
		(layer "In10.Cu")
	)
	(gr_arc
		(start 130.201416 -18.750026)
		(mid 130.750056 -19.298666)
		(end 131.298696 -18.750026)
		(stroke
			(width 0.2)
			(type default)
		)
		(layer "In10.Cu")
	)
	(gr_line
		(start 130.201416 -17.349978)
		(end 130.201416 -18.750026)
		(stroke
			(width 0.2)
			(type default)
		)
		(layer "In10.Cu")
	)
	(gr_line
		(start 131.298696 -22.350222)
		(end 131.298696 -20.950428)
		(stroke
			(width 0.2)
			(type default)
		)
		(layer "In10.Cu")
	)
	(gr_arc
		(start 131.298696 -20.950428)
		(mid 130.750183 -20.401534)
		(end 130.201416 -20.950174)
		(stroke
			(width 0.2)
			(type default)
		)
		(layer "In10.Cu")
	)
	(gr_line
		(start 131.298696 -18.750026)
		(end 131.298696 -17.350232)
		(stroke
			(width 0.2)
			(type default)
		)
		(layer "In10.Cu")
	)
	(gr_arc
		(start 131.298696 -17.350232)
		(mid 130.750183 -16.801338)
		(end 130.201416 -17.349978)
		(stroke
			(width 0.2)
			(type default)
		)
		(layer "In10.Cu")
	)
	(gr_arc
		(start 132.00126 -23.35022)
		(mid 132.5499 -23.89886)
		(end 133.09854 -23.35022)
		(stroke
			(width 0.2)
			(type default)
		)
		(layer "In10.Cu")
	)
	(gr_line
		(start 132.00126 -21.950172)
		(end 132.00126 -23.35022)
		(stroke
			(width 0.2)
			(type default)
		)
		(layer "In10.Cu")
	)
	(gr_arc
		(start 132.00126 -19.74977)
		(mid 132.549773 -20.298664)
		(end 133.09854 -19.750024)
		(stroke
			(width 0.2)
			(type default)
		)
		(layer "In10.Cu")
	)
	(gr_line
		(start 132.00126 -18.35023)
		(end 132.00126 -19.74977)
		(stroke
			(width 0.2)
			(type default)
		)
		(layer "In10.Cu")
	)
	(gr_line
		(start 133.09854 -23.35022)
		(end 133.09854 -21.950426)
		(stroke
			(width 0.2)
			(type default)
		)
		(layer "In10.Cu")
	)
	(gr_arc
		(start 133.09854 -21.950426)
		(mid 132.550027 -21.401532)
		(end 132.00126 -21.950172)
		(stroke
			(width 0.2)
			(type default)
		)
		(layer "In10.Cu")
	)
	(gr_line
		(start 133.09854 -19.750024)
		(end 133.09854 -18.35023)
		(stroke
			(width 0.2)
			(type default)
		)
		(layer "In10.Cu")
	)
	(gr_arc
		(start 133.09854 -18.35023)
		(mid 132.5499 -17.80159)
		(end 132.00126 -18.35023)
		(stroke
			(width 0.2)
			(type default)
		)
		(layer "In10.Cu")
	)
	(gr_arc
		(start 133.801358 -22.350222)
		(mid 134.349998 -22.898862)
		(end 134.898638 -22.350222)
		(stroke
			(width 0.2)
			(type default)
		)
		(layer "In10.Cu")
	)
	(gr_line
		(start 133.801358 -20.950174)
		(end 133.801358 -22.350222)
		(stroke
			(width 0.2)
			(type default)
		)
		(layer "In10.Cu")
	)
	(gr_arc
		(start 133.801358 -18.750026)
		(mid 134.349998 -19.298666)
		(end 134.898638 -18.750026)
		(stroke
			(width 0.2)
			(type default)
		)
		(layer "In10.Cu")
	)
	(gr_line
		(start 133.801358 -17.349978)
		(end 133.801358 -18.750026)
		(stroke
			(width 0.2)
			(type default)
		)
		(layer "In10.Cu")
	)
	(gr_line
		(start 134.898638 -22.350222)
		(end 134.898638 -20.950428)
		(stroke
			(width 0.2)
			(type default)
		)
		(layer "In10.Cu")
	)
	(gr_arc
		(start 134.898638 -20.950428)
		(mid 134.350125 -20.401534)
		(end 133.801358 -20.950174)
		(stroke
			(width 0.2)
			(type default)
		)
		(layer "In10.Cu")
	)
	(gr_line
		(start 134.898638 -18.750026)
		(end 134.898638 -17.350232)
		(stroke
			(width 0.2)
			(type default)
		)
		(layer "In10.Cu")
	)
	(gr_arc
		(start 134.898638 -17.350232)
		(mid 134.350125 -16.801338)
		(end 133.801358 -17.349978)
		(stroke
			(width 0.2)
			(type default)
		)
		(layer "In10.Cu")
	)
	(gr_arc
		(start 135.601456 -30.550104)
		(mid 136.150096 -31.098744)
		(end 136.698736 -30.550104)
		(stroke
			(width 0.2)
			(type default)
		)
		(layer "In10.Cu")
	)
	(gr_line
		(start 135.601456 -29.150056)
		(end 135.601456 -30.550104)
		(stroke
			(width 0.2)
			(type default)
		)
		(layer "In10.Cu")
	)
	(gr_arc
		(start 135.601456 -23.35022)
		(mid 136.150096 -23.89886)
		(end 136.698736 -23.35022)
		(stroke
			(width 0.2)
			(type default)
		)
		(layer "In10.Cu")
	)
	(gr_line
		(start 135.601456 -21.950172)
		(end 135.601456 -23.35022)
		(stroke
			(width 0.2)
			(type default)
		)
		(layer "In10.Cu")
	)
	(gr_arc
		(start 135.601456 -19.750024)
		(mid 136.150096 -20.298664)
		(end 136.698736 -19.750024)
		(stroke
			(width 0.2)
			(type default)
		)
		(layer "In10.Cu")
	)
	(gr_line
		(start 135.601456 -18.35023)
		(end 135.601456 -19.750024)
		(stroke
			(width 0.2)
			(type default)
		)
		(layer "In10.Cu")
	)
	(gr_line
		(start 136.698736 -30.550104)
		(end 136.698736 -29.15031)
		(stroke
			(width 0.2)
			(type default)
		)
		(layer "In10.Cu")
	)
	(gr_arc
		(start 136.698736 -29.15031)
		(mid 136.150223 -28.601416)
		(end 135.601456 -29.150056)
		(stroke
			(width 0.2)
			(type default)
		)
		(layer "In10.Cu")
	)
	(gr_line
		(start 136.698736 -23.35022)
		(end 136.698736 -21.950426)
		(stroke
			(width 0.2)
			(type default)
		)
		(layer "In10.Cu")
	)
	(gr_arc
		(start 136.698736 -21.950426)
		(mid 136.150223 -21.401532)
		(end 135.601456 -21.950172)
		(stroke
			(width 0.2)
			(type default)
		)
		(layer "In10.Cu")
	)
	(gr_line
		(start 136.698736 -19.750024)
		(end 136.698736 -18.350484)
		(stroke
			(width 0.2)
			(type default)
		)
		(layer "In10.Cu")
	)
	(gr_arc
		(start 136.698736 -18.350484)
		(mid 136.150223 -17.80159)
		(end 135.601456 -18.35023)
		(stroke
			(width 0.2)
			(type default)
		)
		(layer "In10.Cu")
	)
	(gr_arc
		(start 137.4013 -22.350222)
		(mid 137.94994 -22.898862)
		(end 138.49858 -22.350222)
		(stroke
			(width 0.2)
			(type default)
		)
		(layer "In10.Cu")
	)
	(gr_line
		(start 137.4013 -20.950174)
		(end 137.4013 -22.350222)
		(stroke
			(width 0.2)
			(type default)
		)
		(layer "In10.Cu")
	)
	(gr_arc
		(start 137.4013 -18.750026)
		(mid 137.94994 -19.298666)
		(end 138.49858 -18.750026)
		(stroke
			(width 0.2)
			(type default)
		)
		(layer "In10.Cu")
	)
	(gr_line
		(start 137.4013 -17.349978)
		(end 137.4013 -18.750026)
		(stroke
			(width 0.2)
			(type default)
		)
		(layer "In10.Cu")
	)
	(gr_line
		(start 138.49858 -22.350222)
		(end 138.49858 -20.950428)
		(stroke
			(width 0.2)
			(type default)
		)
		(layer "In10.Cu")
	)
	(gr_arc
		(start 138.49858 -20.950428)
		(mid 137.950067 -20.401534)
		(end 137.4013 -20.950174)
		(stroke
			(width 0.2)
			(type default)
		)
		(layer "In10.Cu")
	)
	(gr_line
		(start 138.49858 -18.750026)
		(end 138.49858 -17.350232)
		(stroke
			(width 0.2)
			(type default)
		)
		(layer "In10.Cu")
	)
	(gr_arc
		(start 138.49858 -17.350232)
		(mid 137.950067 -16.801338)
		(end 137.4013 -17.349978)
		(stroke
			(width 0.2)
			(type default)
		)
		(layer "In10.Cu")
	)
	(gr_arc
		(start 139.201398 -23.35022)
		(mid 139.750038 -23.89886)
		(end 140.298678 -23.35022)
		(stroke
			(width 0.2)
			(type default)
		)
		(layer "In10.Cu")
	)
	(gr_line
		(start 139.201398 -21.950172)
		(end 139.201398 -23.35022)
		(stroke
			(width 0.2)
			(type default)
		)
		(layer "In10.Cu")
	)
	(gr_arc
		(start 139.201398 -19.750024)
		(mid 139.750038 -20.298664)
		(end 140.298678 -19.750024)
		(stroke
			(width 0.2)
			(type default)
		)
		(layer "In10.Cu")
	)
	(gr_line
		(start 139.201398 -18.35023)
		(end 139.201398 -19.750024)
		(stroke
			(width 0.2)
			(type default)
		)
		(layer "In10.Cu")
	)
	(gr_line
		(start 140.298678 -23.35022)
		(end 140.298678 -21.950426)
		(stroke
			(width 0.2)
			(type default)
		)
		(layer "In10.Cu")
	)
	(gr_arc
		(start 140.298678 -21.950426)
		(mid 139.750165 -21.401532)
		(end 139.201398 -21.950172)
		(stroke
			(width 0.2)
			(type default)
		)
		(layer "In10.Cu")
	)
	(gr_line
		(start 140.298678 -19.750024)
		(end 140.298678 -18.350484)
		(stroke
			(width 0.2)
			(type default)
		)
		(layer "In10.Cu")
	)
	(gr_arc
		(start 140.298678 -18.350484)
		(mid 139.750165 -17.80159)
		(end 139.201398 -18.35023)
		(stroke
			(width 0.2)
			(type default)
		)
		(layer "In10.Cu")
	)
	(gr_arc
		(start 141.001242 -22.350222)
		(mid 141.549882 -22.898862)
		(end 142.098522 -22.350222)
		(stroke
			(width 0.2)
			(type default)
		)
		(layer "In10.Cu")
	)
	(gr_line
		(start 141.001242 -20.950174)
		(end 141.001242 -22.350222)
		(stroke
			(width 0.2)
			(type default)
		)
		(layer "In10.Cu")
	)
	(gr_arc
		(start 141.001242 -18.750026)
		(mid 141.549882 -19.298666)
		(end 142.098522 -18.750026)
		(stroke
			(width 0.2)
			(type default)
		)
		(layer "In10.Cu")
	)
	(gr_line
		(start 141.001242 -17.349978)
		(end 141.001242 -18.750026)
		(stroke
			(width 0.2)
			(type default)
		)
		(layer "In10.Cu")
	)
	(gr_line
		(start 142.098522 -22.350222)
		(end 142.098522 -20.950428)
		(stroke
			(width 0.2)
			(type default)
		)
		(layer "In10.Cu")
	)
	(gr_arc
		(start 142.098522 -20.950428)
		(mid 141.550009 -20.401534)
		(end 141.001242 -20.950174)
		(stroke
			(width 0.2)
			(type default)
		)
		(layer "In10.Cu")
	)
	(gr_line
		(start 142.098522 -18.750026)
		(end 142.098522 -17.350232)
		(stroke
			(width 0.2)
			(type default)
		)
		(layer "In10.Cu")
	)
	(gr_arc
		(start 142.098522 -17.350232)
		(mid 141.550009 -16.801338)
		(end 141.001242 -17.349978)
		(stroke
			(width 0.2)
			(type default)
		)
		(layer "In10.Cu")
	)
	(gr_arc
		(start 142.80134 -30.550104)
		(mid 143.34998 -31.098744)
		(end 143.89862 -30.550104)
		(stroke
			(width 0.2)
			(type default)
		)
		(layer "In10.Cu")
	)
	(gr_line
		(start 142.80134 -29.150056)
		(end 142.80134 -30.550104)
		(stroke
			(width 0.2)
			(type default)
		)
		(layer "In10.Cu")
	)
	(gr_arc
		(start 142.80134 -23.35022)
		(mid 143.34998 -23.89886)
		(end 143.89862 -23.35022)
		(stroke
			(width 0.2)
			(type default)
		)
		(layer "In10.Cu")
	)
	(gr_line
		(start 142.80134 -21.950172)
		(end 142.80134 -23.35022)
		(stroke
			(width 0.2)
			(type default)
		)
		(layer "In10.Cu")
	)
	(gr_arc
		(start 142.80134 -19.750024)
		(mid 143.34998 -20.298664)
		(end 143.89862 -19.750024)
		(stroke
			(width 0.2)
			(type default)
		)
		(layer "In10.Cu")
	)
	(gr_line
		(start 142.80134 -18.35023)
		(end 142.80134 -19.750024)
		(stroke
			(width 0.2)
			(type default)
		)
		(layer "In10.Cu")
	)
	(gr_line
		(start 143.89862 -30.550104)
		(end 143.89862 -29.15031)
		(stroke
			(width 0.2)
			(type default)
		)
		(layer "In10.Cu")
	)
	(gr_arc
		(start 143.89862 -29.15031)
		(mid 143.350107 -28.601416)
		(end 142.80134 -29.150056)
		(stroke
			(width 0.2)
			(type default)
		)
		(layer "In10.Cu")
	)
	(gr_line
		(start 143.89862 -23.35022)
		(end 143.89862 -21.950426)
		(stroke
			(width 0.2)
			(type default)
		)
		(layer "In10.Cu")
	)
	(gr_arc
		(start 143.89862 -21.950426)
		(mid 143.350107 -21.401532)
		(end 142.80134 -21.950172)
		(stroke
			(width 0.2)
			(type default)
		)
		(layer "In10.Cu")
	)
	(gr_line
		(start 143.89862 -19.750024)
		(end 143.89862 -18.350484)
		(stroke
			(width 0.2)
			(type default)
		)
		(layer "In10.Cu")
	)
	(gr_arc
		(start 143.89862 -18.350484)
		(mid 143.350107 -17.80159)
		(end 142.80134 -18.35023)
		(stroke
			(width 0.2)
			(type default)
		)
		(layer "In10.Cu")
	)
	(gr_arc
		(start 148.999956 -14.99997)
		(mid 149.707061 -14.707077)
		(end 149.999954 -13.999972)
		(stroke
			(width 1.524)
			(type default)
		)
		(layer "In10.Cu")
	)
	(gr_line
		(start 149.999954 -13.999972)
		(end 149.999954 -0.999998)
		(stroke
			(width 1.524)
			(type default)
		)
		(layer "In10.Cu")
	)
	(gr_arc
		(start 150.999952 0)
		(mid 150.292877 -0.292909)
		(end 149.999954 -0.999998)
		(stroke
			(width 1.524)
			(type default)
		)
		(layer "In10.Cu")
	)
	(gr_line
		(start 150.999952 0)
		(end 199.00011 0)
		(stroke
			(width 1.524)
			(type default)
		)
		(layer "In10.Cu")
	)
	(gr_arc
		(start 158.327852 -278.321516)
		(mid 158.708852 -278.702516)
		(end 159.089852 -278.321516)
		(stroke
			(width 0.2)
			(type default)
		)
		(layer "In10.Cu")
	)
	(gr_line
		(start 158.327852 -277.178516)
		(end 158.327852 -278.321516)
		(stroke
			(width 0.2)
			(type default)
		)
		(layer "In10.Cu")
	)
	(gr_arc
		(start 158.327852 -163.321492)
		(mid 158.708852 -163.702492)
		(end 159.089852 -163.321492)
		(stroke
			(width 0.2)
			(type default)
		)
		(layer "In10.Cu")
	)
	(gr_line
		(start 158.327852 -162.178492)
		(end 158.327852 -163.321492)
		(stroke
			(width 0.2)
			(type default)
		)
		(layer "In10.Cu")
	)
	(gr_arc
		(start 158.327852 -48.321468)
		(mid 158.708852 -48.702468)
		(end 159.089852 -48.321468)
		(stroke
			(width 0.2)
			(type default)
		)
		(layer "In10.Cu")
	)
	(gr_line
		(start 158.327852 -47.178468)
		(end 158.327852 -48.321468)
		(stroke
			(width 0.2)
			(type default)
		)
		(layer "In10.Cu")
	)
	(gr_line
		(start 159.089852 -278.321516)
		(end 159.089852 -277.17877)
		(stroke
			(width 0.2)
			(type default)
		)
		(layer "In10.Cu")
	)
	(gr_arc
		(start 159.089852 -277.17877)
		(mid 158.708979 -276.797516)
		(end 158.327852 -277.178516)
		(stroke
			(width 0.2)
			(type default)
		)
		(layer "In10.Cu")
	)
	(gr_line
		(start 159.089852 -163.321492)
		(end 159.089852 -162.178746)
		(stroke
			(width 0.2)
			(type default)
		)
		(layer "In10.Cu")
	)
	(gr_arc
		(start 159.089852 -162.178746)
		(mid 158.708979 -161.797492)
		(end 158.327852 -162.178492)
		(stroke
			(width 0.2)
			(type default)
		)
		(layer "In10.Cu")
	)
	(gr_line
		(start 159.089852 -48.321468)
		(end 159.089852 -47.178722)
		(stroke
			(width 0.2)
			(type default)
		)
		(layer "In10.Cu")
	)
	(gr_arc
		(start 159.089852 -47.178722)
		(mid 158.708979 -46.797468)
		(end 158.327852 -47.178468)
		(stroke
			(width 0.2)
			(type default)
		)
		(layer "In10.Cu")
	)
	(gr_line
		(start 189.6999 -349.199962)
		(end 0.999998 -349.199962)
		(stroke
			(width 1.524)
			(type default)
		)
		(layer "In10.Cu")
	)
	(gr_arc
		(start 189.877954 -278.321516)
		(mid 190.258954 -278.702516)
		(end 190.639954 -278.321516)
		(stroke
			(width 0.2)
			(type default)
		)
		(layer "In10.Cu")
	)
	(gr_line
		(start 189.877954 -277.178516)
		(end 189.877954 -278.321516)
		(stroke
			(width 0.2)
			(type default)
		)
		(layer "In10.Cu")
	)
	(gr_arc
		(start 189.877954 -163.321492)
		(mid 190.258954 -163.702492)
		(end 190.639954 -163.321492)
		(stroke
			(width 0.2)
			(type default)
		)
		(layer "In10.Cu")
	)
	(gr_line
		(start 189.877954 -162.178492)
		(end 189.877954 -163.321492)
		(stroke
			(width 0.2)
			(type default)
		)
		(layer "In10.Cu")
	)
	(gr_arc
		(start 189.877954 -48.321468)
		(mid 190.258954 -48.702468)
		(end 190.639954 -48.321468)
		(stroke
			(width 0.2)
			(type default)
		)
		(layer "In10.Cu")
	)
	(gr_line
		(start 189.877954 -47.178468)
		(end 189.877954 -48.321468)
		(stroke
			(width 0.2)
			(type default)
		)
		(layer "In10.Cu")
	)
	(gr_line
		(start 190.639954 -278.321516)
		(end 190.639954 -277.17877)
		(stroke
			(width 0.2)
			(type default)
		)
		(layer "In10.Cu")
	)
	(gr_arc
		(start 190.639954 -277.17877)
		(mid 190.259081 -276.797516)
		(end 189.877954 -277.178516)
		(stroke
			(width 0.2)
			(type default)
		)
		(layer "In10.Cu")
	)
	(gr_line
		(start 190.639954 -163.321492)
		(end 190.639954 -162.178746)
		(stroke
			(width 0.2)
			(type default)
		)
		(layer "In10.Cu")
	)
	(gr_arc
		(start 190.639954 -162.178746)
		(mid 190.259081 -161.797492)
		(end 189.877954 -162.178492)
		(stroke
			(width 0.2)
			(type default)
		)
		(layer "In10.Cu")
	)
	(gr_line
		(start 190.639954 -48.321468)
		(end 190.639954 -47.178722)
		(stroke
			(width 0.2)
			(type default)
		)
		(layer "In10.Cu")
	)
	(gr_arc
		(start 190.639954 -47.178722)
		(mid 190.259081 -46.797468)
		(end 189.877954 -47.178468)
		(stroke
			(width 0.2)
			(type default)
		)
		(layer "In10.Cu")
	)
	(gr_line
		(start 190.699898 -372.000018)
		(end 190.699898 -350.19996)
		(stroke
			(width 1.524)
			(type default)
		)
		(layer "In10.Cu")
	)
	(gr_arc
		(start 190.699898 -372.000018)
		(mid 190.992797 -372.707113)
		(end 191.699896 -373.000016)
		(stroke
			(width 1.524)
			(type default)
		)
		(layer "In10.Cu")
	)
	(gr_arc
		(start 190.699898 -350.19996)
		(mid 190.407005 -349.492855)
		(end 189.6999 -349.199962)
		(stroke
			(width 1.524)
			(type default)
		)
		(layer "In10.Cu")
	)
	(gr_line
		(start 199.00011 -373.000016)
		(end 191.699896 -373.000016)
		(stroke
			(width 1.524)
			(type default)
		)
		(layer "In10.Cu")
	)
	(gr_arc
		(start 199.00011 0)
		(mid 199.707215 0.292893)
		(end 200.000108 0.999998)
		(stroke
			(width 1.524)
			(type default)
		)
		(layer "In10.Cu")
	)
	(gr_line
		(start 200.000108 -420.200074)
		(end 200.000108 -374.000014)
		(stroke
			(width 1.524)
			(type default)
		)
		(layer "In10.Cu")
	)
	(gr_arc
		(start 200.000108 -420.200074)
		(mid 200.292992 -420.907194)
		(end 201.000106 -421.200072)
		(stroke
			(width 1.524)
			(type default)
		)
		(layer "In10.Cu")
	)
	(gr_arc
		(start 200.000108 -374.000014)
		(mid 199.707215 -373.292909)
		(end 199.00011 -373.000016)
		(stroke
			(width 1.524)
			(type default)
		)
		(layer "In10.Cu")
	)
	(gr_arc
		(start 201.000106 1.999996)
		(mid 200.292997 1.707105)
		(end 200.000108 0.999998)
		(stroke
			(width 1.524)
			(type default)
		)
		(layer "In10.Cu")
	)
	(gr_line
		(start 201.000106 1.999996)
		(end 219.00007 1.999996)
		(stroke
			(width 1.524)
			(type default)
		)
		(layer "In10.Cu")
	)
	(gr_arc
		(start 209.451448 -415.600134)
		(mid 210.000088 -416.148774)
		(end 210.548728 -415.600134)
		(stroke
			(width 0.2)
			(type default)
		)
		(layer "In10.Cu")
	)
	(gr_line
		(start 209.451448 -414.200086)
		(end 209.451448 -415.600134)
		(stroke
			(width 0.2)
			(type default)
		)
		(layer "In10.Cu")
	)
	(gr_arc
		(start 209.451448 -412.000192)
		(mid 210.000088 -412.548832)
		(end 210.548728 -412.000192)
		(stroke
			(width 0.2)
			(type default)
		)
		(layer "In10.Cu")
	)
	(gr_line
		(start 209.451448 -410.600144)
		(end 209.451448 -412.000192)
		(stroke
			(width 0.2)
			(type default)
		)
		(layer "In10.Cu")
	)
	(gr_arc
		(start 209.451448 -408.399996)
		(mid 210.000088 -408.948636)
		(end 210.548728 -408.399996)
		(stroke
			(width 0.2)
			(type default)
		)
		(layer "In10.Cu")
	)
	(gr_line
		(start 209.451448 -407.000202)
		(end 209.451448 -408.399996)
		(stroke
			(width 0.2)
			(type default)
		)
		(layer "In10.Cu")
	)
	(gr_line
		(start 210.548728 -415.600134)
		(end 210.548728 -414.20034)
		(stroke
			(width 0.2)
			(type default)
		)
		(layer "In10.Cu")
	)
	(gr_arc
		(start 210.548728 -414.20034)
		(mid 210.000215 -413.651446)
		(end 209.451448 -414.200086)
		(stroke
			(width 0.2)
			(type default)
		)
		(layer "In10.Cu")
	)
	(gr_line
		(start 210.548728 -412.000192)
		(end 210.548728 -410.600398)
		(stroke
			(width 0.2)
			(type default)
		)
		(layer "In10.Cu")
	)
	(gr_arc
		(start 210.548728 -410.600398)
		(mid 210.000215 -410.051504)
		(end 209.451448 -410.600144)
		(stroke
			(width 0.2)
			(type default)
		)
		(layer "In10.Cu")
	)
	(gr_line
		(start 210.548728 -408.399996)
		(end 210.548728 -407.000456)
		(stroke
			(width 0.2)
			(type default)
		)
		(layer "In10.Cu")
	)
	(gr_arc
		(start 210.548728 -407.000456)
		(mid 210.000215 -406.451562)
		(end 209.451448 -407.000202)
		(stroke
			(width 0.2)
			(type default)
		)
		(layer "In10.Cu")
	)
	(gr_arc
		(start 211.251546 -418.200078)
		(mid 211.800186 -418.748718)
		(end 212.348826 -418.200078)
		(stroke
			(width 0.2)
			(type default)
		)
		(layer "In10.Cu")
	)
	(gr_line
		(start 211.251546 -416.80003)
		(end 211.251546 -418.200078)
		(stroke
			(width 0.2)
			(type default)
		)
		(layer "In10.Cu")
	)
	(gr_arc
		(start 211.251546 -407.399998)
		(mid 211.800186 -407.948638)
		(end 212.348826 -407.399998)
		(stroke
			(width 0.2)
			(type default)
		)
		(layer "In10.Cu")
	)
	(gr_line
		(start 211.251546 -405.99995)
		(end 211.251546 -407.399998)
		(stroke
			(width 0.2)
			(type default)
		)
		(layer "In10.Cu")
	)
	(gr_line
		(start 212.348826 -418.200078)
		(end 212.348826 -416.800284)
		(stroke
			(width 0.2)
			(type default)
		)
		(layer "In10.Cu")
	)
	(gr_arc
		(start 212.348826 -416.800284)
		(mid 211.800313 -416.25139)
		(end 211.251546 -416.80003)
		(stroke
			(width 0.2)
			(type default)
		)
		(layer "In10.Cu")
	)
	(gr_line
		(start 212.348826 -407.399998)
		(end 212.348826 -406.000204)
		(stroke
			(width 0.2)
			(type default)
		)
		(layer "In10.Cu")
	)
	(gr_arc
		(start 212.348826 -406.000204)
		(mid 211.800313 -405.45131)
		(end 211.251546 -405.99995)
		(stroke
			(width 0.2)
			(type default)
		)
		(layer "In10.Cu")
	)
	(gr_arc
		(start 213.05139 -415.600134)
		(mid 213.60003 -416.148774)
		(end 214.14867 -415.600134)
		(stroke
			(width 0.2)
			(type default)
		)
		(layer "In10.Cu")
	)
	(gr_line
		(start 213.05139 -414.200086)
		(end 213.05139 -415.600134)
		(stroke
			(width 0.2)
			(type default)
		)
		(layer "In10.Cu")
	)
	(gr_arc
		(start 213.05139 -408.399996)
		(mid 213.60003 -408.948636)
		(end 214.14867 -408.399996)
		(stroke
			(width 0.2)
			(type default)
		)
		(layer "In10.Cu")
	)
	(gr_line
		(start 213.05139 -407.000202)
		(end 213.05139 -408.399996)
		(stroke
			(width 0.2)
			(type default)
		)
		(layer "In10.Cu")
	)
	(gr_line
		(start 214.14867 -415.600134)
		(end 214.14867 -414.20034)
		(stroke
			(width 0.2)
			(type default)
		)
		(layer "In10.Cu")
	)
	(gr_arc
		(start 214.14867 -414.20034)
		(mid 213.600157 -413.651446)
		(end 213.05139 -414.200086)
		(stroke
			(width 0.2)
			(type default)
		)
		(layer "In10.Cu")
	)
	(gr_line
		(start 214.14867 -408.399996)
		(end 214.14867 -407.000456)
		(stroke
			(width 0.2)
			(type default)
		)
		(layer "In10.Cu")
	)
	(gr_arc
		(start 214.14867 -407.000456)
		(mid 213.600157 -406.451562)
		(end 213.05139 -407.000202)
		(stroke
			(width 0.2)
			(type default)
		)
		(layer "In10.Cu")
	)
	(gr_arc
		(start 214.851488 -418.200078)
		(mid 215.400128 -418.748718)
		(end 215.948768 -418.200078)
		(stroke
			(width 0.2)
			(type default)
		)
		(layer "In10.Cu")
	)
	(gr_line
		(start 214.851488 -416.80003)
		(end 214.851488 -418.200078)
		(stroke
			(width 0.2)
			(type default)
		)
		(layer "In10.Cu")
	)
	(gr_arc
		(start 214.851488 -407.399998)
		(mid 215.400128 -407.948638)
		(end 215.948768 -407.399998)
		(stroke
			(width 0.2)
			(type default)
		)
		(layer "In10.Cu")
	)
	(gr_line
		(start 214.851488 -405.99995)
		(end 214.851488 -407.399998)
		(stroke
			(width 0.2)
			(type default)
		)
		(layer "In10.Cu")
	)
	(gr_line
		(start 215.948768 -418.200078)
		(end 215.948768 -416.800284)
		(stroke
			(width 0.2)
			(type default)
		)
		(layer "In10.Cu")
	)
	(gr_arc
		(start 215.948768 -416.800284)
		(mid 215.400255 -416.25139)
		(end 214.851488 -416.80003)
		(stroke
			(width 0.2)
			(type default)
		)
		(layer "In10.Cu")
	)
	(gr_line
		(start 215.948768 -407.399998)
		(end 215.948768 -406.000204)
		(stroke
			(width 0.2)
			(type default)
		)
		(layer "In10.Cu")
	)
	(gr_arc
		(start 215.948768 -406.000204)
		(mid 215.400255 -405.45131)
		(end 214.851488 -405.99995)
		(stroke
			(width 0.2)
			(type default)
		)
		(layer "In10.Cu")
	)
	(gr_arc
		(start 216.651332 -415.600134)
		(mid 217.199972 -416.148774)
		(end 217.748612 -415.600134)
		(stroke
			(width 0.2)
			(type default)
		)
		(layer "In10.Cu")
	)
	(gr_line
		(start 216.651332 -414.200086)
		(end 216.651332 -415.600134)
		(stroke
			(width 0.2)
			(type default)
		)
		(layer "In10.Cu")
	)
	(gr_arc
		(start 216.651332 -408.399996)
		(mid 217.199972 -408.948636)
		(end 217.748612 -408.399996)
		(stroke
			(width 0.2)
			(type default)
		)
		(layer "In10.Cu")
	)
	(gr_line
		(start 216.651332 -407.000202)
		(end 216.651332 -408.399996)
		(stroke
			(width 0.2)
			(type default)
		)
		(layer "In10.Cu")
	)
	(gr_line
		(start 217.748612 -415.600134)
		(end 217.748612 -414.20034)
		(stroke
			(width 0.2)
			(type default)
		)
		(layer "In10.Cu")
	)
	(gr_arc
		(start 217.748612 -414.20034)
		(mid 217.200099 -413.651446)
		(end 216.651332 -414.200086)
		(stroke
			(width 0.2)
			(type default)
		)
		(layer "In10.Cu")
	)
	(gr_line
		(start 217.748612 -408.399996)
		(end 217.748612 -407.000456)
		(stroke
			(width 0.2)
			(type default)
		)
		(layer "In10.Cu")
	)
	(gr_arc
		(start 217.748612 -407.000456)
		(mid 217.200099 -406.451562)
		(end 216.651332 -407.000202)
		(stroke
			(width 0.2)
			(type default)
		)
		(layer "In10.Cu")
	)
	(gr_arc
		(start 218.45143 -418.200078)
		(mid 219.00007 -418.748718)
		(end 219.54871 -418.200078)
		(stroke
			(width 0.2)
			(type default)
		)
		(layer "In10.Cu")
	)
	(gr_line
		(start 218.45143 -416.80003)
		(end 218.45143 -418.200078)
		(stroke
			(width 0.2)
			(type default)
		)
		(layer "In10.Cu")
	)
	(gr_arc
		(start 218.45143 -407.399998)
		(mid 219.00007 -407.948638)
		(end 219.54871 -407.399998)
		(stroke
			(width 0.2)
			(type default)
		)
		(layer "In10.Cu")
	)
	(gr_line
		(start 218.45143 -405.99995)
		(end 218.45143 -407.399998)
		(stroke
			(width 0.2)
			(type default)
		)
		(layer "In10.Cu")
	)
	(gr_arc
		(start 219.00007 1.999996)
		(mid 219.707175 2.292889)
		(end 220.000068 2.999994)
		(stroke
			(width 1.524)
			(type default)
		)
		(layer "In10.Cu")
	)
	(gr_line
		(start 219.54871 -418.200078)
		(end 219.54871 -416.800284)
		(stroke
			(width 0.2)
			(type default)
		)
		(layer "In10.Cu")
	)
	(gr_arc
		(start 219.54871 -416.800284)
		(mid 219.000197 -416.25139)
		(end 218.45143 -416.80003)
		(stroke
			(width 0.2)
			(type default)
		)
		(layer "In10.Cu")
	)
	(gr_line
		(start 219.54871 -407.399998)
		(end 219.54871 -406.000204)
		(stroke
			(width 0.2)
			(type default)
		)
		(layer "In10.Cu")
	)
	(gr_arc
		(start 219.54871 -406.000204)
		(mid 219.000197 -405.45131)
		(end 218.45143 -405.99995)
		(stroke
			(width 0.2)
			(type default)
		)
		(layer "In10.Cu")
	)
	(gr_line
		(start 220.000068 2.999994)
		(end 220.000068 37.800026)
		(stroke
			(width 1.524)
			(type default)
		)
		(layer "In10.Cu")
	)
	(gr_arc
		(start 220.251528 -415.600134)
		(mid 220.800168 -416.148774)
		(end 221.348808 -415.600134)
		(stroke
			(width 0.2)
			(type default)
		)
		(layer "In10.Cu")
	)
	(gr_line
		(start 220.251528 -414.200086)
		(end 220.251528 -415.600134)
		(stroke
			(width 0.2)
			(type default)
		)
		(layer "In10.Cu")
	)
	(gr_arc
		(start 220.251528 -408.399996)
		(mid 220.800168 -408.948636)
		(end 221.348808 -408.399996)
		(stroke
			(width 0.2)
			(type default)
		)
		(layer "In10.Cu")
	)
	(gr_line
		(start 220.251528 -407.000202)
		(end 220.251528 -408.399996)
		(stroke
			(width 0.2)
			(type default)
		)
		(layer "In10.Cu")
	)
	(gr_arc
		(start 221.000066 38.800024)
		(mid 220.292973 38.507121)
		(end 220.000068 37.800026)
		(stroke
			(width 1.524)
			(type default)
		)
		(layer "In10.Cu")
	)
	(gr_line
		(start 221.000066 38.800024)
		(end 298.99991 38.800024)
		(stroke
			(width 1.524)
			(type default)
		)
		(layer "In10.Cu")
	)
	(gr_line
		(start 221.348808 -415.600134)
		(end 221.348808 -414.20034)
		(stroke
			(width 0.2)
			(type default)
		)
		(layer "In10.Cu")
	)
	(gr_arc
		(start 221.348808 -414.20034)
		(mid 220.800295 -413.651446)
		(end 220.251528 -414.200086)
		(stroke
			(width 0.2)
			(type default)
		)
		(layer "In10.Cu")
	)
	(gr_line
		(start 221.348808 -408.399996)
		(end 221.348808 -407.000456)
		(stroke
			(width 0.2)
			(type default)
		)
		(layer "In10.Cu")
	)
	(gr_arc
		(start 221.348808 -407.000456)
		(mid 220.800295 -406.451562)
		(end 220.251528 -407.000202)
		(stroke
			(width 0.2)
			(type default)
		)
		(layer "In10.Cu")
	)
	(gr_arc
		(start 222.051372 -418.200078)
		(mid 222.600012 -418.748718)
		(end 223.148652 -418.200078)
		(stroke
			(width 0.2)
			(type default)
		)
		(layer "In10.Cu")
	)
	(gr_line
		(start 222.051372 -416.80003)
		(end 222.051372 -418.200078)
		(stroke
			(width 0.2)
			(type default)
		)
		(layer "In10.Cu")
	)
	(gr_arc
		(start 222.051372 -407.399998)
		(mid 222.600012 -407.948638)
		(end 223.148652 -407.399998)
		(stroke
			(width 0.2)
			(type default)
		)
		(layer "In10.Cu")
	)
	(gr_line
		(start 222.051372 -405.99995)
		(end 222.051372 -407.399998)
		(stroke
			(width 0.2)
			(type default)
		)
		(layer "In10.Cu")
	)
	(gr_line
		(start 223.148652 -418.200078)
		(end 223.148652 -416.800284)
		(stroke
			(width 0.2)
			(type default)
		)
		(layer "In10.Cu")
	)
	(gr_arc
		(start 223.148652 -416.800284)
		(mid 222.600139 -416.25139)
		(end 222.051372 -416.80003)
		(stroke
			(width 0.2)
			(type default)
		)
		(layer "In10.Cu")
	)
	(gr_line
		(start 223.148652 -407.399998)
		(end 223.148652 -406.000204)
		(stroke
			(width 0.2)
			(type default)
		)
		(layer "In10.Cu")
	)
	(gr_arc
		(start 223.148652 -406.000204)
		(mid 222.600139 -405.45131)
		(end 222.051372 -405.99995)
		(stroke
			(width 0.2)
			(type default)
		)
		(layer "In10.Cu")
	)
	(gr_arc
		(start 235.722922 -121.845578)
		(mid 235.39577 -122.827034)
		(end 236.377226 -123.154186)
		(stroke
			(width 0.2)
			(type default)
		)
		(layer "In10.Cu")
	)
	(gr_line
		(start 235.723938 -65.548002)
		(end 235.725208 -65.550288)
		(stroke
			(width 0.2)
			(type default)
		)
		(layer "In10.Cu")
	)
	(gr_line
		(start 235.724192 -177.848006)
		(end 235.725208 -177.850038)
		(stroke
			(width 0.2)
			(type default)
		)
		(layer "In10.Cu")
	)
	(gr_line
		(start 235.724192 -177.847752)
		(end 235.724192 -177.848006)
		(stroke
			(width 0.2)
			(type default)
		)
		(layer "In10.Cu")
	)
	(gr_line
		(start 235.724192 -173.848014)
		(end 235.725208 -173.850046)
		(stroke
			(width 0.2)
			(type default)
		)
		(layer "In10.Cu")
	)
	(gr_line
		(start 235.724192 -173.84776)
		(end 235.724192 -173.848014)
		(stroke
			(width 0.2)
			(type default)
		)
		(layer "In10.Cu")
	)
	(gr_line
		(start 235.724192 -169.848022)
		(end 235.725208 -169.850054)
		(stroke
			(width 0.2)
			(type default)
		)
		(layer "In10.Cu")
	)
	(gr_line
		(start 235.724192 -169.847768)
		(end 235.724192 -169.848022)
		(stroke
			(width 0.2)
			(type default)
		)
		(layer "In10.Cu")
	)
	(gr_line
		(start 235.724192 -165.84803)
		(end 235.725208 -165.850062)
		(stroke
			(width 0.2)
			(type default)
		)
		(layer "In10.Cu")
	)
	(gr_line
		(start 235.724192 -165.847776)
		(end 235.724192 -165.84803)
		(stroke
			(width 0.2)
			(type default)
		)
		(layer "In10.Cu")
	)
	(gr_line
		(start 235.724192 -137.848086)
		(end 235.725208 -137.850118)
		(stroke
			(width 0.2)
			(type default)
		)
		(layer "In10.Cu")
	)
	(gr_line
		(start 235.724192 -137.847832)
		(end 235.724192 -137.848086)
		(stroke
			(width 0.2)
			(type default)
		)
		(layer "In10.Cu")
	)
	(gr_line
		(start 235.724192 -81.548224)
		(end 235.725208 -81.550256)
		(stroke
			(width 0.2)
			(type default)
		)
		(layer "In10.Cu")
	)
	(gr_line
		(start 235.724192 -81.54797)
		(end 235.724192 -81.548224)
		(stroke
			(width 0.2)
			(type default)
		)
		(layer "In10.Cu")
	)
	(gr_line
		(start 235.724192 -77.548232)
		(end 235.725208 -77.550264)
		(stroke
			(width 0.2)
			(type default)
		)
		(layer "In10.Cu")
	)
	(gr_line
		(start 235.724192 -77.547978)
		(end 235.724192 -77.548232)
		(stroke
			(width 0.2)
			(type default)
		)
		(layer "In10.Cu")
	)
	(gr_line
		(start 235.724192 -73.54824)
		(end 235.725208 -73.550272)
		(stroke
			(width 0.2)
			(type default)
		)
		(layer "In10.Cu")
	)
	(gr_line
		(start 235.724192 -73.547986)
		(end 235.724192 -73.54824)
		(stroke
			(width 0.2)
			(type default)
		)
		(layer "In10.Cu")
	)
	(gr_line
		(start 235.724192 -69.548248)
		(end 235.725208 -69.55028)
		(stroke
			(width 0.2)
			(type default)
		)
		(layer "In10.Cu")
	)
	(gr_line
		(start 235.724192 -69.547994)
		(end 235.724192 -69.548248)
		(stroke
			(width 0.2)
			(type default)
		)
		(layer "In10.Cu")
	)
	(gr_line
		(start 235.724192 -61.548264)
		(end 235.725208 -61.550296)
		(stroke
			(width 0.2)
			(type default)
		)
		(layer "In10.Cu")
	)
	(gr_line
		(start 235.724192 -61.54801)
		(end 235.724192 -61.548264)
		(stroke
			(width 0.2)
			(type default)
		)
		(layer "In10.Cu")
	)
	(gr_line
		(start 235.724192 -57.548272)
		(end 235.725208 -57.550304)
		(stroke
			(width 0.2)
			(type default)
		)
		(layer "In10.Cu")
	)
	(gr_line
		(start 235.724192 -57.548018)
		(end 235.724192 -57.548272)
		(stroke
			(width 0.2)
			(type default)
		)
		(layer "In10.Cu")
	)
	(gr_line
		(start 235.724192 -53.54828)
		(end 235.725208 -53.550312)
		(stroke
			(width 0.2)
			(type default)
		)
		(layer "In10.Cu")
	)
	(gr_line
		(start 235.724192 -53.548026)
		(end 235.724192 -53.54828)
		(stroke
			(width 0.2)
			(type default)
		)
		(layer "In10.Cu")
	)
	(gr_line
		(start 235.724192 -49.548288)
		(end 235.725208 -49.55032)
		(stroke
			(width 0.2)
			(type default)
		)
		(layer "In10.Cu")
	)
	(gr_line
		(start 235.724192 -49.548034)
		(end 235.724192 -49.548288)
		(stroke
			(width 0.2)
			(type default)
		)
		(layer "In10.Cu")
	)
	(gr_line
		(start 235.724192 -45.548296)
		(end 235.725208 -45.550328)
		(stroke
			(width 0.2)
			(type default)
		)
		(layer "In10.Cu")
	)
	(gr_line
		(start 235.724192 -45.548042)
		(end 235.724192 -45.548296)
		(stroke
			(width 0.2)
			(type default)
		)
		(layer "In10.Cu")
	)
	(gr_line
		(start 235.724192 -41.548304)
		(end 235.725208 -41.550336)
		(stroke
			(width 0.2)
			(type default)
		)
		(layer "In10.Cu")
	)
	(gr_line
		(start 235.724192 -41.54805)
		(end 235.724192 -41.548304)
		(stroke
			(width 0.2)
			(type default)
		)
		(layer "In10.Cu")
	)
	(gr_line
		(start 235.724192 -37.548312)
		(end 235.725208 -37.550344)
		(stroke
			(width 0.2)
			(type default)
		)
		(layer "In10.Cu")
	)
	(gr_line
		(start 235.724192 -37.548058)
		(end 235.724192 -37.548312)
		(stroke
			(width 0.2)
			(type default)
		)
		(layer "In10.Cu")
	)
	(gr_line
		(start 235.724192 -17.548352)
		(end 235.725208 -17.550384)
		(stroke
			(width 0.2)
			(type default)
		)
		(layer "In10.Cu")
	)
	(gr_line
		(start 235.724192 -17.548098)
		(end 235.724192 -17.548352)
		(stroke
			(width 0.2)
			(type default)
		)
		(layer "In10.Cu")
	)
	(gr_arc
		(start 235.725208 -177.850038)
		(mid 235.400342 -178.824636)
		(end 236.37494 -179.149502)
		(stroke
			(width 0.2)
			(type default)
		)
		(layer "In10.Cu")
	)
	(gr_arc
		(start 235.725208 -173.850046)
		(mid 235.400342 -174.824644)
		(end 236.37494 -175.14951)
		(stroke
			(width 0.2)
			(type default)
		)
		(layer "In10.Cu")
	)
	(gr_arc
		(start 235.725208 -169.850054)
		(mid 235.400342 -170.824652)
		(end 236.37494 -171.149518)
		(stroke
			(width 0.2)
			(type default)
		)
		(layer "In10.Cu")
	)
	(gr_arc
		(start 235.725208 -165.850062)
		(mid 235.400342 -166.82466)
		(end 236.37494 -167.149526)
		(stroke
			(width 0.2)
			(type default)
		)
		(layer "In10.Cu")
	)
	(gr_arc
		(start 235.725208 -137.850118)
		(mid 235.400342 -138.824716)
		(end 236.37494 -139.149582)
		(stroke
			(width 0.2)
			(type default)
		)
		(layer "In10.Cu")
	)
	(gr_arc
		(start 235.725208 -81.550256)
		(mid 235.400342 -82.524854)
		(end 236.37494 -82.84972)
		(stroke
			(width 0.2)
			(type default)
		)
		(layer "In10.Cu")
	)
	(gr_arc
		(start 235.725208 -77.550264)
		(mid 235.400342 -78.524862)
		(end 236.37494 -78.849728)
		(stroke
			(width 0.2)
			(type default)
		)
		(layer "In10.Cu")
	)
	(gr_arc
		(start 235.725208 -73.550272)
		(mid 235.400342 -74.52487)
		(end 236.37494 -74.849736)
		(stroke
			(width 0.2)
			(type default)
		)
		(layer "In10.Cu")
	)
	(gr_arc
		(start 235.725208 -69.55028)
		(mid 235.400342 -70.524878)
		(end 236.37494 -70.849744)
		(stroke
			(width 0.2)
			(type default)
		)
		(layer "In10.Cu")
	)
	(gr_arc
		(start 235.725208 -65.550288)
		(mid 235.400342 -66.524886)
		(end 236.37494 -66.849752)
		(stroke
			(width 0.2)
			(type default)
		)
		(layer "In10.Cu")
	)
	(gr_arc
		(start 235.725208 -61.550296)
		(mid 235.400342 -62.524894)
		(end 236.37494 -62.84976)
		(stroke
			(width 0.2)
			(type default)
		)
		(layer "In10.Cu")
	)
	(gr_arc
		(start 235.725208 -57.550304)
		(mid 235.400342 -58.524902)
		(end 236.37494 -58.849768)
		(stroke
			(width 0.2)
			(type default)
		)
		(layer "In10.Cu")
	)
	(gr_arc
		(start 235.725208 -53.550312)
		(mid 235.400342 -54.52491)
		(end 236.37494 -54.849776)
		(stroke
			(width 0.2)
			(type default)
		)
		(layer "In10.Cu")
	)
	(gr_arc
		(start 235.725208 -49.55032)
		(mid 235.400342 -50.524918)
		(end 236.37494 -50.849784)
		(stroke
			(width 0.2)
			(type default)
		)
		(layer "In10.Cu")
	)
	(gr_arc
		(start 235.725208 -45.550328)
		(mid 235.400342 -46.524926)
		(end 236.37494 -46.849792)
		(stroke
			(width 0.2)
			(type default)
		)
		(layer "In10.Cu")
	)
	(gr_arc
		(start 235.725208 -41.550336)
		(mid 235.400342 -42.524934)
		(end 236.37494 -42.8498)
		(stroke
			(width 0.2)
			(type default)
		)
		(layer "In10.Cu")
	)
	(gr_arc
		(start 235.725208 -37.550344)
		(mid 235.400342 -38.524942)
		(end 236.37494 -38.849808)
		(stroke
			(width 0.2)
			(type default)
		)
		(layer "In10.Cu")
	)
	(gr_arc
		(start 235.725208 -17.550384)
		(mid 235.400342 -18.524982)
		(end 236.37494 -18.849848)
		(stroke
			(width 0.2)
			(type default)
		)
		(layer "In10.Cu")
	)
	(gr_arc
		(start 235.733844 -161.840164)
		(mid 235.393447 -162.821194)
		(end 236.377226 -163.154106)
		(stroke
			(width 0.2)
			(type default)
		)
		(layer "In10.Cu")
	)
	(gr_arc
		(start 235.733844 -157.840172)
		(mid 235.393447 -158.821202)
		(end 236.377226 -159.154114)
		(stroke
			(width 0.2)
			(type default)
		)
		(layer "In10.Cu")
	)
	(gr_arc
		(start 235.733844 -153.84018)
		(mid 235.393447 -154.82121)
		(end 236.377226 -155.154122)
		(stroke
			(width 0.2)
			(type default)
		)
		(layer "In10.Cu")
	)
	(gr_arc
		(start 235.733844 -149.840188)
		(mid 235.393447 -150.821218)
		(end 236.377226 -151.15413)
		(stroke
			(width 0.2)
			(type default)
		)
		(layer "In10.Cu")
	)
	(gr_arc
		(start 235.733844 -129.840228)
		(mid 235.393447 -130.821258)
		(end 236.377226 -131.15417)
		(stroke
			(width 0.2)
			(type default)
		)
		(layer "In10.Cu")
	)
	(gr_arc
		(start 235.733844 -125.840236)
		(mid 235.393447 -126.821266)
		(end 236.377226 -127.154178)
		(stroke
			(width 0.2)
			(type default)
		)
		(layer "In10.Cu")
	)
	(gr_arc
		(start 235.733844 -117.840252)
		(mid 235.393447 -118.821282)
		(end 236.377226 -119.154194)
		(stroke
			(width 0.2)
			(type default)
		)
		(layer "In10.Cu")
	)
	(gr_arc
		(start 235.733844 -113.84026)
		(mid 235.393447 -114.82129)
		(end 236.377226 -115.154202)
		(stroke
			(width 0.2)
			(type default)
		)
		(layer "In10.Cu")
	)
	(gr_arc
		(start 235.733844 -11.54049)
		(mid 235.393447 -12.52152)
		(end 236.377226 -12.854432)
		(stroke
			(width 0.2)
			(type default)
		)
		(layer "In10.Cu")
	)
	(gr_line
		(start 236.37494 -179.149502)
		(end 236.37621 -179.151788)
		(stroke
			(width 0.2)
			(type default)
		)
		(layer "In10.Cu")
	)
	(gr_line
		(start 236.37494 -175.14951)
		(end 236.37621 -175.151796)
		(stroke
			(width 0.2)
			(type default)
		)
		(layer "In10.Cu")
	)
	(gr_line
		(start 236.37494 -171.149518)
		(end 236.37621 -171.151804)
		(stroke
			(width 0.2)
			(type default)
		)
		(layer "In10.Cu")
	)
	(gr_line
		(start 236.37494 -167.149526)
		(end 236.37621 -167.151812)
		(stroke
			(width 0.2)
			(type default)
		)
		(layer "In10.Cu")
	)
	(gr_line
		(start 236.37494 -139.149582)
		(end 236.37621 -139.151868)
		(stroke
			(width 0.2)
			(type default)
		)
		(layer "In10.Cu")
	)
	(gr_line
		(start 236.37494 -82.84972)
		(end 236.37621 -82.852006)
		(stroke
			(width 0.2)
			(type default)
		)
		(layer "In10.Cu")
	)
	(gr_line
		(start 236.37494 -78.849728)
		(end 236.37621 -78.852014)
		(stroke
			(width 0.2)
			(type default)
		)
		(layer "In10.Cu")
	)
	(gr_line
		(start 236.37494 -74.849736)
		(end 236.37621 -74.852022)
		(stroke
			(width 0.2)
			(type default)
		)
		(layer "In10.Cu")
	)
	(gr_line
		(start 236.37494 -70.849744)
		(end 236.37621 -70.85203)
		(stroke
			(width 0.2)
			(type default)
		)
		(layer "In10.Cu")
	)
	(gr_line
		(start 236.37494 -66.849752)
		(end 236.37621 -66.852038)
		(stroke
			(width 0.2)
			(type default)
		)
		(layer "In10.Cu")
	)
	(gr_line
		(start 236.37494 -62.84976)
		(end 236.37621 -62.852046)
		(stroke
			(width 0.2)
			(type default)
		)
		(layer "In10.Cu")
	)
	(gr_line
		(start 236.37494 -58.849768)
		(end 236.37621 -58.852054)
		(stroke
			(width 0.2)
			(type default)
		)
		(layer "In10.Cu")
	)
	(gr_line
		(start 236.37494 -54.849776)
		(end 236.37621 -54.852062)
		(stroke
			(width 0.2)
			(type default)
		)
		(layer "In10.Cu")
	)
	(gr_line
		(start 236.37494 -50.849784)
		(end 236.37621 -50.85207)
		(stroke
			(width 0.2)
			(type default)
		)
		(layer "In10.Cu")
	)
	(gr_line
		(start 236.37494 -46.849792)
		(end 236.37621 -46.852078)
		(stroke
			(width 0.2)
			(type default)
		)
		(layer "In10.Cu")
	)
	(gr_line
		(start 236.37494 -42.8498)
		(end 236.37621 -42.852086)
		(stroke
			(width 0.2)
			(type default)
		)
		(layer "In10.Cu")
	)
	(gr_line
		(start 236.37494 -38.849808)
		(end 236.37621 -38.852094)
		(stroke
			(width 0.2)
			(type default)
		)
		(layer "In10.Cu")
	)
	(gr_line
		(start 236.37494 -18.849848)
		(end 236.37621 -18.852134)
		(stroke
			(width 0.2)
			(type default)
		)
		(layer "In10.Cu")
	)
	(gr_line
		(start 236.37621 -179.151788)
		(end 238.376206 -178.15179)
		(stroke
			(width 0.2)
			(type default)
		)
		(layer "In10.Cu")
	)
	(gr_line
		(start 236.37621 -175.151796)
		(end 238.376206 -174.151798)
		(stroke
			(width 0.2)
			(type default)
		)
		(layer "In10.Cu")
	)
	(gr_line
		(start 236.37621 -171.151804)
		(end 238.376206 -170.151806)
		(stroke
			(width 0.2)
			(type default)
		)
		(layer "In10.Cu")
	)
	(gr_line
		(start 236.37621 -167.151812)
		(end 238.376206 -166.151814)
		(stroke
			(width 0.2)
			(type default)
		)
		(layer "In10.Cu")
	)
	(gr_line
		(start 236.37621 -139.151868)
		(end 238.376206 -138.15187)
		(stroke
			(width 0.2)
			(type default)
		)
		(layer "In10.Cu")
	)
	(gr_line
		(start 236.37621 -82.852006)
		(end 238.376206 -81.852008)
		(stroke
			(width 0.2)
			(type default)
		)
		(layer "In10.Cu")
	)
	(gr_line
		(start 236.37621 -78.852014)
		(end 238.376206 -77.852016)
		(stroke
			(width 0.2)
			(type default)
		)
		(layer "In10.Cu")
	)
	(gr_line
		(start 236.37621 -74.852022)
		(end 238.376206 -73.852024)
		(stroke
			(width 0.2)
			(type default)
		)
		(layer "In10.Cu")
	)
	(gr_line
		(start 236.37621 -70.85203)
		(end 238.376206 -69.852032)
		(stroke
			(width 0.2)
			(type default)
		)
		(layer "In10.Cu")
	)
	(gr_line
		(start 236.37621 -66.852038)
		(end 238.375952 -65.85204)
		(stroke
			(width 0.2)
			(type default)
		)
		(layer "In10.Cu")
	)
	(gr_line
		(start 236.37621 -62.852046)
		(end 238.376206 -61.852048)
		(stroke
			(width 0.2)
			(type default)
		)
		(layer "In10.Cu")
	)
	(gr_line
		(start 236.37621 -58.852054)
		(end 238.376206 -57.852056)
		(stroke
			(width 0.2)
			(type default)
		)
		(layer "In10.Cu")
	)
	(gr_line
		(start 236.37621 -54.852062)
		(end 238.376206 -53.852064)
		(stroke
			(width 0.2)
			(type default)
		)
		(layer "In10.Cu")
	)
	(gr_line
		(start 236.37621 -50.85207)
		(end 238.376206 -49.852072)
		(stroke
			(width 0.2)
			(type default)
		)
		(layer "In10.Cu")
	)
	(gr_line
		(start 236.37621 -46.852078)
		(end 238.376206 -45.85208)
		(stroke
			(width 0.2)
			(type default)
		)
		(layer "In10.Cu")
	)
	(gr_line
		(start 236.37621 -42.852086)
		(end 238.376206 -41.852088)
		(stroke
			(width 0.2)
			(type default)
		)
		(layer "In10.Cu")
	)
	(gr_line
		(start 236.37621 -38.852094)
		(end 238.376206 -37.852096)
		(stroke
			(width 0.2)
			(type default)
		)
		(layer "In10.Cu")
	)
	(gr_line
		(start 236.37621 -18.852134)
		(end 238.376206 -17.852136)
		(stroke
			(width 0.2)
			(type default)
		)
		(layer "In10.Cu")
	)
	(gr_line
		(start 236.377226 -163.154106)
		(end 238.377222 -162.154108)
		(stroke
			(width 0.2)
			(type default)
		)
		(layer "In10.Cu")
	)
	(gr_line
		(start 236.377226 -159.154114)
		(end 238.377222 -158.154116)
		(stroke
			(width 0.2)
			(type default)
		)
		(layer "In10.Cu")
	)
	(gr_line
		(start 236.377226 -155.154122)
		(end 238.377222 -154.154124)
		(stroke
			(width 0.2)
			(type default)
		)
		(layer "In10.Cu")
	)
	(gr_line
		(start 236.377226 -151.15413)
		(end 238.377222 -150.154132)
		(stroke
			(width 0.2)
			(type default)
		)
		(layer "In10.Cu")
	)
	(gr_line
		(start 236.377226 -131.15417)
		(end 238.377222 -130.154172)
		(stroke
			(width 0.2)
			(type default)
		)
		(layer "In10.Cu")
	)
	(gr_line
		(start 236.377226 -127.154178)
		(end 238.377222 -126.15418)
		(stroke
			(width 0.2)
			(type default)
		)
		(layer "In10.Cu")
	)
	(gr_line
		(start 236.377226 -123.154186)
		(end 238.3663 -122.159522)
		(stroke
			(width 0.2)
			(type default)
		)
		(layer "In10.Cu")
	)
	(gr_line
		(start 236.377226 -119.154194)
		(end 238.377222 -118.154196)
		(stroke
			(width 0.2)
			(type default)
		)
		(layer "In10.Cu")
	)
	(gr_line
		(start 236.377226 -115.154202)
		(end 238.377222 -114.154204)
		(stroke
			(width 0.2)
			(type default)
		)
		(layer "In10.Cu")
	)
	(gr_line
		(start 236.377226 -12.854432)
		(end 238.377222 -11.854434)
		(stroke
			(width 0.2)
			(type default)
		)
		(layer "In10.Cu")
	)
	(gr_line
		(start 237.722918 -160.8455)
		(end 235.733844 -161.840164)
		(stroke
			(width 0.2)
			(type default)
		)
		(layer "In10.Cu")
	)
	(gr_line
		(start 237.722918 -156.845508)
		(end 235.733844 -157.840172)
		(stroke
			(width 0.2)
			(type default)
		)
		(layer "In10.Cu")
	)
	(gr_line
		(start 237.722918 -152.845516)
		(end 235.733844 -153.84018)
		(stroke
			(width 0.2)
			(type default)
		)
		(layer "In10.Cu")
	)
	(gr_line
		(start 237.722918 -148.845524)
		(end 235.733844 -149.840188)
		(stroke
			(width 0.2)
			(type default)
		)
		(layer "In10.Cu")
	)
	(gr_line
		(start 237.722918 -128.845564)
		(end 235.733844 -129.840228)
		(stroke
			(width 0.2)
			(type default)
		)
		(layer "In10.Cu")
	)
	(gr_line
		(start 237.722918 -124.845572)
		(end 235.733844 -125.840236)
		(stroke
			(width 0.2)
			(type default)
		)
		(layer "In10.Cu")
	)
	(gr_line
		(start 237.722918 -120.84558)
		(end 235.722922 -121.845578)
		(stroke
			(width 0.2)
			(type default)
		)
		(layer "In10.Cu")
	)
	(gr_line
		(start 237.722918 -116.845588)
		(end 235.733844 -117.840252)
		(stroke
			(width 0.2)
			(type default)
		)
		(layer "In10.Cu")
	)
	(gr_line
		(start 237.722918 -112.845596)
		(end 235.733844 -113.84026)
		(stroke
			(width 0.2)
			(type default)
		)
		(layer "In10.Cu")
	)
	(gr_line
		(start 237.722918 -10.545826)
		(end 235.733844 -11.54049)
		(stroke
			(width 0.2)
			(type default)
		)
		(layer "In10.Cu")
	)
	(gr_line
		(start 237.723934 -176.847754)
		(end 235.724192 -177.847752)
		(stroke
			(width 0.2)
			(type default)
		)
		(layer "In10.Cu")
	)
	(gr_line
		(start 237.723934 -172.847762)
		(end 235.724192 -173.84776)
		(stroke
			(width 0.2)
			(type default)
		)
		(layer "In10.Cu")
	)
	(gr_line
		(start 237.723934 -168.84777)
		(end 235.724192 -169.847768)
		(stroke
			(width 0.2)
			(type default)
		)
		(layer "In10.Cu")
	)
	(gr_line
		(start 237.723934 -164.847778)
		(end 235.724192 -165.847776)
		(stroke
			(width 0.2)
			(type default)
		)
		(layer "In10.Cu")
	)
	(gr_line
		(start 237.723934 -136.847834)
		(end 235.724192 -137.847832)
		(stroke
			(width 0.2)
			(type default)
		)
		(layer "In10.Cu")
	)
	(gr_line
		(start 237.723934 -80.547972)
		(end 235.724192 -81.54797)
		(stroke
			(width 0.2)
			(type default)
		)
		(layer "In10.Cu")
	)
	(gr_line
		(start 237.723934 -76.54798)
		(end 235.724192 -77.547978)
		(stroke
			(width 0.2)
			(type default)
		)
		(layer "In10.Cu")
	)
	(gr_line
		(start 237.723934 -72.547988)
		(end 235.724192 -73.547986)
		(stroke
			(width 0.2)
			(type default)
		)
		(layer "In10.Cu")
	)
	(gr_line
		(start 237.723934 -68.547996)
		(end 235.724192 -69.547994)
		(stroke
			(width 0.2)
			(type default)
		)
		(layer "In10.Cu")
	)
	(gr_line
		(start 237.723934 -64.548004)
		(end 235.723938 -65.548002)
		(stroke
			(width 0.2)
			(type default)
		)
		(layer "In10.Cu")
	)
	(gr_line
		(start 237.723934 -60.548012)
		(end 235.724192 -61.54801)
		(stroke
			(width 0.2)
			(type default)
		)
		(layer "In10.Cu")
	)
	(gr_line
		(start 237.723934 -56.54802)
		(end 235.724192 -57.548018)
		(stroke
			(width 0.2)
			(type default)
		)
		(layer "In10.Cu")
	)
	(gr_line
		(start 237.723934 -52.548028)
		(end 235.724192 -53.548026)
		(stroke
			(width 0.2)
			(type default)
		)
		(layer "In10.Cu")
	)
	(gr_line
		(start 237.723934 -48.548036)
		(end 235.724192 -49.548034)
		(stroke
			(width 0.2)
			(type default)
		)
		(layer "In10.Cu")
	)
	(gr_line
		(start 237.723934 -44.548044)
		(end 235.724192 -45.548042)
		(stroke
			(width 0.2)
			(type default)
		)
		(layer "In10.Cu")
	)
	(gr_line
		(start 237.723934 -40.548052)
		(end 235.724192 -41.54805)
		(stroke
			(width 0.2)
			(type default)
		)
		(layer "In10.Cu")
	)
	(gr_line
		(start 237.723934 -36.54806)
		(end 235.724192 -37.548058)
		(stroke
			(width 0.2)
			(type default)
		)
		(layer "In10.Cu")
	)
	(gr_line
		(start 237.723934 -16.5481)
		(end 235.724192 -17.548098)
		(stroke
			(width 0.2)
			(type default)
		)
		(layer "In10.Cu")
	)
	(gr_line
		(start 237.725204 -176.85004)
		(end 237.723934 -176.847754)
		(stroke
			(width 0.2)
			(type default)
		)
		(layer "In10.Cu")
	)
	(gr_line
		(start 237.725204 -172.850048)
		(end 237.723934 -172.847762)
		(stroke
			(width 0.2)
			(type default)
		)
		(layer "In10.Cu")
	)
	(gr_line
		(start 237.725204 -168.850056)
		(end 237.723934 -168.84777)
		(stroke
			(width 0.2)
			(type default)
		)
		(layer "In10.Cu")
	)
	(gr_line
		(start 237.725204 -164.850064)
		(end 237.723934 -164.847778)
		(stroke
			(width 0.2)
			(type default)
		)
		(layer "In10.Cu")
	)
	(gr_line
		(start 237.725204 -136.85012)
		(end 237.723934 -136.847834)
		(stroke
			(width 0.2)
			(type default)
		)
		(layer "In10.Cu")
	)
	(gr_line
		(start 237.725204 -80.550258)
		(end 237.723934 -80.547972)
		(stroke
			(width 0.2)
			(type default)
		)
		(layer "In10.Cu")
	)
	(gr_line
		(start 237.725204 -76.550266)
		(end 237.723934 -76.54798)
		(stroke
			(width 0.2)
			(type default)
		)
		(layer "In10.Cu")
	)
	(gr_line
		(start 237.725204 -72.550274)
		(end 237.723934 -72.547988)
		(stroke
			(width 0.2)
			(type default)
		)
		(layer "In10.Cu")
	)
	(gr_line
		(start 237.725204 -68.550282)
		(end 237.723934 -68.547996)
		(stroke
			(width 0.2)
			(type default)
		)
		(layer "In10.Cu")
	)
	(gr_line
		(start 237.725204 -64.55029)
		(end 237.723934 -64.548004)
		(stroke
			(width 0.2)
			(type default)
		)
		(layer "In10.Cu")
	)
	(gr_line
		(start 237.725204 -60.550298)
		(end 237.723934 -60.548012)
		(stroke
			(width 0.2)
			(type default)
		)
		(layer "In10.Cu")
	)
	(gr_line
		(start 237.725204 -56.550306)
		(end 237.723934 -56.54802)
		(stroke
			(width 0.2)
			(type default)
		)
		(layer "In10.Cu")
	)
	(gr_line
		(start 237.725204 -52.550314)
		(end 237.723934 -52.548028)
		(stroke
			(width 0.2)
			(type default)
		)
		(layer "In10.Cu")
	)
	(gr_line
		(start 237.725204 -48.550322)
		(end 237.723934 -48.548036)
		(stroke
			(width 0.2)
			(type default)
		)
		(layer "In10.Cu")
	)
	(gr_line
		(start 237.725204 -44.55033)
		(end 237.723934 -44.548044)
		(stroke
			(width 0.2)
			(type default)
		)
		(layer "In10.Cu")
	)
	(gr_line
		(start 237.725204 -40.550338)
		(end 237.723934 -40.548052)
		(stroke
			(width 0.2)
			(type default)
		)
		(layer "In10.Cu")
	)
	(gr_line
		(start 237.725204 -36.550346)
		(end 237.723934 -36.54806)
		(stroke
			(width 0.2)
			(type default)
		)
		(layer "In10.Cu")
	)
	(gr_line
		(start 237.725204 -16.550386)
		(end 237.723934 -16.5481)
		(stroke
			(width 0.2)
			(type default)
		)
		(layer "In10.Cu")
	)
	(gr_arc
		(start 238.3663 -122.159522)
		(mid 238.706697 -121.178492)
		(end 237.722918 -120.84558)
		(stroke
			(width 0.2)
			(type default)
		)
		(layer "In10.Cu")
	)
	(gr_arc
		(start 238.374936 -178.149504)
		(mid 238.699802 -177.174906)
		(end 237.725204 -176.85004)
		(stroke
			(width 0.2)
			(type default)
		)
		(layer "In10.Cu")
	)
	(gr_arc
		(start 238.374936 -174.149512)
		(mid 238.699802 -173.174914)
		(end 237.725204 -172.850048)
		(stroke
			(width 0.2)
			(type default)
		)
		(layer "In10.Cu")
	)
	(gr_arc
		(start 238.374936 -170.14952)
		(mid 238.699802 -169.174922)
		(end 237.725204 -168.850056)
		(stroke
			(width 0.2)
			(type default)
		)
		(layer "In10.Cu")
	)
	(gr_arc
		(start 238.374936 -166.149528)
		(mid 238.699802 -165.17493)
		(end 237.725204 -164.850064)
		(stroke
			(width 0.2)
			(type default)
		)
		(layer "In10.Cu")
	)
	(gr_arc
		(start 238.374936 -138.149584)
		(mid 238.699802 -137.174986)
		(end 237.725204 -136.85012)
		(stroke
			(width 0.2)
			(type default)
		)
		(layer "In10.Cu")
	)
	(gr_arc
		(start 238.374936 -81.849722)
		(mid 238.699802 -80.875124)
		(end 237.725204 -80.550258)
		(stroke
			(width 0.2)
			(type default)
		)
		(layer "In10.Cu")
	)
	(gr_arc
		(start 238.374936 -77.84973)
		(mid 238.699802 -76.875132)
		(end 237.725204 -76.550266)
		(stroke
			(width 0.2)
			(type default)
		)
		(layer "In10.Cu")
	)
	(gr_arc
		(start 238.374936 -73.849738)
		(mid 238.699802 -72.87514)
		(end 237.725204 -72.550274)
		(stroke
			(width 0.2)
			(type default)
		)
		(layer "In10.Cu")
	)
	(gr_arc
		(start 238.374936 -69.849746)
		(mid 238.699802 -68.875148)
		(end 237.725204 -68.550282)
		(stroke
			(width 0.2)
			(type default)
		)
		(layer "In10.Cu")
	)
	(gr_arc
		(start 238.374936 -65.849754)
		(mid 238.699802 -64.875156)
		(end 237.725204 -64.55029)
		(stroke
			(width 0.2)
			(type default)
		)
		(layer "In10.Cu")
	)
	(gr_arc
		(start 238.374936 -61.849762)
		(mid 238.699802 -60.875164)
		(end 237.725204 -60.550298)
		(stroke
			(width 0.2)
			(type default)
		)
		(layer "In10.Cu")
	)
	(gr_arc
		(start 238.374936 -57.84977)
		(mid 238.699802 -56.875172)
		(end 237.725204 -56.550306)
		(stroke
			(width 0.2)
			(type default)
		)
		(layer "In10.Cu")
	)
	(gr_arc
		(start 238.374936 -53.849778)
		(mid 238.699802 -52.87518)
		(end 237.725204 -52.550314)
		(stroke
			(width 0.2)
			(type default)
		)
		(layer "In10.Cu")
	)
	(gr_arc
		(start 238.374936 -49.849786)
		(mid 238.699802 -48.875188)
		(end 237.725204 -48.550322)
		(stroke
			(width 0.2)
			(type default)
		)
		(layer "In10.Cu")
	)
	(gr_arc
		(start 238.374936 -45.849794)
		(mid 238.699802 -44.875196)
		(end 237.725204 -44.55033)
		(stroke
			(width 0.2)
			(type default)
		)
		(layer "In10.Cu")
	)
	(gr_arc
		(start 238.374936 -41.849802)
		(mid 238.699802 -40.875204)
		(end 237.725204 -40.550338)
		(stroke
			(width 0.2)
			(type default)
		)
		(layer "In10.Cu")
	)
	(gr_arc
		(start 238.374936 -37.84981)
		(mid 238.699802 -36.875212)
		(end 237.725204 -36.550346)
		(stroke
			(width 0.2)
			(type default)
		)
		(layer "In10.Cu")
	)
	(gr_arc
		(start 238.374936 -17.84985)
		(mid 238.699802 -16.875252)
		(end 237.725204 -16.550386)
		(stroke
			(width 0.2)
			(type default)
		)
		(layer "In10.Cu")
	)
	(gr_line
		(start 238.375952 -65.85204)
		(end 238.375952 -65.851786)
		(stroke
			(width 0.2)
			(type default)
		)
		(layer "In10.Cu")
	)
	(gr_line
		(start 238.375952 -65.851786)
		(end 238.374936 -65.849754)
		(stroke
			(width 0.2)
			(type default)
		)
		(layer "In10.Cu")
	)
	(gr_line
		(start 238.376206 -178.15179)
		(end 238.374936 -178.149504)
		(stroke
			(width 0.2)
			(type default)
		)
		(layer "In10.Cu")
	)
	(gr_line
		(start 238.376206 -174.151798)
		(end 238.374936 -174.149512)
		(stroke
			(width 0.2)
			(type default)
		)
		(layer "In10.Cu")
	)
	(gr_line
		(start 238.376206 -170.151806)
		(end 238.374936 -170.14952)
		(stroke
			(width 0.2)
			(type default)
		)
		(layer "In10.Cu")
	)
	(gr_line
		(start 238.376206 -166.151814)
		(end 238.374936 -166.149528)
		(stroke
			(width 0.2)
			(type default)
		)
		(layer "In10.Cu")
	)
	(gr_line
		(start 238.376206 -138.15187)
		(end 238.374936 -138.149584)
		(stroke
			(width 0.2)
			(type default)
		)
		(layer "In10.Cu")
	)
	(gr_line
		(start 238.376206 -81.852008)
		(end 238.374936 -81.849722)
		(stroke
			(width 0.2)
			(type default)
		)
		(layer "In10.Cu")
	)
	(gr_line
		(start 238.376206 -77.852016)
		(end 238.374936 -77.84973)
		(stroke
			(width 0.2)
			(type default)
		)
		(layer "In10.Cu")
	)
	(gr_line
		(start 238.376206 -73.852024)
		(end 238.374936 -73.849738)
		(stroke
			(width 0.2)
			(type default)
		)
		(layer "In10.Cu")
	)
	(gr_line
		(start 238.376206 -69.852032)
		(end 238.374936 -69.849746)
		(stroke
			(width 0.2)
			(type default)
		)
		(layer "In10.Cu")
	)
	(gr_line
		(start 238.376206 -61.852048)
		(end 238.374936 -61.849762)
		(stroke
			(width 0.2)
			(type default)
		)
		(layer "In10.Cu")
	)
	(gr_line
		(start 238.376206 -57.852056)
		(end 238.374936 -57.84977)
		(stroke
			(width 0.2)
			(type default)
		)
		(layer "In10.Cu")
	)
	(gr_line
		(start 238.376206 -53.852064)
		(end 238.374936 -53.849778)
		(stroke
			(width 0.2)
			(type default)
		)
		(layer "In10.Cu")
	)
	(gr_line
		(start 238.376206 -49.852072)
		(end 238.374936 -49.849786)
		(stroke
			(width 0.2)
			(type default)
		)
		(layer "In10.Cu")
	)
	(gr_line
		(start 238.376206 -45.85208)
		(end 238.374936 -45.849794)
		(stroke
			(width 0.2)
			(type default)
		)
		(layer "In10.Cu")
	)
	(gr_line
		(start 238.376206 -41.852088)
		(end 238.374936 -41.849802)
		(stroke
			(width 0.2)
			(type default)
		)
		(layer "In10.Cu")
	)
	(gr_line
		(start 238.376206 -37.852096)
		(end 238.374936 -37.84981)
		(stroke
			(width 0.2)
			(type default)
		)
		(layer "In10.Cu")
	)
	(gr_line
		(start 238.376206 -17.852136)
		(end 238.374936 -17.84985)
		(stroke
			(width 0.2)
			(type default)
		)
		(layer "In10.Cu")
	)
	(gr_arc
		(start 238.377222 -162.154108)
		(mid 238.704374 -161.172652)
		(end 237.722918 -160.8455)
		(stroke
			(width 0.2)
			(type default)
		)
		(layer "In10.Cu")
	)
	(gr_arc
		(start 238.377222 -158.154116)
		(mid 238.704374 -157.17266)
		(end 237.722918 -156.845508)
		(stroke
			(width 0.2)
			(type default)
		)
		(layer "In10.Cu")
	)
	(gr_arc
		(start 238.377222 -154.154124)
		(mid 238.704374 -153.172668)
		(end 237.722918 -152.845516)
		(stroke
			(width 0.2)
			(type default)
		)
		(layer "In10.Cu")
	)
	(gr_arc
		(start 238.377222 -150.154132)
		(mid 238.704374 -149.172676)
		(end 237.722918 -148.845524)
		(stroke
			(width 0.2)
			(type default)
		)
		(layer "In10.Cu")
	)
	(gr_arc
		(start 238.377222 -130.154172)
		(mid 238.704374 -129.172716)
		(end 237.722918 -128.845564)
		(stroke
			(width 0.2)
			(type default)
		)
		(layer "In10.Cu")
	)
	(gr_arc
		(start 238.377222 -126.15418)
		(mid 238.704374 -125.172724)
		(end 237.722918 -124.845572)
		(stroke
			(width 0.2)
			(type default)
		)
		(layer "In10.Cu")
	)
	(gr_arc
		(start 238.377222 -118.154196)
		(mid 238.704374 -117.17274)
		(end 237.722918 -116.845588)
		(stroke
			(width 0.2)
			(type default)
		)
		(layer "In10.Cu")
	)
	(gr_arc
		(start 238.377222 -114.154204)
		(mid 238.704374 -113.172748)
		(end 237.722918 -112.845596)
		(stroke
			(width 0.2)
			(type default)
		)
		(layer "In10.Cu")
	)
	(gr_arc
		(start 238.377222 -11.854434)
		(mid 238.704374 -10.872978)
		(end 237.722918 -10.545826)
		(stroke
			(width 0.2)
			(type default)
		)
		(layer "In10.Cu")
	)
	(gr_line
		(start 240.219484 -128.161034)
		(end 242.21948 -129.161032)
		(stroke
			(width 0.2)
			(type default)
		)
		(layer "In10.Cu")
	)
	(gr_line
		(start 240.219484 -124.161042)
		(end 242.20805 -125.155198)
		(stroke
			(width 0.2)
			(type default)
		)
		(layer "In10.Cu")
	)
	(gr_line
		(start 240.222786 -164.154104)
		(end 242.222782 -165.154102)
		(stroke
			(width 0.2)
			(type default)
		)
		(layer "In10.Cu")
	)
	(gr_line
		(start 240.222786 -160.154112)
		(end 242.222528 -161.15411)
		(stroke
			(width 0.2)
			(type default)
		)
		(layer "In10.Cu")
	)
	(gr_line
		(start 240.222786 -156.15412)
		(end 242.222528 -157.154118)
		(stroke
			(width 0.2)
			(type default)
		)
		(layer "In10.Cu")
	)
	(gr_line
		(start 240.222786 -152.154128)
		(end 242.222782 -153.154126)
		(stroke
			(width 0.2)
			(type default)
		)
		(layer "In10.Cu")
	)
	(gr_line
		(start 240.222786 -120.154192)
		(end 242.222528 -121.15419)
		(stroke
			(width 0.2)
			(type default)
		)
		(layer "In10.Cu")
	)
	(gr_line
		(start 240.222786 -116.1542)
		(end 242.222782 -117.154198)
		(stroke
			(width 0.2)
			(type default)
		)
		(layer "In10.Cu")
	)
	(gr_line
		(start 240.223802 -136.151874)
		(end 242.223798 -137.151872)
		(stroke
			(width 0.2)
			(type default)
		)
		(layer "In10.Cu")
	)
	(gr_line
		(start 240.223802 -108.15193)
		(end 242.223798 -109.151928)
		(stroke
			(width 0.2)
			(type default)
		)
		(layer "In10.Cu")
	)
	(gr_line
		(start 240.223802 -35.8521)
		(end 242.223798 -36.852098)
		(stroke
			(width 0.2)
			(type default)
		)
		(layer "In10.Cu")
	)
	(gr_line
		(start 240.225072 -136.149588)
		(end 240.223802 -136.151874)
		(stroke
			(width 0.2)
			(type default)
		)
		(layer "In10.Cu")
	)
	(gr_line
		(start 240.225072 -108.149644)
		(end 240.223802 -108.15193)
		(stroke
			(width 0.2)
			(type default)
		)
		(layer "In10.Cu")
	)
	(gr_line
		(start 240.236502 -180.126894)
		(end 242.236498 -181.126892)
		(stroke
			(width 0.2)
			(type default)
		)
		(layer "In10.Cu")
	)
	(gr_line
		(start 240.236502 -176.126902)
		(end 242.236498 -177.1269)
		(stroke
			(width 0.2)
			(type default)
		)
		(layer "In10.Cu")
	)
	(gr_line
		(start 240.236502 -172.12691)
		(end 242.236498 -173.126908)
		(stroke
			(width 0.2)
			(type default)
		)
		(layer "In10.Cu")
	)
	(gr_line
		(start 240.236502 -168.126918)
		(end 242.236498 -169.126916)
		(stroke
			(width 0.2)
			(type default)
		)
		(layer "In10.Cu")
	)
	(gr_line
		(start 240.236502 -83.827112)
		(end 242.236498 -84.82711)
		(stroke
			(width 0.2)
			(type default)
		)
		(layer "In10.Cu")
	)
	(gr_line
		(start 240.236502 -79.82712)
		(end 242.228116 -80.8228)
		(stroke
			(width 0.2)
			(type default)
		)
		(layer "In10.Cu")
	)
	(gr_line
		(start 240.236502 -75.827128)
		(end 242.228116 -76.822808)
		(stroke
			(width 0.2)
			(type default)
		)
		(layer "In10.Cu")
	)
	(gr_line
		(start 240.236502 -71.827136)
		(end 242.228116 -72.822816)
		(stroke
			(width 0.2)
			(type default)
		)
		(layer "In10.Cu")
	)
	(gr_line
		(start 240.236502 -67.827144)
		(end 242.236498 -68.827142)
		(stroke
			(width 0.2)
			(type default)
		)
		(layer "In10.Cu")
	)
	(gr_line
		(start 240.236502 -63.827152)
		(end 242.236498 -64.82715)
		(stroke
			(width 0.2)
			(type default)
		)
		(layer "In10.Cu")
	)
	(gr_line
		(start 240.236502 -59.82716)
		(end 242.236498 -60.827158)
		(stroke
			(width 0.2)
			(type default)
		)
		(layer "In10.Cu")
	)
	(gr_line
		(start 240.236502 -55.827168)
		(end 242.236498 -56.827166)
		(stroke
			(width 0.2)
			(type default)
		)
		(layer "In10.Cu")
	)
	(gr_line
		(start 240.236502 -51.827176)
		(end 242.228116 -52.822856)
		(stroke
			(width 0.2)
			(type default)
		)
		(layer "In10.Cu")
	)
	(gr_line
		(start 240.236502 -47.827184)
		(end 242.236498 -48.827182)
		(stroke
			(width 0.2)
			(type default)
		)
		(layer "In10.Cu")
	)
	(gr_line
		(start 240.236502 -43.827192)
		(end 242.236498 -44.82719)
		(stroke
			(width 0.2)
			(type default)
		)
		(layer "In10.Cu")
	)
	(gr_line
		(start 240.236502 -39.8272)
		(end 242.236498 -40.827198)
		(stroke
			(width 0.2)
			(type default)
		)
		(layer "In10.Cu")
	)
	(gr_arc
		(start 240.863374 -78.572868)
		(mid 239.922812 -78.886558)
		(end 240.236502 -79.82712)
		(stroke
			(width 0.2)
			(type default)
		)
		(layer "In10.Cu")
	)
	(gr_arc
		(start 240.863374 -74.572876)
		(mid 239.922812 -74.886566)
		(end 240.236502 -75.827128)
		(stroke
			(width 0.2)
			(type default)
		)
		(layer "In10.Cu")
	)
	(gr_arc
		(start 240.863374 -70.572884)
		(mid 239.922812 -70.886574)
		(end 240.236502 -71.827136)
		(stroke
			(width 0.2)
			(type default)
		)
		(layer "In10.Cu")
	)
	(gr_arc
		(start 240.863374 -50.572924)
		(mid 239.922812 -50.886614)
		(end 240.236502 -51.827176)
		(stroke
			(width 0.2)
			(type default)
		)
		(layer "In10.Cu")
	)
	(gr_arc
		(start 240.871756 -178.87696)
		(mid 239.92498 -179.182145)
		(end 240.236502 -180.126894)
		(stroke
			(width 0.2)
			(type default)
		)
		(layer "In10.Cu")
	)
	(gr_arc
		(start 240.871756 -174.876968)
		(mid 239.92498 -175.182153)
		(end 240.236502 -176.126902)
		(stroke
			(width 0.2)
			(type default)
		)
		(layer "In10.Cu")
	)
	(gr_arc
		(start 240.871756 -170.876976)
		(mid 239.92498 -171.182161)
		(end 240.236502 -172.12691)
		(stroke
			(width 0.2)
			(type default)
		)
		(layer "In10.Cu")
	)
	(gr_arc
		(start 240.871756 -166.876984)
		(mid 239.92498 -167.182169)
		(end 240.236502 -168.126918)
		(stroke
			(width 0.2)
			(type default)
		)
		(layer "In10.Cu")
	)
	(gr_arc
		(start 240.871756 -82.577178)
		(mid 239.92498 -82.882363)
		(end 240.236502 -83.827112)
		(stroke
			(width 0.2)
			(type default)
		)
		(layer "In10.Cu")
	)
	(gr_arc
		(start 240.871756 -66.57721)
		(mid 239.92498 -66.882395)
		(end 240.236502 -67.827144)
		(stroke
			(width 0.2)
			(type default)
		)
		(layer "In10.Cu")
	)
	(gr_arc
		(start 240.871756 -62.577218)
		(mid 239.92498 -62.882403)
		(end 240.236502 -63.827152)
		(stroke
			(width 0.2)
			(type default)
		)
		(layer "In10.Cu")
	)
	(gr_arc
		(start 240.871756 -58.577226)
		(mid 239.92498 -58.882411)
		(end 240.236502 -59.82716)
		(stroke
			(width 0.2)
			(type default)
		)
		(layer "In10.Cu")
	)
	(gr_arc
		(start 240.871756 -54.577234)
		(mid 239.92498 -54.882419)
		(end 240.236502 -55.827168)
		(stroke
			(width 0.2)
			(type default)
		)
		(layer "In10.Cu")
	)
	(gr_arc
		(start 240.871756 -46.57725)
		(mid 239.92498 -46.882435)
		(end 240.236502 -47.827184)
		(stroke
			(width 0.2)
			(type default)
		)
		(layer "In10.Cu")
	)
	(gr_arc
		(start 240.871756 -42.577258)
		(mid 239.92498 -42.882443)
		(end 240.236502 -43.827192)
		(stroke
			(width 0.2)
			(type default)
		)
		(layer "In10.Cu")
	)
	(gr_arc
		(start 240.871756 -38.577266)
		(mid 239.92498 -38.882451)
		(end 240.236502 -39.8272)
		(stroke
			(width 0.2)
			(type default)
		)
		(layer "In10.Cu")
	)
	(gr_arc
		(start 240.874804 -134.850124)
		(mid 239.900206 -135.17499)
		(end 240.225072 -136.149588)
		(stroke
			(width 0.2)
			(type default)
		)
		(layer "In10.Cu")
	)
	(gr_arc
		(start 240.874804 -106.85018)
		(mid 239.900206 -107.175046)
		(end 240.225072 -108.149644)
		(stroke
			(width 0.2)
			(type default)
		)
		(layer "In10.Cu")
	)
	(gr_line
		(start 240.876074 -134.847838)
		(end 240.874804 -134.850124)
		(stroke
			(width 0.2)
			(type default)
		)
		(layer "In10.Cu")
	)
	(gr_line
		(start 240.876074 -106.847894)
		(end 240.874804 -106.85018)
		(stroke
			(width 0.2)
			(type default)
		)
		(layer "In10.Cu")
	)
	(gr_arc
		(start 240.876074 -34.548064)
		(mid 239.89792 -34.873946)
		(end 240.223802 -35.8521)
		(stroke
			(width 0.2)
			(type default)
		)
		(layer "In10.Cu")
	)
	(gr_arc
		(start 240.87709 -158.845504)
		(mid 239.895634 -159.172656)
		(end 240.222786 -160.154112)
		(stroke
			(width 0.2)
			(type default)
		)
		(layer "In10.Cu")
	)
	(gr_arc
		(start 240.87709 -154.845512)
		(mid 239.895634 -155.172664)
		(end 240.222786 -156.15412)
		(stroke
			(width 0.2)
			(type default)
		)
		(layer "In10.Cu")
	)
	(gr_arc
		(start 240.87709 -118.845584)
		(mid 239.895634 -119.172736)
		(end 240.222786 -120.154192)
		(stroke
			(width 0.2)
			(type default)
		)
		(layer "In10.Cu")
	)
	(gr_arc
		(start 240.877344 -162.845496)
		(mid 239.895939 -163.172546)
		(end 240.222786 -164.154104)
		(stroke
			(width 0.2)
			(type default)
		)
		(layer "In10.Cu")
	)
	(gr_arc
		(start 240.877344 -150.84552)
		(mid 239.895939 -151.17257)
		(end 240.222786 -152.154128)
		(stroke
			(width 0.2)
			(type default)
		)
		(layer "In10.Cu")
	)
	(gr_arc
		(start 240.877344 -114.845592)
		(mid 239.895939 -115.172642)
		(end 240.222786 -116.1542)
		(stroke
			(width 0.2)
			(type default)
		)
		(layer "In10.Cu")
	)
	(gr_arc
		(start 240.880392 -122.838718)
		(mid 239.888776 -123.169426)
		(end 240.219484 -124.161042)
		(stroke
			(width 0.2)
			(type default)
		)
		(layer "In10.Cu")
	)
	(gr_arc
		(start 240.891822 -126.844552)
		(mid 239.891674 -127.163691)
		(end 240.219484 -128.161034)
		(stroke
			(width 0.2)
			(type default)
		)
		(layer "In10.Cu")
	)
	(gr_arc
		(start 242.20805 -125.155198)
		(mid 243.208198 -124.836059)
		(end 242.880388 -123.838716)
		(stroke
			(width 0.2)
			(type default)
		)
		(layer "In10.Cu")
	)
	(gr_arc
		(start 242.21948 -129.161032)
		(mid 243.211096 -128.830324)
		(end 242.880388 -127.838708)
		(stroke
			(width 0.2)
			(type default)
		)
		(layer "In10.Cu")
	)
	(gr_arc
		(start 242.222528 -161.15411)
		(mid 243.204289 -160.82711)
		(end 242.877086 -159.845502)
		(stroke
			(width 0.2)
			(type default)
		)
		(layer "In10.Cu")
	)
	(gr_arc
		(start 242.222528 -157.154118)
		(mid 243.204289 -156.827118)
		(end 242.877086 -155.84551)
		(stroke
			(width 0.2)
			(type default)
		)
		(layer "In10.Cu")
	)
	(gr_arc
		(start 242.222528 -121.15419)
		(mid 243.204289 -120.82719)
		(end 242.877086 -119.845582)
		(stroke
			(width 0.2)
			(type default)
		)
		(layer "In10.Cu")
	)
	(gr_arc
		(start 242.222782 -165.154102)
		(mid 243.204238 -164.82695)
		(end 242.877086 -163.845494)
		(stroke
			(width 0.2)
			(type default)
		)
		(layer "In10.Cu")
	)
	(gr_arc
		(start 242.222782 -153.154126)
		(mid 243.204238 -152.826974)
		(end 242.877086 -151.845518)
		(stroke
			(width 0.2)
			(type default)
		)
		(layer "In10.Cu")
	)
	(gr_arc
		(start 242.222782 -117.154198)
		(mid 243.204238 -116.827046)
		(end 242.877086 -115.84559)
		(stroke
			(width 0.2)
			(type default)
		)
		(layer "In10.Cu")
	)
	(gr_line
		(start 242.223798 -137.151872)
		(end 242.224052 -137.151618)
		(stroke
			(width 0.2)
			(type default)
		)
		(layer "In10.Cu")
	)
	(gr_line
		(start 242.223798 -109.151928)
		(end 242.224052 -109.151674)
		(stroke
			(width 0.2)
			(type default)
		)
		(layer "In10.Cu")
	)
	(gr_arc
		(start 242.223798 -36.852098)
		(mid 243.201952 -36.526216)
		(end 242.87607 -35.548062)
		(stroke
			(width 0.2)
			(type default)
		)
		(layer "In10.Cu")
	)
	(gr_line
		(start 242.224052 -137.151618)
		(end 242.225068 -137.149586)
		(stroke
			(width 0.2)
			(type default)
		)
		(layer "In10.Cu")
	)
	(gr_line
		(start 242.224052 -109.151674)
		(end 242.225068 -109.149642)
		(stroke
			(width 0.2)
			(type default)
		)
		(layer "In10.Cu")
	)
	(gr_arc
		(start 242.225068 -137.149586)
		(mid 243.199666 -136.82472)
		(end 242.8748 -135.850122)
		(stroke
			(width 0.2)
			(type default)
		)
		(layer "In10.Cu")
	)
	(gr_arc
		(start 242.225068 -109.149642)
		(mid 243.199666 -108.824776)
		(end 242.8748 -107.850178)
		(stroke
			(width 0.2)
			(type default)
		)
		(layer "In10.Cu")
	)
	(gr_arc
		(start 242.228116 -80.8228)
		(mid 243.174892 -80.517615)
		(end 242.86337 -79.572866)
		(stroke
			(width 0.2)
			(type default)
		)
		(layer "In10.Cu")
	)
	(gr_arc
		(start 242.228116 -76.822808)
		(mid 243.174892 -76.517623)
		(end 242.86337 -75.572874)
		(stroke
			(width 0.2)
			(type default)
		)
		(layer "In10.Cu")
	)
	(gr_arc
		(start 242.228116 -72.822816)
		(mid 243.174892 -72.517631)
		(end 242.86337 -71.572882)
		(stroke
			(width 0.2)
			(type default)
		)
		(layer "In10.Cu")
	)
	(gr_arc
		(start 242.228116 -52.822856)
		(mid 243.174892 -52.517671)
		(end 242.86337 -51.572922)
		(stroke
			(width 0.2)
			(type default)
		)
		(layer "In10.Cu")
	)
	(gr_arc
		(start 242.236498 -181.126892)
		(mid 243.17706 -180.813202)
		(end 242.86337 -179.87264)
		(stroke
			(width 0.2)
			(type default)
		)
		(layer "In10.Cu")
	)
	(gr_arc
		(start 242.236498 -177.1269)
		(mid 243.17706 -176.81321)
		(end 242.86337 -175.872648)
		(stroke
			(width 0.2)
			(type default)
		)
		(layer "In10.Cu")
	)
	(gr_arc
		(start 242.236498 -173.126908)
		(mid 243.17706 -172.813218)
		(end 242.86337 -171.872656)
		(stroke
			(width 0.2)
			(type default)
		)
		(layer "In10.Cu")
	)
	(gr_arc
		(start 242.236498 -169.126916)
		(mid 243.17706 -168.813226)
		(end 242.86337 -167.872664)
		(stroke
			(width 0.2)
			(type default)
		)
		(layer "In10.Cu")
	)
	(gr_arc
		(start 242.236498 -84.82711)
		(mid 243.17706 -84.51342)
		(end 242.86337 -83.572858)
		(stroke
			(width 0.2)
			(type default)
		)
		(layer "In10.Cu")
	)
	(gr_arc
		(start 242.236498 -68.827142)
		(mid 243.17706 -68.513452)
		(end 242.86337 -67.57289)
		(stroke
			(width 0.2)
			(type default)
		)
		(layer "In10.Cu")
	)
	(gr_arc
		(start 242.236498 -64.82715)
		(mid 243.17706 -64.51346)
		(end 242.86337 -63.572898)
		(stroke
			(width 0.2)
			(type default)
		)
		(layer "In10.Cu")
	)
	(gr_arc
		(start 242.236498 -60.827158)
		(mid 243.17706 -60.513468)
		(end 242.86337 -59.572906)
		(stroke
			(width 0.2)
			(type default)
		)
		(layer "In10.Cu")
	)
	(gr_arc
		(start 242.236498 -56.827166)
		(mid 243.17706 -56.513476)
		(end 242.86337 -55.572914)
		(stroke
			(width 0.2)
			(type default)
		)
		(layer "In10.Cu")
	)
	(gr_arc
		(start 242.236498 -48.827182)
		(mid 243.17706 -48.513492)
		(end 242.86337 -47.57293)
		(stroke
			(width 0.2)
			(type default)
		)
		(layer "In10.Cu")
	)
	(gr_arc
		(start 242.236498 -44.82719)
		(mid 243.17706 -44.5135)
		(end 242.86337 -43.572938)
		(stroke
			(width 0.2)
			(type default)
		)
		(layer "In10.Cu")
	)
	(gr_arc
		(start 242.236498 -40.827198)
		(mid 243.17706 -40.513508)
		(end 242.86337 -39.572946)
		(stroke
			(width 0.2)
			(type default)
		)
		(layer "In10.Cu")
	)
	(gr_line
		(start 242.86337 -179.87264)
		(end 240.871756 -178.87696)
		(stroke
			(width 0.2)
			(type default)
		)
		(layer "In10.Cu")
	)
	(gr_line
		(start 242.86337 -175.872648)
		(end 240.871756 -174.876968)
		(stroke
			(width 0.2)
			(type default)
		)
		(layer "In10.Cu")
	)
	(gr_line
		(start 242.86337 -171.872656)
		(end 240.871756 -170.876976)
		(stroke
			(width 0.2)
			(type default)
		)
		(layer "In10.Cu")
	)
	(gr_line
		(start 242.86337 -167.872664)
		(end 240.871756 -166.876984)
		(stroke
			(width 0.2)
			(type default)
		)
		(layer "In10.Cu")
	)
	(gr_line
		(start 242.86337 -83.572858)
		(end 240.871756 -82.577178)
		(stroke
			(width 0.2)
			(type default)
		)
		(layer "In10.Cu")
	)
	(gr_line
		(start 242.86337 -79.572866)
		(end 240.863374 -78.572868)
		(stroke
			(width 0.2)
			(type default)
		)
		(layer "In10.Cu")
	)
	(gr_line
		(start 242.86337 -75.572874)
		(end 240.863374 -74.572876)
		(stroke
			(width 0.2)
			(type default)
		)
		(layer "In10.Cu")
	)
	(gr_line
		(start 242.86337 -71.572882)
		(end 240.863374 -70.572884)
		(stroke
			(width 0.2)
			(type default)
		)
		(layer "In10.Cu")
	)
	(gr_line
		(start 242.86337 -67.57289)
		(end 240.871756 -66.57721)
		(stroke
			(width 0.2)
			(type default)
		)
		(layer "In10.Cu")
	)
	(gr_line
		(start 242.86337 -63.572898)
		(end 240.871756 -62.577218)
		(stroke
			(width 0.2)
			(type default)
		)
		(layer "In10.Cu")
	)
	(gr_line
		(start 242.86337 -59.572906)
		(end 240.871756 -58.577226)
		(stroke
			(width 0.2)
			(type default)
		)
		(layer "In10.Cu")
	)
	(gr_line
		(start 242.86337 -55.572914)
		(end 240.871756 -54.577234)
		(stroke
			(width 0.2)
			(type default)
		)
		(layer "In10.Cu")
	)
	(gr_line
		(start 242.86337 -51.572922)
		(end 240.863374 -50.572924)
		(stroke
			(width 0.2)
			(type default)
		)
		(layer "In10.Cu")
	)
	(gr_line
		(start 242.86337 -47.57293)
		(end 240.871756 -46.57725)
		(stroke
			(width 0.2)
			(type default)
		)
		(layer "In10.Cu")
	)
	(gr_line
		(start 242.86337 -43.572938)
		(end 240.871756 -42.577258)
		(stroke
			(width 0.2)
			(type default)
		)
		(layer "In10.Cu")
	)
	(gr_line
		(start 242.86337 -39.572946)
		(end 240.871756 -38.577266)
		(stroke
			(width 0.2)
			(type default)
		)
		(layer "In10.Cu")
	)
	(gr_line
		(start 242.8748 -135.850122)
		(end 242.87607 -135.847836)
		(stroke
			(width 0.2)
			(type default)
		)
		(layer "In10.Cu")
	)
	(gr_line
		(start 242.8748 -107.850178)
		(end 242.87607 -107.847892)
		(stroke
			(width 0.2)
			(type default)
		)
		(layer "In10.Cu")
	)
	(gr_line
		(start 242.87607 -135.847836)
		(end 240.876074 -134.847838)
		(stroke
			(width 0.2)
			(type default)
		)
		(layer "In10.Cu")
	)
	(gr_line
		(start 242.87607 -107.847892)
		(end 240.876074 -106.847894)
		(stroke
			(width 0.2)
			(type default)
		)
		(layer "In10.Cu")
	)
	(gr_line
		(start 242.87607 -35.548062)
		(end 240.876074 -34.548064)
		(stroke
			(width 0.2)
			(type default)
		)
		(layer "In10.Cu")
	)
	(gr_line
		(start 242.877086 -163.845494)
		(end 240.877344 -162.845496)
		(stroke
			(width 0.2)
			(type default)
		)
		(layer "In10.Cu")
	)
	(gr_line
		(start 242.877086 -159.845502)
		(end 240.87709 -158.845504)
		(stroke
			(width 0.2)
			(type default)
		)
		(layer "In10.Cu")
	)
	(gr_line
		(start 242.877086 -155.84551)
		(end 240.87709 -154.845512)
		(stroke
			(width 0.2)
			(type default)
		)
		(layer "In10.Cu")
	)
	(gr_line
		(start 242.877086 -151.845518)
		(end 240.877344 -150.84552)
		(stroke
			(width 0.2)
			(type default)
		)
		(layer "In10.Cu")
	)
	(gr_line
		(start 242.877086 -119.845582)
		(end 240.87709 -118.845584)
		(stroke
			(width 0.2)
			(type default)
		)
		(layer "In10.Cu")
	)
	(gr_line
		(start 242.877086 -115.84559)
		(end 240.877344 -114.845592)
		(stroke
			(width 0.2)
			(type default)
		)
		(layer "In10.Cu")
	)
	(gr_line
		(start 242.880388 -127.838708)
		(end 240.891822 -126.844552)
		(stroke
			(width 0.2)
			(type default)
		)
		(layer "In10.Cu")
	)
	(gr_line
		(start 242.880388 -123.838716)
		(end 240.880392 -122.838718)
		(stroke
			(width 0.2)
			(type default)
		)
		(layer "In10.Cu")
	)
	(gr_line
		(start 271.9705 -359.885996)
		(end 273.1135 -359.885996)
		(stroke
			(width 0.2)
			(type default)
		)
		(layer "In10.Cu")
	)
	(gr_line
		(start 271.9705 -358.085898)
		(end 273.1135 -358.085898)
		(stroke
			(width 0.2)
			(type default)
		)
		(layer "In10.Cu")
	)
	(gr_line
		(start 271.9705 -356.286054)
		(end 273.1135 -356.286054)
		(stroke
			(width 0.2)
			(type default)
		)
		(layer "In10.Cu")
	)
	(gr_line
		(start 271.9705 -354.485956)
		(end 273.1135 -354.485956)
		(stroke
			(width 0.2)
			(type default)
		)
		(layer "In10.Cu")
	)
	(gr_line
		(start 271.9705 -352.686112)
		(end 273.1135 -352.686112)
		(stroke
			(width 0.2)
			(type default)
		)
		(layer "In10.Cu")
	)
	(gr_line
		(start 271.9705 -350.886014)
		(end 273.1135 -350.886014)
		(stroke
			(width 0.2)
			(type default)
		)
		(layer "In10.Cu")
	)
	(gr_line
		(start 271.9705 -338.28863)
		(end 273.1135 -338.28863)
		(stroke
			(width 0.2)
			(type default)
		)
		(layer "In10.Cu")
	)
	(gr_line
		(start 271.9705 -336.488532)
		(end 273.1135 -336.488532)
		(stroke
			(width 0.2)
			(type default)
		)
		(layer "In10.Cu")
	)
	(gr_line
		(start 271.9705 -334.688434)
		(end 273.1135 -334.688434)
		(stroke
			(width 0.2)
			(type default)
		)
		(layer "In10.Cu")
	)
	(gr_line
		(start 271.9705 -332.88859)
		(end 273.1135 -332.88859)
		(stroke
			(width 0.2)
			(type default)
		)
		(layer "In10.Cu")
	)
	(gr_line
		(start 271.9705 -331.088492)
		(end 273.1135 -331.088492)
		(stroke
			(width 0.2)
			(type default)
		)
		(layer "In10.Cu")
	)
	(gr_line
		(start 271.9705 -329.288648)
		(end 273.1135 -329.288648)
		(stroke
			(width 0.2)
			(type default)
		)
		(layer "In10.Cu")
	)
	(gr_line
		(start 271.9705 -316.68847)
		(end 273.1135 -316.68847)
		(stroke
			(width 0.2)
			(type default)
		)
		(layer "In10.Cu")
	)
	(gr_line
		(start 271.9705 -314.888626)
		(end 273.1135 -314.888626)
		(stroke
			(width 0.2)
			(type default)
		)
		(layer "In10.Cu")
	)
	(gr_line
		(start 271.9705 -313.088528)
		(end 273.1135 -313.088528)
		(stroke
			(width 0.2)
			(type default)
		)
		(layer "In10.Cu")
	)
	(gr_line
		(start 271.9705 -311.28843)
		(end 273.1135 -311.28843)
		(stroke
			(width 0.2)
			(type default)
		)
		(layer "In10.Cu")
	)
	(gr_line
		(start 271.9705 -309.488586)
		(end 273.1135 -309.488586)
		(stroke
			(width 0.2)
			(type default)
		)
		(layer "In10.Cu")
	)
	(gr_line
		(start 271.9705 -307.688488)
		(end 273.1135 -307.688488)
		(stroke
			(width 0.2)
			(type default)
		)
		(layer "In10.Cu")
	)
	(gr_arc
		(start 271.970754 -359.123996)
		(mid 271.5895 -359.504869)
		(end 271.9705 -359.885996)
		(stroke
			(width 0.2)
			(type default)
		)
		(layer "In10.Cu")
	)
	(gr_arc
		(start 271.970754 -357.323898)
		(mid 271.5895 -357.704771)
		(end 271.9705 -358.085898)
		(stroke
			(width 0.2)
			(type default)
		)
		(layer "In10.Cu")
	)
	(gr_arc
		(start 271.970754 -355.524054)
		(mid 271.5895 -355.904927)
		(end 271.9705 -356.286054)
		(stroke
			(width 0.2)
			(type default)
		)
		(layer "In10.Cu")
	)
	(gr_arc
		(start 271.970754 -353.723956)
		(mid 271.5895 -354.104829)
		(end 271.9705 -354.485956)
		(stroke
			(width 0.2)
			(type default)
		)
		(layer "In10.Cu")
	)
	(gr_arc
		(start 271.970754 -351.924112)
		(mid 271.5895 -352.304985)
		(end 271.9705 -352.686112)
		(stroke
			(width 0.2)
			(type default)
		)
		(layer "In10.Cu")
	)
	(gr_arc
		(start 271.970754 -350.124014)
		(mid 271.5895 -350.504887)
		(end 271.9705 -350.886014)
		(stroke
			(width 0.2)
			(type default)
		)
		(layer "In10.Cu")
	)
	(gr_arc
		(start 271.970754 -337.52155)
		(mid 271.58696 -337.904963)
		(end 271.9705 -338.28863)
		(stroke
			(width 0.2)
			(type default)
		)
		(layer "In10.Cu")
	)
	(gr_arc
		(start 271.970754 -335.721452)
		(mid 271.58696 -336.104865)
		(end 271.9705 -336.488532)
		(stroke
			(width 0.2)
			(type default)
		)
		(layer "In10.Cu")
	)
	(gr_arc
		(start 271.970754 -333.921354)
		(mid 271.58696 -334.304767)
		(end 271.9705 -334.688434)
		(stroke
			(width 0.2)
			(type default)
		)
		(layer "In10.Cu")
	)
	(gr_arc
		(start 271.970754 -332.12151)
		(mid 271.58696 -332.504923)
		(end 271.9705 -332.88859)
		(stroke
			(width 0.2)
			(type default)
		)
		(layer "In10.Cu")
	)
	(gr_arc
		(start 271.970754 -330.321412)
		(mid 271.58696 -330.704825)
		(end 271.9705 -331.088492)
		(stroke
			(width 0.2)
			(type default)
		)
		(layer "In10.Cu")
	)
	(gr_arc
		(start 271.970754 -328.521568)
		(mid 271.58696 -328.904981)
		(end 271.9705 -329.288648)
		(stroke
			(width 0.2)
			(type default)
		)
		(layer "In10.Cu")
	)
	(gr_arc
		(start 271.970754 -315.92139)
		(mid 271.58696 -316.304803)
		(end 271.9705 -316.68847)
		(stroke
			(width 0.2)
			(type default)
		)
		(layer "In10.Cu")
	)
	(gr_arc
		(start 271.970754 -314.121546)
		(mid 271.58696 -314.504959)
		(end 271.9705 -314.888626)
		(stroke
			(width 0.2)
			(type default)
		)
		(layer "In10.Cu")
	)
	(gr_arc
		(start 271.970754 -312.321448)
		(mid 271.58696 -312.704861)
		(end 271.9705 -313.088528)
		(stroke
			(width 0.2)
			(type default)
		)
		(layer "In10.Cu")
	)
	(gr_arc
		(start 271.970754 -310.52135)
		(mid 271.58696 -310.904763)
		(end 271.9705 -311.28843)
		(stroke
			(width 0.2)
			(type default)
		)
		(layer "In10.Cu")
	)
	(gr_arc
		(start 271.970754 -308.721506)
		(mid 271.58696 -309.104919)
		(end 271.9705 -309.488586)
		(stroke
			(width 0.2)
			(type default)
		)
		(layer "In10.Cu")
	)
	(gr_arc
		(start 271.970754 -306.921408)
		(mid 271.58696 -307.304821)
		(end 271.9705 -307.688488)
		(stroke
			(width 0.2)
			(type default)
		)
		(layer "In10.Cu")
	)
	(gr_arc
		(start 273.1135 -359.885996)
		(mid 273.4945 -359.504996)
		(end 273.1135 -359.123996)
		(stroke
			(width 0.2)
			(type default)
		)
		(layer "In10.Cu")
	)
	(gr_line
		(start 273.1135 -359.123996)
		(end 271.970754 -359.123996)
		(stroke
			(width 0.2)
			(type default)
		)
		(layer "In10.Cu")
	)
	(gr_arc
		(start 273.1135 -358.085898)
		(mid 273.4945 -357.704898)
		(end 273.1135 -357.323898)
		(stroke
			(width 0.2)
			(type default)
		)
		(layer "In10.Cu")
	)
	(gr_line
		(start 273.1135 -357.323898)
		(end 271.970754 -357.323898)
		(stroke
			(width 0.2)
			(type default)
		)
		(layer "In10.Cu")
	)
	(gr_arc
		(start 273.1135 -356.286054)
		(mid 273.4945 -355.905054)
		(end 273.1135 -355.524054)
		(stroke
			(width 0.2)
			(type default)
		)
		(layer "In10.Cu")
	)
	(gr_line
		(start 273.1135 -355.524054)
		(end 271.970754 -355.524054)
		(stroke
			(width 0.2)
			(type default)
		)
		(layer "In10.Cu")
	)
	(gr_arc
		(start 273.1135 -354.485956)
		(mid 273.4945 -354.104956)
		(end 273.1135 -353.723956)
		(stroke
			(width 0.2)
			(type default)
		)
		(layer "In10.Cu")
	)
	(gr_line
		(start 273.1135 -353.723956)
		(end 271.970754 -353.723956)
		(stroke
			(width 0.2)
			(type default)
		)
		(layer "In10.Cu")
	)
	(gr_arc
		(start 273.1135 -352.686112)
		(mid 273.4945 -352.305112)
		(end 273.1135 -351.924112)
		(stroke
			(width 0.2)
			(type default)
		)
		(layer "In10.Cu")
	)
	(gr_line
		(start 273.1135 -351.924112)
		(end 271.970754 -351.924112)
		(stroke
			(width 0.2)
			(type default)
		)
		(layer "In10.Cu")
	)
	(gr_arc
		(start 273.1135 -350.886014)
		(mid 273.4945 -350.505014)
		(end 273.1135 -350.124014)
		(stroke
			(width 0.2)
			(type default)
		)
		(layer "In10.Cu")
	)
	(gr_line
		(start 273.1135 -350.124014)
		(end 271.970754 -350.124014)
		(stroke
			(width 0.2)
			(type default)
		)
		(layer "In10.Cu")
	)
	(gr_arc
		(start 273.1135 -338.28863)
		(mid 273.49704 -337.90509)
		(end 273.1135 -337.52155)
		(stroke
			(width 0.2)
			(type default)
		)
		(layer "In10.Cu")
	)
	(gr_line
		(start 273.1135 -337.52155)
		(end 271.970754 -337.52155)
		(stroke
			(width 0.2)
			(type default)
		)
		(layer "In10.Cu")
	)
	(gr_arc
		(start 273.1135 -336.488532)
		(mid 273.49704 -336.104992)
		(end 273.1135 -335.721452)
		(stroke
			(width 0.2)
			(type default)
		)
		(layer "In10.Cu")
	)
	(gr_line
		(start 273.1135 -335.721452)
		(end 271.970754 -335.721452)
		(stroke
			(width 0.2)
			(type default)
		)
		(layer "In10.Cu")
	)
	(gr_arc
		(start 273.1135 -334.688434)
		(mid 273.49704 -334.304894)
		(end 273.1135 -333.921354)
		(stroke
			(width 0.2)
			(type default)
		)
		(layer "In10.Cu")
	)
	(gr_line
		(start 273.1135 -333.921354)
		(end 271.970754 -333.921354)
		(stroke
			(width 0.2)
			(type default)
		)
		(layer "In10.Cu")
	)
	(gr_arc
		(start 273.1135 -332.88859)
		(mid 273.49704 -332.50505)
		(end 273.1135 -332.12151)
		(stroke
			(width 0.2)
			(type default)
		)
		(layer "In10.Cu")
	)
	(gr_line
		(start 273.1135 -332.12151)
		(end 271.970754 -332.12151)
		(stroke
			(width 0.2)
			(type default)
		)
		(layer "In10.Cu")
	)
	(gr_arc
		(start 273.1135 -331.088492)
		(mid 273.49704 -330.704952)
		(end 273.1135 -330.321412)
		(stroke
			(width 0.2)
			(type default)
		)
		(layer "In10.Cu")
	)
	(gr_line
		(start 273.1135 -330.321412)
		(end 271.970754 -330.321412)
		(stroke
			(width 0.2)
			(type default)
		)
		(layer "In10.Cu")
	)
	(gr_arc
		(start 273.1135 -329.288648)
		(mid 273.49704 -328.905108)
		(end 273.1135 -328.521568)
		(stroke
			(width 0.2)
			(type default)
		)
		(layer "In10.Cu")
	)
	(gr_line
		(start 273.1135 -328.521568)
		(end 271.970754 -328.521568)
		(stroke
			(width 0.2)
			(type default)
		)
		(layer "In10.Cu")
	)
	(gr_arc
		(start 273.1135 -316.68847)
		(mid 273.49704 -316.30493)
		(end 273.1135 -315.92139)
		(stroke
			(width 0.2)
			(type default)
		)
		(layer "In10.Cu")
	)
	(gr_line
		(start 273.1135 -315.92139)
		(end 271.970754 -315.92139)
		(stroke
			(width 0.2)
			(type default)
		)
		(layer "In10.Cu")
	)
	(gr_arc
		(start 273.1135 -314.888626)
		(mid 273.49704 -314.505086)
		(end 273.1135 -314.121546)
		(stroke
			(width 0.2)
			(type default)
		)
		(layer "In10.Cu")
	)
	(gr_line
		(start 273.1135 -314.121546)
		(end 271.970754 -314.121546)
		(stroke
			(width 0.2)
			(type default)
		)
		(layer "In10.Cu")
	)
	(gr_arc
		(start 273.1135 -313.088528)
		(mid 273.49704 -312.704988)
		(end 273.1135 -312.321448)
		(stroke
			(width 0.2)
			(type default)
		)
		(layer "In10.Cu")
	)
	(gr_line
		(start 273.1135 -312.321448)
		(end 271.970754 -312.321448)
		(stroke
			(width 0.2)
			(type default)
		)
		(layer "In10.Cu")
	)
	(gr_arc
		(start 273.1135 -311.28843)
		(mid 273.49704 -310.90489)
		(end 273.1135 -310.52135)
		(stroke
			(width 0.2)
			(type default)
		)
		(layer "In10.Cu")
	)
	(gr_line
		(start 273.1135 -310.52135)
		(end 271.970754 -310.52135)
		(stroke
			(width 0.2)
			(type default)
		)
		(layer "In10.Cu")
	)
	(gr_arc
		(start 273.1135 -309.488586)
		(mid 273.49704 -309.105046)
		(end 273.1135 -308.721506)
		(stroke
			(width 0.2)
			(type default)
		)
		(layer "In10.Cu")
	)
	(gr_line
		(start 273.1135 -308.721506)
		(end 271.970754 -308.721506)
		(stroke
			(width 0.2)
			(type default)
		)
		(layer "In10.Cu")
	)
	(gr_arc
		(start 273.1135 -307.688488)
		(mid 273.49704 -307.304948)
		(end 273.1135 -306.921408)
		(stroke
			(width 0.2)
			(type default)
		)
		(layer "In10.Cu")
	)
	(gr_line
		(start 273.1135 -306.921408)
		(end 271.970754 -306.921408)
		(stroke
			(width 0.2)
			(type default)
		)
		(layer "In10.Cu")
	)
	(gr_line
		(start 278.23668 -356.453694)
		(end 279.636728 -356.453694)
		(stroke
			(width 0.2)
			(type default)
		)
		(layer "In10.Cu")
	)
	(gr_arc
		(start 278.23668 -355.356414)
		(mid 277.68804 -355.905054)
		(end 278.23668 -356.453694)
		(stroke
			(width 0.2)
			(type default)
		)
		(layer "In10.Cu")
	)
	(gr_line
		(start 278.23668 -352.853752)
		(end 279.636728 -352.853752)
		(stroke
			(width 0.2)
			(type default)
		)
		(layer "In10.Cu")
	)
	(gr_arc
		(start 278.23668 -351.756472)
		(mid 277.68804 -352.305112)
		(end 278.23668 -352.853752)
		(stroke
			(width 0.2)
			(type default)
		)
		(layer "In10.Cu")
	)
	(gr_line
		(start 278.23668 -349.25381)
		(end 279.636728 -349.25381)
		(stroke
			(width 0.2)
			(type default)
		)
		(layer "In10.Cu")
	)
	(gr_arc
		(start 278.23668 -348.15653)
		(mid 277.68804 -348.70517)
		(end 278.23668 -349.25381)
		(stroke
			(width 0.2)
			(type default)
		)
		(layer "In10.Cu")
	)
	(gr_line
		(start 278.23668 -345.653868)
		(end 279.636728 -345.653868)
		(stroke
			(width 0.2)
			(type default)
		)
		(layer "In10.Cu")
	)
	(gr_arc
		(start 278.23668 -344.556588)
		(mid 277.68804 -345.105228)
		(end 278.23668 -345.653868)
		(stroke
			(width 0.2)
			(type default)
		)
		(layer "In10.Cu")
	)
	(gr_line
		(start 278.23668 -342.053672)
		(end 279.636728 -342.053672)
		(stroke
			(width 0.2)
			(type default)
		)
		(layer "In10.Cu")
	)
	(gr_arc
		(start 278.23668 -340.956392)
		(mid 277.68804 -341.505032)
		(end 278.23668 -342.053672)
		(stroke
			(width 0.2)
			(type default)
		)
		(layer "In10.Cu")
	)
	(gr_line
		(start 278.23668 -338.45373)
		(end 279.636728 -338.45373)
		(stroke
			(width 0.2)
			(type default)
		)
		(layer "In10.Cu")
	)
	(gr_arc
		(start 278.23668 -337.35645)
		(mid 277.68804 -337.90509)
		(end 278.23668 -338.45373)
		(stroke
			(width 0.2)
			(type default)
		)
		(layer "In10.Cu")
	)
	(gr_line
		(start 278.23668 -334.853788)
		(end 279.636728 -334.853788)
		(stroke
			(width 0.2)
			(type default)
		)
		(layer "In10.Cu")
	)
	(gr_arc
		(start 278.23668 -333.756508)
		(mid 277.68804 -334.305148)
		(end 278.23668 -334.853788)
		(stroke
			(width 0.2)
			(type default)
		)
		(layer "In10.Cu")
	)
	(gr_line
		(start 278.23668 -331.253846)
		(end 279.636728 -331.253846)
		(stroke
			(width 0.2)
			(type default)
		)
		(layer "In10.Cu")
	)
	(gr_arc
		(start 278.23668 -330.156566)
		(mid 277.68804 -330.705206)
		(end 278.23668 -331.253846)
		(stroke
			(width 0.2)
			(type default)
		)
		(layer "In10.Cu")
	)
	(gr_line
		(start 278.23668 -327.653904)
		(end 279.636728 -327.653904)
		(stroke
			(width 0.2)
			(type default)
		)
		(layer "In10.Cu")
	)
	(gr_arc
		(start 278.23668 -326.556624)
		(mid 277.68804 -327.105264)
		(end 278.23668 -327.653904)
		(stroke
			(width 0.2)
			(type default)
		)
		(layer "In10.Cu")
	)
	(gr_line
		(start 278.23668 -324.053708)
		(end 279.636728 -324.053708)
		(stroke
			(width 0.2)
			(type default)
		)
		(layer "In10.Cu")
	)
	(gr_arc
		(start 278.23668 -322.956428)
		(mid 277.68804 -323.505068)
		(end 278.23668 -324.053708)
		(stroke
			(width 0.2)
			(type default)
		)
		(layer "In10.Cu")
	)
	(gr_line
		(start 278.23668 -320.453766)
		(end 279.636728 -320.453766)
		(stroke
			(width 0.2)
			(type default)
		)
		(layer "In10.Cu")
	)
	(gr_arc
		(start 278.23668 -319.356486)
		(mid 277.68804 -319.905126)
		(end 278.23668 -320.453766)
		(stroke
			(width 0.2)
			(type default)
		)
		(layer "In10.Cu")
	)
	(gr_line
		(start 278.23668 -316.853824)
		(end 279.636728 -316.853824)
		(stroke
			(width 0.2)
			(type default)
		)
		(layer "In10.Cu")
	)
	(gr_arc
		(start 278.23668 -315.756544)
		(mid 277.68804 -316.305184)
		(end 278.23668 -316.853824)
		(stroke
			(width 0.2)
			(type default)
		)
		(layer "In10.Cu")
	)
	(gr_line
		(start 278.23668 -313.253882)
		(end 279.636728 -313.253882)
		(stroke
			(width 0.2)
			(type default)
		)
		(layer "In10.Cu")
	)
	(gr_arc
		(start 278.23668 -312.156602)
		(mid 277.68804 -312.705242)
		(end 278.23668 -313.253882)
		(stroke
			(width 0.2)
			(type default)
		)
		(layer "In10.Cu")
	)
	(gr_line
		(start 278.23668 -309.653686)
		(end 279.636728 -309.653686)
		(stroke
			(width 0.2)
			(type default)
		)
		(layer "In10.Cu")
	)
	(gr_arc
		(start 278.23668 -308.556406)
		(mid 277.68804 -309.105046)
		(end 278.23668 -309.653686)
		(stroke
			(width 0.2)
			(type default)
		)
		(layer "In10.Cu")
	)
	(gr_line
		(start 278.23668 -306.053744)
		(end 279.636728 -306.053744)
		(stroke
			(width 0.2)
			(type default)
		)
		(layer "In10.Cu")
	)
	(gr_arc
		(start 278.23668 -304.956464)
		(mid 277.68804 -305.505104)
		(end 278.23668 -306.053744)
		(stroke
			(width 0.2)
			(type default)
		)
		(layer "In10.Cu")
	)
	(gr_line
		(start 278.23668 -302.453802)
		(end 279.636728 -302.453802)
		(stroke
			(width 0.2)
			(type default)
		)
		(layer "In10.Cu")
	)
	(gr_arc
		(start 278.23668 -301.356522)
		(mid 277.68804 -301.905162)
		(end 278.23668 -302.453802)
		(stroke
			(width 0.2)
			(type default)
		)
		(layer "In10.Cu")
	)
	(gr_line
		(start 278.23668 -298.85386)
		(end 279.636728 -298.85386)
		(stroke
			(width 0.2)
			(type default)
		)
		(layer "In10.Cu")
	)
	(gr_arc
		(start 278.23668 -297.75658)
		(mid 277.68804 -298.30522)
		(end 278.23668 -298.85386)
		(stroke
			(width 0.2)
			(type default)
		)
		(layer "In10.Cu")
	)
	(gr_line
		(start 278.23668 -295.253918)
		(end 279.636728 -295.253918)
		(stroke
			(width 0.2)
			(type default)
		)
		(layer "In10.Cu")
	)
	(gr_arc
		(start 278.23668 -294.156638)
		(mid 277.68804 -294.705278)
		(end 278.23668 -295.253918)
		(stroke
			(width 0.2)
			(type default)
		)
		(layer "In10.Cu")
	)
	(gr_line
		(start 278.23668 -262.453374)
		(end 279.636728 -262.453374)
		(stroke
			(width 0.2)
			(type default)
		)
		(layer "In10.Cu")
	)
	(gr_arc
		(start 278.23668 -261.351014)
		(mid 277.6855 -261.902194)
		(end 278.23668 -262.453374)
		(stroke
			(width 0.2)
			(type default)
		)
		(layer "In10.Cu")
	)
	(gr_line
		(start 278.23668 -258.853432)
		(end 279.636728 -258.853432)
		(stroke
			(width 0.2)
			(type default)
		)
		(layer "In10.Cu")
	)
	(gr_arc
		(start 278.23668 -257.751072)
		(mid 277.6855 -258.302252)
		(end 278.23668 -258.853432)
		(stroke
			(width 0.2)
			(type default)
		)
		(layer "In10.Cu")
	)
	(gr_line
		(start 278.23668 -255.25349)
		(end 279.636728 -255.25349)
		(stroke
			(width 0.2)
			(type default)
		)
		(layer "In10.Cu")
	)
	(gr_arc
		(start 278.23668 -254.15113)
		(mid 277.6855 -254.70231)
		(end 278.23668 -255.25349)
		(stroke
			(width 0.2)
			(type default)
		)
		(layer "In10.Cu")
	)
	(gr_line
		(start 278.23668 -251.653548)
		(end 279.636728 -251.653548)
		(stroke
			(width 0.2)
			(type default)
		)
		(layer "In10.Cu")
	)
	(gr_arc
		(start 278.23668 -250.551188)
		(mid 277.6855 -251.102368)
		(end 278.23668 -251.653548)
		(stroke
			(width 0.2)
			(type default)
		)
		(layer "In10.Cu")
	)
	(gr_line
		(start 278.236934 -355.356414)
		(end 278.23668 -355.356414)
		(stroke
			(width 0.2)
			(type default)
		)
		(layer "In10.Cu")
	)
	(gr_line
		(start 278.236934 -351.756472)
		(end 278.23668 -351.756472)
		(stroke
			(width 0.2)
			(type default)
		)
		(layer "In10.Cu")
	)
	(gr_line
		(start 278.236934 -348.15653)
		(end 278.23668 -348.15653)
		(stroke
			(width 0.2)
			(type default)
		)
		(layer "In10.Cu")
	)
	(gr_line
		(start 278.236934 -344.556588)
		(end 278.23668 -344.556588)
		(stroke
			(width 0.2)
			(type default)
		)
		(layer "In10.Cu")
	)
	(gr_line
		(start 278.236934 -340.956392)
		(end 278.23668 -340.956392)
		(stroke
			(width 0.2)
			(type default)
		)
		(layer "In10.Cu")
	)
	(gr_line
		(start 278.236934 -337.35645)
		(end 278.23668 -337.35645)
		(stroke
			(width 0.2)
			(type default)
		)
		(layer "In10.Cu")
	)
	(gr_line
		(start 278.236934 -333.756508)
		(end 278.23668 -333.756508)
		(stroke
			(width 0.2)
			(type default)
		)
		(layer "In10.Cu")
	)
	(gr_line
		(start 278.236934 -330.156566)
		(end 278.23668 -330.156566)
		(stroke
			(width 0.2)
			(type default)
		)
		(layer "In10.Cu")
	)
	(gr_line
		(start 278.236934 -326.556624)
		(end 278.23668 -326.556624)
		(stroke
			(width 0.2)
			(type default)
		)
		(layer "In10.Cu")
	)
	(gr_line
		(start 278.236934 -322.956428)
		(end 278.23668 -322.956428)
		(stroke
			(width 0.2)
			(type default)
		)
		(layer "In10.Cu")
	)
	(gr_line
		(start 278.236934 -319.356486)
		(end 278.23668 -319.356486)
		(stroke
			(width 0.2)
			(type default)
		)
		(layer "In10.Cu")
	)
	(gr_line
		(start 278.236934 -315.756544)
		(end 278.23668 -315.756544)
		(stroke
			(width 0.2)
			(type default)
		)
		(layer "In10.Cu")
	)
	(gr_line
		(start 278.236934 -312.156602)
		(end 278.23668 -312.156602)
		(stroke
			(width 0.2)
			(type default)
		)
		(layer "In10.Cu")
	)
	(gr_line
		(start 278.236934 -308.556406)
		(end 278.23668 -308.556406)
		(stroke
			(width 0.2)
			(type default)
		)
		(layer "In10.Cu")
	)
	(gr_line
		(start 278.236934 -304.956464)
		(end 278.23668 -304.956464)
		(stroke
			(width 0.2)
			(type default)
		)
		(layer "In10.Cu")
	)
	(gr_line
		(start 278.236934 -301.356522)
		(end 278.23668 -301.356522)
		(stroke
			(width 0.2)
			(type default)
		)
		(layer "In10.Cu")
	)
	(gr_line
		(start 278.236934 -297.75658)
		(end 278.23668 -297.75658)
		(stroke
			(width 0.2)
			(type default)
		)
		(layer "In10.Cu")
	)
	(gr_line
		(start 278.236934 -294.156638)
		(end 278.23668 -294.156638)
		(stroke
			(width 0.2)
			(type default)
		)
		(layer "In10.Cu")
	)
	(gr_line
		(start 278.236934 -261.351014)
		(end 278.23668 -261.351014)
		(stroke
			(width 0.2)
			(type default)
		)
		(layer "In10.Cu")
	)
	(gr_line
		(start 278.236934 -257.751072)
		(end 278.23668 -257.751072)
		(stroke
			(width 0.2)
			(type default)
		)
		(layer "In10.Cu")
	)
	(gr_line
		(start 278.236934 -254.15113)
		(end 278.23668 -254.15113)
		(stroke
			(width 0.2)
			(type default)
		)
		(layer "In10.Cu")
	)
	(gr_line
		(start 278.236934 -250.551188)
		(end 278.23668 -250.551188)
		(stroke
			(width 0.2)
			(type default)
		)
		(layer "In10.Cu")
	)
	(gr_line
		(start 278.424132 -177.848006)
		(end 278.425148 -177.850038)
		(stroke
			(width 0.2)
			(type default)
		)
		(layer "In10.Cu")
	)
	(gr_line
		(start 278.424132 -177.847752)
		(end 278.424132 -177.848006)
		(stroke
			(width 0.2)
			(type default)
		)
		(layer "In10.Cu")
	)
	(gr_line
		(start 278.424132 -173.848014)
		(end 278.425148 -173.850046)
		(stroke
			(width 0.2)
			(type default)
		)
		(layer "In10.Cu")
	)
	(gr_line
		(start 278.424132 -173.84776)
		(end 278.424132 -173.848014)
		(stroke
			(width 0.2)
			(type default)
		)
		(layer "In10.Cu")
	)
	(gr_line
		(start 278.424132 -169.848022)
		(end 278.425148 -169.850054)
		(stroke
			(width 0.2)
			(type default)
		)
		(layer "In10.Cu")
	)
	(gr_line
		(start 278.424132 -169.847768)
		(end 278.424132 -169.848022)
		(stroke
			(width 0.2)
			(type default)
		)
		(layer "In10.Cu")
	)
	(gr_line
		(start 278.424132 -165.84803)
		(end 278.425148 -165.850062)
		(stroke
			(width 0.2)
			(type default)
		)
		(layer "In10.Cu")
	)
	(gr_line
		(start 278.424132 -165.847776)
		(end 278.424132 -165.84803)
		(stroke
			(width 0.2)
			(type default)
		)
		(layer "In10.Cu")
	)
	(gr_line
		(start 278.424132 -137.848086)
		(end 278.425148 -137.850118)
		(stroke
			(width 0.2)
			(type default)
		)
		(layer "In10.Cu")
	)
	(gr_line
		(start 278.424132 -137.847832)
		(end 278.424132 -137.848086)
		(stroke
			(width 0.2)
			(type default)
		)
		(layer "In10.Cu")
	)
	(gr_line
		(start 278.424132 -81.548224)
		(end 278.425148 -81.550256)
		(stroke
			(width 0.2)
			(type default)
		)
		(layer "In10.Cu")
	)
	(gr_line
		(start 278.424132 -81.54797)
		(end 278.424132 -81.548224)
		(stroke
			(width 0.2)
			(type default)
		)
		(layer "In10.Cu")
	)
	(gr_line
		(start 278.424132 -77.548232)
		(end 278.425148 -77.550264)
		(stroke
			(width 0.2)
			(type default)
		)
		(layer "In10.Cu")
	)
	(gr_line
		(start 278.424132 -77.547978)
		(end 278.424132 -77.548232)
		(stroke
			(width 0.2)
			(type default)
		)
		(layer "In10.Cu")
	)
	(gr_line
		(start 278.424132 -73.54824)
		(end 278.425148 -73.550272)
		(stroke
			(width 0.2)
			(type default)
		)
		(layer "In10.Cu")
	)
	(gr_line
		(start 278.424132 -73.547986)
		(end 278.424132 -73.54824)
		(stroke
			(width 0.2)
			(type default)
		)
		(layer "In10.Cu")
	)
	(gr_line
		(start 278.424132 -69.548248)
		(end 278.425148 -69.55028)
		(stroke
			(width 0.2)
			(type default)
		)
		(layer "In10.Cu")
	)
	(gr_line
		(start 278.424132 -69.547994)
		(end 278.424132 -69.548248)
		(stroke
			(width 0.2)
			(type default)
		)
		(layer "In10.Cu")
	)
	(gr_line
		(start 278.424132 -65.548256)
		(end 278.425148 -65.550288)
		(stroke
			(width 0.2)
			(type default)
		)
		(layer "In10.Cu")
	)
	(gr_line
		(start 278.424132 -65.548002)
		(end 278.424132 -65.548256)
		(stroke
			(width 0.2)
			(type default)
		)
		(layer "In10.Cu")
	)
	(gr_line
		(start 278.424132 -61.548264)
		(end 278.425148 -61.550296)
		(stroke
			(width 0.2)
			(type default)
		)
		(layer "In10.Cu")
	)
	(gr_line
		(start 278.424132 -61.54801)
		(end 278.424132 -61.548264)
		(stroke
			(width 0.2)
			(type default)
		)
		(layer "In10.Cu")
	)
	(gr_line
		(start 278.424132 -57.548272)
		(end 278.425148 -57.550304)
		(stroke
			(width 0.2)
			(type default)
		)
		(layer "In10.Cu")
	)
	(gr_line
		(start 278.424132 -57.548018)
		(end 278.424132 -57.548272)
		(stroke
			(width 0.2)
			(type default)
		)
		(layer "In10.Cu")
	)
	(gr_line
		(start 278.424132 -53.54828)
		(end 278.425148 -53.550312)
		(stroke
			(width 0.2)
			(type default)
		)
		(layer "In10.Cu")
	)
	(gr_line
		(start 278.424132 -53.548026)
		(end 278.424132 -53.54828)
		(stroke
			(width 0.2)
			(type default)
		)
		(layer "In10.Cu")
	)
	(gr_line
		(start 278.424132 -49.548288)
		(end 278.425148 -49.55032)
		(stroke
			(width 0.2)
			(type default)
		)
		(layer "In10.Cu")
	)
	(gr_line
		(start 278.424132 -49.548034)
		(end 278.424132 -49.548288)
		(stroke
			(width 0.2)
			(type default)
		)
		(layer "In10.Cu")
	)
	(gr_line
		(start 278.424132 -45.548296)
		(end 278.425148 -45.550328)
		(stroke
			(width 0.2)
			(type default)
		)
		(layer "In10.Cu")
	)
	(gr_line
		(start 278.424132 -45.548042)
		(end 278.424132 -45.548296)
		(stroke
			(width 0.2)
			(type default)
		)
		(layer "In10.Cu")
	)
	(gr_line
		(start 278.424132 -41.548304)
		(end 278.425148 -41.550336)
		(stroke
			(width 0.2)
			(type default)
		)
		(layer "In10.Cu")
	)
	(gr_line
		(start 278.424132 -41.54805)
		(end 278.424132 -41.548304)
		(stroke
			(width 0.2)
			(type default)
		)
		(layer "In10.Cu")
	)
	(gr_line
		(start 278.424132 -37.548312)
		(end 278.425148 -37.550344)
		(stroke
			(width 0.2)
			(type default)
		)
		(layer "In10.Cu")
	)
	(gr_line
		(start 278.424132 -37.548058)
		(end 278.424132 -37.548312)
		(stroke
			(width 0.2)
			(type default)
		)
		(layer "In10.Cu")
	)
	(gr_line
		(start 278.424132 -17.548352)
		(end 278.425148 -17.550384)
		(stroke
			(width 0.2)
			(type default)
		)
		(layer "In10.Cu")
	)
	(gr_line
		(start 278.424132 -17.548098)
		(end 278.424132 -17.548352)
		(stroke
			(width 0.2)
			(type default)
		)
		(layer "In10.Cu")
	)
	(gr_arc
		(start 278.425148 -177.850038)
		(mid 278.100282 -178.824636)
		(end 279.07488 -179.149502)
		(stroke
			(width 0.2)
			(type default)
		)
		(layer "In10.Cu")
	)
	(gr_arc
		(start 278.425148 -173.850046)
		(mid 278.100282 -174.824644)
		(end 279.07488 -175.14951)
		(stroke
			(width 0.2)
			(type default)
		)
		(layer "In10.Cu")
	)
	(gr_arc
		(start 278.425148 -169.850054)
		(mid 278.100282 -170.824652)
		(end 279.07488 -171.149518)
		(stroke
			(width 0.2)
			(type default)
		)
		(layer "In10.Cu")
	)
	(gr_arc
		(start 278.425148 -165.850062)
		(mid 278.100282 -166.82466)
		(end 279.07488 -167.149526)
		(stroke
			(width 0.2)
			(type default)
		)
		(layer "In10.Cu")
	)
	(gr_arc
		(start 278.425148 -137.850118)
		(mid 278.100282 -138.824716)
		(end 279.07488 -139.149582)
		(stroke
			(width 0.2)
			(type default)
		)
		(layer "In10.Cu")
	)
	(gr_arc
		(start 278.425148 -81.550256)
		(mid 278.100282 -82.524854)
		(end 279.07488 -82.84972)
		(stroke
			(width 0.2)
			(type default)
		)
		(layer "In10.Cu")
	)
	(gr_arc
		(start 278.425148 -77.550264)
		(mid 278.100282 -78.524862)
		(end 279.07488 -78.849728)
		(stroke
			(width 0.2)
			(type default)
		)
		(layer "In10.Cu")
	)
	(gr_arc
		(start 278.425148 -73.550272)
		(mid 278.100282 -74.52487)
		(end 279.07488 -74.849736)
		(stroke
			(width 0.2)
			(type default)
		)
		(layer "In10.Cu")
	)
	(gr_arc
		(start 278.425148 -69.55028)
		(mid 278.100282 -70.524878)
		(end 279.07488 -70.849744)
		(stroke
			(width 0.2)
			(type default)
		)
		(layer "In10.Cu")
	)
	(gr_arc
		(start 278.425148 -65.550288)
		(mid 278.100282 -66.524886)
		(end 279.07488 -66.849752)
		(stroke
			(width 0.2)
			(type default)
		)
		(layer "In10.Cu")
	)
	(gr_arc
		(start 278.425148 -61.550296)
		(mid 278.100282 -62.524894)
		(end 279.07488 -62.84976)
		(stroke
			(width 0.2)
			(type default)
		)
		(layer "In10.Cu")
	)
	(gr_arc
		(start 278.425148 -57.550304)
		(mid 278.100282 -58.524902)
		(end 279.07488 -58.849768)
		(stroke
			(width 0.2)
			(type default)
		)
		(layer "In10.Cu")
	)
	(gr_arc
		(start 278.425148 -53.550312)
		(mid 278.100282 -54.52491)
		(end 279.07488 -54.849776)
		(stroke
			(width 0.2)
			(type default)
		)
		(layer "In10.Cu")
	)
	(gr_arc
		(start 278.425148 -49.55032)
		(mid 278.100282 -50.524918)
		(end 279.07488 -50.849784)
		(stroke
			(width 0.2)
			(type default)
		)
		(layer "In10.Cu")
	)
	(gr_arc
		(start 278.425148 -45.550328)
		(mid 278.100282 -46.524926)
		(end 279.07488 -46.849792)
		(stroke
			(width 0.2)
			(type default)
		)
		(layer "In10.Cu")
	)
	(gr_arc
		(start 278.425148 -41.550336)
		(mid 278.100282 -42.524934)
		(end 279.07488 -42.8498)
		(stroke
			(width 0.2)
			(type default)
		)
		(layer "In10.Cu")
	)
	(gr_arc
		(start 278.425148 -37.550344)
		(mid 278.100282 -38.524942)
		(end 279.07488 -38.849808)
		(stroke
			(width 0.2)
			(type default)
		)
		(layer "In10.Cu")
	)
	(gr_arc
		(start 278.425148 -17.550384)
		(mid 278.100282 -18.524982)
		(end 279.07488 -18.849848)
		(stroke
			(width 0.2)
			(type default)
		)
		(layer "In10.Cu")
	)
	(gr_arc
		(start 278.426418 -161.852356)
		(mid 278.102619 -162.8235)
		(end 279.073864 -163.147248)
		(stroke
			(width 0.2)
			(type default)
		)
		(layer "In10.Cu")
	)
	(gr_line
		(start 278.426418 -161.852102)
		(end 278.426418 -161.852356)
		(stroke
			(width 0.2)
			(type default)
		)
		(layer "In10.Cu")
	)
	(gr_arc
		(start 278.426418 -157.852364)
		(mid 278.102619 -158.823508)
		(end 279.073864 -159.147256)
		(stroke
			(width 0.2)
			(type default)
		)
		(layer "In10.Cu")
	)
	(gr_line
		(start 278.426418 -157.85211)
		(end 278.426418 -157.852364)
		(stroke
			(width 0.2)
			(type default)
		)
		(layer "In10.Cu")
	)
	(gr_arc
		(start 278.426418 -153.852372)
		(mid 278.102619 -154.823516)
		(end 279.073864 -155.147264)
		(stroke
			(width 0.2)
			(type default)
		)
		(layer "In10.Cu")
	)
	(gr_line
		(start 278.426418 -153.852118)
		(end 278.426418 -153.852372)
		(stroke
			(width 0.2)
			(type default)
		)
		(layer "In10.Cu")
	)
	(gr_arc
		(start 278.426418 -149.85238)
		(mid 278.102619 -150.823524)
		(end 279.073864 -151.147272)
		(stroke
			(width 0.2)
			(type default)
		)
		(layer "In10.Cu")
	)
	(gr_line
		(start 278.426418 -149.852126)
		(end 278.426418 -149.85238)
		(stroke
			(width 0.2)
			(type default)
		)
		(layer "In10.Cu")
	)
	(gr_arc
		(start 278.426418 -129.85242)
		(mid 278.102619 -130.823564)
		(end 279.073864 -131.147312)
		(stroke
			(width 0.2)
			(type default)
		)
		(layer "In10.Cu")
	)
	(gr_line
		(start 278.426418 -129.852166)
		(end 278.426418 -129.85242)
		(stroke
			(width 0.2)
			(type default)
		)
		(layer "In10.Cu")
	)
	(gr_arc
		(start 278.426418 -125.852428)
		(mid 278.102619 -126.823572)
		(end 279.073864 -127.14732)
		(stroke
			(width 0.2)
			(type default)
		)
		(layer "In10.Cu")
	)
	(gr_line
		(start 278.426418 -125.852174)
		(end 278.426418 -125.852428)
		(stroke
			(width 0.2)
			(type default)
		)
		(layer "In10.Cu")
	)
	(gr_arc
		(start 278.426418 -121.852436)
		(mid 278.102619 -122.82358)
		(end 279.073864 -123.147328)
		(stroke
			(width 0.2)
			(type default)
		)
		(layer "In10.Cu")
	)
	(gr_line
		(start 278.426418 -121.852182)
		(end 278.426418 -121.852436)
		(stroke
			(width 0.2)
			(type default)
		)
		(layer "In10.Cu")
	)
	(gr_arc
		(start 278.426418 -117.852444)
		(mid 278.102619 -118.823588)
		(end 279.073864 -119.147336)
		(stroke
			(width 0.2)
			(type default)
		)
		(layer "In10.Cu")
	)
	(gr_line
		(start 278.426418 -117.85219)
		(end 278.426418 -117.852444)
		(stroke
			(width 0.2)
			(type default)
		)
		(layer "In10.Cu")
	)
	(gr_arc
		(start 278.433784 -11.54049)
		(mid 278.093387 -12.52152)
		(end 279.077166 -12.854432)
		(stroke
			(width 0.2)
			(type default)
		)
		(layer "In10.Cu")
	)
	(gr_arc
		(start 278.44496 -113.868708)
		(mid 278.120865 -114.809139)
		(end 279.06345 -115.127024)
		(stroke
			(width 0.2)
			(type default)
		)
		(layer "In10.Cu")
	)
	(gr_line
		(start 279.06345 -115.127024)
		(end 281.063446 -114.127026)
		(stroke
			(width 0.2)
			(type default)
		)
		(layer "In10.Cu")
	)
	(gr_line
		(start 279.073864 -163.147248)
		(end 281.07386 -162.14725)
		(stroke
			(width 0.2)
			(type default)
		)
		(layer "In10.Cu")
	)
	(gr_line
		(start 279.073864 -159.147256)
		(end 281.07386 -158.147258)
		(stroke
			(width 0.2)
			(type default)
		)
		(layer "In10.Cu")
	)
	(gr_line
		(start 279.073864 -155.147264)
		(end 281.07386 -154.147266)
		(stroke
			(width 0.2)
			(type default)
		)
		(layer "In10.Cu")
	)
	(gr_line
		(start 279.073864 -151.147272)
		(end 281.07386 -150.147274)
		(stroke
			(width 0.2)
			(type default)
		)
		(layer "In10.Cu")
	)
	(gr_line
		(start 279.073864 -131.147312)
		(end 281.07386 -130.147314)
		(stroke
			(width 0.2)
			(type default)
		)
		(layer "In10.Cu")
	)
	(gr_line
		(start 279.073864 -127.14732)
		(end 281.07386 -126.147322)
		(stroke
			(width 0.2)
			(type default)
		)
		(layer "In10.Cu")
	)
	(gr_line
		(start 279.073864 -123.147328)
		(end 281.07386 -122.14733)
		(stroke
			(width 0.2)
			(type default)
		)
		(layer "In10.Cu")
	)
	(gr_line
		(start 279.073864 -119.147336)
		(end 281.07386 -118.147338)
		(stroke
			(width 0.2)
			(type default)
		)
		(layer "In10.Cu")
	)
	(gr_line
		(start 279.07488 -179.149502)
		(end 279.07615 -179.151788)
		(stroke
			(width 0.2)
			(type default)
		)
		(layer "In10.Cu")
	)
	(gr_line
		(start 279.07488 -175.14951)
		(end 279.07615 -175.151796)
		(stroke
			(width 0.2)
			(type default)
		)
		(layer "In10.Cu")
	)
	(gr_line
		(start 279.07488 -171.149518)
		(end 279.07615 -171.151804)
		(stroke
			(width 0.2)
			(type default)
		)
		(layer "In10.Cu")
	)
	(gr_line
		(start 279.07488 -167.149526)
		(end 279.07615 -167.151812)
		(stroke
			(width 0.2)
			(type default)
		)
		(layer "In10.Cu")
	)
	(gr_line
		(start 279.07488 -139.149582)
		(end 279.07615 -139.151868)
		(stroke
			(width 0.2)
			(type default)
		)
		(layer "In10.Cu")
	)
	(gr_line
		(start 279.07488 -82.84972)
		(end 279.07615 -82.852006)
		(stroke
			(width 0.2)
			(type default)
		)
		(layer "In10.Cu")
	)
	(gr_line
		(start 279.07488 -78.849728)
		(end 279.07615 -78.852014)
		(stroke
			(width 0.2)
			(type default)
		)
		(layer "In10.Cu")
	)
	(gr_line
		(start 279.07488 -74.849736)
		(end 279.07615 -74.852022)
		(stroke
			(width 0.2)
			(type default)
		)
		(layer "In10.Cu")
	)
	(gr_line
		(start 279.07488 -70.849744)
		(end 279.07615 -70.85203)
		(stroke
			(width 0.2)
			(type default)
		)
		(layer "In10.Cu")
	)
	(gr_line
		(start 279.07488 -66.849752)
		(end 279.07615 -66.852038)
		(stroke
			(width 0.2)
			(type default)
		)
		(layer "In10.Cu")
	)
	(gr_line
		(start 279.07488 -62.84976)
		(end 279.07615 -62.852046)
		(stroke
			(width 0.2)
			(type default)
		)
		(layer "In10.Cu")
	)
	(gr_line
		(start 279.07488 -58.849768)
		(end 279.07615 -58.852054)
		(stroke
			(width 0.2)
			(type default)
		)
		(layer "In10.Cu")
	)
	(gr_line
		(start 279.07488 -54.849776)
		(end 279.07615 -54.852062)
		(stroke
			(width 0.2)
			(type default)
		)
		(layer "In10.Cu")
	)
	(gr_line
		(start 279.07488 -50.849784)
		(end 279.07615 -50.85207)
		(stroke
			(width 0.2)
			(type default)
		)
		(layer "In10.Cu")
	)
	(gr_line
		(start 279.07488 -46.849792)
		(end 279.07615 -46.852078)
		(stroke
			(width 0.2)
			(type default)
		)
		(layer "In10.Cu")
	)
	(gr_line
		(start 279.07488 -42.8498)
		(end 279.07615 -42.852086)
		(stroke
			(width 0.2)
			(type default)
		)
		(layer "In10.Cu")
	)
	(gr_line
		(start 279.07488 -38.849808)
		(end 279.07615 -38.852094)
		(stroke
			(width 0.2)
			(type default)
		)
		(layer "In10.Cu")
	)
	(gr_line
		(start 279.07488 -18.849848)
		(end 279.07615 -18.852134)
		(stroke
			(width 0.2)
			(type default)
		)
		(layer "In10.Cu")
	)
	(gr_line
		(start 279.07615 -179.151788)
		(end 281.076146 -178.15179)
		(stroke
			(width 0.2)
			(type default)
		)
		(layer "In10.Cu")
	)
	(gr_line
		(start 279.07615 -175.151796)
		(end 281.076146 -174.151798)
		(stroke
			(width 0.2)
			(type default)
		)
		(layer "In10.Cu")
	)
	(gr_line
		(start 279.07615 -171.151804)
		(end 281.076146 -170.151806)
		(stroke
			(width 0.2)
			(type default)
		)
		(layer "In10.Cu")
	)
	(gr_line
		(start 279.07615 -167.151812)
		(end 281.076146 -166.151814)
		(stroke
			(width 0.2)
			(type default)
		)
		(layer "In10.Cu")
	)
	(gr_line
		(start 279.07615 -139.151868)
		(end 281.076146 -138.15187)
		(stroke
			(width 0.2)
			(type default)
		)
		(layer "In10.Cu")
	)
	(gr_line
		(start 279.07615 -82.852006)
		(end 281.076146 -81.852008)
		(stroke
			(width 0.2)
			(type default)
		)
		(layer "In10.Cu")
	)
	(gr_line
		(start 279.07615 -78.852014)
		(end 281.076146 -77.852016)
		(stroke
			(width 0.2)
			(type default)
		)
		(layer "In10.Cu")
	)
	(gr_line
		(start 279.07615 -74.852022)
		(end 281.076146 -73.852024)
		(stroke
			(width 0.2)
			(type default)
		)
		(layer "In10.Cu")
	)
	(gr_line
		(start 279.07615 -70.85203)
		(end 281.076146 -69.852032)
		(stroke
			(width 0.2)
			(type default)
		)
		(layer "In10.Cu")
	)
	(gr_line
		(start 279.07615 -66.852038)
		(end 281.076146 -65.85204)
		(stroke
			(width 0.2)
			(type default)
		)
		(layer "In10.Cu")
	)
	(gr_line
		(start 279.07615 -62.852046)
		(end 281.076146 -61.852048)
		(stroke
			(width 0.2)
			(type default)
		)
		(layer "In10.Cu")
	)
	(gr_line
		(start 279.07615 -58.852054)
		(end 281.076146 -57.852056)
		(stroke
			(width 0.2)
			(type default)
		)
		(layer "In10.Cu")
	)
	(gr_line
		(start 279.07615 -54.852062)
		(end 281.076146 -53.852064)
		(stroke
			(width 0.2)
			(type default)
		)
		(layer "In10.Cu")
	)
	(gr_line
		(start 279.07615 -50.85207)
		(end 281.076146 -49.852072)
		(stroke
			(width 0.2)
			(type default)
		)
		(layer "In10.Cu")
	)
	(gr_line
		(start 279.07615 -46.852078)
		(end 281.076146 -45.85208)
		(stroke
			(width 0.2)
			(type default)
		)
		(layer "In10.Cu")
	)
	(gr_line
		(start 279.07615 -42.852086)
		(end 281.076146 -41.852088)
		(stroke
			(width 0.2)
			(type default)
		)
		(layer "In10.Cu")
	)
	(gr_line
		(start 279.07615 -38.852094)
		(end 281.076146 -37.852096)
		(stroke
			(width 0.2)
			(type default)
		)
		(layer "In10.Cu")
	)
	(gr_line
		(start 279.07615 -18.852134)
		(end 281.076146 -17.852136)
		(stroke
			(width 0.2)
			(type default)
		)
		(layer "In10.Cu")
	)
	(gr_line
		(start 279.077166 -12.854432)
		(end 281.077162 -11.854434)
		(stroke
			(width 0.2)
			(type default)
		)
		(layer "In10.Cu")
	)
	(gr_line
		(start 279.236678 -358.253792)
		(end 280.636726 -358.253792)
		(stroke
			(width 0.2)
			(type default)
		)
		(layer "In10.Cu")
	)
	(gr_arc
		(start 279.236678 -357.156512)
		(mid 278.688038 -357.705152)
		(end 279.236678 -358.253792)
		(stroke
			(width 0.2)
			(type default)
		)
		(layer "In10.Cu")
	)
	(gr_line
		(start 279.236678 -354.65385)
		(end 280.636726 -354.65385)
		(stroke
			(width 0.2)
			(type default)
		)
		(layer "In10.Cu")
	)
	(gr_arc
		(start 279.236678 -353.55657)
		(mid 278.688038 -354.10521)
		(end 279.236678 -354.65385)
		(stroke
			(width 0.2)
			(type default)
		)
		(layer "In10.Cu")
	)
	(gr_line
		(start 279.236678 -351.053908)
		(end 280.636726 -351.053908)
		(stroke
			(width 0.2)
			(type default)
		)
		(layer "In10.Cu")
	)
	(gr_arc
		(start 279.236678 -349.956628)
		(mid 278.688038 -350.505268)
		(end 279.236678 -351.053908)
		(stroke
			(width 0.2)
			(type default)
		)
		(layer "In10.Cu")
	)
	(gr_line
		(start 279.236678 -347.453712)
		(end 280.636726 -347.453712)
		(stroke
			(width 0.2)
			(type default)
		)
		(layer "In10.Cu")
	)
	(gr_arc
		(start 279.236678 -346.356432)
		(mid 278.688038 -346.905072)
		(end 279.236678 -347.453712)
		(stroke
			(width 0.2)
			(type default)
		)
		(layer "In10.Cu")
	)
	(gr_line
		(start 279.236678 -343.85377)
		(end 280.636726 -343.85377)
		(stroke
			(width 0.2)
			(type default)
		)
		(layer "In10.Cu")
	)
	(gr_arc
		(start 279.236678 -342.75649)
		(mid 278.688038 -343.30513)
		(end 279.236678 -343.85377)
		(stroke
			(width 0.2)
			(type default)
		)
		(layer "In10.Cu")
	)
	(gr_line
		(start 279.236678 -340.253828)
		(end 280.636726 -340.253828)
		(stroke
			(width 0.2)
			(type default)
		)
		(layer "In10.Cu")
	)
	(gr_arc
		(start 279.236678 -339.156548)
		(mid 278.688038 -339.705188)
		(end 279.236678 -340.253828)
		(stroke
			(width 0.2)
			(type default)
		)
		(layer "In10.Cu")
	)
	(gr_line
		(start 279.236678 -336.653886)
		(end 280.636726 -336.653886)
		(stroke
			(width 0.2)
			(type default)
		)
		(layer "In10.Cu")
	)
	(gr_arc
		(start 279.236678 -335.556606)
		(mid 278.688038 -336.105246)
		(end 279.236678 -336.653886)
		(stroke
			(width 0.2)
			(type default)
		)
		(layer "In10.Cu")
	)
	(gr_line
		(start 279.236678 -333.05369)
		(end 280.636726 -333.05369)
		(stroke
			(width 0.2)
			(type default)
		)
		(layer "In10.Cu")
	)
	(gr_arc
		(start 279.236678 -331.95641)
		(mid 278.688038 -332.50505)
		(end 279.236678 -333.05369)
		(stroke
			(width 0.2)
			(type default)
		)
		(layer "In10.Cu")
	)
	(gr_line
		(start 279.236678 -329.453748)
		(end 280.636726 -329.453748)
		(stroke
			(width 0.2)
			(type default)
		)
		(layer "In10.Cu")
	)
	(gr_arc
		(start 279.236678 -328.356468)
		(mid 278.688038 -328.905108)
		(end 279.236678 -329.453748)
		(stroke
			(width 0.2)
			(type default)
		)
		(layer "In10.Cu")
	)
	(gr_line
		(start 279.236678 -325.853806)
		(end 280.636726 -325.853806)
		(stroke
			(width 0.2)
			(type default)
		)
		(layer "In10.Cu")
	)
	(gr_arc
		(start 279.236678 -324.756526)
		(mid 278.688038 -325.305166)
		(end 279.236678 -325.853806)
		(stroke
			(width 0.2)
			(type default)
		)
		(layer "In10.Cu")
	)
	(gr_line
		(start 279.236678 -322.253864)
		(end 280.636726 -322.253864)
		(stroke
			(width 0.2)
			(type default)
		)
		(layer "In10.Cu")
	)
	(gr_arc
		(start 279.236678 -321.156584)
		(mid 278.688038 -321.705224)
		(end 279.236678 -322.253864)
		(stroke
			(width 0.2)
			(type default)
		)
		(layer "In10.Cu")
	)
	(gr_line
		(start 279.236678 -318.653668)
		(end 280.636726 -318.653668)
		(stroke
			(width 0.2)
			(type default)
		)
		(layer "In10.Cu")
	)
	(gr_arc
		(start 279.236678 -317.556388)
		(mid 278.688038 -318.105028)
		(end 279.236678 -318.653668)
		(stroke
			(width 0.2)
			(type default)
		)
		(layer "In10.Cu")
	)
	(gr_line
		(start 279.236678 -315.053726)
		(end 280.636726 -315.053726)
		(stroke
			(width 0.2)
			(type default)
		)
		(layer "In10.Cu")
	)
	(gr_arc
		(start 279.236678 -313.956446)
		(mid 278.688038 -314.505086)
		(end 279.236678 -315.053726)
		(stroke
			(width 0.2)
			(type default)
		)
		(layer "In10.Cu")
	)
	(gr_line
		(start 279.236678 -311.453784)
		(end 280.636726 -311.453784)
		(stroke
			(width 0.2)
			(type default)
		)
		(layer "In10.Cu")
	)
	(gr_arc
		(start 279.236678 -310.356504)
		(mid 278.688038 -310.905144)
		(end 279.236678 -311.453784)
		(stroke
			(width 0.2)
			(type default)
		)
		(layer "In10.Cu")
	)
	(gr_line
		(start 279.236678 -307.853842)
		(end 280.636726 -307.853842)
		(stroke
			(width 0.2)
			(type default)
		)
		(layer "In10.Cu")
	)
	(gr_arc
		(start 279.236678 -306.756562)
		(mid 278.688038 -307.305202)
		(end 279.236678 -307.853842)
		(stroke
			(width 0.2)
			(type default)
		)
		(layer "In10.Cu")
	)
	(gr_line
		(start 279.236678 -304.2539)
		(end 280.636726 -304.2539)
		(stroke
			(width 0.2)
			(type default)
		)
		(layer "In10.Cu")
	)
	(gr_arc
		(start 279.236678 -303.15662)
		(mid 278.688038 -303.70526)
		(end 279.236678 -304.2539)
		(stroke
			(width 0.2)
			(type default)
		)
		(layer "In10.Cu")
	)
	(gr_line
		(start 279.236678 -300.653704)
		(end 280.636726 -300.653704)
		(stroke
			(width 0.2)
			(type default)
		)
		(layer "In10.Cu")
	)
	(gr_arc
		(start 279.236678 -299.556424)
		(mid 278.688038 -300.105064)
		(end 279.236678 -300.653704)
		(stroke
			(width 0.2)
			(type default)
		)
		(layer "In10.Cu")
	)
	(gr_line
		(start 279.236678 -297.053762)
		(end 280.636726 -297.053762)
		(stroke
			(width 0.2)
			(type default)
		)
		(layer "In10.Cu")
	)
	(gr_arc
		(start 279.236678 -295.956482)
		(mid 278.688038 -296.505122)
		(end 279.236678 -297.053762)
		(stroke
			(width 0.2)
			(type default)
		)
		(layer "In10.Cu")
	)
	(gr_line
		(start 279.236678 -264.253472)
		(end 280.636726 -264.253472)
		(stroke
			(width 0.2)
			(type default)
		)
		(layer "In10.Cu")
	)
	(gr_arc
		(start 279.236678 -263.151112)
		(mid 278.685498 -263.702292)
		(end 279.236678 -264.253472)
		(stroke
			(width 0.2)
			(type default)
		)
		(layer "In10.Cu")
	)
	(gr_line
		(start 279.236678 -260.65353)
		(end 280.636726 -260.65353)
		(stroke
			(width 0.2)
			(type default)
		)
		(layer "In10.Cu")
	)
	(gr_arc
		(start 279.236678 -259.55117)
		(mid 278.685498 -260.10235)
		(end 279.236678 -260.65353)
		(stroke
			(width 0.2)
			(type default)
		)
		(layer "In10.Cu")
	)
	(gr_line
		(start 279.236678 -257.053588)
		(end 280.636726 -257.053588)
		(stroke
			(width 0.2)
			(type default)
		)
		(layer "In10.Cu")
	)
	(gr_arc
		(start 279.236678 -255.951228)
		(mid 278.685498 -256.502408)
		(end 279.236678 -257.053588)
		(stroke
			(width 0.2)
			(type default)
		)
		(layer "In10.Cu")
	)
	(gr_line
		(start 279.236678 -253.453392)
		(end 280.636726 -253.453392)
		(stroke
			(width 0.2)
			(type default)
		)
		(layer "In10.Cu")
	)
	(gr_arc
		(start 279.236678 -252.351032)
		(mid 278.685498 -252.902212)
		(end 279.236678 -253.453392)
		(stroke
			(width 0.2)
			(type default)
		)
		(layer "In10.Cu")
	)
	(gr_line
		(start 279.236932 -357.156512)
		(end 279.236678 -357.156512)
		(stroke
			(width 0.2)
			(type default)
		)
		(layer "In10.Cu")
	)
	(gr_line
		(start 279.236932 -353.55657)
		(end 279.236678 -353.55657)
		(stroke
			(width 0.2)
			(type default)
		)
		(layer "In10.Cu")
	)
	(gr_line
		(start 279.236932 -349.956628)
		(end 279.236678 -349.956628)
		(stroke
			(width 0.2)
			(type default)
		)
		(layer "In10.Cu")
	)
	(gr_line
		(start 279.236932 -346.356432)
		(end 279.236678 -346.356432)
		(stroke
			(width 0.2)
			(type default)
		)
		(layer "In10.Cu")
	)
	(gr_line
		(start 279.236932 -342.75649)
		(end 279.236678 -342.75649)
		(stroke
			(width 0.2)
			(type default)
		)
		(layer "In10.Cu")
	)
	(gr_line
		(start 279.236932 -339.156548)
		(end 279.236678 -339.156548)
		(stroke
			(width 0.2)
			(type default)
		)
		(layer "In10.Cu")
	)
	(gr_line
		(start 279.236932 -335.556606)
		(end 279.236678 -335.556606)
		(stroke
			(width 0.2)
			(type default)
		)
		(layer "In10.Cu")
	)
	(gr_line
		(start 279.236932 -331.95641)
		(end 279.236678 -331.95641)
		(stroke
			(width 0.2)
			(type default)
		)
		(layer "In10.Cu")
	)
	(gr_line
		(start 279.236932 -328.356468)
		(end 279.236678 -328.356468)
		(stroke
			(width 0.2)
			(type default)
		)
		(layer "In10.Cu")
	)
	(gr_line
		(start 279.236932 -324.756526)
		(end 279.236678 -324.756526)
		(stroke
			(width 0.2)
			(type default)
		)
		(layer "In10.Cu")
	)
	(gr_line
		(start 279.236932 -321.156584)
		(end 279.236678 -321.156584)
		(stroke
			(width 0.2)
			(type default)
		)
		(layer "In10.Cu")
	)
	(gr_line
		(start 279.236932 -317.556388)
		(end 279.236678 -317.556388)
		(stroke
			(width 0.2)
			(type default)
		)
		(layer "In10.Cu")
	)
	(gr_line
		(start 279.236932 -313.956446)
		(end 279.236678 -313.956446)
		(stroke
			(width 0.2)
			(type default)
		)
		(layer "In10.Cu")
	)
	(gr_line
		(start 279.236932 -310.356504)
		(end 279.236678 -310.356504)
		(stroke
			(width 0.2)
			(type default)
		)
		(layer "In10.Cu")
	)
	(gr_line
		(start 279.236932 -306.756562)
		(end 279.236678 -306.756562)
		(stroke
			(width 0.2)
			(type default)
		)
		(layer "In10.Cu")
	)
	(gr_line
		(start 279.236932 -303.15662)
		(end 279.236678 -303.15662)
		(stroke
			(width 0.2)
			(type default)
		)
		(layer "In10.Cu")
	)
	(gr_line
		(start 279.236932 -299.556424)
		(end 279.236678 -299.556424)
		(stroke
			(width 0.2)
			(type default)
		)
		(layer "In10.Cu")
	)
	(gr_line
		(start 279.236932 -295.956482)
		(end 279.236678 -295.956482)
		(stroke
			(width 0.2)
			(type default)
		)
		(layer "In10.Cu")
	)
	(gr_line
		(start 279.236932 -263.151112)
		(end 279.236678 -263.151112)
		(stroke
			(width 0.2)
			(type default)
		)
		(layer "In10.Cu")
	)
	(gr_line
		(start 279.236932 -259.55117)
		(end 279.236678 -259.55117)
		(stroke
			(width 0.2)
			(type default)
		)
		(layer "In10.Cu")
	)
	(gr_line
		(start 279.236932 -255.951228)
		(end 279.236678 -255.951228)
		(stroke
			(width 0.2)
			(type default)
		)
		(layer "In10.Cu")
	)
	(gr_line
		(start 279.236932 -252.351032)
		(end 279.236678 -252.351032)
		(stroke
			(width 0.2)
			(type default)
		)
		(layer "In10.Cu")
	)
	(gr_arc
		(start 279.636728 -356.453694)
		(mid 280.185368 -355.905054)
		(end 279.636728 -355.356414)
		(stroke
			(width 0.2)
			(type default)
		)
		(layer "In10.Cu")
	)
	(gr_line
		(start 279.636728 -355.356414)
		(end 278.236934 -355.356414)
		(stroke
			(width 0.2)
			(type default)
		)
		(layer "In10.Cu")
	)
	(gr_arc
		(start 279.636728 -352.853752)
		(mid 280.185368 -352.305112)
		(end 279.636728 -351.756472)
		(stroke
			(width 0.2)
			(type default)
		)
		(layer "In10.Cu")
	)
	(gr_line
		(start 279.636728 -351.756472)
		(end 278.236934 -351.756472)
		(stroke
			(width 0.2)
			(type default)
		)
		(layer "In10.Cu")
	)
	(gr_arc
		(start 279.636728 -349.25381)
		(mid 280.185368 -348.70517)
		(end 279.636728 -348.15653)
		(stroke
			(width 0.2)
			(type default)
		)
		(layer "In10.Cu")
	)
	(gr_line
		(start 279.636728 -348.15653)
		(end 278.236934 -348.15653)
		(stroke
			(width 0.2)
			(type default)
		)
		(layer "In10.Cu")
	)
	(gr_arc
		(start 279.636728 -345.653868)
		(mid 280.185368 -345.105228)
		(end 279.636728 -344.556588)
		(stroke
			(width 0.2)
			(type default)
		)
		(layer "In10.Cu")
	)
	(gr_line
		(start 279.636728 -344.556588)
		(end 278.236934 -344.556588)
		(stroke
			(width 0.2)
			(type default)
		)
		(layer "In10.Cu")
	)
	(gr_arc
		(start 279.636728 -342.053672)
		(mid 280.185368 -341.505032)
		(end 279.636728 -340.956392)
		(stroke
			(width 0.2)
			(type default)
		)
		(layer "In10.Cu")
	)
	(gr_line
		(start 279.636728 -340.956392)
		(end 278.236934 -340.956392)
		(stroke
			(width 0.2)
			(type default)
		)
		(layer "In10.Cu")
	)
	(gr_arc
		(start 279.636728 -338.45373)
		(mid 280.185368 -337.90509)
		(end 279.636728 -337.35645)
		(stroke
			(width 0.2)
			(type default)
		)
		(layer "In10.Cu")
	)
	(gr_line
		(start 279.636728 -337.35645)
		(end 278.236934 -337.35645)
		(stroke
			(width 0.2)
			(type default)
		)
		(layer "In10.Cu")
	)
	(gr_arc
		(start 279.636728 -334.853788)
		(mid 280.185368 -334.305148)
		(end 279.636728 -333.756508)
		(stroke
			(width 0.2)
			(type default)
		)
		(layer "In10.Cu")
	)
	(gr_line
		(start 279.636728 -333.756508)
		(end 278.236934 -333.756508)
		(stroke
			(width 0.2)
			(type default)
		)
		(layer "In10.Cu")
	)
	(gr_arc
		(start 279.636728 -331.253846)
		(mid 280.185368 -330.705206)
		(end 279.636728 -330.156566)
		(stroke
			(width 0.2)
			(type default)
		)
		(layer "In10.Cu")
	)
	(gr_line
		(start 279.636728 -330.156566)
		(end 278.236934 -330.156566)
		(stroke
			(width 0.2)
			(type default)
		)
		(layer "In10.Cu")
	)
	(gr_arc
		(start 279.636728 -327.653904)
		(mid 280.185368 -327.105264)
		(end 279.636728 -326.556624)
		(stroke
			(width 0.2)
			(type default)
		)
		(layer "In10.Cu")
	)
	(gr_line
		(start 279.636728 -326.556624)
		(end 278.236934 -326.556624)
		(stroke
			(width 0.2)
			(type default)
		)
		(layer "In10.Cu")
	)
	(gr_arc
		(start 279.636728 -324.053708)
		(mid 280.185368 -323.505068)
		(end 279.636728 -322.956428)
		(stroke
			(width 0.2)
			(type default)
		)
		(layer "In10.Cu")
	)
	(gr_line
		(start 279.636728 -322.956428)
		(end 278.236934 -322.956428)
		(stroke
			(width 0.2)
			(type default)
		)
		(layer "In10.Cu")
	)
	(gr_arc
		(start 279.636728 -320.453766)
		(mid 280.185368 -319.905126)
		(end 279.636728 -319.356486)
		(stroke
			(width 0.2)
			(type default)
		)
		(layer "In10.Cu")
	)
	(gr_line
		(start 279.636728 -319.356486)
		(end 278.236934 -319.356486)
		(stroke
			(width 0.2)
			(type default)
		)
		(layer "In10.Cu")
	)
	(gr_arc
		(start 279.636728 -316.853824)
		(mid 280.185368 -316.305184)
		(end 279.636728 -315.756544)
		(stroke
			(width 0.2)
			(type default)
		)
		(layer "In10.Cu")
	)
	(gr_line
		(start 279.636728 -315.756544)
		(end 278.236934 -315.756544)
		(stroke
			(width 0.2)
			(type default)
		)
		(layer "In10.Cu")
	)
	(gr_arc
		(start 279.636728 -313.253882)
		(mid 280.185368 -312.705242)
		(end 279.636728 -312.156602)
		(stroke
			(width 0.2)
			(type default)
		)
		(layer "In10.Cu")
	)
	(gr_line
		(start 279.636728 -312.156602)
		(end 278.236934 -312.156602)
		(stroke
			(width 0.2)
			(type default)
		)
		(layer "In10.Cu")
	)
	(gr_arc
		(start 279.636728 -309.653686)
		(mid 280.185368 -309.105046)
		(end 279.636728 -308.556406)
		(stroke
			(width 0.2)
			(type default)
		)
		(layer "In10.Cu")
	)
	(gr_line
		(start 279.636728 -308.556406)
		(end 278.236934 -308.556406)
		(stroke
			(width 0.2)
			(type default)
		)
		(layer "In10.Cu")
	)
	(gr_arc
		(start 279.636728 -306.053744)
		(mid 280.185368 -305.505104)
		(end 279.636728 -304.956464)
		(stroke
			(width 0.2)
			(type default)
		)
		(layer "In10.Cu")
	)
	(gr_line
		(start 279.636728 -304.956464)
		(end 278.236934 -304.956464)
		(stroke
			(width 0.2)
			(type default)
		)
		(layer "In10.Cu")
	)
	(gr_arc
		(start 279.636728 -302.453802)
		(mid 280.185368 -301.905162)
		(end 279.636728 -301.356522)
		(stroke
			(width 0.2)
			(type default)
		)
		(layer "In10.Cu")
	)
	(gr_line
		(start 279.636728 -301.356522)
		(end 278.236934 -301.356522)
		(stroke
			(width 0.2)
			(type default)
		)
		(layer "In10.Cu")
	)
	(gr_arc
		(start 279.636728 -298.85386)
		(mid 280.185368 -298.30522)
		(end 279.636728 -297.75658)
		(stroke
			(width 0.2)
			(type default)
		)
		(layer "In10.Cu")
	)
	(gr_line
		(start 279.636728 -297.75658)
		(end 278.236934 -297.75658)
		(stroke
			(width 0.2)
			(type default)
		)
		(layer "In10.Cu")
	)
	(gr_arc
		(start 279.636728 -295.253918)
		(mid 280.185368 -294.705278)
		(end 279.636728 -294.156638)
		(stroke
			(width 0.2)
			(type default)
		)
		(layer "In10.Cu")
	)
	(gr_line
		(start 279.636728 -294.156638)
		(end 278.236934 -294.156638)
		(stroke
			(width 0.2)
			(type default)
		)
		(layer "In10.Cu")
	)
	(gr_arc
		(start 279.636728 -262.453374)
		(mid 280.187908 -261.902194)
		(end 279.636728 -261.351014)
		(stroke
			(width 0.2)
			(type default)
		)
		(layer "In10.Cu")
	)
	(gr_line
		(start 279.636728 -261.351014)
		(end 278.236934 -261.351014)
		(stroke
			(width 0.2)
			(type default)
		)
		(layer "In10.Cu")
	)
	(gr_arc
		(start 279.636728 -258.853432)
		(mid 280.187908 -258.302252)
		(end 279.636728 -257.751072)
		(stroke
			(width 0.2)
			(type default)
		)
		(layer "In10.Cu")
	)
	(gr_line
		(start 279.636728 -257.751072)
		(end 278.236934 -257.751072)
		(stroke
			(width 0.2)
			(type default)
		)
		(layer "In10.Cu")
	)
	(gr_arc
		(start 279.636728 -255.25349)
		(mid 280.187908 -254.70231)
		(end 279.636728 -254.15113)
		(stroke
			(width 0.2)
			(type default)
		)
		(layer "In10.Cu")
	)
	(gr_line
		(start 279.636728 -254.15113)
		(end 278.236934 -254.15113)
		(stroke
			(width 0.2)
			(type default)
		)
		(layer "In10.Cu")
	)
	(gr_arc
		(start 279.636728 -251.653548)
		(mid 280.187908 -251.102368)
		(end 279.636728 -250.551188)
		(stroke
			(width 0.2)
			(type default)
		)
		(layer "In10.Cu")
	)
	(gr_line
		(start 279.636728 -250.551188)
		(end 278.236934 -250.551188)
		(stroke
			(width 0.2)
			(type default)
		)
		(layer "In10.Cu")
	)
	(gr_line
		(start 280.422858 -10.545826)
		(end 278.433784 -11.54049)
		(stroke
			(width 0.2)
			(type default)
		)
		(layer "In10.Cu")
	)
	(gr_line
		(start 280.423874 -176.847754)
		(end 278.424132 -177.847752)
		(stroke
			(width 0.2)
			(type default)
		)
		(layer "In10.Cu")
	)
	(gr_line
		(start 280.423874 -172.847762)
		(end 278.424132 -173.84776)
		(stroke
			(width 0.2)
			(type default)
		)
		(layer "In10.Cu")
	)
	(gr_line
		(start 280.423874 -168.84777)
		(end 278.424132 -169.847768)
		(stroke
			(width 0.2)
			(type default)
		)
		(layer "In10.Cu")
	)
	(gr_line
		(start 280.423874 -164.847778)
		(end 278.424132 -165.847776)
		(stroke
			(width 0.2)
			(type default)
		)
		(layer "In10.Cu")
	)
	(gr_line
		(start 280.423874 -136.847834)
		(end 278.424132 -137.847832)
		(stroke
			(width 0.2)
			(type default)
		)
		(layer "In10.Cu")
	)
	(gr_line
		(start 280.423874 -80.547972)
		(end 278.424132 -81.54797)
		(stroke
			(width 0.2)
			(type default)
		)
		(layer "In10.Cu")
	)
	(gr_line
		(start 280.423874 -76.54798)
		(end 278.424132 -77.547978)
		(stroke
			(width 0.2)
			(type default)
		)
		(layer "In10.Cu")
	)
	(gr_line
		(start 280.423874 -72.547988)
		(end 278.424132 -73.547986)
		(stroke
			(width 0.2)
			(type default)
		)
		(layer "In10.Cu")
	)
	(gr_line
		(start 280.423874 -68.547996)
		(end 278.424132 -69.547994)
		(stroke
			(width 0.2)
			(type default)
		)
		(layer "In10.Cu")
	)
	(gr_line
		(start 280.423874 -64.548004)
		(end 278.424132 -65.548002)
		(stroke
			(width 0.2)
			(type default)
		)
		(layer "In10.Cu")
	)
	(gr_line
		(start 280.423874 -60.548012)
		(end 278.424132 -61.54801)
		(stroke
			(width 0.2)
			(type default)
		)
		(layer "In10.Cu")
	)
	(gr_line
		(start 280.423874 -56.54802)
		(end 278.424132 -57.548018)
		(stroke
			(width 0.2)
			(type default)
		)
		(layer "In10.Cu")
	)
	(gr_line
		(start 280.423874 -52.548028)
		(end 278.424132 -53.548026)
		(stroke
			(width 0.2)
			(type default)
		)
		(layer "In10.Cu")
	)
	(gr_line
		(start 280.423874 -48.548036)
		(end 278.424132 -49.548034)
		(stroke
			(width 0.2)
			(type default)
		)
		(layer "In10.Cu")
	)
	(gr_line
		(start 280.423874 -44.548044)
		(end 278.424132 -45.548042)
		(stroke
			(width 0.2)
			(type default)
		)
		(layer "In10.Cu")
	)
	(gr_line
		(start 280.423874 -40.548052)
		(end 278.424132 -41.54805)
		(stroke
			(width 0.2)
			(type default)
		)
		(layer "In10.Cu")
	)
	(gr_line
		(start 280.423874 -36.54806)
		(end 278.424132 -37.548058)
		(stroke
			(width 0.2)
			(type default)
		)
		(layer "In10.Cu")
	)
	(gr_line
		(start 280.423874 -16.5481)
		(end 278.424132 -17.548098)
		(stroke
			(width 0.2)
			(type default)
		)
		(layer "In10.Cu")
	)
	(gr_line
		(start 280.425144 -176.85004)
		(end 280.423874 -176.847754)
		(stroke
			(width 0.2)
			(type default)
		)
		(layer "In10.Cu")
	)
	(gr_line
		(start 280.425144 -172.850048)
		(end 280.423874 -172.847762)
		(stroke
			(width 0.2)
			(type default)
		)
		(layer "In10.Cu")
	)
	(gr_line
		(start 280.425144 -168.850056)
		(end 280.423874 -168.84777)
		(stroke
			(width 0.2)
			(type default)
		)
		(layer "In10.Cu")
	)
	(gr_line
		(start 280.425144 -164.850064)
		(end 280.423874 -164.847778)
		(stroke
			(width 0.2)
			(type default)
		)
		(layer "In10.Cu")
	)
	(gr_line
		(start 280.425144 -136.85012)
		(end 280.423874 -136.847834)
		(stroke
			(width 0.2)
			(type default)
		)
		(layer "In10.Cu")
	)
	(gr_line
		(start 280.425144 -80.550258)
		(end 280.423874 -80.547972)
		(stroke
			(width 0.2)
			(type default)
		)
		(layer "In10.Cu")
	)
	(gr_line
		(start 280.425144 -76.550266)
		(end 280.423874 -76.54798)
		(stroke
			(width 0.2)
			(type default)
		)
		(layer "In10.Cu")
	)
	(gr_line
		(start 280.425144 -72.550274)
		(end 280.423874 -72.547988)
		(stroke
			(width 0.2)
			(type default)
		)
		(layer "In10.Cu")
	)
	(gr_line
		(start 280.425144 -68.550282)
		(end 280.423874 -68.547996)
		(stroke
			(width 0.2)
			(type default)
		)
		(layer "In10.Cu")
	)
	(gr_line
		(start 280.425144 -64.55029)
		(end 280.423874 -64.548004)
		(stroke
			(width 0.2)
			(type default)
		)
		(layer "In10.Cu")
	)
	(gr_line
		(start 280.425144 -60.550298)
		(end 280.423874 -60.548012)
		(stroke
			(width 0.2)
			(type default)
		)
		(layer "In10.Cu")
	)
	(gr_line
		(start 280.425144 -56.550306)
		(end 280.423874 -56.54802)
		(stroke
			(width 0.2)
			(type default)
		)
		(layer "In10.Cu")
	)
	(gr_line
		(start 280.425144 -52.550314)
		(end 280.423874 -52.548028)
		(stroke
			(width 0.2)
			(type default)
		)
		(layer "In10.Cu")
	)
	(gr_line
		(start 280.425144 -48.550322)
		(end 280.423874 -48.548036)
		(stroke
			(width 0.2)
			(type default)
		)
		(layer "In10.Cu")
	)
	(gr_line
		(start 280.425144 -44.55033)
		(end 280.423874 -44.548044)
		(stroke
			(width 0.2)
			(type default)
		)
		(layer "In10.Cu")
	)
	(gr_line
		(start 280.425144 -40.550338)
		(end 280.423874 -40.548052)
		(stroke
			(width 0.2)
			(type default)
		)
		(layer "In10.Cu")
	)
	(gr_line
		(start 280.425144 -36.550346)
		(end 280.423874 -36.54806)
		(stroke
			(width 0.2)
			(type default)
		)
		(layer "In10.Cu")
	)
	(gr_line
		(start 280.425144 -16.550386)
		(end 280.423874 -16.5481)
		(stroke
			(width 0.2)
			(type default)
		)
		(layer "In10.Cu")
	)
	(gr_line
		(start 280.42616 -160.852358)
		(end 278.426418 -161.852102)
		(stroke
			(width 0.2)
			(type default)
		)
		(layer "In10.Cu")
	)
	(gr_line
		(start 280.42616 -156.852366)
		(end 278.426418 -157.85211)
		(stroke
			(width 0.2)
			(type default)
		)
		(layer "In10.Cu")
	)
	(gr_line
		(start 280.42616 -152.852374)
		(end 278.426418 -153.852118)
		(stroke
			(width 0.2)
			(type default)
		)
		(layer "In10.Cu")
	)
	(gr_line
		(start 280.42616 -148.852382)
		(end 278.426418 -149.852126)
		(stroke
			(width 0.2)
			(type default)
		)
		(layer "In10.Cu")
	)
	(gr_line
		(start 280.42616 -128.852422)
		(end 278.426418 -129.852166)
		(stroke
			(width 0.2)
			(type default)
		)
		(layer "In10.Cu")
	)
	(gr_line
		(start 280.42616 -124.85243)
		(end 278.426418 -125.852174)
		(stroke
			(width 0.2)
			(type default)
		)
		(layer "In10.Cu")
	)
	(gr_line
		(start 280.42616 -120.852438)
		(end 278.426418 -121.852182)
		(stroke
			(width 0.2)
			(type default)
		)
		(layer "In10.Cu")
	)
	(gr_line
		(start 280.42616 -116.852446)
		(end 278.426418 -117.85219)
		(stroke
			(width 0.2)
			(type default)
		)
		(layer "In10.Cu")
	)
	(gr_line
		(start 280.436574 -112.872774)
		(end 278.44496 -113.868708)
		(stroke
			(width 0.2)
			(type default)
		)
		(layer "In10.Cu")
	)
	(gr_arc
		(start 280.636726 -358.253792)
		(mid 281.185366 -357.705152)
		(end 280.636726 -357.156512)
		(stroke
			(width 0.2)
			(type default)
		)
		(layer "In10.Cu")
	)
	(gr_line
		(start 280.636726 -357.156512)
		(end 279.236932 -357.156512)
		(stroke
			(width 0.2)
			(type default)
		)
		(layer "In10.Cu")
	)
	(gr_arc
		(start 280.636726 -354.65385)
		(mid 281.185366 -354.10521)
		(end 280.636726 -353.55657)
		(stroke
			(width 0.2)
			(type default)
		)
		(layer "In10.Cu")
	)
	(gr_line
		(start 280.636726 -353.55657)
		(end 279.236932 -353.55657)
		(stroke
			(width 0.2)
			(type default)
		)
		(layer "In10.Cu")
	)
	(gr_arc
		(start 280.636726 -351.053908)
		(mid 281.185366 -350.505268)
		(end 280.636726 -349.956628)
		(stroke
			(width 0.2)
			(type default)
		)
		(layer "In10.Cu")
	)
	(gr_line
		(start 280.636726 -349.956628)
		(end 279.236932 -349.956628)
		(stroke
			(width 0.2)
			(type default)
		)
		(layer "In10.Cu")
	)
	(gr_arc
		(start 280.636726 -347.453712)
		(mid 281.185366 -346.905072)
		(end 280.636726 -346.356432)
		(stroke
			(width 0.2)
			(type default)
		)
		(layer "In10.Cu")
	)
	(gr_line
		(start 280.636726 -346.356432)
		(end 279.236932 -346.356432)
		(stroke
			(width 0.2)
			(type default)
		)
		(layer "In10.Cu")
	)
	(gr_arc
		(start 280.636726 -343.85377)
		(mid 281.185366 -343.30513)
		(end 280.636726 -342.75649)
		(stroke
			(width 0.2)
			(type default)
		)
		(layer "In10.Cu")
	)
	(gr_line
		(start 280.636726 -342.75649)
		(end 279.236932 -342.75649)
		(stroke
			(width 0.2)
			(type default)
		)
		(layer "In10.Cu")
	)
	(gr_arc
		(start 280.636726 -340.253828)
		(mid 281.185366 -339.705188)
		(end 280.636726 -339.156548)
		(stroke
			(width 0.2)
			(type default)
		)
		(layer "In10.Cu")
	)
	(gr_line
		(start 280.636726 -339.156548)
		(end 279.236932 -339.156548)
		(stroke
			(width 0.2)
			(type default)
		)
		(layer "In10.Cu")
	)
	(gr_arc
		(start 280.636726 -336.653886)
		(mid 281.185366 -336.105246)
		(end 280.636726 -335.556606)
		(stroke
			(width 0.2)
			(type default)
		)
		(layer "In10.Cu")
	)
	(gr_line
		(start 280.636726 -335.556606)
		(end 279.236932 -335.556606)
		(stroke
			(width 0.2)
			(type default)
		)
		(layer "In10.Cu")
	)
	(gr_arc
		(start 280.636726 -333.05369)
		(mid 281.185366 -332.50505)
		(end 280.636726 -331.95641)
		(stroke
			(width 0.2)
			(type default)
		)
		(layer "In10.Cu")
	)
	(gr_line
		(start 280.636726 -331.95641)
		(end 279.236932 -331.95641)
		(stroke
			(width 0.2)
			(type default)
		)
		(layer "In10.Cu")
	)
	(gr_arc
		(start 280.636726 -329.453748)
		(mid 281.185366 -328.905108)
		(end 280.636726 -328.356468)
		(stroke
			(width 0.2)
			(type default)
		)
		(layer "In10.Cu")
	)
	(gr_line
		(start 280.636726 -328.356468)
		(end 279.236932 -328.356468)
		(stroke
			(width 0.2)
			(type default)
		)
		(layer "In10.Cu")
	)
	(gr_arc
		(start 280.636726 -325.853806)
		(mid 281.185366 -325.305166)
		(end 280.636726 -324.756526)
		(stroke
			(width 0.2)
			(type default)
		)
		(layer "In10.Cu")
	)
	(gr_line
		(start 280.636726 -324.756526)
		(end 279.236932 -324.756526)
		(stroke
			(width 0.2)
			(type default)
		)
		(layer "In10.Cu")
	)
	(gr_arc
		(start 280.636726 -322.253864)
		(mid 281.185366 -321.705224)
		(end 280.636726 -321.156584)
		(stroke
			(width 0.2)
			(type default)
		)
		(layer "In10.Cu")
	)
	(gr_line
		(start 280.636726 -321.156584)
		(end 279.236932 -321.156584)
		(stroke
			(width 0.2)
			(type default)
		)
		(layer "In10.Cu")
	)
	(gr_arc
		(start 280.636726 -318.653668)
		(mid 281.185366 -318.105028)
		(end 280.636726 -317.556388)
		(stroke
			(width 0.2)
			(type default)
		)
		(layer "In10.Cu")
	)
	(gr_line
		(start 280.636726 -317.556388)
		(end 279.236932 -317.556388)
		(stroke
			(width 0.2)
			(type default)
		)
		(layer "In10.Cu")
	)
	(gr_arc
		(start 280.636726 -315.053726)
		(mid 281.185366 -314.505086)
		(end 280.636726 -313.956446)
		(stroke
			(width 0.2)
			(type default)
		)
		(layer "In10.Cu")
	)
	(gr_line
		(start 280.636726 -313.956446)
		(end 279.236932 -313.956446)
		(stroke
			(width 0.2)
			(type default)
		)
		(layer "In10.Cu")
	)
	(gr_arc
		(start 280.636726 -311.453784)
		(mid 281.185366 -310.905144)
		(end 280.636726 -310.356504)
		(stroke
			(width 0.2)
			(type default)
		)
		(layer "In10.Cu")
	)
	(gr_line
		(start 280.636726 -310.356504)
		(end 279.236932 -310.356504)
		(stroke
			(width 0.2)
			(type default)
		)
		(layer "In10.Cu")
	)
	(gr_arc
		(start 280.636726 -307.853842)
		(mid 281.185366 -307.305202)
		(end 280.636726 -306.756562)
		(stroke
			(width 0.2)
			(type default)
		)
		(layer "In10.Cu")
	)
	(gr_line
		(start 280.636726 -306.756562)
		(end 279.236932 -306.756562)
		(stroke
			(width 0.2)
			(type default)
		)
		(layer "In10.Cu")
	)
	(gr_arc
		(start 280.636726 -304.2539)
		(mid 281.185366 -303.70526)
		(end 280.636726 -303.15662)
		(stroke
			(width 0.2)
			(type default)
		)
		(layer "In10.Cu")
	)
	(gr_line
		(start 280.636726 -303.15662)
		(end 279.236932 -303.15662)
		(stroke
			(width 0.2)
			(type default)
		)
		(layer "In10.Cu")
	)
	(gr_arc
		(start 280.636726 -300.653704)
		(mid 281.185366 -300.105064)
		(end 280.636726 -299.556424)
		(stroke
			(width 0.2)
			(type default)
		)
		(layer "In10.Cu")
	)
	(gr_line
		(start 280.636726 -299.556424)
		(end 279.236932 -299.556424)
		(stroke
			(width 0.2)
			(type default)
		)
		(layer "In10.Cu")
	)
	(gr_arc
		(start 280.636726 -297.053762)
		(mid 281.185366 -296.505122)
		(end 280.636726 -295.956482)
		(stroke
			(width 0.2)
			(type default)
		)
		(layer "In10.Cu")
	)
	(gr_line
		(start 280.636726 -295.956482)
		(end 279.236932 -295.956482)
		(stroke
			(width 0.2)
			(type default)
		)
		(layer "In10.Cu")
	)
	(gr_arc
		(start 280.636726 -264.253472)
		(mid 281.187906 -263.702292)
		(end 280.636726 -263.151112)
		(stroke
			(width 0.2)
			(type default)
		)
		(layer "In10.Cu")
	)
	(gr_line
		(start 280.636726 -263.151112)
		(end 279.236932 -263.151112)
		(stroke
			(width 0.2)
			(type default)
		)
		(layer "In10.Cu")
	)
	(gr_arc
		(start 280.636726 -260.65353)
		(mid 281.187906 -260.10235)
		(end 280.636726 -259.55117)
		(stroke
			(width 0.2)
			(type default)
		)
		(layer "In10.Cu")
	)
	(gr_line
		(start 280.636726 -259.55117)
		(end 279.236932 -259.55117)
		(stroke
			(width 0.2)
			(type default)
		)
		(layer "In10.Cu")
	)
	(gr_arc
		(start 280.636726 -257.053588)
		(mid 281.187906 -256.502408)
		(end 280.636726 -255.951228)
		(stroke
			(width 0.2)
			(type default)
		)
		(layer "In10.Cu")
	)
	(gr_line
		(start 280.636726 -255.951228)
		(end 279.236932 -255.951228)
		(stroke
			(width 0.2)
			(type default)
		)
		(layer "In10.Cu")
	)
	(gr_arc
		(start 280.636726 -253.453392)
		(mid 281.187906 -252.902212)
		(end 280.636726 -252.351032)
		(stroke
			(width 0.2)
			(type default)
		)
		(layer "In10.Cu")
	)
	(gr_line
		(start 280.636726 -252.351032)
		(end 279.236932 -252.351032)
		(stroke
			(width 0.2)
			(type default)
		)
		(layer "In10.Cu")
	)
	(gr_arc
		(start 281.063446 -114.127026)
		(mid 281.377136 -113.186464)
		(end 280.436574 -112.872774)
		(stroke
			(width 0.2)
			(type default)
		)
		(layer "In10.Cu")
	)
	(gr_arc
		(start 281.07386 -162.14725)
		(mid 281.397456 -161.175954)
		(end 280.42616 -160.852358)
		(stroke
			(width 0.2)
			(type default)
		)
		(layer "In10.Cu")
	)
	(gr_arc
		(start 281.07386 -158.147258)
		(mid 281.397456 -157.175962)
		(end 280.42616 -156.852366)
		(stroke
			(width 0.2)
			(type default)
		)
		(layer "In10.Cu")
	)
	(gr_arc
		(start 281.07386 -154.147266)
		(mid 281.397456 -153.17597)
		(end 280.42616 -152.852374)
		(stroke
			(width 0.2)
			(type default)
		)
		(layer "In10.Cu")
	)
	(gr_arc
		(start 281.07386 -150.147274)
		(mid 281.397456 -149.175978)
		(end 280.42616 -148.852382)
		(stroke
			(width 0.2)
			(type default)
		)
		(layer "In10.Cu")
	)
	(gr_arc
		(start 281.07386 -130.147314)
		(mid 281.397456 -129.176018)
		(end 280.42616 -128.852422)
		(stroke
			(width 0.2)
			(type default)
		)
		(layer "In10.Cu")
	)
	(gr_arc
		(start 281.07386 -126.147322)
		(mid 281.397456 -125.176026)
		(end 280.42616 -124.85243)
		(stroke
			(width 0.2)
			(type default)
		)
		(layer "In10.Cu")
	)
	(gr_arc
		(start 281.07386 -122.14733)
		(mid 281.397456 -121.176034)
		(end 280.42616 -120.852438)
		(stroke
			(width 0.2)
			(type default)
		)
		(layer "In10.Cu")
	)
	(gr_arc
		(start 281.07386 -118.147338)
		(mid 281.397456 -117.176042)
		(end 280.42616 -116.852446)
		(stroke
			(width 0.2)
			(type default)
		)
		(layer "In10.Cu")
	)
	(gr_arc
		(start 281.074876 -178.149504)
		(mid 281.399742 -177.174906)
		(end 280.425144 -176.85004)
		(stroke
			(width 0.2)
			(type default)
		)
		(layer "In10.Cu")
	)
	(gr_arc
		(start 281.074876 -174.149512)
		(mid 281.399742 -173.174914)
		(end 280.425144 -172.850048)
		(stroke
			(width 0.2)
			(type default)
		)
		(layer "In10.Cu")
	)
	(gr_arc
		(start 281.074876 -170.14952)
		(mid 281.399742 -169.174922)
		(end 280.425144 -168.850056)
		(stroke
			(width 0.2)
			(type default)
		)
		(layer "In10.Cu")
	)
	(gr_arc
		(start 281.074876 -166.149528)
		(mid 281.399742 -165.17493)
		(end 280.425144 -164.850064)
		(stroke
			(width 0.2)
			(type default)
		)
		(layer "In10.Cu")
	)
	(gr_arc
		(start 281.074876 -138.149584)
		(mid 281.399742 -137.174986)
		(end 280.425144 -136.85012)
		(stroke
			(width 0.2)
			(type default)
		)
		(layer "In10.Cu")
	)
	(gr_arc
		(start 281.074876 -81.849722)
		(mid 281.399742 -80.875124)
		(end 280.425144 -80.550258)
		(stroke
			(width 0.2)
			(type default)
		)
		(layer "In10.Cu")
	)
	(gr_arc
		(start 281.074876 -77.84973)
		(mid 281.399742 -76.875132)
		(end 280.425144 -76.550266)
		(stroke
			(width 0.2)
			(type default)
		)
		(layer "In10.Cu")
	)
	(gr_arc
		(start 281.074876 -73.849738)
		(mid 281.399742 -72.87514)
		(end 280.425144 -72.550274)
		(stroke
			(width 0.2)
			(type default)
		)
		(layer "In10.Cu")
	)
	(gr_arc
		(start 281.074876 -69.849746)
		(mid 281.399742 -68.875148)
		(end 280.425144 -68.550282)
		(stroke
			(width 0.2)
			(type default)
		)
		(layer "In10.Cu")
	)
	(gr_arc
		(start 281.074876 -65.849754)
		(mid 281.399742 -64.875156)
		(end 280.425144 -64.55029)
		(stroke
			(width 0.2)
			(type default)
		)
		(layer "In10.Cu")
	)
	(gr_arc
		(start 281.074876 -61.849762)
		(mid 281.399742 -60.875164)
		(end 280.425144 -60.550298)
		(stroke
			(width 0.2)
			(type default)
		)
		(layer "In10.Cu")
	)
	(gr_arc
		(start 281.074876 -57.84977)
		(mid 281.399742 -56.875172)
		(end 280.425144 -56.550306)
		(stroke
			(width 0.2)
			(type default)
		)
		(layer "In10.Cu")
	)
	(gr_arc
		(start 281.074876 -53.849778)
		(mid 281.399742 -52.87518)
		(end 280.425144 -52.550314)
		(stroke
			(width 0.2)
			(type default)
		)
		(layer "In10.Cu")
	)
	(gr_arc
		(start 281.074876 -49.849786)
		(mid 281.399742 -48.875188)
		(end 280.425144 -48.550322)
		(stroke
			(width 0.2)
			(type default)
		)
		(layer "In10.Cu")
	)
	(gr_arc
		(start 281.074876 -45.849794)
		(mid 281.399742 -44.875196)
		(end 280.425144 -44.55033)
		(stroke
			(width 0.2)
			(type default)
		)
		(layer "In10.Cu")
	)
	(gr_arc
		(start 281.074876 -41.849802)
		(mid 281.399742 -40.875204)
		(end 280.425144 -40.550338)
		(stroke
			(width 0.2)
			(type default)
		)
		(layer "In10.Cu")
	)
	(gr_arc
		(start 281.074876 -37.84981)
		(mid 281.399742 -36.875212)
		(end 280.425144 -36.550346)
		(stroke
			(width 0.2)
			(type default)
		)
		(layer "In10.Cu")
	)
	(gr_arc
		(start 281.074876 -17.84985)
		(mid 281.399742 -16.875252)
		(end 280.425144 -16.550386)
		(stroke
			(width 0.2)
			(type default)
		)
		(layer "In10.Cu")
	)
	(gr_line
		(start 281.076146 -178.15179)
		(end 281.074876 -178.149504)
		(stroke
			(width 0.2)
			(type default)
		)
		(layer "In10.Cu")
	)
	(gr_line
		(start 281.076146 -174.151798)
		(end 281.074876 -174.149512)
		(stroke
			(width 0.2)
			(type default)
		)
		(layer "In10.Cu")
	)
	(gr_line
		(start 281.076146 -170.151806)
		(end 281.074876 -170.14952)
		(stroke
			(width 0.2)
			(type default)
		)
		(layer "In10.Cu")
	)
	(gr_line
		(start 281.076146 -166.151814)
		(end 281.074876 -166.149528)
		(stroke
			(width 0.2)
			(type default)
		)
		(layer "In10.Cu")
	)
	(gr_line
		(start 281.076146 -138.15187)
		(end 281.074876 -138.149584)
		(stroke
			(width 0.2)
			(type default)
		)
		(layer "In10.Cu")
	)
	(gr_line
		(start 281.076146 -81.852008)
		(end 281.074876 -81.849722)
		(stroke
			(width 0.2)
			(type default)
		)
		(layer "In10.Cu")
	)
	(gr_line
		(start 281.076146 -77.852016)
		(end 281.074876 -77.84973)
		(stroke
			(width 0.2)
			(type default)
		)
		(layer "In10.Cu")
	)
	(gr_line
		(start 281.076146 -73.852024)
		(end 281.074876 -73.849738)
		(stroke
			(width 0.2)
			(type default)
		)
		(layer "In10.Cu")
	)
	(gr_line
		(start 281.076146 -69.852032)
		(end 281.074876 -69.849746)
		(stroke
			(width 0.2)
			(type default)
		)
		(layer "In10.Cu")
	)
	(gr_line
		(start 281.076146 -65.85204)
		(end 281.074876 -65.849754)
		(stroke
			(width 0.2)
			(type default)
		)
		(layer "In10.Cu")
	)
	(gr_line
		(start 281.076146 -61.852048)
		(end 281.074876 -61.849762)
		(stroke
			(width 0.2)
			(type default)
		)
		(layer "In10.Cu")
	)
	(gr_line
		(start 281.076146 -57.852056)
		(end 281.074876 -57.84977)
		(stroke
			(width 0.2)
			(type default)
		)
		(layer "In10.Cu")
	)
	(gr_line
		(start 281.076146 -53.852064)
		(end 281.074876 -53.849778)
		(stroke
			(width 0.2)
			(type default)
		)
		(layer "In10.Cu")
	)
	(gr_line
		(start 281.076146 -49.852072)
		(end 281.074876 -49.849786)
		(stroke
			(width 0.2)
			(type default)
		)
		(layer "In10.Cu")
	)
	(gr_line
		(start 281.076146 -45.85208)
		(end 281.074876 -45.849794)
		(stroke
			(width 0.2)
			(type default)
		)
		(layer "In10.Cu")
	)
	(gr_line
		(start 281.076146 -41.852088)
		(end 281.074876 -41.849802)
		(stroke
			(width 0.2)
			(type default)
		)
		(layer "In10.Cu")
	)
	(gr_line
		(start 281.076146 -37.852096)
		(end 281.074876 -37.84981)
		(stroke
			(width 0.2)
			(type default)
		)
		(layer "In10.Cu")
	)
	(gr_line
		(start 281.076146 -17.852136)
		(end 281.074876 -17.84985)
		(stroke
			(width 0.2)
			(type default)
		)
		(layer "In10.Cu")
	)
	(gr_arc
		(start 281.077162 -11.854434)
		(mid 281.404314 -10.872978)
		(end 280.422858 -10.545826)
		(stroke
			(width 0.2)
			(type default)
		)
		(layer "In10.Cu")
	)
	(gr_line
		(start 282.83662 -264.250932)
		(end 284.236668 -264.250932)
		(stroke
			(width 0.2)
			(type default)
		)
		(layer "In10.Cu")
	)
	(gr_arc
		(start 282.83662 -263.153652)
		(mid 282.28798 -263.702292)
		(end 282.83662 -264.250932)
		(stroke
			(width 0.2)
			(type default)
		)
		(layer "In10.Cu")
	)
	(gr_line
		(start 282.922726 -35.854386)
		(end 284.922468 -36.854384)
		(stroke
			(width 0.2)
			(type default)
		)
		(layer "In10.Cu")
	)
	(gr_line
		(start 282.923742 -136.151874)
		(end 284.923738 -137.151872)
		(stroke
			(width 0.2)
			(type default)
		)
		(layer "In10.Cu")
	)
	(gr_line
		(start 282.923742 -108.15193)
		(end 284.923738 -109.151928)
		(stroke
			(width 0.2)
			(type default)
		)
		(layer "In10.Cu")
	)
	(gr_line
		(start 282.925012 -136.149588)
		(end 282.923742 -136.151874)
		(stroke
			(width 0.2)
			(type default)
		)
		(layer "In10.Cu")
	)
	(gr_line
		(start 282.936442 -180.126894)
		(end 284.928056 -181.122574)
		(stroke
			(width 0.2)
			(type default)
		)
		(layer "In10.Cu")
	)
	(gr_line
		(start 282.936442 -176.126902)
		(end 284.928056 -177.122582)
		(stroke
			(width 0.2)
			(type default)
		)
		(layer "In10.Cu")
	)
	(gr_line
		(start 282.936442 -172.12691)
		(end 284.928056 -173.12259)
		(stroke
			(width 0.2)
			(type default)
		)
		(layer "In10.Cu")
	)
	(gr_line
		(start 282.936442 -168.126918)
		(end 284.928056 -169.122598)
		(stroke
			(width 0.2)
			(type default)
		)
		(layer "In10.Cu")
	)
	(gr_line
		(start 282.936442 -164.126926)
		(end 284.928056 -165.122606)
		(stroke
			(width 0.2)
			(type default)
		)
		(layer "In10.Cu")
	)
	(gr_line
		(start 282.936442 -160.126934)
		(end 284.936438 -161.126932)
		(stroke
			(width 0.2)
			(type default)
		)
		(layer "In10.Cu")
	)
	(gr_line
		(start 282.936442 -156.126942)
		(end 284.928056 -157.122622)
		(stroke
			(width 0.2)
			(type default)
		)
		(layer "In10.Cu")
	)
	(gr_line
		(start 282.936442 -152.12695)
		(end 284.928056 -153.12263)
		(stroke
			(width 0.2)
			(type default)
		)
		(layer "In10.Cu")
	)
	(gr_line
		(start 282.936442 -128.126998)
		(end 284.928056 -129.122678)
		(stroke
			(width 0.2)
			(type default)
		)
		(layer "In10.Cu")
	)
	(gr_line
		(start 282.936442 -124.127006)
		(end 284.928056 -125.122686)
		(stroke
			(width 0.2)
			(type default)
		)
		(layer "In10.Cu")
	)
	(gr_line
		(start 282.936442 -120.127014)
		(end 284.928056 -121.122694)
		(stroke
			(width 0.2)
			(type default)
		)
		(layer "In10.Cu")
	)
	(gr_line
		(start 282.936442 -116.127022)
		(end 284.928056 -117.122702)
		(stroke
			(width 0.2)
			(type default)
		)
		(layer "In10.Cu")
	)
	(gr_line
		(start 282.936442 -83.827112)
		(end 284.928056 -84.822792)
		(stroke
			(width 0.2)
			(type default)
		)
		(layer "In10.Cu")
	)
	(gr_line
		(start 282.936442 -79.82712)
		(end 284.928056 -80.8228)
		(stroke
			(width 0.2)
			(type default)
		)
		(layer "In10.Cu")
	)
	(gr_line
		(start 282.936442 -75.827128)
		(end 284.928056 -76.822808)
		(stroke
			(width 0.2)
			(type default)
		)
		(layer "In10.Cu")
	)
	(gr_line
		(start 282.936442 -71.827136)
		(end 284.928056 -72.822816)
		(stroke
			(width 0.2)
			(type default)
		)
		(layer "In10.Cu")
	)
	(gr_line
		(start 282.936442 -67.827144)
		(end 284.928056 -68.822824)
		(stroke
			(width 0.2)
			(type default)
		)
		(layer "In10.Cu")
	)
	(gr_line
		(start 282.936442 -63.827152)
		(end 284.928056 -64.822832)
		(stroke
			(width 0.2)
			(type default)
		)
		(layer "In10.Cu")
	)
	(gr_line
		(start 282.936442 -59.82716)
		(end 284.928056 -60.82284)
		(stroke
			(width 0.2)
			(type default)
		)
		(layer "In10.Cu")
	)
	(gr_line
		(start 282.936442 -55.827168)
		(end 284.928056 -56.822848)
		(stroke
			(width 0.2)
			(type default)
		)
		(layer "In10.Cu")
	)
	(gr_line
		(start 282.936442 -51.827176)
		(end 284.928056 -52.822856)
		(stroke
			(width 0.2)
			(type default)
		)
		(layer "In10.Cu")
	)
	(gr_line
		(start 282.936442 -47.827184)
		(end 284.928056 -48.822864)
		(stroke
			(width 0.2)
			(type default)
		)
		(layer "In10.Cu")
	)
	(gr_line
		(start 282.936442 -43.827192)
		(end 284.928056 -44.822872)
		(stroke
			(width 0.2)
			(type default)
		)
		(layer "In10.Cu")
	)
	(gr_line
		(start 282.936442 -39.8272)
		(end 284.928056 -40.82288)
		(stroke
			(width 0.2)
			(type default)
		)
		(layer "In10.Cu")
	)
	(gr_arc
		(start 283.563314 -178.872642)
		(mid 282.622752 -179.186332)
		(end 282.936442 -180.126894)
		(stroke
			(width 0.2)
			(type default)
		)
		(layer "In10.Cu")
	)
	(gr_arc
		(start 283.563314 -174.87265)
		(mid 282.622752 -175.18634)
		(end 282.936442 -176.126902)
		(stroke
			(width 0.2)
			(type default)
		)
		(layer "In10.Cu")
	)
	(gr_arc
		(start 283.563314 -170.872658)
		(mid 282.622752 -171.186348)
		(end 282.936442 -172.12691)
		(stroke
			(width 0.2)
			(type default)
		)
		(layer "In10.Cu")
	)
	(gr_arc
		(start 283.563314 -166.872666)
		(mid 282.622752 -167.186356)
		(end 282.936442 -168.126918)
		(stroke
			(width 0.2)
			(type default)
		)
		(layer "In10.Cu")
	)
	(gr_arc
		(start 283.563314 -162.872674)
		(mid 282.622752 -163.186364)
		(end 282.936442 -164.126926)
		(stroke
			(width 0.2)
			(type default)
		)
		(layer "In10.Cu")
	)
	(gr_arc
		(start 283.563314 -154.87269)
		(mid 282.622752 -155.18638)
		(end 282.936442 -156.126942)
		(stroke
			(width 0.2)
			(type default)
		)
		(layer "In10.Cu")
	)
	(gr_arc
		(start 283.563314 -150.872698)
		(mid 282.622752 -151.186388)
		(end 282.936442 -152.12695)
		(stroke
			(width 0.2)
			(type default)
		)
		(layer "In10.Cu")
	)
	(gr_arc
		(start 283.563314 -126.872746)
		(mid 282.622752 -127.186436)
		(end 282.936442 -128.126998)
		(stroke
			(width 0.2)
			(type default)
		)
		(layer "In10.Cu")
	)
	(gr_arc
		(start 283.563314 -122.872754)
		(mid 282.622752 -123.186444)
		(end 282.936442 -124.127006)
		(stroke
			(width 0.2)
			(type default)
		)
		(layer "In10.Cu")
	)
	(gr_arc
		(start 283.563314 -118.872762)
		(mid 282.622752 -119.186452)
		(end 282.936442 -120.127014)
		(stroke
			(width 0.2)
			(type default)
		)
		(layer "In10.Cu")
	)
	(gr_arc
		(start 283.563314 -114.87277)
		(mid 282.622752 -115.18646)
		(end 282.936442 -116.127022)
		(stroke
			(width 0.2)
			(type default)
		)
		(layer "In10.Cu")
	)
	(gr_arc
		(start 283.563314 -82.57286)
		(mid 282.622752 -82.88655)
		(end 282.936442 -83.827112)
		(stroke
			(width 0.2)
			(type default)
		)
		(layer "In10.Cu")
	)
	(gr_arc
		(start 283.563314 -78.572868)
		(mid 282.622752 -78.886558)
		(end 282.936442 -79.82712)
		(stroke
			(width 0.2)
			(type default)
		)
		(layer "In10.Cu")
	)
	(gr_arc
		(start 283.563314 -74.572876)
		(mid 282.622752 -74.886566)
		(end 282.936442 -75.827128)
		(stroke
			(width 0.2)
			(type default)
		)
		(layer "In10.Cu")
	)
	(gr_arc
		(start 283.563314 -70.572884)
		(mid 282.622752 -70.886574)
		(end 282.936442 -71.827136)
		(stroke
			(width 0.2)
			(type default)
		)
		(layer "In10.Cu")
	)
	(gr_arc
		(start 283.563314 -66.572892)
		(mid 282.622752 -66.886582)
		(end 282.936442 -67.827144)
		(stroke
			(width 0.2)
			(type default)
		)
		(layer "In10.Cu")
	)
	(gr_arc
		(start 283.563314 -62.5729)
		(mid 282.622752 -62.88659)
		(end 282.936442 -63.827152)
		(stroke
			(width 0.2)
			(type default)
		)
		(layer "In10.Cu")
	)
	(gr_arc
		(start 283.563314 -58.572908)
		(mid 282.622752 -58.886598)
		(end 282.936442 -59.82716)
		(stroke
			(width 0.2)
			(type default)
		)
		(layer "In10.Cu")
	)
	(gr_arc
		(start 283.563314 -54.572916)
		(mid 282.622752 -54.886606)
		(end 282.936442 -55.827168)
		(stroke
			(width 0.2)
			(type default)
		)
		(layer "In10.Cu")
	)
	(gr_arc
		(start 283.563314 -50.572924)
		(mid 282.622752 -50.886614)
		(end 282.936442 -51.827176)
		(stroke
			(width 0.2)
			(type default)
		)
		(layer "In10.Cu")
	)
	(gr_arc
		(start 283.563314 -46.572932)
		(mid 282.622752 -46.886622)
		(end 282.936442 -47.827184)
		(stroke
			(width 0.2)
			(type default)
		)
		(layer "In10.Cu")
	)
	(gr_arc
		(start 283.563314 -42.57294)
		(mid 282.622752 -42.88663)
		(end 282.936442 -43.827192)
		(stroke
			(width 0.2)
			(type default)
		)
		(layer "In10.Cu")
	)
	(gr_arc
		(start 283.563314 -38.572948)
		(mid 282.622752 -38.886638)
		(end 282.936442 -39.8272)
		(stroke
			(width 0.2)
			(type default)
		)
		(layer "In10.Cu")
	)
	(gr_arc
		(start 283.571696 -158.877)
		(mid 282.62492 -159.182185)
		(end 282.936442 -160.126934)
		(stroke
			(width 0.2)
			(type default)
		)
		(layer "In10.Cu")
	)
	(gr_arc
		(start 283.574744 -134.850124)
		(mid 282.600146 -135.17499)
		(end 282.925012 -136.149588)
		(stroke
			(width 0.2)
			(type default)
		)
		(layer "In10.Cu")
	)
	(gr_line
		(start 283.576014 -134.847838)
		(end 283.574744 -134.850124)
		(stroke
			(width 0.2)
			(type default)
		)
		(layer "In10.Cu")
	)
	(gr_arc
		(start 283.576014 -106.847894)
		(mid 282.59786 -107.173776)
		(end 282.923742 -108.15193)
		(stroke
			(width 0.2)
			(type default)
		)
		(layer "In10.Cu")
	)
	(gr_arc
		(start 283.57703 -34.545778)
		(mid 282.595574 -34.87293)
		(end 282.922726 -35.854386)
		(stroke
			(width 0.2)
			(type default)
		)
		(layer "In10.Cu")
	)
	(gr_arc
		(start 284.236668 -264.250932)
		(mid 284.785308 -263.702292)
		(end 284.236668 -263.153652)
		(stroke
			(width 0.2)
			(type default)
		)
		(layer "In10.Cu")
	)
	(gr_line
		(start 284.236668 -263.153652)
		(end 282.83662 -263.153652)
		(stroke
			(width 0.2)
			(type default)
		)
		(layer "In10.Cu")
	)
	(gr_arc
		(start 284.922468 -36.854384)
		(mid 285.904229 -36.527384)
		(end 285.577026 -35.545776)
		(stroke
			(width 0.2)
			(type default)
		)
		(layer "In10.Cu")
	)
	(gr_line
		(start 284.923738 -137.151872)
		(end 284.923992 -137.151618)
		(stroke
			(width 0.2)
			(type default)
		)
		(layer "In10.Cu")
	)
	(gr_arc
		(start 284.923738 -109.151928)
		(mid 285.901892 -108.826046)
		(end 285.57601 -107.847892)
		(stroke
			(width 0.2)
			(type default)
		)
		(layer "In10.Cu")
	)
	(gr_line
		(start 284.923992 -137.151618)
		(end 284.925008 -137.149586)
		(stroke
			(width 0.2)
			(type default)
		)
		(layer "In10.Cu")
	)
	(gr_arc
		(start 284.925008 -137.149586)
		(mid 285.899606 -136.82472)
		(end 285.57474 -135.850122)
		(stroke
			(width 0.2)
			(type default)
		)
		(layer "In10.Cu")
	)
	(gr_arc
		(start 284.928056 -181.122574)
		(mid 285.874832 -180.817389)
		(end 285.56331 -179.87264)
		(stroke
			(width 0.2)
			(type default)
		)
		(layer "In10.Cu")
	)
	(gr_arc
		(start 284.928056 -177.122582)
		(mid 285.874832 -176.817397)
		(end 285.56331 -175.872648)
		(stroke
			(width 0.2)
			(type default)
		)
		(layer "In10.Cu")
	)
	(gr_arc
		(start 284.928056 -173.12259)
		(mid 285.874832 -172.817405)
		(end 285.56331 -171.872656)
		(stroke
			(width 0.2)
			(type default)
		)
		(layer "In10.Cu")
	)
	(gr_arc
		(start 284.928056 -169.122598)
		(mid 285.874832 -168.817413)
		(end 285.56331 -167.872664)
		(stroke
			(width 0.2)
			(type default)
		)
		(layer "In10.Cu")
	)
	(gr_arc
		(start 284.928056 -165.122606)
		(mid 285.874832 -164.817421)
		(end 285.56331 -163.872672)
		(stroke
			(width 0.2)
			(type default)
		)
		(layer "In10.Cu")
	)
	(gr_arc
		(start 284.928056 -157.122622)
		(mid 285.874832 -156.817437)
		(end 285.56331 -155.872688)
		(stroke
			(width 0.2)
			(type default)
		)
		(layer "In10.Cu")
	)
	(gr_arc
		(start 284.928056 -153.12263)
		(mid 285.874832 -152.817445)
		(end 285.56331 -151.872696)
		(stroke
			(width 0.2)
			(type default)
		)
		(layer "In10.Cu")
	)
	(gr_arc
		(start 284.928056 -129.122678)
		(mid 285.874832 -128.817493)
		(end 285.56331 -127.872744)
		(stroke
			(width 0.2)
			(type default)
		)
		(layer "In10.Cu")
	)
	(gr_arc
		(start 284.928056 -125.122686)
		(mid 285.874832 -124.817501)
		(end 285.56331 -123.872752)
		(stroke
			(width 0.2)
			(type default)
		)
		(layer "In10.Cu")
	)
	(gr_arc
		(start 284.928056 -121.122694)
		(mid 285.874832 -120.817509)
		(end 285.56331 -119.87276)
		(stroke
			(width 0.2)
			(type default)
		)
		(layer "In10.Cu")
	)
	(gr_arc
		(start 284.928056 -117.122702)
		(mid 285.874832 -116.817517)
		(end 285.56331 -115.872768)
		(stroke
			(width 0.2)
			(type default)
		)
		(layer "In10.Cu")
	)
	(gr_arc
		(start 284.928056 -84.822792)
		(mid 285.874832 -84.517607)
		(end 285.56331 -83.572858)
		(stroke
			(width 0.2)
			(type default)
		)
		(layer "In10.Cu")
	)
	(gr_arc
		(start 284.928056 -80.8228)
		(mid 285.874832 -80.517615)
		(end 285.56331 -79.572866)
		(stroke
			(width 0.2)
			(type default)
		)
		(layer "In10.Cu")
	)
	(gr_arc
		(start 284.928056 -76.822808)
		(mid 285.874832 -76.517623)
		(end 285.56331 -75.572874)
		(stroke
			(width 0.2)
			(type default)
		)
		(layer "In10.Cu")
	)
	(gr_arc
		(start 284.928056 -72.822816)
		(mid 285.874832 -72.517631)
		(end 285.56331 -71.572882)
		(stroke
			(width 0.2)
			(type default)
		)
		(layer "In10.Cu")
	)
	(gr_arc
		(start 284.928056 -68.822824)
		(mid 285.874832 -68.517639)
		(end 285.56331 -67.57289)
		(stroke
			(width 0.2)
			(type default)
		)
		(layer "In10.Cu")
	)
	(gr_arc
		(start 284.928056 -64.822832)
		(mid 285.874832 -64.517647)
		(end 285.56331 -63.572898)
		(stroke
			(width 0.2)
			(type default)
		)
		(layer "In10.Cu")
	)
	(gr_arc
		(start 284.928056 -60.82284)
		(mid 285.874832 -60.517655)
		(end 285.56331 -59.572906)
		(stroke
			(width 0.2)
			(type default)
		)
		(layer "In10.Cu")
	)
	(gr_arc
		(start 284.928056 -56.822848)
		(mid 285.874832 -56.517663)
		(end 285.56331 -55.572914)
		(stroke
			(width 0.2)
			(type default)
		)
		(layer "In10.Cu")
	)
	(gr_arc
		(start 284.928056 -52.822856)
		(mid 285.874832 -52.517671)
		(end 285.56331 -51.572922)
		(stroke
			(width 0.2)
			(type default)
		)
		(layer "In10.Cu")
	)
	(gr_arc
		(start 284.928056 -48.822864)
		(mid 285.874832 -48.517679)
		(end 285.56331 -47.57293)
		(stroke
			(width 0.2)
			(type default)
		)
		(layer "In10.Cu")
	)
	(gr_arc
		(start 284.928056 -44.822872)
		(mid 285.874832 -44.517687)
		(end 285.56331 -43.572938)
		(stroke
			(width 0.2)
			(type default)
		)
		(layer "In10.Cu")
	)
	(gr_arc
		(start 284.928056 -40.82288)
		(mid 285.874832 -40.517695)
		(end 285.56331 -39.572946)
		(stroke
			(width 0.2)
			(type default)
		)
		(layer "In10.Cu")
	)
	(gr_arc
		(start 284.936438 -161.126932)
		(mid 285.877 -160.813242)
		(end 285.56331 -159.87268)
		(stroke
			(width 0.2)
			(type default)
		)
		(layer "In10.Cu")
	)
	(gr_line
		(start 285.436564 -356.456234)
		(end 286.836612 -356.456234)
		(stroke
			(width 0.2)
			(type default)
		)
		(layer "In10.Cu")
	)
	(gr_arc
		(start 285.436564 -355.353874)
		(mid 284.885384 -355.905054)
		(end 285.436564 -356.456234)
		(stroke
			(width 0.2)
			(type default)
		)
		(layer "In10.Cu")
	)
	(gr_line
		(start 285.436564 -352.856292)
		(end 286.836612 -352.856292)
		(stroke
			(width 0.2)
			(type default)
		)
		(layer "In10.Cu")
	)
	(gr_arc
		(start 285.436564 -351.753932)
		(mid 284.885384 -352.305112)
		(end 285.436564 -352.856292)
		(stroke
			(width 0.2)
			(type default)
		)
		(layer "In10.Cu")
	)
	(gr_line
		(start 285.436564 -349.25635)
		(end 286.836612 -349.25635)
		(stroke
			(width 0.2)
			(type default)
		)
		(layer "In10.Cu")
	)
	(gr_arc
		(start 285.436564 -348.15399)
		(mid 284.885384 -348.70517)
		(end 285.436564 -349.25635)
		(stroke
			(width 0.2)
			(type default)
		)
		(layer "In10.Cu")
	)
	(gr_line
		(start 285.436564 -345.653868)
		(end 286.836612 -345.653868)
		(stroke
			(width 0.2)
			(type default)
		)
		(layer "In10.Cu")
	)
	(gr_arc
		(start 285.436564 -344.556588)
		(mid 284.887924 -345.105228)
		(end 285.436564 -345.653868)
		(stroke
			(width 0.2)
			(type default)
		)
		(layer "In10.Cu")
	)
	(gr_line
		(start 285.436564 -342.053672)
		(end 286.836612 -342.053672)
		(stroke
			(width 0.2)
			(type default)
		)
		(layer "In10.Cu")
	)
	(gr_arc
		(start 285.436564 -340.956392)
		(mid 284.887924 -341.505032)
		(end 285.436564 -342.053672)
		(stroke
			(width 0.2)
			(type default)
		)
		(layer "In10.Cu")
	)
	(gr_line
		(start 285.436564 -338.45373)
		(end 286.836612 -338.45373)
		(stroke
			(width 0.2)
			(type default)
		)
		(layer "In10.Cu")
	)
	(gr_arc
		(start 285.436564 -337.35645)
		(mid 284.887924 -337.90509)
		(end 285.436564 -338.45373)
		(stroke
			(width 0.2)
			(type default)
		)
		(layer "In10.Cu")
	)
	(gr_line
		(start 285.436564 -334.856328)
		(end 286.836612 -334.856328)
		(stroke
			(width 0.2)
			(type default)
		)
		(layer "In10.Cu")
	)
	(gr_arc
		(start 285.436564 -333.753968)
		(mid 284.885384 -334.305148)
		(end 285.436564 -334.856328)
		(stroke
			(width 0.2)
			(type default)
		)
		(layer "In10.Cu")
	)
	(gr_line
		(start 285.436564 -331.256386)
		(end 286.836612 -331.256386)
		(stroke
			(width 0.2)
			(type default)
		)
		(layer "In10.Cu")
	)
	(gr_arc
		(start 285.436564 -330.154026)
		(mid 284.885384 -330.705206)
		(end 285.436564 -331.256386)
		(stroke
			(width 0.2)
			(type default)
		)
		(layer "In10.Cu")
	)
	(gr_line
		(start 285.436564 -327.656444)
		(end 286.836612 -327.656444)
		(stroke
			(width 0.2)
			(type default)
		)
		(layer "In10.Cu")
	)
	(gr_arc
		(start 285.436564 -326.554084)
		(mid 284.885384 -327.105264)
		(end 285.436564 -327.656444)
		(stroke
			(width 0.2)
			(type default)
		)
		(layer "In10.Cu")
	)
	(gr_line
		(start 285.436564 -324.053708)
		(end 286.836612 -324.053708)
		(stroke
			(width 0.2)
			(type default)
		)
		(layer "In10.Cu")
	)
	(gr_arc
		(start 285.436564 -322.956428)
		(mid 284.887924 -323.505068)
		(end 285.436564 -324.053708)
		(stroke
			(width 0.2)
			(type default)
		)
		(layer "In10.Cu")
	)
	(gr_line
		(start 285.436564 -320.453766)
		(end 286.836612 -320.453766)
		(stroke
			(width 0.2)
			(type default)
		)
		(layer "In10.Cu")
	)
	(gr_arc
		(start 285.436564 -319.356486)
		(mid 284.887924 -319.905126)
		(end 285.436564 -320.453766)
		(stroke
			(width 0.2)
			(type default)
		)
		(layer "In10.Cu")
	)
	(gr_line
		(start 285.436564 -316.853824)
		(end 286.836612 -316.853824)
		(stroke
			(width 0.2)
			(type default)
		)
		(layer "In10.Cu")
	)
	(gr_arc
		(start 285.436564 -315.756544)
		(mid 284.887924 -316.305184)
		(end 285.436564 -316.853824)
		(stroke
			(width 0.2)
			(type default)
		)
		(layer "In10.Cu")
	)
	(gr_line
		(start 285.436564 -313.256422)
		(end 286.836612 -313.256422)
		(stroke
			(width 0.2)
			(type default)
		)
		(layer "In10.Cu")
	)
	(gr_arc
		(start 285.436564 -312.154062)
		(mid 284.885384 -312.705242)
		(end 285.436564 -313.256422)
		(stroke
			(width 0.2)
			(type default)
		)
		(layer "In10.Cu")
	)
	(gr_line
		(start 285.436564 -309.656226)
		(end 286.836612 -309.656226)
		(stroke
			(width 0.2)
			(type default)
		)
		(layer "In10.Cu")
	)
	(gr_arc
		(start 285.436564 -308.553866)
		(mid 284.885384 -309.105046)
		(end 285.436564 -309.656226)
		(stroke
			(width 0.2)
			(type default)
		)
		(layer "In10.Cu")
	)
	(gr_line
		(start 285.436564 -306.056284)
		(end 286.836612 -306.056284)
		(stroke
			(width 0.2)
			(type default)
		)
		(layer "In10.Cu")
	)
	(gr_arc
		(start 285.436564 -304.953924)
		(mid 284.885384 -305.505104)
		(end 285.436564 -306.056284)
		(stroke
			(width 0.2)
			(type default)
		)
		(layer "In10.Cu")
	)
	(gr_line
		(start 285.436564 -302.453802)
		(end 286.836612 -302.453802)
		(stroke
			(width 0.2)
			(type default)
		)
		(layer "In10.Cu")
	)
	(gr_arc
		(start 285.436564 -301.356522)
		(mid 284.887924 -301.905162)
		(end 285.436564 -302.453802)
		(stroke
			(width 0.2)
			(type default)
		)
		(layer "In10.Cu")
	)
	(gr_line
		(start 285.436564 -298.85386)
		(end 286.836612 -298.85386)
		(stroke
			(width 0.2)
			(type default)
		)
		(layer "In10.Cu")
	)
	(gr_arc
		(start 285.436564 -297.75658)
		(mid 284.887924 -298.30522)
		(end 285.436564 -298.85386)
		(stroke
			(width 0.2)
			(type default)
		)
		(layer "In10.Cu")
	)
	(gr_line
		(start 285.436564 -295.256458)
		(end 286.836612 -295.256458)
		(stroke
			(width 0.2)
			(type default)
		)
		(layer "In10.Cu")
	)
	(gr_arc
		(start 285.436564 -294.154098)
		(mid 284.885384 -294.705278)
		(end 285.436564 -295.256458)
		(stroke
			(width 0.2)
			(type default)
		)
		(layer "In10.Cu")
	)
	(gr_line
		(start 285.436564 -262.453374)
		(end 286.836612 -262.453374)
		(stroke
			(width 0.2)
			(type default)
		)
		(layer "In10.Cu")
	)
	(gr_arc
		(start 285.436564 -261.351014)
		(mid 284.885384 -261.902194)
		(end 285.436564 -262.453374)
		(stroke
			(width 0.2)
			(type default)
		)
		(layer "In10.Cu")
	)
	(gr_line
		(start 285.436564 -258.853432)
		(end 286.836612 -258.853432)
		(stroke
			(width 0.2)
			(type default)
		)
		(layer "In10.Cu")
	)
	(gr_arc
		(start 285.436564 -257.751072)
		(mid 284.885384 -258.302252)
		(end 285.436564 -258.853432)
		(stroke
			(width 0.2)
			(type default)
		)
		(layer "In10.Cu")
	)
	(gr_line
		(start 285.436564 -255.25349)
		(end 286.836612 -255.25349)
		(stroke
			(width 0.2)
			(type default)
		)
		(layer "In10.Cu")
	)
	(gr_arc
		(start 285.436564 -254.15113)
		(mid 284.885384 -254.70231)
		(end 285.436564 -255.25349)
		(stroke
			(width 0.2)
			(type default)
		)
		(layer "In10.Cu")
	)
	(gr_line
		(start 285.436564 -251.653548)
		(end 286.836612 -251.653548)
		(stroke
			(width 0.2)
			(type default)
		)
		(layer "In10.Cu")
	)
	(gr_arc
		(start 285.436564 -250.551188)
		(mid 284.885384 -251.102368)
		(end 285.436564 -251.653548)
		(stroke
			(width 0.2)
			(type default)
		)
		(layer "In10.Cu")
	)
	(gr_line
		(start 285.436818 -355.353874)
		(end 285.436564 -355.353874)
		(stroke
			(width 0.2)
			(type default)
		)
		(layer "In10.Cu")
	)
	(gr_line
		(start 285.436818 -351.753932)
		(end 285.436564 -351.753932)
		(stroke
			(width 0.2)
			(type default)
		)
		(layer "In10.Cu")
	)
	(gr_line
		(start 285.436818 -348.15399)
		(end 285.436564 -348.15399)
		(stroke
			(width 0.2)
			(type default)
		)
		(layer "In10.Cu")
	)
	(gr_line
		(start 285.436818 -344.556588)
		(end 285.436564 -344.556588)
		(stroke
			(width 0.2)
			(type default)
		)
		(layer "In10.Cu")
	)
	(gr_line
		(start 285.436818 -340.956392)
		(end 285.436564 -340.956392)
		(stroke
			(width 0.2)
			(type default)
		)
		(layer "In10.Cu")
	)
	(gr_line
		(start 285.436818 -337.35645)
		(end 285.436564 -337.35645)
		(stroke
			(width 0.2)
			(type default)
		)
		(layer "In10.Cu")
	)
	(gr_line
		(start 285.436818 -333.753968)
		(end 285.436564 -333.753968)
		(stroke
			(width 0.2)
			(type default)
		)
		(layer "In10.Cu")
	)
	(gr_line
		(start 285.436818 -330.154026)
		(end 285.436564 -330.154026)
		(stroke
			(width 0.2)
			(type default)
		)
		(layer "In10.Cu")
	)
	(gr_line
		(start 285.436818 -326.554084)
		(end 285.436564 -326.554084)
		(stroke
			(width 0.2)
			(type default)
		)
		(layer "In10.Cu")
	)
	(gr_line
		(start 285.436818 -322.956428)
		(end 285.436564 -322.956428)
		(stroke
			(width 0.2)
			(type default)
		)
		(layer "In10.Cu")
	)
	(gr_line
		(start 285.436818 -319.356486)
		(end 285.436564 -319.356486)
		(stroke
			(width 0.2)
			(type default)
		)
		(layer "In10.Cu")
	)
	(gr_line
		(start 285.436818 -315.756544)
		(end 285.436564 -315.756544)
		(stroke
			(width 0.2)
			(type default)
		)
		(layer "In10.Cu")
	)
	(gr_line
		(start 285.436818 -312.154062)
		(end 285.436564 -312.154062)
		(stroke
			(width 0.2)
			(type default)
		)
		(layer "In10.Cu")
	)
	(gr_line
		(start 285.436818 -308.553866)
		(end 285.436564 -308.553866)
		(stroke
			(width 0.2)
			(type default)
		)
		(layer "In10.Cu")
	)
	(gr_line
		(start 285.436818 -304.953924)
		(end 285.436564 -304.953924)
		(stroke
			(width 0.2)
			(type default)
		)
		(layer "In10.Cu")
	)
	(gr_line
		(start 285.436818 -301.356522)
		(end 285.436564 -301.356522)
		(stroke
			(width 0.2)
			(type default)
		)
		(layer "In10.Cu")
	)
	(gr_line
		(start 285.436818 -297.75658)
		(end 285.436564 -297.75658)
		(stroke
			(width 0.2)
			(type default)
		)
		(layer "In10.Cu")
	)
	(gr_line
		(start 285.436818 -294.154098)
		(end 285.436564 -294.154098)
		(stroke
			(width 0.2)
			(type default)
		)
		(layer "In10.Cu")
	)
	(gr_line
		(start 285.436818 -261.351014)
		(end 285.436564 -261.351014)
		(stroke
			(width 0.2)
			(type default)
		)
		(layer "In10.Cu")
	)
	(gr_line
		(start 285.436818 -257.751072)
		(end 285.436564 -257.751072)
		(stroke
			(width 0.2)
			(type default)
		)
		(layer "In10.Cu")
	)
	(gr_line
		(start 285.436818 -254.15113)
		(end 285.436564 -254.15113)
		(stroke
			(width 0.2)
			(type default)
		)
		(layer "In10.Cu")
	)
	(gr_line
		(start 285.436818 -250.551188)
		(end 285.436564 -250.551188)
		(stroke
			(width 0.2)
			(type default)
		)
		(layer "In10.Cu")
	)
	(gr_line
		(start 285.56331 -179.87264)
		(end 283.563314 -178.872642)
		(stroke
			(width 0.2)
			(type default)
		)
		(layer "In10.Cu")
	)
	(gr_line
		(start 285.56331 -175.872648)
		(end 283.563314 -174.87265)
		(stroke
			(width 0.2)
			(type default)
		)
		(layer "In10.Cu")
	)
	(gr_line
		(start 285.56331 -171.872656)
		(end 283.563314 -170.872658)
		(stroke
			(width 0.2)
			(type default)
		)
		(layer "In10.Cu")
	)
	(gr_line
		(start 285.56331 -167.872664)
		(end 283.563314 -166.872666)
		(stroke
			(width 0.2)
			(type default)
		)
		(layer "In10.Cu")
	)
	(gr_line
		(start 285.56331 -163.872672)
		(end 283.563314 -162.872674)
		(stroke
			(width 0.2)
			(type default)
		)
		(layer "In10.Cu")
	)
	(gr_line
		(start 285.56331 -159.87268)
		(end 283.571696 -158.877)
		(stroke
			(width 0.2)
			(type default)
		)
		(layer "In10.Cu")
	)
	(gr_line
		(start 285.56331 -155.872688)
		(end 283.563314 -154.87269)
		(stroke
			(width 0.2)
			(type default)
		)
		(layer "In10.Cu")
	)
	(gr_line
		(start 285.56331 -151.872696)
		(end 283.563314 -150.872698)
		(stroke
			(width 0.2)
			(type default)
		)
		(layer "In10.Cu")
	)
	(gr_line
		(start 285.56331 -127.872744)
		(end 283.563314 -126.872746)
		(stroke
			(width 0.2)
			(type default)
		)
		(layer "In10.Cu")
	)
	(gr_line
		(start 285.56331 -123.872752)
		(end 283.563314 -122.872754)
		(stroke
			(width 0.2)
			(type default)
		)
		(layer "In10.Cu")
	)
	(gr_line
		(start 285.56331 -119.87276)
		(end 283.563314 -118.872762)
		(stroke
			(width 0.2)
			(type default)
		)
		(layer "In10.Cu")
	)
	(gr_line
		(start 285.56331 -115.872768)
		(end 283.563314 -114.87277)
		(stroke
			(width 0.2)
			(type default)
		)
		(layer "In10.Cu")
	)
	(gr_line
		(start 285.56331 -83.572858)
		(end 283.563314 -82.57286)
		(stroke
			(width 0.2)
			(type default)
		)
		(layer "In10.Cu")
	)
	(gr_line
		(start 285.56331 -79.572866)
		(end 283.563314 -78.572868)
		(stroke
			(width 0.2)
			(type default)
		)
		(layer "In10.Cu")
	)
	(gr_line
		(start 285.56331 -75.572874)
		(end 283.563314 -74.572876)
		(stroke
			(width 0.2)
			(type default)
		)
		(layer "In10.Cu")
	)
	(gr_line
		(start 285.56331 -71.572882)
		(end 283.563314 -70.572884)
		(stroke
			(width 0.2)
			(type default)
		)
		(layer "In10.Cu")
	)
	(gr_line
		(start 285.56331 -67.57289)
		(end 283.563314 -66.572892)
		(stroke
			(width 0.2)
			(type default)
		)
		(layer "In10.Cu")
	)
	(gr_line
		(start 285.56331 -63.572898)
		(end 283.563314 -62.5729)
		(stroke
			(width 0.2)
			(type default)
		)
		(layer "In10.Cu")
	)
	(gr_line
		(start 285.56331 -59.572906)
		(end 283.563314 -58.572908)
		(stroke
			(width 0.2)
			(type default)
		)
		(layer "In10.Cu")
	)
	(gr_line
		(start 285.56331 -55.572914)
		(end 283.563314 -54.572916)
		(stroke
			(width 0.2)
			(type default)
		)
		(layer "In10.Cu")
	)
	(gr_line
		(start 285.56331 -51.572922)
		(end 283.563314 -50.572924)
		(stroke
			(width 0.2)
			(type default)
		)
		(layer "In10.Cu")
	)
	(gr_line
		(start 285.56331 -47.57293)
		(end 283.563314 -46.572932)
		(stroke
			(width 0.2)
			(type default)
		)
		(layer "In10.Cu")
	)
	(gr_line
		(start 285.56331 -43.572938)
		(end 283.563314 -42.57294)
		(stroke
			(width 0.2)
			(type default)
		)
		(layer "In10.Cu")
	)
	(gr_line
		(start 285.56331 -39.572946)
		(end 283.563314 -38.572948)
		(stroke
			(width 0.2)
			(type default)
		)
		(layer "In10.Cu")
	)
	(gr_line
		(start 285.57474 -135.850122)
		(end 285.57601 -135.847836)
		(stroke
			(width 0.2)
			(type default)
		)
		(layer "In10.Cu")
	)
	(gr_line
		(start 285.57601 -135.847836)
		(end 283.576014 -134.847838)
		(stroke
			(width 0.2)
			(type default)
		)
		(layer "In10.Cu")
	)
	(gr_line
		(start 285.57601 -107.847892)
		(end 283.576014 -106.847894)
		(stroke
			(width 0.2)
			(type default)
		)
		(layer "In10.Cu")
	)
	(gr_line
		(start 285.577026 -35.545776)
		(end 283.57703 -34.545778)
		(stroke
			(width 0.2)
			(type default)
		)
		(layer "In10.Cu")
	)
	(gr_line
		(start 286.436562 -358.256332)
		(end 287.83661 -358.256332)
		(stroke
			(width 0.2)
			(type default)
		)
		(layer "In10.Cu")
	)
	(gr_arc
		(start 286.436562 -357.153972)
		(mid 285.885382 -357.705152)
		(end 286.436562 -358.256332)
		(stroke
			(width 0.2)
			(type default)
		)
		(layer "In10.Cu")
	)
	(gr_line
		(start 286.436562 -354.65639)
		(end 287.83661 -354.65639)
		(stroke
			(width 0.2)
			(type default)
		)
		(layer "In10.Cu")
	)
	(gr_arc
		(start 286.436562 -353.55403)
		(mid 285.885382 -354.10521)
		(end 286.436562 -354.65639)
		(stroke
			(width 0.2)
			(type default)
		)
		(layer "In10.Cu")
	)
	(gr_line
		(start 286.436562 -351.056448)
		(end 287.83661 -351.056448)
		(stroke
			(width 0.2)
			(type default)
		)
		(layer "In10.Cu")
	)
	(gr_arc
		(start 286.436562 -349.954088)
		(mid 285.885382 -350.505268)
		(end 286.436562 -351.056448)
		(stroke
			(width 0.2)
			(type default)
		)
		(layer "In10.Cu")
	)
	(gr_line
		(start 286.436562 -347.453712)
		(end 287.83661 -347.453712)
		(stroke
			(width 0.2)
			(type default)
		)
		(layer "In10.Cu")
	)
	(gr_arc
		(start 286.436562 -346.356432)
		(mid 285.887922 -346.905072)
		(end 286.436562 -347.453712)
		(stroke
			(width 0.2)
			(type default)
		)
		(layer "In10.Cu")
	)
	(gr_line
		(start 286.436562 -343.85377)
		(end 287.83661 -343.85377)
		(stroke
			(width 0.2)
			(type default)
		)
		(layer "In10.Cu")
	)
	(gr_arc
		(start 286.436562 -342.75649)
		(mid 285.887922 -343.30513)
		(end 286.436562 -343.85377)
		(stroke
			(width 0.2)
			(type default)
		)
		(layer "In10.Cu")
	)
	(gr_line
		(start 286.436562 -340.253828)
		(end 287.83661 -340.253828)
		(stroke
			(width 0.2)
			(type default)
		)
		(layer "In10.Cu")
	)
	(gr_arc
		(start 286.436562 -339.156548)
		(mid 285.887922 -339.705188)
		(end 286.436562 -340.253828)
		(stroke
			(width 0.2)
			(type default)
		)
		(layer "In10.Cu")
	)
	(gr_line
		(start 286.436562 -336.656426)
		(end 287.83661 -336.656426)
		(stroke
			(width 0.2)
			(type default)
		)
		(layer "In10.Cu")
	)
	(gr_arc
		(start 286.436562 -335.554066)
		(mid 285.885382 -336.105246)
		(end 286.436562 -336.656426)
		(stroke
			(width 0.2)
			(type default)
		)
		(layer "In10.Cu")
	)
	(gr_line
		(start 286.436562 -333.05623)
		(end 287.83661 -333.05623)
		(stroke
			(width 0.2)
			(type default)
		)
		(layer "In10.Cu")
	)
	(gr_arc
		(start 286.436562 -331.95387)
		(mid 285.885382 -332.50505)
		(end 286.436562 -333.05623)
		(stroke
			(width 0.2)
			(type default)
		)
		(layer "In10.Cu")
	)
	(gr_line
		(start 286.436562 -329.456288)
		(end 287.83661 -329.456288)
		(stroke
			(width 0.2)
			(type default)
		)
		(layer "In10.Cu")
	)
	(gr_arc
		(start 286.436562 -328.353928)
		(mid 285.885382 -328.905108)
		(end 286.436562 -329.456288)
		(stroke
			(width 0.2)
			(type default)
		)
		(layer "In10.Cu")
	)
	(gr_line
		(start 286.436562 -325.853806)
		(end 287.83661 -325.853806)
		(stroke
			(width 0.2)
			(type default)
		)
		(layer "In10.Cu")
	)
	(gr_arc
		(start 286.436562 -324.756526)
		(mid 285.887922 -325.305166)
		(end 286.436562 -325.853806)
		(stroke
			(width 0.2)
			(type default)
		)
		(layer "In10.Cu")
	)
	(gr_line
		(start 286.436562 -322.253864)
		(end 287.83661 -322.253864)
		(stroke
			(width 0.2)
			(type default)
		)
		(layer "In10.Cu")
	)
	(gr_arc
		(start 286.436562 -321.156584)
		(mid 285.887922 -321.705224)
		(end 286.436562 -322.253864)
		(stroke
			(width 0.2)
			(type default)
		)
		(layer "In10.Cu")
	)
	(gr_line
		(start 286.436562 -318.653668)
		(end 287.83661 -318.653668)
		(stroke
			(width 0.2)
			(type default)
		)
		(layer "In10.Cu")
	)
	(gr_arc
		(start 286.436562 -317.556388)
		(mid 285.887922 -318.105028)
		(end 286.436562 -318.653668)
		(stroke
			(width 0.2)
			(type default)
		)
		(layer "In10.Cu")
	)
	(gr_line
		(start 286.436562 -315.056266)
		(end 287.83661 -315.056266)
		(stroke
			(width 0.2)
			(type default)
		)
		(layer "In10.Cu")
	)
	(gr_arc
		(start 286.436562 -313.953906)
		(mid 285.885382 -314.505086)
		(end 286.436562 -315.056266)
		(stroke
			(width 0.2)
			(type default)
		)
		(layer "In10.Cu")
	)
	(gr_line
		(start 286.436562 -311.456324)
		(end 287.83661 -311.456324)
		(stroke
			(width 0.2)
			(type default)
		)
		(layer "In10.Cu")
	)
	(gr_arc
		(start 286.436562 -310.353964)
		(mid 285.885382 -310.905144)
		(end 286.436562 -311.456324)
		(stroke
			(width 0.2)
			(type default)
		)
		(layer "In10.Cu")
	)
	(gr_line
		(start 286.436562 -307.856382)
		(end 287.83661 -307.856382)
		(stroke
			(width 0.2)
			(type default)
		)
		(layer "In10.Cu")
	)
	(gr_arc
		(start 286.436562 -306.754022)
		(mid 285.885382 -307.305202)
		(end 286.436562 -307.856382)
		(stroke
			(width 0.2)
			(type default)
		)
		(layer "In10.Cu")
	)
	(gr_line
		(start 286.436562 -304.2539)
		(end 287.83661 -304.2539)
		(stroke
			(width 0.2)
			(type default)
		)
		(layer "In10.Cu")
	)
	(gr_arc
		(start 286.436562 -303.15662)
		(mid 285.887922 -303.70526)
		(end 286.436562 -304.2539)
		(stroke
			(width 0.2)
			(type default)
		)
		(layer "In10.Cu")
	)
	(gr_line
		(start 286.436562 -300.653704)
		(end 287.83661 -300.653704)
		(stroke
			(width 0.2)
			(type default)
		)
		(layer "In10.Cu")
	)
	(gr_arc
		(start 286.436562 -299.556424)
		(mid 285.887922 -300.105064)
		(end 286.436562 -300.653704)
		(stroke
			(width 0.2)
			(type default)
		)
		(layer "In10.Cu")
	)
	(gr_line
		(start 286.436562 -297.056302)
		(end 287.83661 -297.056302)
		(stroke
			(width 0.2)
			(type default)
		)
		(layer "In10.Cu")
	)
	(gr_arc
		(start 286.436562 -295.953942)
		(mid 285.885382 -296.505122)
		(end 286.436562 -297.056302)
		(stroke
			(width 0.2)
			(type default)
		)
		(layer "In10.Cu")
	)
	(gr_line
		(start 286.436562 -264.253472)
		(end 287.83661 -264.253472)
		(stroke
			(width 0.2)
			(type default)
		)
		(layer "In10.Cu")
	)
	(gr_arc
		(start 286.436562 -263.151112)
		(mid 285.885382 -263.702292)
		(end 286.436562 -264.253472)
		(stroke
			(width 0.2)
			(type default)
		)
		(layer "In10.Cu")
	)
	(gr_line
		(start 286.436562 -260.65353)
		(end 287.83661 -260.65353)
		(stroke
			(width 0.2)
			(type default)
		)
		(layer "In10.Cu")
	)
	(gr_arc
		(start 286.436562 -259.55117)
		(mid 285.885382 -260.10235)
		(end 286.436562 -260.65353)
		(stroke
			(width 0.2)
			(type default)
		)
		(layer "In10.Cu")
	)
	(gr_line
		(start 286.436562 -257.053588)
		(end 287.83661 -257.053588)
		(stroke
			(width 0.2)
			(type default)
		)
		(layer "In10.Cu")
	)
	(gr_arc
		(start 286.436562 -255.951228)
		(mid 285.885382 -256.502408)
		(end 286.436562 -257.053588)
		(stroke
			(width 0.2)
			(type default)
		)
		(layer "In10.Cu")
	)
	(gr_line
		(start 286.436562 -253.453392)
		(end 287.83661 -253.453392)
		(stroke
			(width 0.2)
			(type default)
		)
		(layer "In10.Cu")
	)
	(gr_arc
		(start 286.436562 -252.351032)
		(mid 285.885382 -252.902212)
		(end 286.436562 -253.453392)
		(stroke
			(width 0.2)
			(type default)
		)
		(layer "In10.Cu")
	)
	(gr_line
		(start 286.436816 -357.153972)
		(end 286.436562 -357.153972)
		(stroke
			(width 0.2)
			(type default)
		)
		(layer "In10.Cu")
	)
	(gr_line
		(start 286.436816 -353.55403)
		(end 286.436562 -353.55403)
		(stroke
			(width 0.2)
			(type default)
		)
		(layer "In10.Cu")
	)
	(gr_line
		(start 286.436816 -349.954088)
		(end 286.436562 -349.954088)
		(stroke
			(width 0.2)
			(type default)
		)
		(layer "In10.Cu")
	)
	(gr_line
		(start 286.436816 -346.356432)
		(end 286.436562 -346.356432)
		(stroke
			(width 0.2)
			(type default)
		)
		(layer "In10.Cu")
	)
	(gr_line
		(start 286.436816 -342.75649)
		(end 286.436562 -342.75649)
		(stroke
			(width 0.2)
			(type default)
		)
		(layer "In10.Cu")
	)
	(gr_line
		(start 286.436816 -339.156548)
		(end 286.436562 -339.156548)
		(stroke
			(width 0.2)
			(type default)
		)
		(layer "In10.Cu")
	)
	(gr_line
		(start 286.436816 -335.554066)
		(end 286.436562 -335.554066)
		(stroke
			(width 0.2)
			(type default)
		)
		(layer "In10.Cu")
	)
	(gr_line
		(start 286.436816 -331.95387)
		(end 286.436562 -331.95387)
		(stroke
			(width 0.2)
			(type default)
		)
		(layer "In10.Cu")
	)
	(gr_line
		(start 286.436816 -328.353928)
		(end 286.436562 -328.353928)
		(stroke
			(width 0.2)
			(type default)
		)
		(layer "In10.Cu")
	)
	(gr_line
		(start 286.436816 -324.756526)
		(end 286.436562 -324.756526)
		(stroke
			(width 0.2)
			(type default)
		)
		(layer "In10.Cu")
	)
	(gr_line
		(start 286.436816 -321.156584)
		(end 286.436562 -321.156584)
		(stroke
			(width 0.2)
			(type default)
		)
		(layer "In10.Cu")
	)
	(gr_line
		(start 286.436816 -317.556388)
		(end 286.436562 -317.556388)
		(stroke
			(width 0.2)
			(type default)
		)
		(layer "In10.Cu")
	)
	(gr_line
		(start 286.436816 -313.953906)
		(end 286.436562 -313.953906)
		(stroke
			(width 0.2)
			(type default)
		)
		(layer "In10.Cu")
	)
	(gr_line
		(start 286.436816 -310.353964)
		(end 286.436562 -310.353964)
		(stroke
			(width 0.2)
			(type default)
		)
		(layer "In10.Cu")
	)
	(gr_line
		(start 286.436816 -306.754022)
		(end 286.436562 -306.754022)
		(stroke
			(width 0.2)
			(type default)
		)
		(layer "In10.Cu")
	)
	(gr_line
		(start 286.436816 -303.15662)
		(end 286.436562 -303.15662)
		(stroke
			(width 0.2)
			(type default)
		)
		(layer "In10.Cu")
	)
	(gr_line
		(start 286.436816 -299.556424)
		(end 286.436562 -299.556424)
		(stroke
			(width 0.2)
			(type default)
		)
		(layer "In10.Cu")
	)
	(gr_line
		(start 286.436816 -295.953942)
		(end 286.436562 -295.953942)
		(stroke
			(width 0.2)
			(type default)
		)
		(layer "In10.Cu")
	)
	(gr_line
		(start 286.436816 -263.151112)
		(end 286.436562 -263.151112)
		(stroke
			(width 0.2)
			(type default)
		)
		(layer "In10.Cu")
	)
	(gr_line
		(start 286.436816 -259.55117)
		(end 286.436562 -259.55117)
		(stroke
			(width 0.2)
			(type default)
		)
		(layer "In10.Cu")
	)
	(gr_line
		(start 286.436816 -255.951228)
		(end 286.436562 -255.951228)
		(stroke
			(width 0.2)
			(type default)
		)
		(layer "In10.Cu")
	)
	(gr_line
		(start 286.436816 -252.351032)
		(end 286.436562 -252.351032)
		(stroke
			(width 0.2)
			(type default)
		)
		(layer "In10.Cu")
	)
	(gr_arc
		(start 286.836612 -356.456234)
		(mid 287.387792 -355.905054)
		(end 286.836612 -355.353874)
		(stroke
			(width 0.2)
			(type default)
		)
		(layer "In10.Cu")
	)
	(gr_line
		(start 286.836612 -355.353874)
		(end 285.436818 -355.353874)
		(stroke
			(width 0.2)
			(type default)
		)
		(layer "In10.Cu")
	)
	(gr_arc
		(start 286.836612 -352.856292)
		(mid 287.387792 -352.305112)
		(end 286.836612 -351.753932)
		(stroke
			(width 0.2)
			(type default)
		)
		(layer "In10.Cu")
	)
	(gr_line
		(start 286.836612 -351.753932)
		(end 285.436818 -351.753932)
		(stroke
			(width 0.2)
			(type default)
		)
		(layer "In10.Cu")
	)
	(gr_arc
		(start 286.836612 -349.25635)
		(mid 287.387792 -348.70517)
		(end 286.836612 -348.15399)
		(stroke
			(width 0.2)
			(type default)
		)
		(layer "In10.Cu")
	)
	(gr_line
		(start 286.836612 -348.15399)
		(end 285.436818 -348.15399)
		(stroke
			(width 0.2)
			(type default)
		)
		(layer "In10.Cu")
	)
	(gr_arc
		(start 286.836612 -345.653868)
		(mid 287.385252 -345.105228)
		(end 286.836612 -344.556588)
		(stroke
			(width 0.2)
			(type default)
		)
		(layer "In10.Cu")
	)
	(gr_line
		(start 286.836612 -344.556588)
		(end 285.436818 -344.556588)
		(stroke
			(width 0.2)
			(type default)
		)
		(layer "In10.Cu")
	)
	(gr_arc
		(start 286.836612 -342.053672)
		(mid 287.385252 -341.505032)
		(end 286.836612 -340.956392)
		(stroke
			(width 0.2)
			(type default)
		)
		(layer "In10.Cu")
	)
	(gr_line
		(start 286.836612 -340.956392)
		(end 285.436818 -340.956392)
		(stroke
			(width 0.2)
			(type default)
		)
		(layer "In10.Cu")
	)
	(gr_arc
		(start 286.836612 -338.45373)
		(mid 287.385252 -337.90509)
		(end 286.836612 -337.35645)
		(stroke
			(width 0.2)
			(type default)
		)
		(layer "In10.Cu")
	)
	(gr_line
		(start 286.836612 -337.35645)
		(end 285.436818 -337.35645)
		(stroke
			(width 0.2)
			(type default)
		)
		(layer "In10.Cu")
	)
	(gr_arc
		(start 286.836612 -334.856328)
		(mid 287.387792 -334.305148)
		(end 286.836612 -333.753968)
		(stroke
			(width 0.2)
			(type default)
		)
		(layer "In10.Cu")
	)
	(gr_line
		(start 286.836612 -333.753968)
		(end 285.436818 -333.753968)
		(stroke
			(width 0.2)
			(type default)
		)
		(layer "In10.Cu")
	)
	(gr_arc
		(start 286.836612 -331.256386)
		(mid 287.387792 -330.705206)
		(end 286.836612 -330.154026)
		(stroke
			(width 0.2)
			(type default)
		)
		(layer "In10.Cu")
	)
	(gr_line
		(start 286.836612 -330.154026)
		(end 285.436818 -330.154026)
		(stroke
			(width 0.2)
			(type default)
		)
		(layer "In10.Cu")
	)
	(gr_arc
		(start 286.836612 -327.656444)
		(mid 287.387792 -327.105264)
		(end 286.836612 -326.554084)
		(stroke
			(width 0.2)
			(type default)
		)
		(layer "In10.Cu")
	)
	(gr_line
		(start 286.836612 -326.554084)
		(end 285.436818 -326.554084)
		(stroke
			(width 0.2)
			(type default)
		)
		(layer "In10.Cu")
	)
	(gr_arc
		(start 286.836612 -324.053708)
		(mid 287.385252 -323.505068)
		(end 286.836612 -322.956428)
		(stroke
			(width 0.2)
			(type default)
		)
		(layer "In10.Cu")
	)
	(gr_line
		(start 286.836612 -322.956428)
		(end 285.436818 -322.956428)
		(stroke
			(width 0.2)
			(type default)
		)
		(layer "In10.Cu")
	)
	(gr_arc
		(start 286.836612 -320.453766)
		(mid 287.385252 -319.905126)
		(end 286.836612 -319.356486)
		(stroke
			(width 0.2)
			(type default)
		)
		(layer "In10.Cu")
	)
	(gr_line
		(start 286.836612 -319.356486)
		(end 285.436818 -319.356486)
		(stroke
			(width 0.2)
			(type default)
		)
		(layer "In10.Cu")
	)
	(gr_arc
		(start 286.836612 -316.853824)
		(mid 287.385252 -316.305184)
		(end 286.836612 -315.756544)
		(stroke
			(width 0.2)
			(type default)
		)
		(layer "In10.Cu")
	)
	(gr_line
		(start 286.836612 -315.756544)
		(end 285.436818 -315.756544)
		(stroke
			(width 0.2)
			(type default)
		)
		(layer "In10.Cu")
	)
	(gr_arc
		(start 286.836612 -313.256422)
		(mid 287.387792 -312.705242)
		(end 286.836612 -312.154062)
		(stroke
			(width 0.2)
			(type default)
		)
		(layer "In10.Cu")
	)
	(gr_line
		(start 286.836612 -312.154062)
		(end 285.436818 -312.154062)
		(stroke
			(width 0.2)
			(type default)
		)
		(layer "In10.Cu")
	)
	(gr_arc
		(start 286.836612 -309.656226)
		(mid 287.387792 -309.105046)
		(end 286.836612 -308.553866)
		(stroke
			(width 0.2)
			(type default)
		)
		(layer "In10.Cu")
	)
	(gr_line
		(start 286.836612 -308.553866)
		(end 285.436818 -308.553866)
		(stroke
			(width 0.2)
			(type default)
		)
		(layer "In10.Cu")
	)
	(gr_arc
		(start 286.836612 -306.056284)
		(mid 287.387792 -305.505104)
		(end 286.836612 -304.953924)
		(stroke
			(width 0.2)
			(type default)
		)
		(layer "In10.Cu")
	)
	(gr_line
		(start 286.836612 -304.953924)
		(end 285.436818 -304.953924)
		(stroke
			(width 0.2)
			(type default)
		)
		(layer "In10.Cu")
	)
	(gr_arc
		(start 286.836612 -302.453802)
		(mid 287.385252 -301.905162)
		(end 286.836612 -301.356522)
		(stroke
			(width 0.2)
			(type default)
		)
		(layer "In10.Cu")
	)
	(gr_line
		(start 286.836612 -301.356522)
		(end 285.436818 -301.356522)
		(stroke
			(width 0.2)
			(type default)
		)
		(layer "In10.Cu")
	)
	(gr_arc
		(start 286.836612 -298.85386)
		(mid 287.385252 -298.30522)
		(end 286.836612 -297.75658)
		(stroke
			(width 0.2)
			(type default)
		)
		(layer "In10.Cu")
	)
	(gr_line
		(start 286.836612 -297.75658)
		(end 285.436818 -297.75658)
		(stroke
			(width 0.2)
			(type default)
		)
		(layer "In10.Cu")
	)
	(gr_arc
		(start 286.836612 -295.256458)
		(mid 287.387792 -294.705278)
		(end 286.836612 -294.154098)
		(stroke
			(width 0.2)
			(type default)
		)
		(layer "In10.Cu")
	)
	(gr_line
		(start 286.836612 -294.154098)
		(end 285.436818 -294.154098)
		(stroke
			(width 0.2)
			(type default)
		)
		(layer "In10.Cu")
	)
	(gr_arc
		(start 286.836612 -262.453374)
		(mid 287.387792 -261.902194)
		(end 286.836612 -261.351014)
		(stroke
			(width 0.2)
			(type default)
		)
		(layer "In10.Cu")
	)
	(gr_line
		(start 286.836612 -261.351014)
		(end 285.436818 -261.351014)
		(stroke
			(width 0.2)
			(type default)
		)
		(layer "In10.Cu")
	)
	(gr_arc
		(start 286.836612 -258.853432)
		(mid 287.387792 -258.302252)
		(end 286.836612 -257.751072)
		(stroke
			(width 0.2)
			(type default)
		)
		(layer "In10.Cu")
	)
	(gr_line
		(start 286.836612 -257.751072)
		(end 285.436818 -257.751072)
		(stroke
			(width 0.2)
			(type default)
		)
		(layer "In10.Cu")
	)
	(gr_arc
		(start 286.836612 -255.25349)
		(mid 287.387792 -254.70231)
		(end 286.836612 -254.15113)
		(stroke
			(width 0.2)
			(type default)
		)
		(layer "In10.Cu")
	)
	(gr_line
		(start 286.836612 -254.15113)
		(end 285.436818 -254.15113)
		(stroke
			(width 0.2)
			(type default)
		)
		(layer "In10.Cu")
	)
	(gr_arc
		(start 286.836612 -251.653548)
		(mid 287.387792 -251.102368)
		(end 286.836612 -250.551188)
		(stroke
			(width 0.2)
			(type default)
		)
		(layer "In10.Cu")
	)
	(gr_line
		(start 286.836612 -250.551188)
		(end 285.436818 -250.551188)
		(stroke
			(width 0.2)
			(type default)
		)
		(layer "In10.Cu")
	)
	(gr_arc
		(start 287.83661 -358.256332)
		(mid 288.38779 -357.705152)
		(end 287.83661 -357.153972)
		(stroke
			(width 0.2)
			(type default)
		)
		(layer "In10.Cu")
	)
	(gr_line
		(start 287.83661 -357.153972)
		(end 286.436816 -357.153972)
		(stroke
			(width 0.2)
			(type default)
		)
		(layer "In10.Cu")
	)
	(gr_arc
		(start 287.83661 -354.65639)
		(mid 288.38779 -354.10521)
		(end 287.83661 -353.55403)
		(stroke
			(width 0.2)
			(type default)
		)
		(layer "In10.Cu")
	)
	(gr_line
		(start 287.83661 -353.55403)
		(end 286.436816 -353.55403)
		(stroke
			(width 0.2)
			(type default)
		)
		(layer "In10.Cu")
	)
	(gr_arc
		(start 287.83661 -351.056448)
		(mid 288.38779 -350.505268)
		(end 287.83661 -349.954088)
		(stroke
			(width 0.2)
			(type default)
		)
		(layer "In10.Cu")
	)
	(gr_line
		(start 287.83661 -349.954088)
		(end 286.436816 -349.954088)
		(stroke
			(width 0.2)
			(type default)
		)
		(layer "In10.Cu")
	)
	(gr_arc
		(start 287.83661 -347.453712)
		(mid 288.38525 -346.905072)
		(end 287.83661 -346.356432)
		(stroke
			(width 0.2)
			(type default)
		)
		(layer "In10.Cu")
	)
	(gr_line
		(start 287.83661 -346.356432)
		(end 286.436816 -346.356432)
		(stroke
			(width 0.2)
			(type default)
		)
		(layer "In10.Cu")
	)
	(gr_arc
		(start 287.83661 -343.85377)
		(mid 288.38525 -343.30513)
		(end 287.83661 -342.75649)
		(stroke
			(width 0.2)
			(type default)
		)
		(layer "In10.Cu")
	)
	(gr_line
		(start 287.83661 -342.75649)
		(end 286.436816 -342.75649)
		(stroke
			(width 0.2)
			(type default)
		)
		(layer "In10.Cu")
	)
	(gr_arc
		(start 287.83661 -340.253828)
		(mid 288.38525 -339.705188)
		(end 287.83661 -339.156548)
		(stroke
			(width 0.2)
			(type default)
		)
		(layer "In10.Cu")
	)
	(gr_line
		(start 287.83661 -339.156548)
		(end 286.436816 -339.156548)
		(stroke
			(width 0.2)
			(type default)
		)
		(layer "In10.Cu")
	)
	(gr_arc
		(start 287.83661 -336.656426)
		(mid 288.38779 -336.105246)
		(end 287.83661 -335.554066)
		(stroke
			(width 0.2)
			(type default)
		)
		(layer "In10.Cu")
	)
	(gr_line
		(start 287.83661 -335.554066)
		(end 286.436816 -335.554066)
		(stroke
			(width 0.2)
			(type default)
		)
		(layer "In10.Cu")
	)
	(gr_arc
		(start 287.83661 -333.05623)
		(mid 288.38779 -332.50505)
		(end 287.83661 -331.95387)
		(stroke
			(width 0.2)
			(type default)
		)
		(layer "In10.Cu")
	)
	(gr_line
		(start 287.83661 -331.95387)
		(end 286.436816 -331.95387)
		(stroke
			(width 0.2)
			(type default)
		)
		(layer "In10.Cu")
	)
	(gr_arc
		(start 287.83661 -329.456288)
		(mid 288.38779 -328.905108)
		(end 287.83661 -328.353928)
		(stroke
			(width 0.2)
			(type default)
		)
		(layer "In10.Cu")
	)
	(gr_line
		(start 287.83661 -328.353928)
		(end 286.436816 -328.353928)
		(stroke
			(width 0.2)
			(type default)
		)
		(layer "In10.Cu")
	)
	(gr_arc
		(start 287.83661 -325.853806)
		(mid 288.38525 -325.305166)
		(end 287.83661 -324.756526)
		(stroke
			(width 0.2)
			(type default)
		)
		(layer "In10.Cu")
	)
	(gr_line
		(start 287.83661 -324.756526)
		(end 286.436816 -324.756526)
		(stroke
			(width 0.2)
			(type default)
		)
		(layer "In10.Cu")
	)
	(gr_arc
		(start 287.83661 -322.253864)
		(mid 288.38525 -321.705224)
		(end 287.83661 -321.156584)
		(stroke
			(width 0.2)
			(type default)
		)
		(layer "In10.Cu")
	)
	(gr_line
		(start 287.83661 -321.156584)
		(end 286.436816 -321.156584)
		(stroke
			(width 0.2)
			(type default)
		)
		(layer "In10.Cu")
	)
	(gr_arc
		(start 287.83661 -318.653668)
		(mid 288.38525 -318.105028)
		(end 287.83661 -317.556388)
		(stroke
			(width 0.2)
			(type default)
		)
		(layer "In10.Cu")
	)
	(gr_line
		(start 287.83661 -317.556388)
		(end 286.436816 -317.556388)
		(stroke
			(width 0.2)
			(type default)
		)
		(layer "In10.Cu")
	)
	(gr_arc
		(start 287.83661 -315.056266)
		(mid 288.38779 -314.505086)
		(end 287.83661 -313.953906)
		(stroke
			(width 0.2)
			(type default)
		)
		(layer "In10.Cu")
	)
	(gr_line
		(start 287.83661 -313.953906)
		(end 286.436816 -313.953906)
		(stroke
			(width 0.2)
			(type default)
		)
		(layer "In10.Cu")
	)
	(gr_arc
		(start 287.83661 -311.456324)
		(mid 288.38779 -310.905144)
		(end 287.83661 -310.353964)
		(stroke
			(width 0.2)
			(type default)
		)
		(layer "In10.Cu")
	)
	(gr_line
		(start 287.83661 -310.353964)
		(end 286.436816 -310.353964)
		(stroke
			(width 0.2)
			(type default)
		)
		(layer "In10.Cu")
	)
	(gr_arc
		(start 287.83661 -307.856382)
		(mid 288.38779 -307.305202)
		(end 287.83661 -306.754022)
		(stroke
			(width 0.2)
			(type default)
		)
		(layer "In10.Cu")
	)
	(gr_line
		(start 287.83661 -306.754022)
		(end 286.436816 -306.754022)
		(stroke
			(width 0.2)
			(type default)
		)
		(layer "In10.Cu")
	)
	(gr_arc
		(start 287.83661 -304.2539)
		(mid 288.38525 -303.70526)
		(end 287.83661 -303.15662)
		(stroke
			(width 0.2)
			(type default)
		)
		(layer "In10.Cu")
	)
	(gr_line
		(start 287.83661 -303.15662)
		(end 286.436816 -303.15662)
		(stroke
			(width 0.2)
			(type default)
		)
		(layer "In10.Cu")
	)
	(gr_arc
		(start 287.83661 -300.653704)
		(mid 288.38525 -300.105064)
		(end 287.83661 -299.556424)
		(stroke
			(width 0.2)
			(type default)
		)
		(layer "In10.Cu")
	)
	(gr_line
		(start 287.83661 -299.556424)
		(end 286.436816 -299.556424)
		(stroke
			(width 0.2)
			(type default)
		)
		(layer "In10.Cu")
	)
	(gr_arc
		(start 287.83661 -297.056302)
		(mid 288.38779 -296.505122)
		(end 287.83661 -295.953942)
		(stroke
			(width 0.2)
			(type default)
		)
		(layer "In10.Cu")
	)
	(gr_line
		(start 287.83661 -295.953942)
		(end 286.436816 -295.953942)
		(stroke
			(width 0.2)
			(type default)
		)
		(layer "In10.Cu")
	)
	(gr_arc
		(start 287.83661 -264.253472)
		(mid 288.38779 -263.702292)
		(end 287.83661 -263.151112)
		(stroke
			(width 0.2)
			(type default)
		)
		(layer "In10.Cu")
	)
	(gr_line
		(start 287.83661 -263.151112)
		(end 286.436816 -263.151112)
		(stroke
			(width 0.2)
			(type default)
		)
		(layer "In10.Cu")
	)
	(gr_arc
		(start 287.83661 -260.65353)
		(mid 288.38779 -260.10235)
		(end 287.83661 -259.55117)
		(stroke
			(width 0.2)
			(type default)
		)
		(layer "In10.Cu")
	)
	(gr_line
		(start 287.83661 -259.55117)
		(end 286.436816 -259.55117)
		(stroke
			(width 0.2)
			(type default)
		)
		(layer "In10.Cu")
	)
	(gr_arc
		(start 287.83661 -257.053588)
		(mid 288.38779 -256.502408)
		(end 287.83661 -255.951228)
		(stroke
			(width 0.2)
			(type default)
		)
		(layer "In10.Cu")
	)
	(gr_line
		(start 287.83661 -255.951228)
		(end 286.436816 -255.951228)
		(stroke
			(width 0.2)
			(type default)
		)
		(layer "In10.Cu")
	)
	(gr_arc
		(start 287.83661 -253.453392)
		(mid 288.38779 -252.902212)
		(end 287.83661 -252.351032)
		(stroke
			(width 0.2)
			(type default)
		)
		(layer "In10.Cu")
	)
	(gr_line
		(start 287.83661 -252.351032)
		(end 286.436816 -252.351032)
		(stroke
			(width 0.2)
			(type default)
		)
		(layer "In10.Cu")
	)
	(gr_arc
		(start 295.699942 -373.000016)
		(mid 295.992835 -373.707121)
		(end 296.69994 -374.000014)
		(stroke
			(width 1.524)
			(type default)
		)
		(layer "In10.Cu")
	)
	(gr_line
		(start 295.699942 -350.19996)
		(end 295.699942 -373.000016)
		(stroke
			(width 1.524)
			(type default)
		)
		(layer "In10.Cu")
	)
	(gr_line
		(start 296.69994 -374.000014)
		(end 308.99989 -374.000014)
		(stroke
			(width 1.524)
			(type default)
		)
		(layer "In10.Cu")
	)
	(gr_arc
		(start 296.69994 -349.199962)
		(mid 295.992835 -349.492855)
		(end 295.699942 -350.19996)
		(stroke
			(width 1.524)
			(type default)
		)
		(layer "In10.Cu")
	)
	(gr_arc
		(start 299.999908 0.999998)
		(mid 300.292801 0.292893)
		(end 300.999906 0)
		(stroke
			(width 1.524)
			(type default)
		)
		(layer "In10.Cu")
	)
	(gr_arc
		(start 299.999908 37.800026)
		(mid 299.707007 38.507118)
		(end 298.99991 38.800024)
		(stroke
			(width 1.524)
			(type default)
		)
		(layer "In10.Cu")
	)
	(gr_line
		(start 299.999908 37.800026)
		(end 299.999908 0.999998)
		(stroke
			(width 1.524)
			(type default)
		)
		(layer "In10.Cu")
	)
	(gr_line
		(start 300.999906 0)
		(end 347.000068 0)
		(stroke
			(width 1.524)
			(type default)
		)
		(layer "In10.Cu")
	)
	(gr_line
		(start 308.99989 -421.200072)
		(end 201.000106 -421.200072)
		(stroke
			(width 1.524)
			(type default)
		)
		(layer "In10.Cu")
	)
	(gr_arc
		(start 308.99989 -421.200072)
		(mid 309.706993 -420.907181)
		(end 309.999888 -420.200074)
		(stroke
			(width 1.524)
			(type default)
		)
		(layer "In10.Cu")
	)
	(gr_arc
		(start 309.999888 -375.000012)
		(mid 309.706999 -374.292902)
		(end 308.99989 -374.000014)
		(stroke
			(width 1.524)
			(type default)
		)
		(layer "In10.Cu")
	)
	(gr_line
		(start 309.999888 -375.000012)
		(end 309.999888 -420.200074)
		(stroke
			(width 1.524)
			(type default)
		)
		(layer "In10.Cu")
	)
	(gr_line
		(start 319.2145 -43.008042)
		(end 320.3575 -43.008042)
		(stroke
			(width 0.2)
			(type default)
		)
		(layer "In10.Cu")
	)
	(gr_arc
		(start 319.214754 -42.246042)
		(mid 318.8335 -42.626915)
		(end 319.2145 -43.008042)
		(stroke
			(width 0.2)
			(type default)
		)
		(layer "In10.Cu")
	)
	(gr_arc
		(start 319.56756 -274.511516)
		(mid 319.9892 -274.933156)
		(end 320.41084 -274.511516)
		(stroke
			(width 0.2)
			(type default)
		)
		(layer "In10.Cu")
	)
	(gr_line
		(start 319.56756 -273.368516)
		(end 319.56756 -274.511516)
		(stroke
			(width 0.2)
			(type default)
		)
		(layer "In10.Cu")
	)
	(gr_arc
		(start 319.6082 -159.511238)
		(mid 319.989073 -159.892492)
		(end 320.3702 -159.511492)
		(stroke
			(width 0.2)
			(type default)
		)
		(layer "In10.Cu")
	)
	(gr_line
		(start 319.6082 -158.368492)
		(end 319.6082 -159.511238)
		(stroke
			(width 0.2)
			(type default)
		)
		(layer "In10.Cu")
	)
	(gr_arc
		(start 320.3575 -43.008042)
		(mid 320.7385 -42.627042)
		(end 320.3575 -42.246042)
		(stroke
			(width 0.2)
			(type default)
		)
		(layer "In10.Cu")
	)
	(gr_line
		(start 320.3575 -42.246042)
		(end 319.214754 -42.246042)
		(stroke
			(width 0.2)
			(type default)
		)
		(layer "In10.Cu")
	)
	(gr_line
		(start 320.3702 -159.511492)
		(end 320.3702 -158.368492)
		(stroke
			(width 0.2)
			(type default)
		)
		(layer "In10.Cu")
	)
	(gr_arc
		(start 320.3702 -158.368492)
		(mid 319.9892 -157.987492)
		(end 319.6082 -158.368492)
		(stroke
			(width 0.2)
			(type default)
		)
		(layer "In10.Cu")
	)
	(gr_line
		(start 320.41084 -274.511516)
		(end 320.41084 -273.36877)
		(stroke
			(width 0.2)
			(type default)
		)
		(layer "In10.Cu")
	)
	(gr_arc
		(start 320.41084 -273.36877)
		(mid 319.989327 -272.946876)
		(end 319.56756 -273.368516)
		(stroke
			(width 0.2)
			(type default)
		)
		(layer "In10.Cu")
	)
	(gr_line
		(start 322.6816 -46.818042)
		(end 323.824346 -46.818042)
		(stroke
			(width 0.2)
			(type default)
		)
		(layer "In10.Cu")
	)
	(gr_arc
		(start 322.6816 -46.056042)
		(mid 322.3006 -46.437042)
		(end 322.6816 -46.818042)
		(stroke
			(width 0.2)
			(type default)
		)
		(layer "In10.Cu")
	)
	(gr_arc
		(start 323.824346 -46.818042)
		(mid 324.2056 -46.437169)
		(end 323.8246 -46.056042)
		(stroke
			(width 0.2)
			(type default)
		)
		(layer "In10.Cu")
	)
	(gr_line
		(start 323.8246 -46.056042)
		(end 322.6816 -46.056042)
		(stroke
			(width 0.2)
			(type default)
		)
		(layer "In10.Cu")
	)
	(gr_arc
		(start 324.358 -278.321516)
		(mid 324.739 -278.702516)
		(end 325.12 -278.321516)
		(stroke
			(width 0.2)
			(type default)
		)
		(layer "In10.Cu")
	)
	(gr_line
		(start 324.358 -277.178516)
		(end 324.358 -278.321516)
		(stroke
			(width 0.2)
			(type default)
		)
		(layer "In10.Cu")
	)
	(gr_arc
		(start 324.358 -163.321492)
		(mid 324.739 -163.702492)
		(end 325.12 -163.321492)
		(stroke
			(width 0.2)
			(type default)
		)
		(layer "In10.Cu")
	)
	(gr_line
		(start 324.358 -162.178492)
		(end 324.358 -163.321492)
		(stroke
			(width 0.2)
			(type default)
		)
		(layer "In10.Cu")
	)
	(gr_line
		(start 325.12 -278.321516)
		(end 325.12 -277.17877)
		(stroke
			(width 0.2)
			(type default)
		)
		(layer "In10.Cu")
	)
	(gr_arc
		(start 325.12 -277.17877)
		(mid 324.739127 -276.797516)
		(end 324.358 -277.178516)
		(stroke
			(width 0.2)
			(type default)
		)
		(layer "In10.Cu")
	)
	(gr_line
		(start 325.12 -163.321492)
		(end 325.12 -162.178746)
		(stroke
			(width 0.2)
			(type default)
		)
		(layer "In10.Cu")
	)
	(gr_arc
		(start 325.12 -162.178746)
		(mid 324.739127 -161.797492)
		(end 324.358 -162.178492)
		(stroke
			(width 0.2)
			(type default)
		)
		(layer "In10.Cu")
	)
	(gr_arc
		(start 348.000066 -13.999972)
		(mid 348.292959 -14.707077)
		(end 349.000064 -14.99997)
		(stroke
			(width 1.524)
			(type default)
		)
		(layer "In10.Cu")
	)
	(gr_arc
		(start 348.000066 -0.999998)
		(mid 347.707171 -0.292905)
		(end 347.000068 0)
		(stroke
			(width 1.524)
			(type default)
		)
		(layer "In10.Cu")
	)
	(gr_line
		(start 348.000066 -0.999998)
		(end 348.000066 -13.999972)
		(stroke
			(width 1.524)
			(type default)
		)
		(layer "In10.Cu")
	)
	(gr_line
		(start 349.000064 -14.99997)
		(end 394.999972 -14.99997)
		(stroke
			(width 1.524)
			(type default)
		)
		(layer "In10.Cu")
	)
	(gr_line
		(start 350.764602 -43.013122)
		(end 351.907602 -43.013122)
		(stroke
			(width 0.2)
			(type default)
		)
		(layer "In10.Cu")
	)
	(gr_arc
		(start 350.764856 -42.240962)
		(mid 350.378522 -42.626915)
		(end 350.764602 -43.013122)
		(stroke
			(width 0.2)
			(type default)
		)
		(layer "In10.Cu")
	)
	(gr_arc
		(start 351.158302 -274.511262)
		(mid 351.539175 -274.892516)
		(end 351.920302 -274.511516)
		(stroke
			(width 0.2)
			(type default)
		)
		(layer "In10.Cu")
	)
	(gr_line
		(start 351.158302 -273.368516)
		(end 351.158302 -274.511262)
		(stroke
			(width 0.2)
			(type default)
		)
		(layer "In10.Cu")
	)
	(gr_arc
		(start 351.158302 -159.511238)
		(mid 351.539175 -159.892492)
		(end 351.920302 -159.511492)
		(stroke
			(width 0.2)
			(type default)
		)
		(layer "In10.Cu")
	)
	(gr_line
		(start 351.158302 -158.368492)
		(end 351.158302 -159.511238)
		(stroke
			(width 0.2)
			(type default)
		)
		(layer "In10.Cu")
	)
	(gr_arc
		(start 351.907602 -43.013122)
		(mid 352.293682 -42.627042)
		(end 351.907602 -42.240962)
		(stroke
			(width 0.2)
			(type default)
		)
		(layer "In10.Cu")
	)
	(gr_line
		(start 351.907602 -42.240962)
		(end 350.764856 -42.240962)
		(stroke
			(width 0.2)
			(type default)
		)
		(layer "In10.Cu")
	)
	(gr_line
		(start 351.920302 -274.511516)
		(end 351.920302 -273.368516)
		(stroke
			(width 0.2)
			(type default)
		)
		(layer "In10.Cu")
	)
	(gr_arc
		(start 351.920302 -273.368516)
		(mid 351.539302 -272.987516)
		(end 351.158302 -273.368516)
		(stroke
			(width 0.2)
			(type default)
		)
		(layer "In10.Cu")
	)
	(gr_line
		(start 351.920302 -159.511492)
		(end 351.920302 -158.368492)
		(stroke
			(width 0.2)
			(type default)
		)
		(layer "In10.Cu")
	)
	(gr_arc
		(start 351.920302 -158.368492)
		(mid 351.539302 -157.987492)
		(end 351.158302 -158.368492)
		(stroke
			(width 0.2)
			(type default)
		)
		(layer "In10.Cu")
	)
	(gr_arc
		(start 354.601272 -22.350222)
		(mid 355.149912 -22.898862)
		(end 355.698552 -22.350222)
		(stroke
			(width 0.2)
			(type default)
		)
		(layer "In10.Cu")
	)
	(gr_line
		(start 354.601272 -20.950174)
		(end 354.601272 -22.350222)
		(stroke
			(width 0.2)
			(type default)
		)
		(layer "In10.Cu")
	)
	(gr_arc
		(start 354.601272 -18.750026)
		(mid 355.149912 -19.298666)
		(end 355.698552 -18.750026)
		(stroke
			(width 0.2)
			(type default)
		)
		(layer "In10.Cu")
	)
	(gr_line
		(start 354.601272 -17.349978)
		(end 354.601272 -18.750026)
		(stroke
			(width 0.2)
			(type default)
		)
		(layer "In10.Cu")
	)
	(gr_line
		(start 355.698552 -22.350222)
		(end 355.698552 -20.950428)
		(stroke
			(width 0.2)
			(type default)
		)
		(layer "In10.Cu")
	)
	(gr_arc
		(start 355.698552 -20.950428)
		(mid 355.150039 -20.401534)
		(end 354.601272 -20.950174)
		(stroke
			(width 0.2)
			(type default)
		)
		(layer "In10.Cu")
	)
	(gr_line
		(start 355.698552 -18.750026)
		(end 355.698552 -17.350232)
		(stroke
			(width 0.2)
			(type default)
		)
		(layer "In10.Cu")
	)
	(gr_arc
		(start 355.698552 -17.350232)
		(mid 355.150039 -16.801338)
		(end 354.601272 -17.349978)
		(stroke
			(width 0.2)
			(type default)
		)
		(layer "In10.Cu")
	)
	(gr_arc
		(start 355.903022 -48.321468)
		(mid 356.289102 -48.707548)
		(end 356.675182 -48.321468)
		(stroke
			(width 0.2)
			(type default)
		)
		(layer "In10.Cu")
	)
	(gr_line
		(start 355.903022 -47.178468)
		(end 355.903022 -48.321468)
		(stroke
			(width 0.2)
			(type default)
		)
		(layer "In10.Cu")
	)
	(gr_arc
		(start 355.908102 -278.321516)
		(mid 356.289102 -278.702516)
		(end 356.670102 -278.321516)
		(stroke
			(width 0.2)
			(type default)
		)
		(layer "In10.Cu")
	)
	(gr_line
		(start 355.908102 -277.178516)
		(end 355.908102 -278.321516)
		(stroke
			(width 0.2)
			(type default)
		)
		(layer "In10.Cu")
	)
	(gr_arc
		(start 355.908102 -163.321492)
		(mid 356.289102 -163.702492)
		(end 356.670102 -163.321492)
		(stroke
			(width 0.2)
			(type default)
		)
		(layer "In10.Cu")
	)
	(gr_line
		(start 355.908102 -162.178492)
		(end 355.908102 -163.321492)
		(stroke
			(width 0.2)
			(type default)
		)
		(layer "In10.Cu")
	)
	(gr_arc
		(start 356.40137 -23.35022)
		(mid 356.95001 -23.89886)
		(end 357.49865 -23.35022)
		(stroke
			(width 0.2)
			(type default)
		)
		(layer "In10.Cu")
	)
	(gr_line
		(start 356.40137 -21.950172)
		(end 356.40137 -23.35022)
		(stroke
			(width 0.2)
			(type default)
		)
		(layer "In10.Cu")
	)
	(gr_arc
		(start 356.40137 -19.750024)
		(mid 356.95001 -20.298664)
		(end 357.49865 -19.750024)
		(stroke
			(width 0.2)
			(type default)
		)
		(layer "In10.Cu")
	)
	(gr_line
		(start 356.40137 -18.35023)
		(end 356.40137 -19.750024)
		(stroke
			(width 0.2)
			(type default)
		)
		(layer "In10.Cu")
	)
	(gr_line
		(start 356.670102 -278.321516)
		(end 356.670102 -277.17877)
		(stroke
			(width 0.2)
			(type default)
		)
		(layer "In10.Cu")
	)
	(gr_arc
		(start 356.670102 -277.17877)
		(mid 356.289229 -276.797516)
		(end 355.908102 -277.178516)
		(stroke
			(width 0.2)
			(type default)
		)
		(layer "In10.Cu")
	)
	(gr_line
		(start 356.670102 -163.321492)
		(end 356.670102 -162.178746)
		(stroke
			(width 0.2)
			(type default)
		)
		(layer "In10.Cu")
	)
	(gr_arc
		(start 356.670102 -162.178746)
		(mid 356.289229 -161.797492)
		(end 355.908102 -162.178492)
		(stroke
			(width 0.2)
			(type default)
		)
		(layer "In10.Cu")
	)
	(gr_line
		(start 356.675182 -48.321468)
		(end 356.675182 -47.178722)
		(stroke
			(width 0.2)
			(type default)
		)
		(layer "In10.Cu")
	)
	(gr_arc
		(start 356.675182 -47.178722)
		(mid 356.289229 -46.792388)
		(end 355.903022 -47.178468)
		(stroke
			(width 0.2)
			(type default)
		)
		(layer "In10.Cu")
	)
	(gr_line
		(start 357.49865 -23.35022)
		(end 357.49865 -21.950426)
		(stroke
			(width 0.2)
			(type default)
		)
		(layer "In10.Cu")
	)
	(gr_arc
		(start 357.49865 -21.950426)
		(mid 356.950137 -21.401532)
		(end 356.40137 -21.950172)
		(stroke
			(width 0.2)
			(type default)
		)
		(layer "In10.Cu")
	)
	(gr_line
		(start 357.49865 -19.750024)
		(end 357.49865 -18.350484)
		(stroke
			(width 0.2)
			(type default)
		)
		(layer "In10.Cu")
	)
	(gr_arc
		(start 357.49865 -18.350484)
		(mid 356.950137 -17.80159)
		(end 356.40137 -18.35023)
		(stroke
			(width 0.2)
			(type default)
		)
		(layer "In10.Cu")
	)
	(gr_arc
		(start 358.201468 -22.350222)
		(mid 358.750108 -22.898862)
		(end 359.298748 -22.350222)
		(stroke
			(width 0.2)
			(type default)
		)
		(layer "In10.Cu")
	)
	(gr_line
		(start 358.201468 -20.950174)
		(end 358.201468 -22.350222)
		(stroke
			(width 0.2)
			(type default)
		)
		(layer "In10.Cu")
	)
	(gr_arc
		(start 358.201468 -18.750026)
		(mid 358.750108 -19.298666)
		(end 359.298748 -18.750026)
		(stroke
			(width 0.2)
			(type default)
		)
		(layer "In10.Cu")
	)
	(gr_line
		(start 358.201468 -17.349978)
		(end 358.201468 -18.750026)
		(stroke
			(width 0.2)
			(type default)
		)
		(layer "In10.Cu")
	)
	(gr_line
		(start 359.298748 -22.350222)
		(end 359.298748 -20.950428)
		(stroke
			(width 0.2)
			(type default)
		)
		(layer "In10.Cu")
	)
	(gr_arc
		(start 359.298748 -20.950428)
		(mid 358.750235 -20.401534)
		(end 358.201468 -20.950174)
		(stroke
			(width 0.2)
			(type default)
		)
		(layer "In10.Cu")
	)
	(gr_line
		(start 359.298748 -18.750026)
		(end 359.298748 -17.350232)
		(stroke
			(width 0.2)
			(type default)
		)
		(layer "In10.Cu")
	)
	(gr_arc
		(start 359.298748 -17.350232)
		(mid 358.750235 -16.801338)
		(end 358.201468 -17.349978)
		(stroke
			(width 0.2)
			(type default)
		)
		(layer "In10.Cu")
	)
	(gr_arc
		(start 360.001312 -23.35022)
		(mid 360.549952 -23.89886)
		(end 361.098592 -23.35022)
		(stroke
			(width 0.2)
			(type default)
		)
		(layer "In10.Cu")
	)
	(gr_line
		(start 360.001312 -21.950172)
		(end 360.001312 -23.35022)
		(stroke
			(width 0.2)
			(type default)
		)
		(layer "In10.Cu")
	)
	(gr_arc
		(start 360.001312 -19.750024)
		(mid 360.549952 -20.298664)
		(end 361.098592 -19.750024)
		(stroke
			(width 0.2)
			(type default)
		)
		(layer "In10.Cu")
	)
	(gr_line
		(start 360.001312 -18.35023)
		(end 360.001312 -19.750024)
		(stroke
			(width 0.2)
			(type default)
		)
		(layer "In10.Cu")
	)
	(gr_line
		(start 361.098592 -23.35022)
		(end 361.098592 -21.950426)
		(stroke
			(width 0.2)
			(type default)
		)
		(layer "In10.Cu")
	)
	(gr_arc
		(start 361.098592 -21.950426)
		(mid 360.550079 -21.401532)
		(end 360.001312 -21.950172)
		(stroke
			(width 0.2)
			(type default)
		)
		(layer "In10.Cu")
	)
	(gr_line
		(start 361.098592 -19.750024)
		(end 361.098592 -18.350484)
		(stroke
			(width 0.2)
			(type default)
		)
		(layer "In10.Cu")
	)
	(gr_arc
		(start 361.098592 -18.350484)
		(mid 360.550079 -17.80159)
		(end 360.001312 -18.35023)
		(stroke
			(width 0.2)
			(type default)
		)
		(layer "In10.Cu")
	)
	(gr_arc
		(start 361.80141 -29.550106)
		(mid 362.35005 -30.098746)
		(end 362.89869 -29.550106)
		(stroke
			(width 0.2)
			(type default)
		)
		(layer "In10.Cu")
	)
	(gr_line
		(start 361.80141 -28.150058)
		(end 361.80141 -29.550106)
		(stroke
			(width 0.2)
			(type default)
		)
		(layer "In10.Cu")
	)
	(gr_arc
		(start 361.80141 -22.350222)
		(mid 362.35005 -22.898862)
		(end 362.89869 -22.350222)
		(stroke
			(width 0.2)
			(type default)
		)
		(layer "In10.Cu")
	)
	(gr_line
		(start 361.80141 -20.950174)
		(end 361.80141 -22.350222)
		(stroke
			(width 0.2)
			(type default)
		)
		(layer "In10.Cu")
	)
	(gr_arc
		(start 361.80141 -18.750026)
		(mid 362.35005 -19.298666)
		(end 362.89869 -18.750026)
		(stroke
			(width 0.2)
			(type default)
		)
		(layer "In10.Cu")
	)
	(gr_line
		(start 361.80141 -17.349978)
		(end 361.80141 -18.750026)
		(stroke
			(width 0.2)
			(type default)
		)
		(layer "In10.Cu")
	)
	(gr_line
		(start 362.89869 -29.550106)
		(end 362.89869 -28.150312)
		(stroke
			(width 0.2)
			(type default)
		)
		(layer "In10.Cu")
	)
	(gr_arc
		(start 362.89869 -28.150312)
		(mid 362.350177 -27.601418)
		(end 361.80141 -28.150058)
		(stroke
			(width 0.2)
			(type default)
		)
		(layer "In10.Cu")
	)
	(gr_line
		(start 362.89869 -22.350222)
		(end 362.89869 -20.950428)
		(stroke
			(width 0.2)
			(type default)
		)
		(layer "In10.Cu")
	)
	(gr_arc
		(start 362.89869 -20.950428)
		(mid 362.350177 -20.401534)
		(end 361.80141 -20.950174)
		(stroke
			(width 0.2)
			(type default)
		)
		(layer "In10.Cu")
	)
	(gr_line
		(start 362.89869 -18.750026)
		(end 362.89869 -17.350232)
		(stroke
			(width 0.2)
			(type default)
		)
		(layer "In10.Cu")
	)
	(gr_arc
		(start 362.89869 -17.350232)
		(mid 362.350177 -16.801338)
		(end 361.80141 -17.349978)
		(stroke
			(width 0.2)
			(type default)
		)
		(layer "In10.Cu")
	)
	(gr_arc
		(start 363.601254 -23.35022)
		(mid 364.149894 -23.89886)
		(end 364.698534 -23.35022)
		(stroke
			(width 0.2)
			(type default)
		)
		(layer "In10.Cu")
	)
	(gr_line
		(start 363.601254 -21.950172)
		(end 363.601254 -23.35022)
		(stroke
			(width 0.2)
			(type default)
		)
		(layer "In10.Cu")
	)
	(gr_arc
		(start 363.601254 -19.750024)
		(mid 364.149894 -20.298664)
		(end 364.698534 -19.750024)
		(stroke
			(width 0.2)
			(type default)
		)
		(layer "In10.Cu")
	)
	(gr_line
		(start 363.601254 -18.35023)
		(end 363.601254 -19.750024)
		(stroke
			(width 0.2)
			(type default)
		)
		(layer "In10.Cu")
	)
	(gr_line
		(start 364.698534 -23.35022)
		(end 364.698534 -21.950426)
		(stroke
			(width 0.2)
			(type default)
		)
		(layer "In10.Cu")
	)
	(gr_arc
		(start 364.698534 -21.950426)
		(mid 364.150021 -21.401532)
		(end 363.601254 -21.950172)
		(stroke
			(width 0.2)
			(type default)
		)
		(layer "In10.Cu")
	)
	(gr_line
		(start 364.698534 -19.750024)
		(end 364.698534 -18.350484)
		(stroke
			(width 0.2)
			(type default)
		)
		(layer "In10.Cu")
	)
	(gr_arc
		(start 364.698534 -18.350484)
		(mid 364.150021 -17.80159)
		(end 363.601254 -18.35023)
		(stroke
			(width 0.2)
			(type default)
		)
		(layer "In10.Cu")
	)
	(gr_arc
		(start 365.401352 -22.350222)
		(mid 365.949992 -22.898862)
		(end 366.498632 -22.350222)
		(stroke
			(width 0.2)
			(type default)
		)
		(layer "In10.Cu")
	)
	(gr_line
		(start 365.401352 -20.950174)
		(end 365.401352 -22.350222)
		(stroke
			(width 0.2)
			(type default)
		)
		(layer "In10.Cu")
	)
	(gr_arc
		(start 365.401352 -18.750026)
		(mid 365.949992 -19.298666)
		(end 366.498632 -18.750026)
		(stroke
			(width 0.2)
			(type default)
		)
		(layer "In10.Cu")
	)
	(gr_line
		(start 365.401352 -17.349978)
		(end 365.401352 -18.750026)
		(stroke
			(width 0.2)
			(type default)
		)
		(layer "In10.Cu")
	)
	(gr_line
		(start 366.498632 -22.350222)
		(end 366.498632 -20.950428)
		(stroke
			(width 0.2)
			(type default)
		)
		(layer "In10.Cu")
	)
	(gr_arc
		(start 366.498632 -20.950428)
		(mid 365.950119 -20.401534)
		(end 365.401352 -20.950174)
		(stroke
			(width 0.2)
			(type default)
		)
		(layer "In10.Cu")
	)
	(gr_line
		(start 366.498632 -18.750026)
		(end 366.498632 -17.350232)
		(stroke
			(width 0.2)
			(type default)
		)
		(layer "In10.Cu")
	)
	(gr_arc
		(start 366.498632 -17.350232)
		(mid 365.950119 -16.801338)
		(end 365.401352 -17.349978)
		(stroke
			(width 0.2)
			(type default)
		)
		(layer "In10.Cu")
	)
	(gr_arc
		(start 367.19891 -30.54985)
		(mid 367.749963 -31.101284)
		(end 368.30127 -30.550104)
		(stroke
			(width 0.2)
			(type default)
		)
		(layer "In10.Cu")
	)
	(gr_line
		(start 367.19891 -29.150056)
		(end 367.19891 -30.54985)
		(stroke
			(width 0.2)
			(type default)
		)
		(layer "In10.Cu")
	)
	(gr_arc
		(start 367.20145 -23.35022)
		(mid 367.75009 -23.89886)
		(end 368.29873 -23.35022)
		(stroke
			(width 0.2)
			(type default)
		)
		(layer "In10.Cu")
	)
	(gr_line
		(start 367.20145 -21.950172)
		(end 367.20145 -23.35022)
		(stroke
			(width 0.2)
			(type default)
		)
		(layer "In10.Cu")
	)
	(gr_arc
		(start 367.20145 -19.750024)
		(mid 367.75009 -20.298664)
		(end 368.29873 -19.750024)
		(stroke
			(width 0.2)
			(type default)
		)
		(layer "In10.Cu")
	)
	(gr_line
		(start 367.20145 -18.35023)
		(end 367.20145 -19.750024)
		(stroke
			(width 0.2)
			(type default)
		)
		(layer "In10.Cu")
	)
	(gr_line
		(start 368.29873 -23.35022)
		(end 368.29873 -21.950426)
		(stroke
			(width 0.2)
			(type default)
		)
		(layer "In10.Cu")
	)
	(gr_arc
		(start 368.29873 -21.950426)
		(mid 367.750217 -21.401532)
		(end 367.20145 -21.950172)
		(stroke
			(width 0.2)
			(type default)
		)
		(layer "In10.Cu")
	)
	(gr_line
		(start 368.29873 -19.750024)
		(end 368.29873 -18.350484)
		(stroke
			(width 0.2)
			(type default)
		)
		(layer "In10.Cu")
	)
	(gr_arc
		(start 368.29873 -18.350484)
		(mid 367.750217 -17.80159)
		(end 367.20145 -18.35023)
		(stroke
			(width 0.2)
			(type default)
		)
		(layer "In10.Cu")
	)
	(gr_line
		(start 368.30127 -30.550104)
		(end 368.30127 -29.150056)
		(stroke
			(width 0.2)
			(type default)
		)
		(layer "In10.Cu")
	)
	(gr_arc
		(start 368.30127 -29.150056)
		(mid 367.75009 -28.598876)
		(end 367.19891 -29.150056)
		(stroke
			(width 0.2)
			(type default)
		)
		(layer "In10.Cu")
	)
	(gr_arc
		(start 376.201432 -22.350222)
		(mid 376.750072 -22.898862)
		(end 377.298712 -22.350222)
		(stroke
			(width 0.2)
			(type default)
		)
		(layer "In10.Cu")
	)
	(gr_line
		(start 376.201432 -20.950174)
		(end 376.201432 -22.350222)
		(stroke
			(width 0.2)
			(type default)
		)
		(layer "In10.Cu")
	)
	(gr_arc
		(start 376.201432 -18.750026)
		(mid 376.750072 -19.298666)
		(end 377.298712 -18.750026)
		(stroke
			(width 0.2)
			(type default)
		)
		(layer "In10.Cu")
	)
	(gr_line
		(start 376.201432 -17.349978)
		(end 376.201432 -18.750026)
		(stroke
			(width 0.2)
			(type default)
		)
		(layer "In10.Cu")
	)
	(gr_line
		(start 377.298712 -22.350222)
		(end 377.298712 -20.950428)
		(stroke
			(width 0.2)
			(type default)
		)
		(layer "In10.Cu")
	)
	(gr_arc
		(start 377.298712 -20.950428)
		(mid 376.750199 -20.401534)
		(end 376.201432 -20.950174)
		(stroke
			(width 0.2)
			(type default)
		)
		(layer "In10.Cu")
	)
	(gr_line
		(start 377.298712 -18.750026)
		(end 377.298712 -17.350232)
		(stroke
			(width 0.2)
			(type default)
		)
		(layer "In10.Cu")
	)
	(gr_arc
		(start 377.298712 -17.350232)
		(mid 376.750199 -16.801338)
		(end 376.201432 -17.349978)
		(stroke
			(width 0.2)
			(type default)
		)
		(layer "In10.Cu")
	)
	(gr_arc
		(start 378.001276 -23.35022)
		(mid 378.549916 -23.89886)
		(end 379.098556 -23.35022)
		(stroke
			(width 0.2)
			(type default)
		)
		(layer "In10.Cu")
	)
	(gr_line
		(start 378.001276 -21.950172)
		(end 378.001276 -23.35022)
		(stroke
			(width 0.2)
			(type default)
		)
		(layer "In10.Cu")
	)
	(gr_arc
		(start 378.001276 -19.750024)
		(mid 378.549916 -20.298664)
		(end 379.098556 -19.750024)
		(stroke
			(width 0.2)
			(type default)
		)
		(layer "In10.Cu")
	)
	(gr_line
		(start 378.001276 -18.35023)
		(end 378.001276 -19.750024)
		(stroke
			(width 0.2)
			(type default)
		)
		(layer "In10.Cu")
	)
	(gr_line
		(start 379.098556 -23.35022)
		(end 379.098556 -21.950426)
		(stroke
			(width 0.2)
			(type default)
		)
		(layer "In10.Cu")
	)
	(gr_arc
		(start 379.098556 -21.950426)
		(mid 378.550043 -21.401532)
		(end 378.001276 -21.950172)
		(stroke
			(width 0.2)
			(type default)
		)
		(layer "In10.Cu")
	)
	(gr_line
		(start 379.098556 -19.750024)
		(end 379.098556 -18.350484)
		(stroke
			(width 0.2)
			(type default)
		)
		(layer "In10.Cu")
	)
	(gr_arc
		(start 379.098556 -18.350484)
		(mid 378.550043 -17.80159)
		(end 378.001276 -18.35023)
		(stroke
			(width 0.2)
			(type default)
		)
		(layer "In10.Cu")
	)
	(gr_arc
		(start 379.801374 -22.350222)
		(mid 380.350014 -22.898862)
		(end 380.898654 -22.350222)
		(stroke
			(width 0.2)
			(type default)
		)
		(layer "In10.Cu")
	)
	(gr_line
		(start 379.801374 -20.950174)
		(end 379.801374 -22.350222)
		(stroke
			(width 0.2)
			(type default)
		)
		(layer "In10.Cu")
	)
	(gr_arc
		(start 379.801374 -18.750026)
		(mid 380.350014 -19.298666)
		(end 380.898654 -18.750026)
		(stroke
			(width 0.2)
			(type default)
		)
		(layer "In10.Cu")
	)
	(gr_line
		(start 379.801374 -17.349978)
		(end 379.801374 -18.750026)
		(stroke
			(width 0.2)
			(type default)
		)
		(layer "In10.Cu")
	)
	(gr_line
		(start 380.898654 -22.350222)
		(end 380.898654 -20.950428)
		(stroke
			(width 0.2)
			(type default)
		)
		(layer "In10.Cu")
	)
	(gr_arc
		(start 380.898654 -20.950428)
		(mid 380.350141 -20.401534)
		(end 379.801374 -20.950174)
		(stroke
			(width 0.2)
			(type default)
		)
		(layer "In10.Cu")
	)
	(gr_line
		(start 380.898654 -18.750026)
		(end 380.898654 -17.350232)
		(stroke
			(width 0.2)
			(type default)
		)
		(layer "In10.Cu")
	)
	(gr_arc
		(start 380.898654 -17.350232)
		(mid 380.350141 -16.801338)
		(end 379.801374 -17.349978)
		(stroke
			(width 0.2)
			(type default)
		)
		(layer "In10.Cu")
	)
	(gr_arc
		(start 381.598932 -30.550104)
		(mid 382.150112 -31.101284)
		(end 382.701292 -30.550104)
		(stroke
			(width 0.2)
			(type default)
		)
		(layer "In10.Cu")
	)
	(gr_line
		(start 381.598932 -29.150056)
		(end 381.598932 -30.550104)
		(stroke
			(width 0.2)
			(type default)
		)
		(layer "In10.Cu")
	)
	(gr_arc
		(start 381.601472 -23.35022)
		(mid 382.150112 -23.89886)
		(end 382.698752 -23.35022)
		(stroke
			(width 0.2)
			(type default)
		)
		(layer "In10.Cu")
	)
	(gr_line
		(start 381.601472 -21.950172)
		(end 381.601472 -23.35022)
		(stroke
			(width 0.2)
			(type default)
		)
		(layer "In10.Cu")
	)
	(gr_arc
		(start 381.601472 -19.750024)
		(mid 382.150112 -20.298664)
		(end 382.698752 -19.750024)
		(stroke
			(width 0.2)
			(type default)
		)
		(layer "In10.Cu")
	)
	(gr_line
		(start 381.601472 -18.35023)
		(end 381.601472 -19.750024)
		(stroke
			(width 0.2)
			(type default)
		)
		(layer "In10.Cu")
	)
	(gr_line
		(start 382.698752 -23.35022)
		(end 382.698752 -21.950426)
		(stroke
			(width 0.2)
			(type default)
		)
		(layer "In10.Cu")
	)
	(gr_arc
		(start 382.698752 -21.950426)
		(mid 382.150239 -21.401532)
		(end 381.601472 -21.950172)
		(stroke
			(width 0.2)
			(type default)
		)
		(layer "In10.Cu")
	)
	(gr_line
		(start 382.698752 -19.750024)
		(end 382.698752 -18.350484)
		(stroke
			(width 0.2)
			(type default)
		)
		(layer "In10.Cu")
	)
	(gr_arc
		(start 382.698752 -18.350484)
		(mid 382.150239 -17.80159)
		(end 381.601472 -18.35023)
		(stroke
			(width 0.2)
			(type default)
		)
		(layer "In10.Cu")
	)
	(gr_line
		(start 382.701292 -30.550104)
		(end 382.701292 -29.15031)
		(stroke
			(width 0.2)
			(type default)
		)
		(layer "In10.Cu")
	)
	(gr_arc
		(start 382.701292 -29.15031)
		(mid 382.150239 -28.598876)
		(end 381.598932 -29.150056)
		(stroke
			(width 0.2)
			(type default)
		)
		(layer "In10.Cu")
	)
	(gr_arc
		(start 382.70815 -274.511262)
		(mid 383.089023 -274.892516)
		(end 383.47015 -274.511516)
		(stroke
			(width 0.2)
			(type default)
		)
		(layer "In10.Cu")
	)
	(gr_line
		(start 382.70815 -273.368516)
		(end 382.70815 -274.511262)
		(stroke
			(width 0.2)
			(type default)
		)
		(layer "In10.Cu")
	)
	(gr_arc
		(start 382.70815 -159.511238)
		(mid 383.089023 -159.892492)
		(end 383.47015 -159.511492)
		(stroke
			(width 0.2)
			(type default)
		)
		(layer "In10.Cu")
	)
	(gr_line
		(start 382.70815 -158.368492)
		(end 382.70815 -159.511238)
		(stroke
			(width 0.2)
			(type default)
		)
		(layer "In10.Cu")
	)
	(gr_line
		(start 382.7653 -46.5328)
		(end 383.908046 -46.5328)
		(stroke
			(width 0.2)
			(type default)
		)
		(layer "In10.Cu")
	)
	(gr_arc
		(start 382.7653 -45.7708)
		(mid 382.3843 -46.1518)
		(end 382.7653 -46.5328)
		(stroke
			(width 0.2)
			(type default)
		)
		(layer "In10.Cu")
	)
	(gr_arc
		(start 383.401316 -22.350222)
		(mid 383.949956 -22.898862)
		(end 384.498596 -22.350222)
		(stroke
			(width 0.2)
			(type default)
		)
		(layer "In10.Cu")
	)
	(gr_line
		(start 383.401316 -20.950174)
		(end 383.401316 -22.350222)
		(stroke
			(width 0.2)
			(type default)
		)
		(layer "In10.Cu")
	)
	(gr_arc
		(start 383.401316 -18.750026)
		(mid 383.949956 -19.298666)
		(end 384.498596 -18.750026)
		(stroke
			(width 0.2)
			(type default)
		)
		(layer "In10.Cu")
	)
	(gr_line
		(start 383.401316 -17.349978)
		(end 383.401316 -18.750026)
		(stroke
			(width 0.2)
			(type default)
		)
		(layer "In10.Cu")
	)
	(gr_line
		(start 383.47015 -274.511516)
		(end 383.47015 -273.368516)
		(stroke
			(width 0.2)
			(type default)
		)
		(layer "In10.Cu")
	)
	(gr_arc
		(start 383.47015 -273.368516)
		(mid 383.08915 -272.987516)
		(end 382.70815 -273.368516)
		(stroke
			(width 0.2)
			(type default)
		)
		(layer "In10.Cu")
	)
	(gr_line
		(start 383.47015 -159.511492)
		(end 383.47015 -158.368492)
		(stroke
			(width 0.2)
			(type default)
		)
		(layer "In10.Cu")
	)
	(gr_arc
		(start 383.47015 -158.368492)
		(mid 383.08915 -157.987492)
		(end 382.70815 -158.368492)
		(stroke
			(width 0.2)
			(type default)
		)
		(layer "In10.Cu")
	)
	(gr_arc
		(start 383.908046 -46.5328)
		(mid 384.2893 -46.151927)
		(end 383.9083 -45.7708)
		(stroke
			(width 0.2)
			(type default)
		)
		(layer "In10.Cu")
	)
	(gr_line
		(start 383.9083 -45.7708)
		(end 382.7653 -45.7708)
		(stroke
			(width 0.2)
			(type default)
		)
		(layer "In10.Cu")
	)
	(gr_line
		(start 384.498596 -22.350222)
		(end 384.498596 -20.950428)
		(stroke
			(width 0.2)
			(type default)
		)
		(layer "In10.Cu")
	)
	(gr_arc
		(start 384.498596 -20.950428)
		(mid 383.950083 -20.401534)
		(end 383.401316 -20.950174)
		(stroke
			(width 0.2)
			(type default)
		)
		(layer "In10.Cu")
	)
	(gr_line
		(start 384.498596 -18.750026)
		(end 384.498596 -17.350232)
		(stroke
			(width 0.2)
			(type default)
		)
		(layer "In10.Cu")
	)
	(gr_arc
		(start 384.498596 -17.350232)
		(mid 383.950083 -16.801338)
		(end 383.401316 -17.349978)
		(stroke
			(width 0.2)
			(type default)
		)
		(layer "In10.Cu")
	)
	(gr_arc
		(start 385.201414 -23.35022)
		(mid 385.750054 -23.89886)
		(end 386.298694 -23.35022)
		(stroke
			(width 0.2)
			(type default)
		)
		(layer "In10.Cu")
	)
	(gr_line
		(start 385.201414 -21.950172)
		(end 385.201414 -23.35022)
		(stroke
			(width 0.2)
			(type default)
		)
		(layer "In10.Cu")
	)
	(gr_arc
		(start 385.201414 -19.750024)
		(mid 385.750054 -20.298664)
		(end 386.298694 -19.750024)
		(stroke
			(width 0.2)
			(type default)
		)
		(layer "In10.Cu")
	)
	(gr_line
		(start 385.201414 -18.35023)
		(end 385.201414 -19.750024)
		(stroke
			(width 0.2)
			(type default)
		)
		(layer "In10.Cu")
	)
	(gr_line
		(start 386.298694 -23.35022)
		(end 386.298694 -21.950426)
		(stroke
			(width 0.2)
			(type default)
		)
		(layer "In10.Cu")
	)
	(gr_arc
		(start 386.298694 -21.950426)
		(mid 385.750181 -21.401532)
		(end 385.201414 -21.950172)
		(stroke
			(width 0.2)
			(type default)
		)
		(layer "In10.Cu")
	)
	(gr_line
		(start 386.298694 -19.750024)
		(end 386.298694 -18.350484)
		(stroke
			(width 0.2)
			(type default)
		)
		(layer "In10.Cu")
	)
	(gr_arc
		(start 386.298694 -18.350484)
		(mid 385.750181 -17.80159)
		(end 385.201414 -18.35023)
		(stroke
			(width 0.2)
			(type default)
		)
		(layer "In10.Cu")
	)
	(gr_arc
		(start 387.001258 -22.350222)
		(mid 387.549898 -22.898862)
		(end 388.098538 -22.350222)
		(stroke
			(width 0.2)
			(type default)
		)
		(layer "In10.Cu")
	)
	(gr_line
		(start 387.001258 -20.950174)
		(end 387.001258 -22.350222)
		(stroke
			(width 0.2)
			(type default)
		)
		(layer "In10.Cu")
	)
	(gr_arc
		(start 387.001258 -18.750026)
		(mid 387.549898 -19.298666)
		(end 388.098538 -18.750026)
		(stroke
			(width 0.2)
			(type default)
		)
		(layer "In10.Cu")
	)
	(gr_line
		(start 387.001258 -17.349978)
		(end 387.001258 -18.750026)
		(stroke
			(width 0.2)
			(type default)
		)
		(layer "In10.Cu")
	)
	(gr_arc
		(start 387.45795 -278.321516)
		(mid 387.83895 -278.702516)
		(end 388.21995 -278.321516)
		(stroke
			(width 0.2)
			(type default)
		)
		(layer "In10.Cu")
	)
	(gr_line
		(start 387.45795 -277.178516)
		(end 387.45795 -278.321516)
		(stroke
			(width 0.2)
			(type default)
		)
		(layer "In10.Cu")
	)
	(gr_arc
		(start 387.45795 -163.321492)
		(mid 387.83895 -163.702492)
		(end 388.21995 -163.321492)
		(stroke
			(width 0.2)
			(type default)
		)
		(layer "In10.Cu")
	)
	(gr_line
		(start 387.45795 -162.178492)
		(end 387.45795 -163.321492)
		(stroke
			(width 0.2)
			(type default)
		)
		(layer "In10.Cu")
	)
	(gr_arc
		(start 387.45795 -48.321468)
		(mid 387.83895 -48.702468)
		(end 388.21995 -48.321468)
		(stroke
			(width 0.2)
			(type default)
		)
		(layer "In10.Cu")
	)
	(gr_line
		(start 387.45795 -47.178468)
		(end 387.45795 -48.321468)
		(stroke
			(width 0.2)
			(type default)
		)
		(layer "In10.Cu")
	)
	(gr_line
		(start 388.098538 -22.350222)
		(end 388.098538 -20.950428)
		(stroke
			(width 0.2)
			(type default)
		)
		(layer "In10.Cu")
	)
	(gr_arc
		(start 388.098538 -20.950428)
		(mid 387.550025 -20.401534)
		(end 387.001258 -20.950174)
		(stroke
			(width 0.2)
			(type default)
		)
		(layer "In10.Cu")
	)
	(gr_line
		(start 388.098538 -18.750026)
		(end 388.098538 -17.350232)
		(stroke
			(width 0.2)
			(type default)
		)
		(layer "In10.Cu")
	)
	(gr_arc
		(start 388.098538 -17.350232)
		(mid 387.550025 -16.801338)
		(end 387.001258 -17.349978)
		(stroke
			(width 0.2)
			(type default)
		)
		(layer "In10.Cu")
	)
	(gr_line
		(start 388.21995 -278.321516)
		(end 388.21995 -277.17877)
		(stroke
			(width 0.2)
			(type default)
		)
		(layer "In10.Cu")
	)
	(gr_arc
		(start 388.21995 -277.17877)
		(mid 387.839077 -276.797516)
		(end 387.45795 -277.178516)
		(stroke
			(width 0.2)
			(type default)
		)
		(layer "In10.Cu")
	)
	(gr_line
		(start 388.21995 -163.321492)
		(end 388.21995 -162.178746)
		(stroke
			(width 0.2)
			(type default)
		)
		(layer "In10.Cu")
	)
	(gr_arc
		(start 388.21995 -162.178746)
		(mid 387.839077 -161.797492)
		(end 387.45795 -162.178492)
		(stroke
			(width 0.2)
			(type default)
		)
		(layer "In10.Cu")
	)
	(gr_line
		(start 388.21995 -48.321468)
		(end 388.21995 -47.178722)
		(stroke
			(width 0.2)
			(type default)
		)
		(layer "In10.Cu")
	)
	(gr_arc
		(start 388.21995 -47.178722)
		(mid 387.839077 -46.797468)
		(end 387.45795 -47.178468)
		(stroke
			(width 0.2)
			(type default)
		)
		(layer "In10.Cu")
	)
	(gr_arc
		(start 388.801356 -30.550104)
		(mid 389.349996 -31.098744)
		(end 389.898636 -30.550104)
		(stroke
			(width 0.2)
			(type default)
		)
		(layer "In10.Cu")
	)
	(gr_line
		(start 388.801356 -29.150056)
		(end 388.801356 -30.550104)
		(stroke
			(width 0.2)
			(type default)
		)
		(layer "In10.Cu")
	)
	(gr_arc
		(start 388.801356 -23.35022)
		(mid 389.349996 -23.89886)
		(end 389.898636 -23.35022)
		(stroke
			(width 0.2)
			(type default)
		)
		(layer "In10.Cu")
	)
	(gr_line
		(start 388.801356 -21.950172)
		(end 388.801356 -23.35022)
		(stroke
			(width 0.2)
			(type default)
		)
		(layer "In10.Cu")
	)
	(gr_arc
		(start 388.801356 -19.750024)
		(mid 389.349996 -20.298664)
		(end 389.898636 -19.750024)
		(stroke
			(width 0.2)
			(type default)
		)
		(layer "In10.Cu")
	)
	(gr_line
		(start 388.801356 -18.35023)
		(end 388.801356 -19.750024)
		(stroke
			(width 0.2)
			(type default)
		)
		(layer "In10.Cu")
	)
	(gr_line
		(start 389.898636 -30.550104)
		(end 389.898636 -29.15031)
		(stroke
			(width 0.2)
			(type default)
		)
		(layer "In10.Cu")
	)
	(gr_arc
		(start 389.898636 -29.15031)
		(mid 389.350123 -28.601416)
		(end 388.801356 -29.150056)
		(stroke
			(width 0.2)
			(type default)
		)
		(layer "In10.Cu")
	)
	(gr_line
		(start 389.898636 -23.35022)
		(end 389.898636 -21.950426)
		(stroke
			(width 0.2)
			(type default)
		)
		(layer "In10.Cu")
	)
	(gr_arc
		(start 389.898636 -21.950426)
		(mid 389.350123 -21.401532)
		(end 388.801356 -21.950172)
		(stroke
			(width 0.2)
			(type default)
		)
		(layer "In10.Cu")
	)
	(gr_line
		(start 389.898636 -19.750024)
		(end 389.898636 -18.350484)
		(stroke
			(width 0.2)
			(type default)
		)
		(layer "In10.Cu")
	)
	(gr_arc
		(start 389.898636 -18.350484)
		(mid 389.350123 -17.80159)
		(end 388.801356 -18.35023)
		(stroke
			(width 0.2)
			(type default)
		)
		(layer "In10.Cu")
	)
	(gr_arc
		(start 394.999972 -14.99997)
		(mid 395.707077 -14.707077)
		(end 395.99997 -13.999972)
		(stroke
			(width 1.524)
			(type default)
		)
		(layer "In10.Cu")
	)
	(gr_line
		(start 395.99997 -13.999972)
		(end 395.99997 -0.999998)
		(stroke
			(width 1.524)
			(type default)
		)
		(layer "In10.Cu")
	)
	(gr_arc
		(start 396.999968 0)
		(mid 396.292883 -0.292904)
		(end 395.99997 -0.999998)
		(stroke
			(width 1.524)
			(type default)
		)
		(layer "In10.Cu")
	)
	(gr_line
		(start 396.999968 0)
		(end 490.450124 0)
		(stroke
			(width 1.524)
			(type default)
		)
		(layer "In10.Cu")
	)
	(gr_arc
		(start 414.258252 -274.511262)
		(mid 414.639125 -274.892516)
		(end 415.020252 -274.511516)
		(stroke
			(width 0.2)
			(type default)
		)
		(layer "In10.Cu")
	)
	(gr_line
		(start 414.258252 -273.368516)
		(end 414.258252 -274.511262)
		(stroke
			(width 0.2)
			(type default)
		)
		(layer "In10.Cu")
	)
	(gr_arc
		(start 414.258252 -159.511238)
		(mid 414.639125 -159.892492)
		(end 415.020252 -159.511492)
		(stroke
			(width 0.2)
			(type default)
		)
		(layer "In10.Cu")
	)
	(gr_line
		(start 414.258252 -158.368492)
		(end 414.258252 -159.511238)
		(stroke
			(width 0.2)
			(type default)
		)
		(layer "In10.Cu")
	)
	(gr_arc
		(start 414.258252 -44.511214)
		(mid 414.639125 -44.892468)
		(end 415.020252 -44.511468)
		(stroke
			(width 0.2)
			(type default)
		)
		(layer "In10.Cu")
	)
	(gr_line
		(start 414.258252 -43.368468)
		(end 414.258252 -44.511214)
		(stroke
			(width 0.2)
			(type default)
		)
		(layer "In10.Cu")
	)
	(gr_line
		(start 415.020252 -274.511516)
		(end 415.020252 -273.368516)
		(stroke
			(width 0.2)
			(type default)
		)
		(layer "In10.Cu")
	)
	(gr_arc
		(start 415.020252 -273.368516)
		(mid 414.639252 -272.987516)
		(end 414.258252 -273.368516)
		(stroke
			(width 0.2)
			(type default)
		)
		(layer "In10.Cu")
	)
	(gr_line
		(start 415.020252 -159.511492)
		(end 415.020252 -158.368492)
		(stroke
			(width 0.2)
			(type default)
		)
		(layer "In10.Cu")
	)
	(gr_arc
		(start 415.020252 -158.368492)
		(mid 414.639252 -157.987492)
		(end 414.258252 -158.368492)
		(stroke
			(width 0.2)
			(type default)
		)
		(layer "In10.Cu")
	)
	(gr_line
		(start 415.020252 -44.511468)
		(end 415.020252 -43.368468)
		(stroke
			(width 0.2)
			(type default)
		)
		(layer "In10.Cu")
	)
	(gr_arc
		(start 415.020252 -43.368468)
		(mid 414.639252 -42.987468)
		(end 414.258252 -43.368468)
		(stroke
			(width 0.2)
			(type default)
		)
		(layer "In10.Cu")
	)
	(gr_arc
		(start 419.008052 -278.321516)
		(mid 419.389052 -278.702516)
		(end 419.770052 -278.321516)
		(stroke
			(width 0.2)
			(type default)
		)
		(layer "In10.Cu")
	)
	(gr_line
		(start 419.008052 -277.178516)
		(end 419.008052 -278.321516)
		(stroke
			(width 0.2)
			(type default)
		)
		(layer "In10.Cu")
	)
	(gr_arc
		(start 419.008052 -163.321492)
		(mid 419.389052 -163.702492)
		(end 419.770052 -163.321492)
		(stroke
			(width 0.2)
			(type default)
		)
		(layer "In10.Cu")
	)
	(gr_line
		(start 419.008052 -162.178492)
		(end 419.008052 -163.321492)
		(stroke
			(width 0.2)
			(type default)
		)
		(layer "In10.Cu")
	)
	(gr_arc
		(start 419.008052 -48.321468)
		(mid 419.389052 -48.702468)
		(end 419.770052 -48.321468)
		(stroke
			(width 0.2)
			(type default)
		)
		(layer "In10.Cu")
	)
	(gr_line
		(start 419.008052 -47.178468)
		(end 419.008052 -48.321468)
		(stroke
			(width 0.2)
			(type default)
		)
		(layer "In10.Cu")
	)
	(gr_line
		(start 419.770052 -278.321516)
		(end 419.770052 -277.17877)
		(stroke
			(width 0.2)
			(type default)
		)
		(layer "In10.Cu")
	)
	(gr_arc
		(start 419.770052 -277.17877)
		(mid 419.389179 -276.797516)
		(end 419.008052 -277.178516)
		(stroke
			(width 0.2)
			(type default)
		)
		(layer "In10.Cu")
	)
	(gr_line
		(start 419.770052 -163.321492)
		(end 419.770052 -162.178746)
		(stroke
			(width 0.2)
			(type default)
		)
		(layer "In10.Cu")
	)
	(gr_arc
		(start 419.770052 -162.178746)
		(mid 419.389179 -161.797492)
		(end 419.008052 -162.178492)
		(stroke
			(width 0.2)
			(type default)
		)
		(layer "In10.Cu")
	)
	(gr_line
		(start 419.770052 -48.321468)
		(end 419.770052 -47.178722)
		(stroke
			(width 0.2)
			(type default)
		)
		(layer "In10.Cu")
	)
	(gr_arc
		(start 419.770052 -47.178722)
		(mid 419.389179 -46.797468)
		(end 419.008052 -47.178468)
		(stroke
			(width 0.2)
			(type default)
		)
		(layer "In10.Cu")
	)
	(gr_arc
		(start 437.8579 -163.321492)
		(mid 438.2389 -163.702492)
		(end 438.6199 -163.321492)
		(stroke
			(width 0.2)
			(type default)
		)
		(layer "In10.Cu")
	)
	(gr_line
		(start 437.8579 -162.178492)
		(end 437.8579 -163.321492)
		(stroke
			(width 0.2)
			(type default)
		)
		(layer "In10.Cu")
	)
	(gr_line
		(start 438.6199 -163.321492)
		(end 438.6199 -162.178746)
		(stroke
			(width 0.2)
			(type default)
		)
		(layer "In10.Cu")
	)
	(gr_arc
		(start 438.6199 -162.178746)
		(mid 438.239027 -161.797492)
		(end 437.8579 -162.178492)
		(stroke
			(width 0.2)
			(type default)
		)
		(layer "In10.Cu")
	)
	(gr_arc
		(start 439.4581 -159.511238)
		(mid 439.838973 -159.892492)
		(end 440.2201 -159.511492)
		(stroke
			(width 0.2)
			(type default)
		)
		(layer "In10.Cu")
	)
	(gr_line
		(start 439.4581 -158.368492)
		(end 439.4581 -159.511238)
		(stroke
			(width 0.2)
			(type default)
		)
		(layer "In10.Cu")
	)
	(gr_line
		(start 440.2201 -159.511492)
		(end 440.2201 -158.368492)
		(stroke
			(width 0.2)
			(type default)
		)
		(layer "In10.Cu")
	)
	(gr_arc
		(start 440.2201 -158.368492)
		(mid 439.8391 -157.987492)
		(end 439.4581 -158.368492)
		(stroke
			(width 0.2)
			(type default)
		)
		(layer "In10.Cu")
	)
	(gr_arc
		(start 445.8081 -274.511262)
		(mid 446.188973 -274.892516)
		(end 446.5701 -274.511516)
		(stroke
			(width 0.2)
			(type default)
		)
		(layer "In10.Cu")
	)
	(gr_line
		(start 445.8081 -273.368516)
		(end 445.8081 -274.511262)
		(stroke
			(width 0.2)
			(type default)
		)
		(layer "In10.Cu")
	)
	(gr_arc
		(start 445.8081 -44.511214)
		(mid 446.188973 -44.892468)
		(end 446.5701 -44.511468)
		(stroke
			(width 0.2)
			(type default)
		)
		(layer "In10.Cu")
	)
	(gr_line
		(start 445.8081 -43.368468)
		(end 445.8081 -44.511214)
		(stroke
			(width 0.2)
			(type default)
		)
		(layer "In10.Cu")
	)
	(gr_line
		(start 446.5701 -274.511516)
		(end 446.5701 -273.368516)
		(stroke
			(width 0.2)
			(type default)
		)
		(layer "In10.Cu")
	)
	(gr_arc
		(start 446.5701 -273.368516)
		(mid 446.1891 -272.987516)
		(end 445.8081 -273.368516)
		(stroke
			(width 0.2)
			(type default)
		)
		(layer "In10.Cu")
	)
	(gr_line
		(start 446.5701 -44.511468)
		(end 446.5701 -43.368468)
		(stroke
			(width 0.2)
			(type default)
		)
		(layer "In10.Cu")
	)
	(gr_arc
		(start 446.5701 -43.368468)
		(mid 446.1891 -42.987468)
		(end 445.8081 -43.368468)
		(stroke
			(width 0.2)
			(type default)
		)
		(layer "In10.Cu")
	)
	(gr_arc
		(start 450.5579 -278.321516)
		(mid 450.9389 -278.702516)
		(end 451.3199 -278.321516)
		(stroke
			(width 0.2)
			(type default)
		)
		(layer "In10.Cu")
	)
	(gr_line
		(start 450.5579 -277.178516)
		(end 450.5579 -278.321516)
		(stroke
			(width 0.2)
			(type default)
		)
		(layer "In10.Cu")
	)
	(gr_arc
		(start 450.5579 -48.321468)
		(mid 450.9389 -48.702468)
		(end 451.3199 -48.321468)
		(stroke
			(width 0.2)
			(type default)
		)
		(layer "In10.Cu")
	)
	(gr_line
		(start 450.5579 -47.178468)
		(end 450.5579 -48.321468)
		(stroke
			(width 0.2)
			(type default)
		)
		(layer "In10.Cu")
	)
	(gr_line
		(start 451.3199 -278.321516)
		(end 451.3199 -277.17877)
		(stroke
			(width 0.2)
			(type default)
		)
		(layer "In10.Cu")
	)
	(gr_arc
		(start 451.3199 -277.17877)
		(mid 450.939027 -276.797516)
		(end 450.5579 -277.178516)
		(stroke
			(width 0.2)
			(type default)
		)
		(layer "In10.Cu")
	)
	(gr_line
		(start 451.3199 -48.321468)
		(end 451.3199 -47.178722)
		(stroke
			(width 0.2)
			(type default)
		)
		(layer "In10.Cu")
	)
	(gr_arc
		(start 451.3199 -47.178722)
		(mid 450.939027 -46.797468)
		(end 450.5579 -47.178468)
		(stroke
			(width 0.2)
			(type default)
		)
		(layer "In10.Cu")
	)
	(gr_arc
		(start 477.358202 -274.511262)
		(mid 477.739075 -274.892516)
		(end 478.120202 -274.511516)
		(stroke
			(width 0.2)
			(type default)
		)
		(layer "In10.Cu")
	)
	(gr_line
		(start 477.358202 -273.368516)
		(end 477.358202 -274.511262)
		(stroke
			(width 0.2)
			(type default)
		)
		(layer "In10.Cu")
	)
	(gr_arc
		(start 477.358202 -159.511238)
		(mid 477.739075 -159.892492)
		(end 478.120202 -159.511492)
		(stroke
			(width 0.2)
			(type default)
		)
		(layer "In10.Cu")
	)
	(gr_line
		(start 477.358202 -158.368492)
		(end 477.358202 -159.511238)
		(stroke
			(width 0.2)
			(type default)
		)
		(layer "In10.Cu")
	)
	(gr_arc
		(start 477.358202 -44.511214)
		(mid 477.739075 -44.892468)
		(end 478.120202 -44.511468)
		(stroke
			(width 0.2)
			(type default)
		)
		(layer "In10.Cu")
	)
	(gr_line
		(start 477.358202 -43.368468)
		(end 477.358202 -44.511214)
		(stroke
			(width 0.2)
			(type default)
		)
		(layer "In10.Cu")
	)
	(gr_line
		(start 478.120202 -274.511516)
		(end 478.120202 -273.368516)
		(stroke
			(width 0.2)
			(type default)
		)
		(layer "In10.Cu")
	)
	(gr_arc
		(start 478.120202 -273.368516)
		(mid 477.739202 -272.987516)
		(end 477.358202 -273.368516)
		(stroke
			(width 0.2)
			(type default)
		)
		(layer "In10.Cu")
	)
	(gr_line
		(start 478.120202 -159.511492)
		(end 478.120202 -158.368492)
		(stroke
			(width 0.2)
			(type default)
		)
		(layer "In10.Cu")
	)
	(gr_arc
		(start 478.120202 -158.368492)
		(mid 477.739202 -157.987492)
		(end 477.358202 -158.368492)
		(stroke
			(width 0.2)
			(type default)
		)
		(layer "In10.Cu")
	)
	(gr_line
		(start 478.120202 -44.511468)
		(end 478.120202 -43.368468)
		(stroke
			(width 0.2)
			(type default)
		)
		(layer "In10.Cu")
	)
	(gr_arc
		(start 478.120202 -43.368468)
		(mid 477.739202 -42.987468)
		(end 477.358202 -43.368468)
		(stroke
			(width 0.2)
			(type default)
		)
		(layer "In10.Cu")
	)
	(gr_arc
		(start 482.108002 -278.321516)
		(mid 482.489002 -278.702516)
		(end 482.870002 -278.321516)
		(stroke
			(width 0.2)
			(type default)
		)
		(layer "In10.Cu")
	)
	(gr_line
		(start 482.108002 -277.178516)
		(end 482.108002 -278.321516)
		(stroke
			(width 0.2)
			(type default)
		)
		(layer "In10.Cu")
	)
	(gr_arc
		(start 482.108002 -163.321492)
		(mid 482.489002 -163.702492)
		(end 482.870002 -163.321492)
		(stroke
			(width 0.2)
			(type default)
		)
		(layer "In10.Cu")
	)
	(gr_line
		(start 482.108002 -162.178492)
		(end 482.108002 -163.321492)
		(stroke
			(width 0.2)
			(type default)
		)
		(layer "In10.Cu")
	)
	(gr_arc
		(start 482.108002 -48.321468)
		(mid 482.489002 -48.702468)
		(end 482.870002 -48.321468)
		(stroke
			(width 0.2)
			(type default)
		)
		(layer "In10.Cu")
	)
	(gr_line
		(start 482.108002 -47.178468)
		(end 482.108002 -48.321468)
		(stroke
			(width 0.2)
			(type default)
		)
		(layer "In10.Cu")
	)
	(gr_line
		(start 482.870002 -278.321516)
		(end 482.870002 -277.17877)
		(stroke
			(width 0.2)
			(type default)
		)
		(layer "In10.Cu")
	)
	(gr_arc
		(start 482.870002 -277.17877)
		(mid 482.489129 -276.797516)
		(end 482.108002 -277.178516)
		(stroke
			(width 0.2)
			(type default)
		)
		(layer "In10.Cu")
	)
	(gr_line
		(start 482.870002 -163.321492)
		(end 482.870002 -162.178746)
		(stroke
			(width 0.2)
			(type default)
		)
		(layer "In10.Cu")
	)
	(gr_arc
		(start 482.870002 -162.178746)
		(mid 482.489129 -161.797492)
		(end 482.108002 -162.178492)
		(stroke
			(width 0.2)
			(type default)
		)
		(layer "In10.Cu")
	)
	(gr_line
		(start 482.870002 -48.321468)
		(end 482.870002 -47.178722)
		(stroke
			(width 0.2)
			(type default)
		)
		(layer "In10.Cu")
	)
	(gr_arc
		(start 482.870002 -47.178722)
		(mid 482.489129 -46.797468)
		(end 482.108002 -47.178468)
		(stroke
			(width 0.2)
			(type default)
		)
		(layer "In10.Cu")
	)
	(gr_line
		(start 490.450124 -349.199962)
		(end 296.69994 -349.199962)
		(stroke
			(width 1.524)
			(type default)
		)
		(layer "In10.Cu")
	)
	(gr_arc
		(start 490.450124 -349.199962)
		(mid 491.157201 -348.907059)
		(end 491.450122 -348.199964)
		(stroke
			(width 1.524)
			(type default)
		)
		(layer "In10.Cu")
	)
	(gr_arc
		(start 491.450122 -0.999998)
		(mid 491.15723 -0.292885)
		(end 490.450124 0)
		(stroke
			(width 1.524)
			(type default)
		)
		(layer "In10.Cu")
	)
	(gr_line
		(start 491.450122 -0.999998)
		(end 491.450122 -348.199964)
		(stroke
			(width 1.524)
			(type default)
		)
		(layer "In10.Cu")
	)
	(gr_line
		(start 0 -348.199964)
		(end 0 -0.999998)
		(stroke
			(width 0.05)
			(type default)
		)
		(layer "Edge.Cuts")
	)
	(gr_arc
		(start 0 -348.199964)
		(mid 0.292894 -348.907067)
		(end 0.999998 -349.199962)
		(stroke
			(width 0.05)
			(type default)
		)
		(layer "Edge.Cuts")
	)
	(gr_arc
		(start 0.999998 0)
		(mid 0.292893 -0.292893)
		(end 0 -0.999998)
		(stroke
			(width 0.05)
			(type default)
		)
		(layer "Edge.Cuts")
	)
	(gr_line
		(start 0.999998 0)
		(end 101.000052 0)
		(stroke
			(width 0.05)
			(type default)
		)
		(layer "Edge.Cuts")
	)
	(gr_arc
		(start 1.75006 -121.499884)
		(mid 3.850132 -123.599956)
		(end 5.94995 -121.499884)
		(stroke
			(width 0.05)
			(type default)
		)
		(layer "Edge.Cuts")
	)
	(gr_line
		(start 1.75006 -119.499888)
		(end 1.75006 -121.499884)
		(stroke
			(width 0.05)
			(type default)
		)
		(layer "Edge.Cuts")
	)
	(gr_arc
		(start 1.75006 -5.500116)
		(mid 3.850132 -7.600188)
		(end 5.94995 -5.500116)
		(stroke
			(width 0.05)
			(type default)
		)
		(layer "Edge.Cuts")
	)
	(gr_arc
		(start 5.899912 -224.199958)
		(mid 7.999984 -226.30003)
		(end 10.100056 -224.199958)
		(stroke
			(width 0.05)
			(type default)
		)
		(layer "Edge.Cuts")
	)
	(gr_line
		(start 5.94995 -121.499884)
		(end 5.94995 -119.499888)
		(stroke
			(width 0.05)
			(type default)
		)
		(layer "Edge.Cuts")
	)
	(gr_arc
		(start 5.94995 -119.499888)
		(mid 3.850132 -117.40007)
		(end 1.75006 -119.499888)
		(stroke
			(width 0.05)
			(type default)
		)
		(layer "Edge.Cuts")
	)
	(gr_arc
		(start 5.94995 -5.500116)
		(mid 3.850132 -3.400298)
		(end 1.75006 -5.500116)
		(stroke
			(width 0.05)
			(type default)
		)
		(layer "Edge.Cuts")
	)
	(gr_arc
		(start 10.100056 -224.199958)
		(mid 7.999984 -222.099886)
		(end 5.899912 -224.199958)
		(stroke
			(width 0.05)
			(type default)
		)
		(layer "Edge.Cuts")
	)
	(gr_arc
		(start 19.225006 -13.200126)
		(mid 20.32508 -14.3002)
		(end 21.4249 -13.200126)
		(stroke
			(width 0.05)
			(type default)
		)
		(layer "Edge.Cuts")
	)
	(gr_arc
		(start 21.4249 -13.200126)
		(mid 20.32508 -12.100306)
		(end 19.225006 -13.200126)
		(stroke
			(width 0.05)
			(type default)
		)
		(layer "Edge.Cuts")
	)
	(gr_arc
		(start 23.474934 -9.19988)
		(mid 26.325068 -12.050014)
		(end 29.174948 -9.19988)
		(stroke
			(width 0.05)
			(type default)
		)
		(layer "Edge.Cuts")
	)
	(gr_arc
		(start 29.174948 -9.19988)
		(mid 26.325068 -6.35)
		(end 23.474934 -9.19988)
		(stroke
			(width 0.05)
			(type default)
		)
		(layer "Edge.Cuts")
	)
	(gr_arc
		(start 30.78988 -329.572112)
		(mid 30.069042 -327.820814)
		(end 29.03093 -326.236838)
		(stroke
			(width 0.05)
			(type default)
		)
		(layer "Edge.Cuts")
	)
	(gr_arc
		(start 30.78988 -329.572112)
		(mid 33.325017 -331.45011)
		(end 35.859974 -329.572112)
		(stroke
			(width 0.05)
			(type default)
		)
		(layer "Edge.Cuts")
	)
	(gr_arc
		(start 30.78988 -214.572088)
		(mid 30.069054 -212.820782)
		(end 29.03093 -211.236814)
		(stroke
			(width 0.05)
			(type default)
		)
		(layer "Edge.Cuts")
	)
	(gr_arc
		(start 30.78988 -214.572088)
		(mid 33.325017 -216.450086)
		(end 35.859974 -214.572088)
		(stroke
			(width 0.05)
			(type default)
		)
		(layer "Edge.Cuts")
	)
	(gr_arc
		(start 30.78988 -99.572064)
		(mid 30.06905 -97.820761)
		(end 29.03093 -96.23679)
		(stroke
			(width 0.05)
			(type default)
		)
		(layer "Edge.Cuts")
	)
	(gr_arc
		(start 30.78988 -99.572064)
		(mid 33.325017 -101.450062)
		(end 35.859974 -99.572064)
		(stroke
			(width 0.05)
			(type default)
		)
		(layer "Edge.Cuts")
	)
	(gr_arc
		(start 31.224982 -5.199888)
		(mid 32.325056 -6.299962)
		(end 33.424876 -5.199888)
		(stroke
			(width 0.05)
			(type default)
		)
		(layer "Edge.Cuts")
	)
	(gr_arc
		(start 33.424876 -5.199888)
		(mid 32.325056 -4.100068)
		(end 31.224982 -5.199888)
		(stroke
			(width 0.05)
			(type default)
		)
		(layer "Edge.Cuts")
	)
	(gr_arc
		(start 37.618924 -326.236838)
		(mid 33.325133 -317.300017)
		(end 29.03093 -326.236838)
		(stroke
			(width 0.05)
			(type default)
		)
		(layer "Edge.Cuts")
	)
	(gr_arc
		(start 37.618924 -326.236838)
		(mid 36.580849 -327.820832)
		(end 35.859974 -329.572112)
		(stroke
			(width 0.05)
			(type default)
		)
		(layer "Edge.Cuts")
	)
	(gr_arc
		(start 37.618924 -211.236814)
		(mid 33.325133 -202.299993)
		(end 29.03093 -211.236814)
		(stroke
			(width 0.05)
			(type default)
		)
		(layer "Edge.Cuts")
	)
	(gr_arc
		(start 37.618924 -211.236814)
		(mid 36.580845 -212.820806)
		(end 35.859974 -214.572088)
		(stroke
			(width 0.05)
			(type default)
		)
		(layer "Edge.Cuts")
	)
	(gr_arc
		(start 37.618924 -96.23679)
		(mid 33.325133 -87.299969)
		(end 29.03093 -96.23679)
		(stroke
			(width 0.05)
			(type default)
		)
		(layer "Edge.Cuts")
	)
	(gr_arc
		(start 37.618924 -96.23679)
		(mid 36.580842 -97.820781)
		(end 35.859974 -99.572064)
		(stroke
			(width 0.05)
			(type default)
		)
		(layer "Edge.Cuts")
	)
	(gr_arc
		(start 40.649906 -164.200078)
		(mid 42.749978 -166.30015)
		(end 44.85005 -164.200078)
		(stroke
			(width 0.05)
			(type default)
		)
		(layer "Edge.Cuts")
	)
	(gr_arc
		(start 42.22496 -269.999968)
		(mid 44.000166 -271.775174)
		(end 45.775118 -269.999968)
		(stroke
			(width 0.05)
			(type default)
		)
		(layer "Edge.Cuts")
	)
	(gr_arc
		(start 42.600118 -282.999942)
		(mid 44.000166 -284.39999)
		(end 45.39996 -282.999942)
		(stroke
			(width 0.05)
			(type default)
		)
		(layer "Edge.Cuts")
	)
	(gr_arc
		(start 44.85005 -164.200078)
		(mid 42.749978 -162.100006)
		(end 40.649906 -164.200078)
		(stroke
			(width 0.05)
			(type default)
		)
		(layer "Edge.Cuts")
	)
	(gr_arc
		(start 45.39996 -282.999942)
		(mid 44.000166 -281.600148)
		(end 42.600118 -282.999942)
		(stroke
			(width 0.05)
			(type default)
		)
		(layer "Edge.Cuts")
	)
	(gr_arc
		(start 45.775118 -269.999968)
		(mid 44.000166 -268.225016)
		(end 42.22496 -269.999968)
		(stroke
			(width 0.05)
			(type default)
		)
		(layer "Edge.Cuts")
	)
	(gr_arc
		(start 93.790008 -329.572112)
		(mid 93.069172 -327.820812)
		(end 92.031058 -326.236838)
		(stroke
			(width 0.05)
			(type default)
		)
		(layer "Edge.Cuts")
	)
	(gr_arc
		(start 93.790008 -329.572112)
		(mid 96.325145 -331.45011)
		(end 98.860102 -329.572112)
		(stroke
			(width 0.05)
			(type default)
		)
		(layer "Edge.Cuts")
	)
	(gr_arc
		(start 93.790008 -214.572088)
		(mid 93.069183 -212.820781)
		(end 92.031058 -211.236814)
		(stroke
			(width 0.05)
			(type default)
		)
		(layer "Edge.Cuts")
	)
	(gr_arc
		(start 93.790008 -214.572088)
		(mid 96.325145 -216.450086)
		(end 98.860102 -214.572088)
		(stroke
			(width 0.05)
			(type default)
		)
		(layer "Edge.Cuts")
	)
	(gr_arc
		(start 93.790008 -99.572064)
		(mid 93.06918 -97.820759)
		(end 92.031058 -96.23679)
		(stroke
			(width 0.05)
			(type default)
		)
		(layer "Edge.Cuts")
	)
	(gr_arc
		(start 93.790008 -99.572064)
		(mid 96.325145 -101.450062)
		(end 98.860102 -99.572064)
		(stroke
			(width 0.05)
			(type default)
		)
		(layer "Edge.Cuts")
	)
	(gr_arc
		(start 100.619052 -326.236838)
		(mid 96.325261 -317.300017)
		(end 92.031058 -326.236838)
		(stroke
			(width 0.05)
			(type default)
		)
		(layer "Edge.Cuts")
	)
	(gr_arc
		(start 100.619052 -326.236838)
		(mid 99.580974 -327.820831)
		(end 98.860102 -329.572112)
		(stroke
			(width 0.05)
			(type default)
		)
		(layer "Edge.Cuts")
	)
	(gr_arc
		(start 100.619052 -211.236814)
		(mid 96.325261 -202.299993)
		(end 92.031058 -211.236814)
		(stroke
			(width 0.05)
			(type default)
		)
		(layer "Edge.Cuts")
	)
	(gr_arc
		(start 100.619052 -211.236814)
		(mid 99.580971 -212.820805)
		(end 98.860102 -214.572088)
		(stroke
			(width 0.05)
			(type default)
		)
		(layer "Edge.Cuts")
	)
	(gr_arc
		(start 100.619052 -96.23679)
		(mid 96.325261 -87.299969)
		(end 92.031058 -96.23679)
		(stroke
			(width 0.05)
			(type default)
		)
		(layer "Edge.Cuts")
	)
	(gr_arc
		(start 100.619052 -96.23679)
		(mid 99.580967 -97.82078)
		(end 98.860102 -99.572064)
		(stroke
			(width 0.05)
			(type default)
		)
		(layer "Edge.Cuts")
	)
	(gr_arc
		(start 102.00005 -13.999972)
		(mid 102.292943 -14.707077)
		(end 103.000048 -14.99997)
		(stroke
			(width 0.05)
			(type default)
		)
		(layer "Edge.Cuts")
	)
	(gr_arc
		(start 102.00005 -0.999998)
		(mid 101.707154 -0.292911)
		(end 101.000052 0)
		(stroke
			(width 0.05)
			(type default)
		)
		(layer "Edge.Cuts")
	)
	(gr_line
		(start 102.00005 -0.999998)
		(end 102.00005 -13.999972)
		(stroke
			(width 0.05)
			(type default)
		)
		(layer "Edge.Cuts")
	)
	(gr_line
		(start 103.000048 -14.99997)
		(end 148.999956 -14.99997)
		(stroke
			(width 0.05)
			(type default)
		)
		(layer "Edge.Cuts")
	)
	(gr_arc
		(start 105.32491 -289.999928)
		(mid 107.100116 -291.775134)
		(end 108.875068 -289.999928)
		(stroke
			(width 0.05)
			(type default)
		)
		(layer "Edge.Cuts")
	)
	(gr_arc
		(start 108.875068 -289.999928)
		(mid 107.100116 -288.224976)
		(end 105.32491 -289.999928)
		(stroke
			(width 0.05)
			(type default)
		)
		(layer "Edge.Cuts")
	)
	(gr_arc
		(start 122.724926 -210.799934)
		(mid 127.824992 -215.9)
		(end 132.925058 -210.799934)
		(stroke
			(width 0.05)
			(type default)
		)
		(layer "Edge.Cuts")
	)
	(gr_arc
		(start 124.875036 -28.079954)
		(mid 126.150116 -29.355034)
		(end 127.424942 -28.079954)
		(stroke
			(width 0.05)
			(type default)
		)
		(layer "Edge.Cuts")
	)
	(gr_arc
		(start 124.944886 -20.550124)
		(mid 126.150116 -21.755354)
		(end 127.355092 -20.550124)
		(stroke
			(width 0.05)
			(type default)
		)
		(layer "Edge.Cuts")
	)
	(gr_arc
		(start 127.355092 -20.550124)
		(mid 126.150116 -19.345148)
		(end 124.944886 -20.550124)
		(stroke
			(width 0.05)
			(type default)
		)
		(layer "Edge.Cuts")
	)
	(gr_arc
		(start 127.424942 -28.079954)
		(mid 126.150116 -26.805128)
		(end 124.875036 -28.079954)
		(stroke
			(width 0.05)
			(type default)
		)
		(layer "Edge.Cuts")
	)
	(gr_arc
		(start 132.925058 -210.799934)
		(mid 127.824992 -205.699868)
		(end 122.724926 -210.799934)
		(stroke
			(width 0.05)
			(type default)
		)
		(layer "Edge.Cuts")
	)
	(gr_arc
		(start 148.999956 -14.99997)
		(mid 149.707061 -14.707077)
		(end 149.999954 -13.999972)
		(stroke
			(width 0.05)
			(type default)
		)
		(layer "Edge.Cuts")
	)
	(gr_line
		(start 149.999954 -13.999972)
		(end 149.999954 -0.999998)
		(stroke
			(width 0.05)
			(type default)
		)
		(layer "Edge.Cuts")
	)
	(gr_arc
		(start 150.999952 0)
		(mid 150.292877 -0.292909)
		(end 149.999954 -0.999998)
		(stroke
			(width 0.05)
			(type default)
		)
		(layer "Edge.Cuts")
	)
	(gr_line
		(start 150.999952 0)
		(end 199.00011 0)
		(stroke
			(width 0.05)
			(type default)
		)
		(layer "Edge.Cuts")
	)
	(gr_arc
		(start 156.789882 -329.572112)
		(mid 156.069045 -327.820813)
		(end 155.030932 -326.236838)
		(stroke
			(width 0.05)
			(type default)
		)
		(layer "Edge.Cuts")
	)
	(gr_arc
		(start 156.789882 -329.572112)
		(mid 159.325019 -331.45011)
		(end 161.859976 -329.572112)
		(stroke
			(width 0.05)
			(type default)
		)
		(layer "Edge.Cuts")
	)
	(gr_arc
		(start 156.789882 -214.572088)
		(mid 156.069056 -212.820782)
		(end 155.030932 -211.236814)
		(stroke
			(width 0.05)
			(type default)
		)
		(layer "Edge.Cuts")
	)
	(gr_arc
		(start 156.789882 -214.572088)
		(mid 159.325019 -216.450086)
		(end 161.859976 -214.572088)
		(stroke
			(width 0.05)
			(type default)
		)
		(layer "Edge.Cuts")
	)
	(gr_arc
		(start 156.789882 -99.572064)
		(mid 156.069052 -97.82076)
		(end 155.030932 -96.23679)
		(stroke
			(width 0.05)
			(type default)
		)
		(layer "Edge.Cuts")
	)
	(gr_arc
		(start 156.789882 -99.572064)
		(mid 159.325019 -101.450062)
		(end 161.859976 -99.572064)
		(stroke
			(width 0.05)
			(type default)
		)
		(layer "Edge.Cuts")
	)
	(gr_arc
		(start 159.22498 -13.200126)
		(mid 160.325054 -14.3002)
		(end 161.424874 -13.200126)
		(stroke
			(width 0.05)
			(type default)
		)
		(layer "Edge.Cuts")
	)
	(gr_arc
		(start 161.424874 -13.200126)
		(mid 160.325054 -12.100306)
		(end 159.22498 -13.200126)
		(stroke
			(width 0.05)
			(type default)
		)
		(layer "Edge.Cuts")
	)
	(gr_arc
		(start 163.474908 -9.19988)
		(mid 166.325042 -12.050014)
		(end 169.174922 -9.19988)
		(stroke
			(width 0.05)
			(type default)
		)
		(layer "Edge.Cuts")
	)
	(gr_arc
		(start 163.618926 -326.236838)
		(mid 159.325135 -317.300017)
		(end 155.030932 -326.236838)
		(stroke
			(width 0.05)
			(type default)
		)
		(layer "Edge.Cuts")
	)
	(gr_arc
		(start 163.618926 -326.236838)
		(mid 162.580851 -327.820832)
		(end 161.859976 -329.572112)
		(stroke
			(width 0.05)
			(type default)
		)
		(layer "Edge.Cuts")
	)
	(gr_arc
		(start 163.618926 -211.236814)
		(mid 159.325135 -202.299993)
		(end 155.030932 -211.236814)
		(stroke
			(width 0.05)
			(type default)
		)
		(layer "Edge.Cuts")
	)
	(gr_arc
		(start 163.618926 -211.236814)
		(mid 162.580847 -212.820806)
		(end 161.859976 -214.572088)
		(stroke
			(width 0.05)
			(type default)
		)
		(layer "Edge.Cuts")
	)
	(gr_arc
		(start 163.618926 -96.23679)
		(mid 159.325135 -87.299969)
		(end 155.030932 -96.23679)
		(stroke
			(width 0.05)
			(type default)
		)
		(layer "Edge.Cuts")
	)
	(gr_arc
		(start 163.618926 -96.23679)
		(mid 162.580843 -97.820781)
		(end 161.859976 -99.572064)
		(stroke
			(width 0.05)
			(type default)
		)
		(layer "Edge.Cuts")
	)
	(gr_arc
		(start 165.600126 -164.200078)
		(mid 167.700198 -166.30015)
		(end 169.800016 -164.200078)
		(stroke
			(width 0.05)
			(type default)
		)
		(layer "Edge.Cuts")
	)
	(gr_arc
		(start 168.425114 -269.999968)
		(mid 170.200066 -271.77492)
		(end 171.975018 -269.999968)
		(stroke
			(width 0.05)
			(type default)
		)
		(layer "Edge.Cuts")
	)
	(gr_arc
		(start 168.800018 -282.999942)
		(mid 170.200066 -284.39999)
		(end 171.600114 -282.999942)
		(stroke
			(width 0.05)
			(type default)
		)
		(layer "Edge.Cuts")
	)
	(gr_arc
		(start 169.174922 -9.19988)
		(mid 166.325042 -6.35)
		(end 163.474908 -9.19988)
		(stroke
			(width 0.05)
			(type default)
		)
		(layer "Edge.Cuts")
	)
	(gr_arc
		(start 169.800016 -164.200078)
		(mid 167.700198 -162.10026)
		(end 165.600126 -164.200078)
		(stroke
			(width 0.05)
			(type default)
		)
		(layer "Edge.Cuts")
	)
	(gr_arc
		(start 171.224956 -5.199888)
		(mid 172.32503 -6.299962)
		(end 173.425104 -5.199888)
		(stroke
			(width 0.05)
			(type default)
		)
		(layer "Edge.Cuts")
	)
	(gr_arc
		(start 171.600114 -282.999942)
		(mid 170.200066 -281.599894)
		(end 168.800018 -282.999942)
		(stroke
			(width 0.05)
			(type default)
		)
		(layer "Edge.Cuts")
	)
	(gr_arc
		(start 171.975018 -269.999968)
		(mid 170.200066 -268.225016)
		(end 168.425114 -269.999968)
		(stroke
			(width 0.05)
			(type default)
		)
		(layer "Edge.Cuts")
	)
	(gr_arc
		(start 173.425104 -5.199888)
		(mid 172.32503 -4.099814)
		(end 171.224956 -5.199888)
		(stroke
			(width 0.05)
			(type default)
		)
		(layer "Edge.Cuts")
	)
	(gr_arc
		(start 180.300122 -208.499964)
		(mid 182.400194 -210.600036)
		(end 184.500012 -208.499964)
		(stroke
			(width 0.05)
			(type default)
		)
		(layer "Edge.Cuts")
	)
	(gr_arc
		(start 184.500012 -208.499964)
		(mid 182.400194 -206.400146)
		(end 180.300122 -208.499964)
		(stroke
			(width 0.05)
			(type default)
		)
		(layer "Edge.Cuts")
	)
	(gr_line
		(start 189.6999 -349.199962)
		(end 0.999998 -349.199962)
		(stroke
			(width 0.05)
			(type default)
		)
		(layer "Edge.Cuts")
	)
	(gr_line
		(start 190.699898 -372.000018)
		(end 190.699898 -350.19996)
		(stroke
			(width 0.05)
			(type default)
		)
		(layer "Edge.Cuts")
	)
	(gr_arc
		(start 190.699898 -372.000018)
		(mid 190.992797 -372.707113)
		(end 191.699896 -373.000016)
		(stroke
			(width 0.05)
			(type default)
		)
		(layer "Edge.Cuts")
	)
	(gr_arc
		(start 190.699898 -350.19996)
		(mid 190.407005 -349.492855)
		(end 189.6999 -349.199962)
		(stroke
			(width 0.05)
			(type default)
		)
		(layer "Edge.Cuts")
	)
	(gr_line
		(start 199.00011 -373.000016)
		(end 191.699896 -373.000016)
		(stroke
			(width 0.05)
			(type default)
		)
		(layer "Edge.Cuts")
	)
	(gr_arc
		(start 199.00011 0)
		(mid 199.707215 0.292893)
		(end 200.000108 0.999998)
		(stroke
			(width 0.05)
			(type default)
		)
		(layer "Edge.Cuts")
	)
	(gr_arc
		(start 199.764904 -190.572136)
		(mid 199.044071 -188.820834)
		(end 198.005954 -187.236862)
		(stroke
			(width 0.05)
			(type default)
		)
		(layer "Edge.Cuts")
	)
	(gr_arc
		(start 199.764904 -190.572136)
		(mid 202.300041 -192.450134)
		(end 204.834998 -190.572136)
		(stroke
			(width 0.05)
			(type default)
		)
		(layer "Edge.Cuts")
	)
	(gr_arc
		(start 199.764904 -70.572122)
		(mid 199.044069 -68.820822)
		(end 198.005954 -67.236848)
		(stroke
			(width 0.05)
			(type default)
		)
		(layer "Edge.Cuts")
	)
	(gr_arc
		(start 199.764904 -70.572122)
		(mid 202.300041 -72.45012)
		(end 204.834998 -70.572122)
		(stroke
			(width 0.05)
			(type default)
		)
		(layer "Edge.Cuts")
	)
	(gr_line
		(start 200.000108 -420.200074)
		(end 200.000108 -374.000014)
		(stroke
			(width 0.05)
			(type default)
		)
		(layer "Edge.Cuts")
	)
	(gr_arc
		(start 200.000108 -420.200074)
		(mid 200.292992 -420.907194)
		(end 201.000106 -421.200072)
		(stroke
			(width 0.05)
			(type default)
		)
		(layer "Edge.Cuts")
	)
	(gr_arc
		(start 200.000108 -374.000014)
		(mid 199.707215 -373.292909)
		(end 199.00011 -373.000016)
		(stroke
			(width 0.05)
			(type default)
		)
		(layer "Edge.Cuts")
	)
	(gr_arc
		(start 201.000106 1.999996)
		(mid 200.292997 1.707105)
		(end 200.000108 0.999998)
		(stroke
			(width 0.05)
			(type default)
		)
		(layer "Edge.Cuts")
	)
	(gr_line
		(start 201.000106 1.999996)
		(end 219.00007 1.999996)
		(stroke
			(width 0.05)
			(type default)
		)
		(layer "Edge.Cuts")
	)
	(gr_arc
		(start 206.593948 -187.236862)
		(mid 202.300157 -178.300041)
		(end 198.005954 -187.236862)
		(stroke
			(width 0.05)
			(type default)
		)
		(layer "Edge.Cuts")
	)
	(gr_arc
		(start 206.593948 -187.236862)
		(mid 205.555859 -188.82085)
		(end 204.834998 -190.572136)
		(stroke
			(width 0.05)
			(type default)
		)
		(layer "Edge.Cuts")
	)
	(gr_arc
		(start 206.593948 -67.236848)
		(mid 202.300157 -58.300027)
		(end 198.005954 -67.236848)
		(stroke
			(width 0.05)
			(type default)
		)
		(layer "Edge.Cuts")
	)
	(gr_arc
		(start 206.593948 -67.236848)
		(mid 205.555872 -68.820841)
		(end 204.834998 -70.572122)
		(stroke
			(width 0.05)
			(type default)
		)
		(layer "Edge.Cuts")
	)
	(gr_arc
		(start 219.00007 1.999996)
		(mid 219.707175 2.292889)
		(end 220.000068 2.999994)
		(stroke
			(width 0.05)
			(type default)
		)
		(layer "Edge.Cuts")
	)
	(gr_line
		(start 220.000068 2.999994)
		(end 220.000068 37.800026)
		(stroke
			(width 0.05)
			(type default)
		)
		(layer "Edge.Cuts")
	)
	(gr_arc
		(start 221.000066 38.800024)
		(mid 220.292973 38.507121)
		(end 220.000068 37.800026)
		(stroke
			(width 0.05)
			(type default)
		)
		(layer "Edge.Cuts")
	)
	(gr_line
		(start 221.000066 38.800024)
		(end 298.99991 38.800024)
		(stroke
			(width 0.05)
			(type default)
		)
		(layer "Edge.Cuts")
	)
	(gr_arc
		(start 227.750116 -143.500094)
		(mid 229.850188 -145.600166)
		(end 231.950006 -143.500094)
		(stroke
			(width 0.05)
			(type default)
		)
		(layer "Edge.Cuts")
	)
	(gr_arc
		(start 227.750116 5.500116)
		(mid 229.850188 3.400044)
		(end 231.950006 5.500116)
		(stroke
			(width 0.05)
			(type default)
		)
		(layer "Edge.Cuts")
	)
	(gr_line
		(start 227.750116 7.500112)
		(end 227.750116 5.500116)
		(stroke
			(width 0.05)
			(type default)
		)
		(layer "Edge.Cuts")
	)
	(gr_arc
		(start 231.950006 -143.500094)
		(mid 229.850188 -141.400276)
		(end 227.750116 -143.500094)
		(stroke
			(width 0.05)
			(type default)
		)
		(layer "Edge.Cuts")
	)
	(gr_line
		(start 231.950006 5.500116)
		(end 231.950006 7.500112)
		(stroke
			(width 0.05)
			(type default)
		)
		(layer "Edge.Cuts")
	)
	(gr_arc
		(start 231.950006 7.500112)
		(mid 229.850188 9.59993)
		(end 227.750116 7.500112)
		(stroke
			(width 0.05)
			(type default)
		)
		(layer "Edge.Cuts")
	)
	(gr_arc
		(start 237.540546 10.813034)
		(mid 236.610034 12.806925)
		(end 235.466128 14.686534)
		(stroke
			(width 0.05)
			(type default)
		)
		(layer "Edge.Cuts")
	)
	(gr_arc
		(start 237.540546 10.813034)
		(mid 239.999981 9.149926)
		(end 242.459256 10.813034)
		(stroke
			(width 0.05)
			(type default)
		)
		(layer "Edge.Cuts")
	)
	(gr_arc
		(start 241.664998 -366.972088)
		(mid 240.944173 -365.220782)
		(end 239.906048 -363.636814)
		(stroke
			(width 0.05)
			(type default)
		)
		(layer "Edge.Cuts")
	)
	(gr_arc
		(start 241.664998 -366.972088)
		(mid 244.200135 -368.850086)
		(end 246.735092 -366.972088)
		(stroke
			(width 0.05)
			(type default)
		)
		(layer "Edge.Cuts")
	)
	(gr_arc
		(start 241.664998 -279.972008)
		(mid 240.944161 -278.220709)
		(end 239.906048 -276.636734)
		(stroke
			(width 0.05)
			(type default)
		)
		(layer "Edge.Cuts")
	)
	(gr_arc
		(start 241.664998 -279.972008)
		(mid 244.200135 -281.850186)
		(end 246.735092 -279.972008)
		(stroke
			(width 0.05)
			(type default)
		)
		(layer "Edge.Cuts")
	)
	(gr_arc
		(start 244.533928 14.686534)
		(mid 240.000028 23.300096)
		(end 235.466128 14.686534)
		(stroke
			(width 0.05)
			(type default)
		)
		(layer "Edge.Cuts")
	)
	(gr_arc
		(start 244.533928 14.686534)
		(mid 243.389893 12.806933)
		(end 242.459256 10.813034)
		(stroke
			(width 0.05)
			(type default)
		)
		(layer "Edge.Cuts")
	)
	(gr_arc
		(start 246.350028 -143.500094)
		(mid 247.850152 -145.000218)
		(end 249.350022 -143.500094)
		(stroke
			(width 0.05)
			(type default)
		)
		(layer "Edge.Cuts")
	)
	(gr_arc
		(start 246.350028 5.500116)
		(mid 247.850152 3.999992)
		(end 249.350022 5.500116)
		(stroke
			(width 0.05)
			(type default)
		)
		(layer "Edge.Cuts")
	)
	(gr_line
		(start 246.350028 7.500112)
		(end 246.350028 5.500116)
		(stroke
			(width 0.05)
			(type default)
		)
		(layer "Edge.Cuts")
	)
	(gr_arc
		(start 248.494042 -363.636814)
		(mid 244.200251 -354.699993)
		(end 239.906048 -363.636814)
		(stroke
			(width 0.05)
			(type default)
		)
		(layer "Edge.Cuts")
	)
	(gr_arc
		(start 248.494042 -363.636814)
		(mid 247.455962 -365.220806)
		(end 246.735092 -366.972088)
		(stroke
			(width 0.05)
			(type default)
		)
		(layer "Edge.Cuts")
	)
	(gr_arc
		(start 248.494042 -276.636734)
		(mid 244.200251 -267.699913)
		(end 239.906048 -276.636734)
		(stroke
			(width 0.05)
			(type default)
		)
		(layer "Edge.Cuts")
	)
	(gr_arc
		(start 248.494042 -276.636734)
		(mid 247.455964 -278.220727)
		(end 246.735092 -279.972008)
		(stroke
			(width 0.05)
			(type default)
		)
		(layer "Edge.Cuts")
	)
	(gr_arc
		(start 249.350022 -143.500094)
		(mid 247.850152 -142.000224)
		(end 246.350028 -143.500094)
		(stroke
			(width 0.05)
			(type default)
		)
		(layer "Edge.Cuts")
	)
	(gr_line
		(start 249.350022 5.500116)
		(end 249.350022 7.500112)
		(stroke
			(width 0.05)
			(type default)
		)
		(layer "Edge.Cuts")
	)
	(gr_arc
		(start 249.350022 7.500112)
		(mid 247.850152 8.999982)
		(end 246.350028 7.500112)
		(stroke
			(width 0.05)
			(type default)
		)
		(layer "Edge.Cuts")
	)
	(gr_arc
		(start 278.800052 -414.219898)
		(mid 280.550112 -415.969958)
		(end 282.299918 -414.219898)
		(stroke
			(width 0.05)
			(type default)
		)
		(layer "Edge.Cuts")
	)
	(gr_arc
		(start 282.299918 -414.219898)
		(mid 280.550112 -412.470092)
		(end 278.800052 -414.219898)
		(stroke
			(width 0.05)
			(type default)
		)
		(layer "Edge.Cuts")
	)
	(gr_arc
		(start 295.699942 -373.000016)
		(mid 295.992835 -373.707121)
		(end 296.69994 -374.000014)
		(stroke
			(width 0.05)
			(type default)
		)
		(layer "Edge.Cuts")
	)
	(gr_line
		(start 295.699942 -350.19996)
		(end 295.699942 -373.000016)
		(stroke
			(width 0.05)
			(type default)
		)
		(layer "Edge.Cuts")
	)
	(gr_line
		(start 296.69994 -374.000014)
		(end 308.99989 -374.000014)
		(stroke
			(width 0.05)
			(type default)
		)
		(layer "Edge.Cuts")
	)
	(gr_arc
		(start 296.69994 -349.199962)
		(mid 295.992835 -349.492855)
		(end 295.699942 -350.19996)
		(stroke
			(width 0.05)
			(type default)
		)
		(layer "Edge.Cuts")
	)
	(gr_arc
		(start 297.664886 -399.972022)
		(mid 296.94405 -398.220722)
		(end 295.905936 -396.636748)
		(stroke
			(width 0.05)
			(type default)
		)
		(layer "Edge.Cuts")
	)
	(gr_arc
		(start 297.664886 -399.972022)
		(mid 300.200023 -401.8502)
		(end 302.73498 -399.972022)
		(stroke
			(width 0.05)
			(type default)
		)
		(layer "Edge.Cuts")
	)
	(gr_arc
		(start 297.664886 -249.972068)
		(mid 296.944057 -248.220764)
		(end 295.905936 -246.636794)
		(stroke
			(width 0.05)
			(type default)
		)
		(layer "Edge.Cuts")
	)
	(gr_arc
		(start 297.664886 -249.972068)
		(mid 300.200023 -251.850066)
		(end 302.73498 -249.972068)
		(stroke
			(width 0.05)
			(type default)
		)
		(layer "Edge.Cuts")
	)
	(gr_arc
		(start 297.664886 -144.972024)
		(mid 296.944051 -143.220724)
		(end 295.905936 -141.63675)
		(stroke
			(width 0.05)
			(type default)
		)
		(layer "Edge.Cuts")
	)
	(gr_arc
		(start 297.664886 -144.972024)
		(mid 300.200023 -146.850202)
		(end 302.73498 -144.972024)
		(stroke
			(width 0.05)
			(type default)
		)
		(layer "Edge.Cuts")
	)
	(gr_arc
		(start 299.999908 0.999998)
		(mid 300.292801 0.292893)
		(end 300.999906 0)
		(stroke
			(width 0.05)
			(type default)
		)
		(layer "Edge.Cuts")
	)
	(gr_arc
		(start 299.999908 37.800026)
		(mid 299.707007 38.507118)
		(end 298.99991 38.800024)
		(stroke
			(width 0.05)
			(type default)
		)
		(layer "Edge.Cuts")
	)
	(gr_line
		(start 299.999908 37.800026)
		(end 299.999908 0.999998)
		(stroke
			(width 0.05)
			(type default)
		)
		(layer "Edge.Cuts")
	)
	(gr_line
		(start 300.999906 0)
		(end 347.000068 0)
		(stroke
			(width 0.05)
			(type default)
		)
		(layer "Edge.Cuts")
	)
	(gr_arc
		(start 304.49393 -396.636748)
		(mid 300.200139 -387.699927)
		(end 295.905936 -396.636748)
		(stroke
			(width 0.05)
			(type default)
		)
		(layer "Edge.Cuts")
	)
	(gr_arc
		(start 304.49393 -396.636748)
		(mid 303.455856 -398.220742)
		(end 302.73498 -399.972022)
		(stroke
			(width 0.05)
			(type default)
		)
		(layer "Edge.Cuts")
	)
	(gr_arc
		(start 304.49393 -246.636794)
		(mid 300.200139 -237.699973)
		(end 295.905936 -246.636794)
		(stroke
			(width 0.05)
			(type default)
		)
		(layer "Edge.Cuts")
	)
	(gr_arc
		(start 304.49393 -246.636794)
		(mid 303.455848 -248.220785)
		(end 302.73498 -249.972068)
		(stroke
			(width 0.05)
			(type default)
		)
		(layer "Edge.Cuts")
	)
	(gr_arc
		(start 304.49393 -141.63675)
		(mid 300.200139 -132.699929)
		(end 295.905936 -141.63675)
		(stroke
			(width 0.05)
			(type default)
		)
		(layer "Edge.Cuts")
	)
	(gr_arc
		(start 304.49393 -141.63675)
		(mid 303.455856 -143.220744)
		(end 302.73498 -144.972024)
		(stroke
			(width 0.05)
			(type default)
		)
		(layer "Edge.Cuts")
	)
	(gr_line
		(start 308.99989 -421.200072)
		(end 201.000106 -421.200072)
		(stroke
			(width 0.05)
			(type default)
		)
		(layer "Edge.Cuts")
	)
	(gr_arc
		(start 308.99989 -421.200072)
		(mid 309.706993 -420.907181)
		(end 309.999888 -420.200074)
		(stroke
			(width 0.05)
			(type default)
		)
		(layer "Edge.Cuts")
	)
	(gr_arc
		(start 309.999888 -375.000012)
		(mid 309.706999 -374.292902)
		(end 308.99989 -374.000014)
		(stroke
			(width 0.05)
			(type default)
		)
		(layer "Edge.Cuts")
	)
	(gr_line
		(start 309.999888 -375.000012)
		(end 309.999888 -420.200074)
		(stroke
			(width 0.05)
			(type default)
		)
		(layer "Edge.Cuts")
	)
	(gr_arc
		(start 316.574932 -13.200126)
		(mid 317.675006 -14.3002)
		(end 318.77508 -13.200126)
		(stroke
			(width 0.05)
			(type default)
		)
		(layer "Edge.Cuts")
	)
	(gr_arc
		(start 318.77508 -13.200126)
		(mid 317.675006 -12.100052)
		(end 316.574932 -13.200126)
		(stroke
			(width 0.05)
			(type default)
		)
		(layer "Edge.Cuts")
	)
	(gr_arc
		(start 320.825114 -9.19988)
		(mid 323.674994 -12.04976)
		(end 326.524874 -9.19988)
		(stroke
			(width 0.05)
			(type default)
		)
		(layer "Edge.Cuts")
	)
	(gr_arc
		(start 326.524874 -9.19988)
		(mid 323.674994 -6.35)
		(end 320.825114 -9.19988)
		(stroke
			(width 0.05)
			(type default)
		)
		(layer "Edge.Cuts")
	)
	(gr_arc
		(start 328.14006 -329.572112)
		(mid 327.419221 -327.820814)
		(end 326.38111 -326.236838)
		(stroke
			(width 0.05)
			(type default)
		)
		(layer "Edge.Cuts")
	)
	(gr_arc
		(start 328.14006 -329.572112)
		(mid 330.675197 -331.45011)
		(end 333.210154 -329.572112)
		(stroke
			(width 0.05)
			(type default)
		)
		(layer "Edge.Cuts")
	)
	(gr_arc
		(start 328.14006 -214.572088)
		(mid 327.419232 -212.820783)
		(end 326.38111 -211.236814)
		(stroke
			(width 0.05)
			(type default)
		)
		(layer "Edge.Cuts")
	)
	(gr_arc
		(start 328.14006 -214.572088)
		(mid 330.675197 -216.450086)
		(end 333.210154 -214.572088)
		(stroke
			(width 0.05)
			(type default)
		)
		(layer "Edge.Cuts")
	)
	(gr_arc
		(start 328.14006 -99.572064)
		(mid 327.419229 -97.820761)
		(end 326.38111 -96.23679)
		(stroke
			(width 0.05)
			(type default)
		)
		(layer "Edge.Cuts")
	)
	(gr_arc
		(start 328.14006 -99.572064)
		(mid 330.675197 -101.450062)
		(end 333.210154 -99.572064)
		(stroke
			(width 0.05)
			(type default)
		)
		(layer "Edge.Cuts")
	)
	(gr_arc
		(start 328.574908 -5.199888)
		(mid 329.674982 -6.299962)
		(end 330.775056 -5.199888)
		(stroke
			(width 0.05)
			(type default)
		)
		(layer "Edge.Cuts")
	)
	(gr_arc
		(start 330.775056 -5.199888)
		(mid 329.674982 -4.099814)
		(end 328.574908 -5.199888)
		(stroke
			(width 0.05)
			(type default)
		)
		(layer "Edge.Cuts")
	)
	(gr_arc
		(start 334.96885 -326.236838)
		(mid 330.67498 -317.300017)
		(end 326.38111 -326.236838)
		(stroke
			(width 0.05)
			(type default)
		)
		(layer "Edge.Cuts")
	)
	(gr_arc
		(start 334.96885 -326.236838)
		(mid 333.930888 -327.820838)
		(end 333.210154 -329.572112)
		(stroke
			(width 0.05)
			(type default)
		)
		(layer "Edge.Cuts")
	)
	(gr_arc
		(start 334.96885 -211.236814)
		(mid 330.67498 -202.299993)
		(end 326.38111 -211.236814)
		(stroke
			(width 0.05)
			(type default)
		)
		(layer "Edge.Cuts")
	)
	(gr_arc
		(start 334.96885 -211.236814)
		(mid 333.930899 -212.820819)
		(end 333.210154 -214.572088)
		(stroke
			(width 0.05)
			(type default)
		)
		(layer "Edge.Cuts")
	)
	(gr_arc
		(start 334.96885 -96.23679)
		(mid 330.67498 -87.299969)
		(end 326.38111 -96.23679)
		(stroke
			(width 0.05)
			(type default)
		)
		(layer "Edge.Cuts")
	)
	(gr_arc
		(start 334.96885 -96.23679)
		(mid 333.930895 -97.820793)
		(end 333.210154 -99.572064)
		(stroke
			(width 0.05)
			(type default)
		)
		(layer "Edge.Cuts")
	)
	(gr_arc
		(start 339.525102 -269.999968)
		(mid 341.300054 -271.77492)
		(end 343.075006 -269.999968)
		(stroke
			(width 0.05)
			(type default)
		)
		(layer "Edge.Cuts")
	)
	(gr_arc
		(start 339.900006 -282.999942)
		(mid 341.300054 -284.39999)
		(end 342.700102 -282.999942)
		(stroke
			(width 0.05)
			(type default)
		)
		(layer "Edge.Cuts")
	)
	(gr_arc
		(start 342.700102 -282.999942)
		(mid 341.300054 -281.599894)
		(end 339.900006 -282.999942)
		(stroke
			(width 0.05)
			(type default)
		)
		(layer "Edge.Cuts")
	)
	(gr_arc
		(start 343.075006 -269.999968)
		(mid 341.300054 -268.225016)
		(end 339.525102 -269.999968)
		(stroke
			(width 0.05)
			(type default)
		)
		(layer "Edge.Cuts")
	)
	(gr_arc
		(start 344.899996 -164.200078)
		(mid 347.000068 -166.30015)
		(end 349.099886 -164.200078)
		(stroke
			(width 0.05)
			(type default)
		)
		(layer "Edge.Cuts")
	)
	(gr_arc
		(start 348.000066 -13.999972)
		(mid 348.292959 -14.707077)
		(end 349.000064 -14.99997)
		(stroke
			(width 0.05)
			(type default)
		)
		(layer "Edge.Cuts")
	)
	(gr_arc
		(start 348.000066 -0.999998)
		(mid 347.707171 -0.292905)
		(end 347.000068 0)
		(stroke
			(width 0.05)
			(type default)
		)
		(layer "Edge.Cuts")
	)
	(gr_line
		(start 348.000066 -0.999998)
		(end 348.000066 -13.999972)
		(stroke
			(width 0.05)
			(type default)
		)
		(layer "Edge.Cuts")
	)
	(gr_line
		(start 349.000064 -14.99997)
		(end 394.999972 -14.99997)
		(stroke
			(width 0.05)
			(type default)
		)
		(layer "Edge.Cuts")
	)
	(gr_arc
		(start 349.099886 -164.200078)
		(mid 347.000068 -162.10026)
		(end 344.899996 -164.200078)
		(stroke
			(width 0.05)
			(type default)
		)
		(layer "Edge.Cuts")
	)
	(gr_arc
		(start 369.499896 -220.199966)
		(mid 371.599968 -222.300038)
		(end 373.70004 -220.199966)
		(stroke
			(width 0.05)
			(type default)
		)
		(layer "Edge.Cuts")
	)
	(gr_arc
		(start 370.875052 -28.079954)
		(mid 372.150132 -29.355034)
		(end 373.424958 -28.079954)
		(stroke
			(width 0.05)
			(type default)
		)
		(layer "Edge.Cuts")
	)
	(gr_arc
		(start 370.944902 -20.550124)
		(mid 372.150132 -21.755354)
		(end 373.355108 -20.550124)
		(stroke
			(width 0.05)
			(type default)
		)
		(layer "Edge.Cuts")
	)
	(gr_arc
		(start 373.355108 -20.550124)
		(mid 372.150132 -19.345148)
		(end 370.944902 -20.550124)
		(stroke
			(width 0.05)
			(type default)
		)
		(layer "Edge.Cuts")
	)
	(gr_arc
		(start 373.424958 -28.079954)
		(mid 372.150132 -26.805128)
		(end 370.875052 -28.079954)
		(stroke
			(width 0.05)
			(type default)
		)
		(layer "Edge.Cuts")
	)
	(gr_arc
		(start 373.70004 -220.199966)
		(mid 371.599968 -218.099894)
		(end 369.499896 -220.199966)
		(stroke
			(width 0.05)
			(type default)
		)
		(layer "Edge.Cuts")
	)
	(gr_arc
		(start 391.139934 -329.572112)
		(mid 390.419094 -327.820815)
		(end 389.380984 -326.236838)
		(stroke
			(width 0.05)
			(type default)
		)
		(layer "Edge.Cuts")
	)
	(gr_arc
		(start 391.139934 -329.572112)
		(mid 393.675071 -331.45011)
		(end 396.210028 -329.572112)
		(stroke
			(width 0.05)
			(type default)
		)
		(layer "Edge.Cuts")
	)
	(gr_arc
		(start 391.139934 -214.572088)
		(mid 390.419105 -212.820784)
		(end 389.380984 -211.236814)
		(stroke
			(width 0.05)
			(type default)
		)
		(layer "Edge.Cuts")
	)
	(gr_arc
		(start 391.139934 -214.572088)
		(mid 393.675071 -216.450086)
		(end 396.210028 -214.572088)
		(stroke
			(width 0.05)
			(type default)
		)
		(layer "Edge.Cuts")
	)
	(gr_arc
		(start 391.139934 -99.572064)
		(mid 390.419101 -97.820762)
		(end 389.380984 -96.23679)
		(stroke
			(width 0.05)
			(type default)
		)
		(layer "Edge.Cuts")
	)
	(gr_arc
		(start 391.139934 -99.572064)
		(mid 393.675071 -101.450062)
		(end 396.210028 -99.572064)
		(stroke
			(width 0.05)
			(type default)
		)
		(layer "Edge.Cuts")
	)
	(gr_arc
		(start 394.999972 -14.99997)
		(mid 395.707077 -14.707077)
		(end 395.99997 -13.999972)
		(stroke
			(width 0.05)
			(type default)
		)
		(layer "Edge.Cuts")
	)
	(gr_line
		(start 395.99997 -13.999972)
		(end 395.99997 -0.999998)
		(stroke
			(width 0.05)
			(type default)
		)
		(layer "Edge.Cuts")
	)
	(gr_arc
		(start 396.999968 0)
		(mid 396.292883 -0.292904)
		(end 395.99997 -0.999998)
		(stroke
			(width 0.05)
			(type default)
		)
		(layer "Edge.Cuts")
	)
	(gr_line
		(start 396.999968 0)
		(end 490.450124 0)
		(stroke
			(width 0.05)
			(type default)
		)
		(layer "Edge.Cuts")
	)
	(gr_arc
		(start 397.968978 -326.236838)
		(mid 393.675187 -317.300017)
		(end 389.380984 -326.236838)
		(stroke
			(width 0.05)
			(type default)
		)
		(layer "Edge.Cuts")
	)
	(gr_arc
		(start 397.968978 -326.236838)
		(mid 396.930898 -327.82083)
		(end 396.210028 -329.572112)
		(stroke
			(width 0.05)
			(type default)
		)
		(layer "Edge.Cuts")
	)
	(gr_arc
		(start 397.968978 -211.236814)
		(mid 393.675187 -202.299993)
		(end 389.380984 -211.236814)
		(stroke
			(width 0.05)
			(type default)
		)
		(layer "Edge.Cuts")
	)
	(gr_arc
		(start 397.968978 -211.236814)
		(mid 396.930894 -212.820804)
		(end 396.210028 -214.572088)
		(stroke
			(width 0.05)
			(type default)
		)
		(layer "Edge.Cuts")
	)
	(gr_arc
		(start 397.968978 -96.23679)
		(mid 393.675187 -87.299969)
		(end 389.380984 -96.23679)
		(stroke
			(width 0.05)
			(type default)
		)
		(layer "Edge.Cuts")
	)
	(gr_arc
		(start 397.968978 -96.23679)
		(mid 396.930891 -97.820779)
		(end 396.210028 -99.572064)
		(stroke
			(width 0.05)
			(type default)
		)
		(layer "Edge.Cuts")
	)
	(gr_arc
		(start 402.625052 -289.999928)
		(mid 404.400004 -291.77488)
		(end 406.174956 -289.999928)
		(stroke
			(width 0.05)
			(type default)
		)
		(layer "Edge.Cuts")
	)
	(gr_arc
		(start 404.999952 -164.200078)
		(mid 407.100024 -166.30015)
		(end 409.200096 -164.200078)
		(stroke
			(width 0.05)
			(type default)
		)
		(layer "Edge.Cuts")
	)
	(gr_arc
		(start 406.174956 -289.999928)
		(mid 404.400004 -288.224976)
		(end 402.625052 -289.999928)
		(stroke
			(width 0.05)
			(type default)
		)
		(layer "Edge.Cuts")
	)
	(gr_arc
		(start 409.200096 -164.200078)
		(mid 407.100024 -162.100006)
		(end 404.999952 -164.200078)
		(stroke
			(width 0.05)
			(type default)
		)
		(layer "Edge.Cuts")
	)
	(gr_arc
		(start 420.075106 -210.799934)
		(mid 425.175172 -215.9)
		(end 430.274984 -210.799934)
		(stroke
			(width 0.05)
			(type default)
		)
		(layer "Edge.Cuts")
	)
	(gr_arc
		(start 430.274984 -210.799934)
		(mid 425.175172 -205.700122)
		(end 420.075106 -210.799934)
		(stroke
			(width 0.05)
			(type default)
		)
		(layer "Edge.Cuts")
	)
	(gr_arc
		(start 454.140062 -329.572112)
		(mid 453.419223 -327.820814)
		(end 452.381112 -326.236838)
		(stroke
			(width 0.05)
			(type default)
		)
		(layer "Edge.Cuts")
	)
	(gr_arc
		(start 454.140062 -329.572112)
		(mid 456.675199 -331.45011)
		(end 459.210156 -329.572112)
		(stroke
			(width 0.05)
			(type default)
		)
		(layer "Edge.Cuts")
	)
	(gr_arc
		(start 454.140062 -214.572088)
		(mid 453.419235 -212.820783)
		(end 452.381112 -211.236814)
		(stroke
			(width 0.05)
			(type default)
		)
		(layer "Edge.Cuts")
	)
	(gr_arc
		(start 454.140062 -214.572088)
		(mid 456.675199 -216.450086)
		(end 459.210156 -214.572088)
		(stroke
			(width 0.05)
			(type default)
		)
		(layer "Edge.Cuts")
	)
	(gr_arc
		(start 454.140062 -99.572064)
		(mid 453.419231 -97.820761)
		(end 452.381112 -96.23679)
		(stroke
			(width 0.05)
			(type default)
		)
		(layer "Edge.Cuts")
	)
	(gr_arc
		(start 454.140062 -99.572064)
		(mid 456.675199 -101.450062)
		(end 459.210156 -99.572064)
		(stroke
			(width 0.05)
			(type default)
		)
		(layer "Edge.Cuts")
	)
	(gr_arc
		(start 456.574906 -13.200126)
		(mid 457.67498 -14.3002)
		(end 458.775054 -13.200126)
		(stroke
			(width 0.05)
			(type default)
		)
		(layer "Edge.Cuts")
	)
	(gr_arc
		(start 458.775054 -13.200126)
		(mid 457.67498 -12.100052)
		(end 456.574906 -13.200126)
		(stroke
			(width 0.05)
			(type default)
		)
		(layer "Edge.Cuts")
	)
	(gr_arc
		(start 460.825088 -9.19988)
		(mid 463.675222 -12.050014)
		(end 466.525102 -9.19988)
		(stroke
			(width 0.05)
			(type default)
		)
		(layer "Edge.Cuts")
	)
	(gr_arc
		(start 460.968852 -326.236838)
		(mid 456.674982 -317.300017)
		(end 452.381112 -326.236838)
		(stroke
			(width 0.05)
			(type default)
		)
		(layer "Edge.Cuts")
	)
	(gr_arc
		(start 460.968852 -326.236838)
		(mid 459.930889 -327.820838)
		(end 459.210156 -329.572112)
		(stroke
			(width 0.05)
			(type default)
		)
		(layer "Edge.Cuts")
	)
	(gr_arc
		(start 460.968852 -211.236814)
		(mid 456.674982 -202.299993)
		(end 452.381112 -211.236814)
		(stroke
			(width 0.05)
			(type default)
		)
		(layer "Edge.Cuts")
	)
	(gr_arc
		(start 460.968852 -211.236814)
		(mid 459.930901 -212.820819)
		(end 459.210156 -214.572088)
		(stroke
			(width 0.05)
			(type default)
		)
		(layer "Edge.Cuts")
	)
	(gr_arc
		(start 460.968852 -96.23679)
		(mid 456.674982 -87.299969)
		(end 452.381112 -96.23679)
		(stroke
			(width 0.05)
			(type default)
		)
		(layer "Edge.Cuts")
	)
	(gr_arc
		(start 460.968852 -96.23679)
		(mid 459.930897 -97.820793)
		(end 459.210156 -99.572064)
		(stroke
			(width 0.05)
			(type default)
		)
		(layer "Edge.Cuts")
	)
	(gr_arc
		(start 465.725002 -269.999968)
		(mid 467.499954 -271.77492)
		(end 469.274906 -269.999968)
		(stroke
			(width 0.05)
			(type default)
		)
		(layer "Edge.Cuts")
	)
	(gr_arc
		(start 466.099906 -282.999942)
		(mid 467.499954 -284.39999)
		(end 468.900002 -282.999942)
		(stroke
			(width 0.05)
			(type default)
		)
		(layer "Edge.Cuts")
	)
	(gr_arc
		(start 466.525102 -9.19988)
		(mid 463.675222 -6.35)
		(end 460.825088 -9.19988)
		(stroke
			(width 0.05)
			(type default)
		)
		(layer "Edge.Cuts")
	)
	(gr_arc
		(start 468.574882 -5.199888)
		(mid 469.674956 -6.299962)
		(end 470.77503 -5.199888)
		(stroke
			(width 0.05)
			(type default)
		)
		(layer "Edge.Cuts")
	)
	(gr_arc
		(start 468.900002 -282.999942)
		(mid 467.499954 -281.599894)
		(end 466.099906 -282.999942)
		(stroke
			(width 0.05)
			(type default)
		)
		(layer "Edge.Cuts")
	)
	(gr_arc
		(start 469.274906 -269.999968)
		(mid 467.499954 -268.225016)
		(end 465.725002 -269.999968)
		(stroke
			(width 0.05)
			(type default)
		)
		(layer "Edge.Cuts")
	)
	(gr_arc
		(start 470.77503 -5.199888)
		(mid 469.674956 -4.099814)
		(end 468.574882 -5.199888)
		(stroke
			(width 0.05)
			(type default)
		)
		(layer "Edge.Cuts")
	)
	(gr_arc
		(start 479.149918 -121.499884)
		(mid 481.24999 -123.599956)
		(end 483.350062 -121.499884)
		(stroke
			(width 0.05)
			(type default)
		)
		(layer "Edge.Cuts")
	)
	(gr_line
		(start 479.149918 -119.499888)
		(end 479.149918 -121.499884)
		(stroke
			(width 0.05)
			(type default)
		)
		(layer "Edge.Cuts")
	)
	(gr_arc
		(start 479.149918 -5.500116)
		(mid 481.24999 -7.600188)
		(end 483.350062 -5.500116)
		(stroke
			(width 0.05)
			(type default)
		)
		(layer "Edge.Cuts")
	)
	(gr_arc
		(start 481.350066 -204.199998)
		(mid 483.450138 -206.30007)
		(end 485.549956 -204.199998)
		(stroke
			(width 0.05)
			(type default)
		)
		(layer "Edge.Cuts")
	)
	(gr_line
		(start 483.350062 -121.499884)
		(end 483.350062 -119.499888)
		(stroke
			(width 0.05)
			(type default)
		)
		(layer "Edge.Cuts")
	)
	(gr_arc
		(start 483.350062 -119.499888)
		(mid 481.24999 -117.399816)
		(end 479.149918 -119.499888)
		(stroke
			(width 0.05)
			(type default)
		)
		(layer "Edge.Cuts")
	)
	(gr_arc
		(start 483.350062 -5.500116)
		(mid 481.24999 -3.400044)
		(end 479.149918 -5.500116)
		(stroke
			(width 0.05)
			(type default)
		)
		(layer "Edge.Cuts")
	)
	(gr_arc
		(start 485.549956 -204.199998)
		(mid 483.450138 -202.10018)
		(end 481.350066 -204.199998)
		(stroke
			(width 0.05)
			(type default)
		)
		(layer "Edge.Cuts")
	)
	(gr_line
		(start 490.450124 -349.199962)
		(end 296.69994 -349.199962)
		(stroke
			(width 0.05)
			(type default)
		)
		(layer "Edge.Cuts")
	)
	(gr_arc
		(start 490.450124 -349.199962)
		(mid 491.157201 -348.907059)
		(end 491.450122 -348.199964)
		(stroke
			(width 0.05)
			(type default)
		)
		(layer "Edge.Cuts")
	)
	(gr_arc
		(start 491.450122 -0.999998)
		(mid 491.15723 -0.292885)
		(end 490.450124 0)
		(stroke
			(width 0.05)
			(type default)
		)
		(layer "Edge.Cuts")
	)
	(gr_line
		(start 491.450122 -0.999998)
		(end 491.450122 -348.199964)
		(stroke
			(width 0.05)
			(type default)
		)
		(layer "Edge.Cuts")
	)
	(segment
		(start 301.4218 -62.2554)
		(end 301.595028 -62.428628)
		(width 0.17145)
		(layer "F.Cu")
		(net "I2C_BMC_B_COMP_B_SDA_R")
	)
	(segment
		(start 300.7106 -62.2554)
		(end 300.4947 -62.4713)
		(width 0.17145)
		(layer "F.Cu")
		(net "I2C_BMC_B_COMP_B_SDA_R")
	)
	(segment
		(start 301.0154 -62.2554)
		(end 301.4218 -62.2554)
		(width 0.17145)
		(layer "F.Cu")
		(net "I2C_BMC_B_COMP_B_SDA_R")
	)
	(segment
		(start 301.0154 -62.2554)
		(end 300.7106 -62.2554)
		(width 0.17145)
		(layer "F.Cu")
		(net "I2C_BMC_B_COMP_B_SDA_R")
	)
	(segment
		(start 300.4947 -62.4713)
		(end 300.4947 -63.4492)
		(width 0.17145)
		(layer "F.Cu")
		(net "I2C_BMC_B_COMP_B_SDA_R")
	)
	(segment
		(start 301.595028 -62.428628)
		(end 301.595028 -63.4492)
		(width 0.17145)
		(layer "F.Cu")
		(net "I2C_BMC_B_COMP_B_SDA_R")
	)
	(via
		(at 301.0154 -62.2554)
		(size 0.6604)
		(drill 0.3302)
		(layers "F.Cu" "B.Cu")
		(net "I2C_BMC_B_COMP_B_SDA_R")
	)
	(segment
		(start 303.5681 -69.2023)
		(end 304.0634 -69.2023)
		(width 0.17145)
		(layer "F.Cu")
		(net "I2C_BMC_B_COMP_B_SCL_R")
	)
	(segment
		(start 302.8442 -68.228972)
		(end 302.8442 -69.3674)
		(width 0.17145)
		(layer "F.Cu")
		(net "I2C_BMC_B_COMP_B_SCL_R")
	)
	(segment
		(start 302.8442 -69.3674)
		(end 302.9204 -69.4436)
		(width 0.17145)
		(layer "F.Cu")
		(net "I2C_BMC_B_COMP_B_SCL_R")
	)
	(segment
		(start 302.9204 -69.4436)
		(end 303.3268 -69.4436)
		(width 0.17145)
		(layer "F.Cu")
		(net "I2C_BMC_B_COMP_B_SCL_R")
	)
	(segment
		(start 303.3268 -69.4436)
		(end 303.5681 -69.2023)
		(width 0.17145)
		(layer "F.Cu")
		(net "I2C_BMC_B_COMP_B_SCL_R")
	)
	(via
		(at 302.9204 -69.4436)
		(size 0.6604)
		(drill 0.3302)
		(layers "F.Cu" "B.Cu")
		(net "I2C_BMC_B_COMP_B_SCL_R")
	)
	(via
		(at 217.0684 -125.222)
		(size 0.6096)
		(drill 0.3048)
		(layers "F.Cu" "B.Cu")
		(net "I2C_BMC_A_COMP_A_SDA_R")
	)
	(segment
		(start 217.3986 -125.222)
		(end 217.6526 -124.968)
		(width 0.17145)
		(layer "B.Cu")
		(net "I2C_BMC_A_COMP_A_SDA_R")
	)
	(segment
		(start 216.789 -125.222)
		(end 217.0684 -125.222)
		(width 0.17145)
		(layer "B.Cu")
		(net "I2C_BMC_A_COMP_A_SDA_R")
	)
	(segment
		(start 217.6526 -124.968)
		(end 217.6526 -123.9393)
		(width 0.17145)
		(layer "B.Cu")
		(net "I2C_BMC_A_COMP_A_SDA_R")
	)
	(segment
		(start 217.0684 -125.222)
		(end 217.3986 -125.222)
		(width 0.17145)
		(layer "B.Cu")
		(net "I2C_BMC_A_COMP_A_SDA_R")
	)
	(segment
		(start 216.535 -124.968)
		(end 216.789 -125.222)
		(width 0.17145)
		(layer "B.Cu")
		(net "I2C_BMC_A_COMP_A_SDA_R")
	)
	(segment
		(start 216.535 -123.9393)
		(end 216.535 -124.968)
		(width 0.17145)
		(layer "B.Cu")
		(net "I2C_BMC_A_COMP_A_SDA_R")
	)
	(via
		(at 219.4814 -125.1712)
		(size 0.6096)
		(drill 0.3048)
		(layers "F.Cu" "B.Cu")
		(net "I2C_BMC_A_COMP_A_SCL_R")
	)
	(segment
		(start 219.9894 -123.9139)
		(end 219.9894 -124.8664)
		(width 0.17145)
		(layer "B.Cu")
		(net "I2C_BMC_A_COMP_A_SCL_R")
	)
	(segment
		(start 219.9894 -124.8664)
		(end 219.6846 -125.1712)
		(width 0.17145)
		(layer "B.Cu")
		(net "I2C_BMC_A_COMP_A_SCL_R")
	)
	(segment
		(start 219.6846 -125.1712)
		(end 219.4814 -125.1712)
		(width 0.17145)
		(layer "B.Cu")
		(net "I2C_BMC_A_COMP_A_SCL_R")
	)
	(segment
		(start 218.9226 -124.968)
		(end 219.1258 -125.1712)
		(width 0.17145)
		(layer "B.Cu")
		(net "I2C_BMC_A_COMP_A_SCL_R")
	)
	(segment
		(start 219.1258 -125.1712)
		(end 219.4814 -125.1712)
		(width 0.17145)
		(layer "B.Cu")
		(net "I2C_BMC_A_COMP_A_SCL_R")
	)
	(segment
		(start 218.9226 -123.9139)
		(end 218.9226 -124.968)
		(width 0.17145)
		(layer "B.Cu")
		(net "I2C_BMC_A_COMP_A_SCL_R")
	)
	(via
		(at 221.742 -121.8946)
		(size 0.6096)
		(drill 0.3048)
		(layers "F.Cu" "B.Cu")
		(net "TXS0102_A_OE")
	)
	(segment
		(start 221.488 -122.1486)
		(end 221.742 -121.8946)
		(width 0.17145)
		(layer "B.Cu")
		(net "TXS0102_A_OE")
	)
	(segment
		(start 221.02699 -120.01119)
		(end 221.6785 -120.6627)
		(width 0.17145)
		(layer "B.Cu")
		(net "TXS0102_A_OE")
	)
	(segment
		(start 221.488 -122.9995)
		(end 221.488 -122.1486)
		(width 0.17145)
		(layer "B.Cu")
		(net "TXS0102_A_OE")
	)
	(segment
		(start 222.2246 -120.6627)
		(end 222.2246 -121.412)
		(width 0.17145)
		(layer "B.Cu")
		(net "TXS0102_A_OE")
	)
	(segment
		(start 221.6785 -120.6627)
		(end 222.2246 -120.6627)
		(width 0.17145)
		(layer "B.Cu")
		(net "TXS0102_A_OE")
	)
	(segment
		(start 219.9894 -120.01119)
		(end 221.02699 -120.01119)
		(width 0.17145)
		(layer "B.Cu")
		(net "TXS0102_A_OE")
	)
	(segment
		(start 222.2246 -121.412)
		(end 221.742 -121.8946)
		(width 0.17145)
		(layer "B.Cu")
		(net "TXS0102_A_OE")
	)
	(segment
		(start 304.3174 -73.152762)
		(end 304.546 -73.381362)
		(width 0.17145)
		(layer "F.Cu")
		(net "TXS0102_B_OE")
	)
	(segment
		(start 301.01159 -70.48119)
		(end 301.9806 -71.4502)
		(width 0.17145)
		(layer "F.Cu")
		(net "TXS0102_B_OE")
	)
	(segment
		(start 302.3362 -71.8058)
		(end 304.138076 -71.8058)
		(width 0.17145)
		(layer "F.Cu")
		(net "TXS0102_B_OE")
	)
	(segment
		(start 304.546 -73.381362)
		(end 304.546 -74.2315)
		(width 0.17145)
		(layer "F.Cu")
		(net "TXS0102_B_OE")
	)
	(segment
		(start 304.3174 -71.985124)
		(end 304.3174 -72.3265)
		(width 0.17145)
		(layer "F.Cu")
		(net "TXS0102_B_OE")
	)
	(segment
		(start 304.138076 -71.8058)
		(end 304.3174 -71.985124)
		(width 0.17145)
		(layer "F.Cu")
		(net "TXS0102_B_OE")
	)
	(segment
		(start 301.01159 -69.6214)
		(end 301.01159 -70.48119)
		(width 0.17145)
		(layer "F.Cu")
		(net "TXS0102_B_OE")
	)
	(segment
		(start 301.9806 -71.4502)
		(end 302.3362 -71.8058)
		(width 0.17145)
		(layer "F.Cu")
		(net "TXS0102_B_OE")
	)
	(segment
		(start 304.3174 -72.3265)
		(end 304.3174 -73.152762)
		(width 0.17145)
		(layer "F.Cu")
		(net "TXS0102_B_OE")
	)
	(via
		(at 301.9806 -71.4502)
		(size 0.6604)
		(drill 0.3302)
		(layers "F.Cu" "B.Cu")
		(net "TXS0102_B_OE")
	)
	(segment
		(start 218.44 -382.2065)
		(end 218.44 -383.4765)
		(width 0.17145)
		(layer "F.Cu")
		(net "SCC_FULL_PWR_EN_5V_R")
	)
	(segment
		(start 216.027 -382.2065)
		(end 217.302842 -382.2065)
		(width 0.17145)
		(layer "F.Cu")
		(net "SCC_FULL_PWR_EN_5V_R")
	)
	(segment
		(start 217.302842 -382.2065)
		(end 218.44 -382.2065)
		(width 0.17145)
		(layer "F.Cu")
		(net "SCC_FULL_PWR_EN_5V_R")
	)
	(segment
		(start 218.44 -383.4765)
		(end 218.059 -383.8575)
		(width 0.17145)
		(layer "F.Cu")
		(net "SCC_FULL_PWR_EN_5V_R")
	)
	(via
		(at 217.302842 -382.2065)
		(size 0.6604)
		(drill 0.3302)
		(layers "F.Cu" "B.Cu")
		(net "SCC_FULL_PWR_EN_5V_R")
	)
	(segment
		(start 239.083596 -229.91953)
		(end 239.083596 -232.517188)
		(width 0.17145)
		(layer "F.Cu")
		(net "SCC_FULL_PWR_EN_5V")
	)
	(segment
		(start 216.027 -381.3175)
		(end 216.65946 -381.3175)
		(width 0.17145)
		(layer "F.Cu")
		(net "SCC_FULL_PWR_EN_5V")
	)
	(segment
		(start 239.083596 -228.81463)
		(end 239.083596 -229.91953)
		(width 0.17145)
		(layer "F.Cu")
		(net "SCC_FULL_PWR_EN_5V")
	)
	(segment
		(start 237.987332 -233.613452)
		(end 237.987332 -236.295946)
		(width 0.17145)
		(layer "F.Cu")
		(net "SCC_FULL_PWR_EN_5V")
	)
	(segment
		(start 257.561588 -232.06075)
		(end 258.277868 -232.77703)
		(width 0.17145)
		(layer "F.Cu")
		(net "SCC_FULL_PWR_EN_5V")
	)
	(segment
		(start 257.2385 -232.06075)
		(end 257.561588 -232.06075)
		(width 0.17145)
		(layer "F.Cu")
		(net "SCC_FULL_PWR_EN_5V")
	)
	(segment
		(start 216.65946 -381.3175)
		(end 217.30589 -380.67107)
		(width 0.17145)
		(layer "F.Cu")
		(net "SCC_FULL_PWR_EN_5V")
	)
	(segment
		(start 239.083596 -232.517188)
		(end 237.987332 -233.613452)
		(width 0.17145)
		(layer "F.Cu")
		(net "SCC_FULL_PWR_EN_5V")
	)
	(segment
		(start 218.485466 -379.491494)
		(end 218.485466 -378.75718)
		(width 0.17145)
		(layer "F.Cu")
		(net "SCC_FULL_PWR_EN_5V")
	)
	(segment
		(start 236.49559 -237.787688)
		(end 236.49559 -239.19053)
		(width 0.17145)
		(layer "F.Cu")
		(net "SCC_FULL_PWR_EN_5V")
	)
	(segment
		(start 217.30589 -380.67107)
		(end 218.485466 -379.491494)
		(width 0.17145)
		(layer "F.Cu")
		(net "SCC_FULL_PWR_EN_5V")
	)
	(segment
		(start 237.987332 -236.295946)
		(end 236.49559 -237.787688)
		(width 0.17145)
		(layer "F.Cu")
		(net "SCC_FULL_PWR_EN_5V")
	)
	(via
		(at 239.083596 -228.81463)
		(size 0.5588)
		(drill 0.3048)
		(layers "F.Cu" "B.Cu")
		(net "SCC_FULL_PWR_EN_5V")
	)
	(via
		(at 258.277868 -232.77703)
		(size 0.5588)
		(drill 0.3048)
		(layers "F.Cu" "B.Cu")
		(net "SCC_FULL_PWR_EN_5V")
	)
	(via
		(at 236.49559 -237.787688)
		(size 0.5588)
		(drill 0.3048)
		(layers "F.Cu" "B.Cu")
		(net "SCC_FULL_PWR_EN_5V")
	)
	(via
		(at 224.112582 -227.66528)
		(size 0.5588)
		(drill 0.3048)
		(layers "F.Cu" "B.Cu")
		(net "SCC_FULL_PWR_EN_5V")
	)
	(via
		(at 218.485466 -378.75718)
		(size 0.5588)
		(drill 0.3048)
		(layers "F.Cu" "B.Cu")
		(net "SCC_FULL_PWR_EN_5V")
	)
	(via
		(at 217.30589 -380.67107)
		(size 0.6604)
		(drill 0.3302)
		(layers "F.Cu" "B.Cu")
		(net "SCC_FULL_PWR_EN_5V")
	)
	(segment
		(start 236.49559 -237.787688)
		(end 241.116866 -233.166412)
		(width 0.13335)
		(layer "In2.Cu")
		(net "SCC_FULL_PWR_EN_5V")
	)
	(segment
		(start 257.888486 -233.166412)
		(end 258.277868 -232.77703)
		(width 0.13335)
		(layer "In2.Cu")
		(net "SCC_FULL_PWR_EN_5V")
	)
	(segment
		(start 241.116866 -233.166412)
		(end 257.888486 -233.166412)
		(width 0.13335)
		(layer "In2.Cu")
		(net "SCC_FULL_PWR_EN_5V")
	)
	(segment
		(start 224.116646 -227.669344)
		(end 224.112582 -227.66528)
		(width 0.12065)
		(layer "In4.Cu")
		(net "SCC_FULL_PWR_EN_5V")
	)
	(segment
		(start 218.485466 -378.75718)
		(end 217.557096 -377.82881)
		(width 0.12065)
		(layer "In4.Cu")
		(net "SCC_FULL_PWR_EN_5V")
	)
	(segment
		(start 224.116646 -320.300604)
		(end 224.116646 -227.669344)
		(width 0.12065)
		(layer "In4.Cu")
		(net "SCC_FULL_PWR_EN_5V")
	)
	(segment
		(start 217.557096 -326.860154)
		(end 224.116646 -320.300604)
		(width 0.12065)
		(layer "In4.Cu")
		(net "SCC_FULL_PWR_EN_5V")
	)
	(segment
		(start 217.557096 -377.82881)
		(end 217.557096 -326.860154)
		(width 0.12065)
		(layer "In4.Cu")
		(net "SCC_FULL_PWR_EN_5V")
	)
	(segment
		(start 236.307122 -227.66528)
		(end 224.112582 -227.66528)
		(width 0.12065)
		(layer "In7.Cu")
		(net "SCC_FULL_PWR_EN_5V")
	)
	(segment
		(start 239.083596 -228.81463)
		(end 237.456472 -228.81463)
		(width 0.12065)
		(layer "In7.Cu")
		(net "SCC_FULL_PWR_EN_5V")
	)
	(segment
		(start 237.456472 -228.81463)
		(end 236.307122 -227.66528)
		(width 0.12065)
		(layer "In7.Cu")
		(net "SCC_FULL_PWR_EN_5V")
	)
	(segment
		(start 220.345 -385.953)
		(end 220.588332 -386.196332)
		(width 0.17145)
		(layer "F.Cu")
		(net "SCC_A_FULL_PWR_EN_12V")
	)
	(segment
		(start 219.04325 -385.7625)
		(end 220.1545 -385.7625)
		(width 0.17145)
		(layer "F.Cu")
		(net "SCC_A_FULL_PWR_EN_12V")
	)
	(segment
		(start 220.588332 -386.196332)
		(end 220.588332 -387.02488)
		(width 0.17145)
		(layer "F.Cu")
		(net "SCC_A_FULL_PWR_EN_12V")
	)
	(segment
		(start 220.1545 -385.7625)
		(end 220.345 -385.953)
		(width 0.17145)
		(layer "F.Cu")
		(net "SCC_A_FULL_PWR_EN_12V")
	)
	(segment
		(start 220.588332 -388.540498)
		(end 220.588332 -387.02488)
		(width 0.17145)
		(layer "F.Cu")
		(net "SCC_A_FULL_PWR_EN_12V")
	)
	(via
		(at 220.345 -385.953)
		(size 0.6604)
		(drill 0.3302)
		(layers "F.Cu" "B.Cu")
		(net "SCC_A_FULL_PWR_EN_12V")
	)
	(segment
		(start 302.484028 -63.4492)
		(end 302.484028 -64.968628)
		(width 0.17145)
		(layer "F.Cu")
		(net "I2C_BMC_B_COMP_B_SDA_BUF")
	)
	(segment
		(start 302.6918 -66.4718)
		(end 303.4538 -66.4718)
		(width 0.17145)
		(layer "F.Cu")
		(net "I2C_BMC_B_COMP_B_SDA_BUF")
	)
	(segment
		(start 301.879 -67.2846)
		(end 302.6918 -66.4718)
		(width 0.17145)
		(layer "F.Cu")
		(net "I2C_BMC_B_COMP_B_SDA_BUF")
	)
	(segment
		(start 302.484028 -65.688972)
		(end 301.51197 -66.66103)
		(width 0.17145)
		(layer "F.Cu")
		(net "I2C_BMC_B_COMP_B_SDA_BUF")
	)
	(segment
		(start 301.51197 -66.66103)
		(end 301.51197 -67.2846)
		(width 0.17145)
		(layer "F.Cu")
		(net "I2C_BMC_B_COMP_B_SDA_BUF")
	)
	(segment
		(start 302.484028 -64.968628)
		(end 302.484028 -65.688972)
		(width 0.17145)
		(layer "F.Cu")
		(net "I2C_BMC_B_COMP_B_SDA_BUF")
	)
	(segment
		(start 301.51197 -67.2846)
		(end 301.879 -67.2846)
		(width 0.17145)
		(layer "F.Cu")
		(net "I2C_BMC_B_COMP_B_SDA_BUF")
	)
	(via
		(at 365.672116 -88.862408)
		(size 0.5588)
		(drill 0.3048)
		(layers "F.Cu" "B.Cu")
		(net "I2C_BMC_B_COMP_B_SDA_BUF")
	)
	(via
		(at 303.4538 -66.4718)
		(size 0.5588)
		(drill 0.3048)
		(layers "F.Cu" "B.Cu")
		(net "I2C_BMC_B_COMP_B_SDA_BUF")
	)
	(via
		(at 302.484028 -64.968628)
		(size 0.6604)
		(drill 0.3302)
		(layers "F.Cu" "B.Cu")
		(net "I2C_BMC_B_COMP_B_SDA_BUF")
	)
	(segment
		(start 348.191328 -65.132204)
		(end 347.815916 -64.756792)
		(width 0.13335)
		(layer "In2.Cu")
		(net "I2C_BMC_B_COMP_B_SDA_BUF")
	)
	(segment
		(start 365.147098 -82.619596)
		(end 365.147352 -82.619342)
		(width 0.13335)
		(layer "In2.Cu")
		(net "I2C_BMC_B_COMP_B_SDA_BUF")
	)
	(segment
		(start 365.672116 -88.862408)
		(end 365.147098 -88.33739)
		(width 0.13335)
		(layer "In2.Cu")
		(net "I2C_BMC_B_COMP_B_SDA_BUF")
	)
	(segment
		(start 304.9016 -67.9196)
		(end 303.4538 -66.4718)
		(width 0.13335)
		(layer "In2.Cu")
		(net "I2C_BMC_B_COMP_B_SDA_BUF")
	)
	(segment
		(start 347.815916 -64.756792)
		(end 313.804808 -64.756792)
		(width 0.13335)
		(layer "In2.Cu")
		(net "I2C_BMC_B_COMP_B_SDA_BUF")
	)
	(segment
		(start 313.804808 -64.756792)
		(end 310.642 -67.9196)
		(width 0.13335)
		(layer "In2.Cu")
		(net "I2C_BMC_B_COMP_B_SDA_BUF")
	)
	(segment
		(start 310.642 -67.9196)
		(end 304.9016 -67.9196)
		(width 0.13335)
		(layer "In2.Cu")
		(net "I2C_BMC_B_COMP_B_SDA_BUF")
	)
	(segment
		(start 365.147352 -82.619342)
		(end 365.147352 -82.088482)
		(width 0.13335)
		(layer "In2.Cu")
		(net "I2C_BMC_B_COMP_B_SDA_BUF")
	)
	(segment
		(start 365.147098 -88.33739)
		(end 365.147098 -82.619596)
		(width 0.13335)
		(layer "In2.Cu")
		(net "I2C_BMC_B_COMP_B_SDA_BUF")
	)
	(segment
		(start 348.191328 -65.132458)
		(end 348.191328 -65.132204)
		(width 0.13335)
		(layer "In2.Cu")
		(net "I2C_BMC_B_COMP_B_SDA_BUF")
	)
	(segment
		(start 365.147352 -82.088482)
		(end 348.191328 -65.132458)
		(width 0.13335)
		(layer "In2.Cu")
		(net "I2C_BMC_B_COMP_B_SDA_BUF")
	)
	(segment
		(start 365.949992 -25.950164)
		(end 365.266224 -26.633932)
		(width 0.12065)
		(layer "In4.Cu")
		(net "I2C_BMC_B_COMP_B_SDA_BUF")
	)
	(segment
		(start 366.189006 -72.68718)
		(end 366.189006 -88.345518)
		(width 0.12065)
		(layer "In4.Cu")
		(net "I2C_BMC_B_COMP_B_SDA_BUF")
	)
	(segment
		(start 365.266224 -32.04591)
		(end 365.924338 -32.704024)
		(width 0.12065)
		(layer "In4.Cu")
		(net "I2C_BMC_B_COMP_B_SDA_BUF")
	)
	(segment
		(start 363.2454 -69.743574)
		(end 366.189006 -72.68718)
		(width 0.12065)
		(layer "In4.Cu")
		(net "I2C_BMC_B_COMP_B_SDA_BUF")
	)
	(segment
		(start 365.924338 -43.774106)
		(end 363.2454 -46.453044)
		(width 0.12065)
		(layer "In4.Cu")
		(net "I2C_BMC_B_COMP_B_SDA_BUF")
	)
	(segment
		(start 363.2454 -46.453044)
		(end 363.2454 -69.743574)
		(width 0.12065)
		(layer "In4.Cu")
		(net "I2C_BMC_B_COMP_B_SDA_BUF")
	)
	(segment
		(start 365.266224 -26.633932)
		(end 365.266224 -32.04591)
		(width 0.12065)
		(layer "In4.Cu")
		(net "I2C_BMC_B_COMP_B_SDA_BUF")
	)
	(segment
		(start 366.189006 -88.345518)
		(end 365.672116 -88.862408)
		(width 0.12065)
		(layer "In4.Cu")
		(net "I2C_BMC_B_COMP_B_SDA_BUF")
	)
	(segment
		(start 365.924338 -32.704024)
		(end 365.924338 -43.774106)
		(width 0.12065)
		(layer "In4.Cu")
		(net "I2C_BMC_B_COMP_B_SDA_BUF")
	)
	(segment
		(start 301.8028 -70.5358)
		(end 301.51197 -70.24497)
		(width 0.17145)
		(layer "F.Cu")
		(net "I2C_BMC_B_COMP_B_SCL_BUF")
	)
	(segment
		(start 301.51197 -70.24497)
		(end 301.51197 -69.6214)
		(width 0.17145)
		(layer "F.Cu")
		(net "I2C_BMC_B_COMP_B_SCL_BUF")
	)
	(segment
		(start 303.1236 -70.5358)
		(end 302.9204 -70.5358)
		(width 0.17145)
		(layer "F.Cu")
		(net "I2C_BMC_B_COMP_B_SCL_BUF")
	)
	(segment
		(start 304.0634 -70.0913)
		(end 303.5681 -70.0913)
		(width 0.17145)
		(layer "F.Cu")
		(net "I2C_BMC_B_COMP_B_SCL_BUF")
	)
	(segment
		(start 304.0634 -70.0913)
		(end 304.0634 -70.9422)
		(width 0.17145)
		(layer "F.Cu")
		(net "I2C_BMC_B_COMP_B_SCL_BUF")
	)
	(segment
		(start 302.9204 -70.5358)
		(end 301.8028 -70.5358)
		(width 0.17145)
		(layer "F.Cu")
		(net "I2C_BMC_B_COMP_B_SCL_BUF")
	)
	(segment
		(start 304.0634 -70.9422)
		(end 304.038 -70.9676)
		(width 0.17145)
		(layer "F.Cu")
		(net "I2C_BMC_B_COMP_B_SCL_BUF")
	)
	(segment
		(start 303.5681 -70.0913)
		(end 303.1236 -70.5358)
		(width 0.17145)
		(layer "F.Cu")
		(net "I2C_BMC_B_COMP_B_SCL_BUF")
	)
	(via
		(at 304.038 -70.9676)
		(size 0.5588)
		(drill 0.3048)
		(layers "F.Cu" "B.Cu")
		(net "I2C_BMC_B_COMP_B_SCL_BUF")
	)
	(via
		(at 366.836452 -88.862408)
		(size 0.5588)
		(drill 0.3048)
		(layers "F.Cu" "B.Cu")
		(net "I2C_BMC_B_COMP_B_SCL_BUF")
	)
	(via
		(at 302.9204 -70.5358)
		(size 0.6604)
		(drill 0.3302)
		(layers "F.Cu" "B.Cu")
		(net "I2C_BMC_B_COMP_B_SCL_BUF")
	)
	(segment
		(start 347.549978 -65.398142)
		(end 314.509658 -65.398142)
		(width 0.13335)
		(layer "In2.Cu")
		(net "I2C_BMC_B_COMP_B_SCL_BUF")
	)
	(segment
		(start 314.509658 -65.398142)
		(end 311.34685 -68.56095)
		(width 0.13335)
		(layer "In2.Cu")
		(net "I2C_BMC_B_COMP_B_SCL_BUF")
	)
	(segment
		(start 311.34685 -68.56095)
		(end 306.44465 -68.56095)
		(width 0.13335)
		(layer "In2.Cu")
		(net "I2C_BMC_B_COMP_B_SCL_BUF")
	)
	(segment
		(start 366.250474 -89.448386)
		(end 365.316516 -89.448386)
		(width 0.13335)
		(layer "In2.Cu")
		(net "I2C_BMC_B_COMP_B_SCL_BUF")
	)
	(segment
		(start 364.505748 -82.353912)
		(end 347.549978 -65.398142)
		(width 0.13335)
		(layer "In2.Cu")
		(net "I2C_BMC_B_COMP_B_SCL_BUF")
	)
	(segment
		(start 365.316516 -89.448386)
		(end 364.505748 -88.637618)
		(width 0.13335)
		(layer "In2.Cu")
		(net "I2C_BMC_B_COMP_B_SCL_BUF")
	)
	(segment
		(start 306.44465 -68.56095)
		(end 304.038 -70.9676)
		(width 0.13335)
		(layer "In2.Cu")
		(net "I2C_BMC_B_COMP_B_SCL_BUF")
	)
	(segment
		(start 364.505748 -88.637618)
		(end 364.505748 -82.353912)
		(width 0.13335)
		(layer "In2.Cu")
		(net "I2C_BMC_B_COMP_B_SCL_BUF")
	)
	(segment
		(start 366.836452 -88.862408)
		(end 366.250474 -89.448386)
		(width 0.13335)
		(layer "In2.Cu")
		(net "I2C_BMC_B_COMP_B_SCL_BUF")
	)
	(segment
		(start 366.764062 -25.364186)
		(end 366.764062 -43.823636)
		(width 0.12065)
		(layer "In4.Cu")
		(net "I2C_BMC_B_COMP_B_SCL_BUF")
	)
	(segment
		(start 365.949992 -24.550116)
		(end 366.764062 -25.364186)
		(width 0.12065)
		(layer "In4.Cu")
		(net "I2C_BMC_B_COMP_B_SCL_BUF")
	)
	(segment
		(start 363.87405 -46.713648)
		(end 363.87405 -69.48297)
		(width 0.12065)
		(layer "In4.Cu")
		(net "I2C_BMC_B_COMP_B_SCL_BUF")
	)
	(segment
		(start 366.830102 -88.856058)
		(end 366.836452 -88.862408)
		(width 0.12065)
		(layer "In4.Cu")
		(net "I2C_BMC_B_COMP_B_SCL_BUF")
	)
	(segment
		(start 366.830102 -72.439022)
		(end 366.830102 -88.856058)
		(width 0.12065)
		(layer "In4.Cu")
		(net "I2C_BMC_B_COMP_B_SCL_BUF")
	)
	(segment
		(start 366.764062 -43.823636)
		(end 363.87405 -46.713648)
		(width 0.12065)
		(layer "In4.Cu")
		(net "I2C_BMC_B_COMP_B_SCL_BUF")
	)
	(segment
		(start 363.87405 -69.48297)
		(end 366.830102 -72.439022)
		(width 0.12065)
		(layer "In4.Cu")
		(net "I2C_BMC_B_COMP_B_SCL_BUF")
	)
	(via
		(at 217.6526 -121.9073)
		(size 0.6096)
		(drill 0.3048)
		(layers "F.Cu" "B.Cu")
		(net "I2C_BMC_A_COMP_A_SDA_BUF")
	)
	(via
		(at 216.3572 -121.2088)
		(size 0.5588)
		(drill 0.3048)
		(layers "F.Cu" "B.Cu")
		(net "I2C_BMC_A_COMP_A_SDA_BUF")
	)
	(via
		(at 112.17783 -72.300338)
		(size 0.5588)
		(drill 0.3048)
		(layers "F.Cu" "B.Cu")
		(net "I2C_BMC_A_COMP_A_SDA_BUF")
	)
	(segment
		(start 217.6526 -123.0503)
		(end 217.6526 -121.9073)
		(width 0.17145)
		(layer "B.Cu")
		(net "I2C_BMC_A_COMP_A_SDA_BUF")
	)
	(segment
		(start 217.05443 -120.51157)
		(end 217.6526 -120.51157)
		(width 0.17145)
		(layer "B.Cu")
		(net "I2C_BMC_A_COMP_A_SDA_BUF")
	)
	(segment
		(start 217.6526 -121.9073)
		(end 217.6526 -120.51157)
		(width 0.17145)
		(layer "B.Cu")
		(net "I2C_BMC_A_COMP_A_SDA_BUF")
	)
	(segment
		(start 216.3572 -121.2088)
		(end 217.05443 -120.51157)
		(width 0.17145)
		(layer "B.Cu")
		(net "I2C_BMC_A_COMP_A_SDA_BUF")
	)
	(segment
		(start 119.295418 -38.285928)
		(end 112.17783 -45.403516)
		(width 0.12065)
		(layer "In4.Cu")
		(net "I2C_BMC_A_COMP_A_SDA_BUF")
	)
	(segment
		(start 112.17783 -45.403516)
		(end 112.17783 -72.300338)
		(width 0.12065)
		(layer "In4.Cu")
		(net "I2C_BMC_A_COMP_A_SDA_BUF")
	)
	(segment
		(start 119.303292 -32.24784)
		(end 119.295418 -32.255714)
		(width 0.12065)
		(layer "In4.Cu")
		(net "I2C_BMC_A_COMP_A_SDA_BUF")
	)
	(segment
		(start 119.295418 -32.255714)
		(end 119.295418 -38.285928)
		(width 0.12065)
		(layer "In4.Cu")
		(net "I2C_BMC_A_COMP_A_SDA_BUF")
	)
	(segment
		(start 119.303292 -26.596848)
		(end 119.303292 -32.24784)
		(width 0.12065)
		(layer "In4.Cu")
		(net "I2C_BMC_A_COMP_A_SDA_BUF")
	)
	(segment
		(start 119.949976 -25.950164)
		(end 119.303292 -26.596848)
		(width 0.12065)
		(layer "In4.Cu")
		(net "I2C_BMC_A_COMP_A_SDA_BUF")
	)
	(segment
		(start 216.3572 -121.2088)
		(end 214.8332 -121.2088)
		(width 0.13335)
		(layer "In9.Cu")
		(net "I2C_BMC_A_COMP_A_SDA_BUF")
	)
	(segment
		(start 140.97381 -83.498944)
		(end 129.775204 -72.300338)
		(width 0.13335)
		(layer "In9.Cu")
		(net "I2C_BMC_A_COMP_A_SDA_BUF")
	)
	(segment
		(start 177.123344 -83.498944)
		(end 140.97381 -83.498944)
		(width 0.13335)
		(layer "In9.Cu")
		(net "I2C_BMC_A_COMP_A_SDA_BUF")
	)
	(segment
		(start 129.775204 -72.300338)
		(end 112.17783 -72.300338)
		(width 0.13335)
		(layer "In9.Cu")
		(net "I2C_BMC_A_COMP_A_SDA_BUF")
	)
	(segment
		(start 214.8332 -121.2088)
		(end 177.123344 -83.498944)
		(width 0.13335)
		(layer "In9.Cu")
		(net "I2C_BMC_A_COMP_A_SDA_BUF")
	)
	(via
		(at 112.17783 -73.367138)
		(size 0.5588)
		(drill 0.3048)
		(layers "F.Cu" "B.Cu")
		(net "I2C_BMC_A_COMP_A_SCL_BUF")
	)
	(via
		(at 219.9894 -121.8946)
		(size 0.6096)
		(drill 0.3048)
		(layers "F.Cu" "B.Cu")
		(net "I2C_BMC_A_COMP_A_SCL_BUF")
	)
	(via
		(at 221.1324 -121.1326)
		(size 0.5588)
		(drill 0.3048)
		(layers "F.Cu" "B.Cu")
		(net "I2C_BMC_A_COMP_A_SCL_BUF")
	)
	(segment
		(start 220.51137 -120.51157)
		(end 219.9894 -120.51157)
		(width 0.17145)
		(layer "B.Cu")
		(net "I2C_BMC_A_COMP_A_SCL_BUF")
	)
	(segment
		(start 219.9894 -120.51157)
		(end 219.9894 -121.8946)
		(width 0.17145)
		(layer "B.Cu")
		(net "I2C_BMC_A_COMP_A_SCL_BUF")
	)
	(segment
		(start 219.9894 -123.0249)
		(end 219.9894 -121.8946)
		(width 0.17145)
		(layer "B.Cu")
		(net "I2C_BMC_A_COMP_A_SCL_BUF")
	)
	(segment
		(start 221.1324 -121.1326)
		(end 220.51137 -120.51157)
		(width 0.17145)
		(layer "B.Cu")
		(net "I2C_BMC_A_COMP_A_SCL_BUF")
	)
	(segment
		(start 118.827042 -32.050482)
		(end 118.431818 -32.445706)
		(width 0.12065)
		(layer "In4.Cu")
		(net "I2C_BMC_A_COMP_A_SCL_BUF")
	)
	(segment
		(start 111.5441 -45.147992)
		(end 111.5441 -72.733408)
		(width 0.12065)
		(layer "In4.Cu")
		(net "I2C_BMC_A_COMP_A_SCL_BUF")
	)
	(segment
		(start 118.431818 -32.445706)
		(end 118.431818 -38.260274)
		(width 0.12065)
		(layer "In4.Cu")
		(net "I2C_BMC_A_COMP_A_SCL_BUF")
	)
	(segment
		(start 111.5441 -72.733408)
		(end 112.17783 -73.367138)
		(width 0.12065)
		(layer "In4.Cu")
		(net "I2C_BMC_A_COMP_A_SCL_BUF")
	)
	(segment
		(start 119.949976 -24.550116)
		(end 118.827042 -25.67305)
		(width 0.12065)
		(layer "In4.Cu")
		(net "I2C_BMC_A_COMP_A_SCL_BUF")
	)
	(segment
		(start 118.827042 -25.67305)
		(end 118.827042 -32.050482)
		(width 0.12065)
		(layer "In4.Cu")
		(net "I2C_BMC_A_COMP_A_SCL_BUF")
	)
	(segment
		(start 118.431818 -38.260274)
		(end 111.5441 -45.147992)
		(width 0.12065)
		(layer "In4.Cu")
		(net "I2C_BMC_A_COMP_A_SCL_BUF")
	)
	(segment
		(start 220.3958 -121.8692)
		(end 214.376 -121.8692)
		(width 0.13335)
		(layer "In9.Cu")
		(net "I2C_BMC_A_COMP_A_SCL_BUF")
	)
	(segment
		(start 221.1324 -121.1326)
		(end 220.3958 -121.8692)
		(width 0.13335)
		(layer "In9.Cu")
		(net "I2C_BMC_A_COMP_A_SCL_BUF")
	)
	(segment
		(start 140.671296 -84.229194)
		(end 129.80924 -73.367138)
		(width 0.13335)
		(layer "In9.Cu")
		(net "I2C_BMC_A_COMP_A_SCL_BUF")
	)
	(segment
		(start 129.80924 -73.367138)
		(end 112.17783 -73.367138)
		(width 0.13335)
		(layer "In9.Cu")
		(net "I2C_BMC_A_COMP_A_SCL_BUF")
	)
	(segment
		(start 176.735994 -84.229194)
		(end 140.671296 -84.229194)
		(width 0.13335)
		(layer "In9.Cu")
		(net "I2C_BMC_A_COMP_A_SCL_BUF")
	)
	(segment
		(start 214.376 -121.8692)
		(end 176.735994 -84.229194)
		(width 0.13335)
		(layer "In9.Cu")
		(net "I2C_BMC_A_COMP_A_SCL_BUF")
	)
	(segment
		(start 257.4163 -238.506)
		(end 258.96316 -238.506)
		(width 0.254)
		(layer "F.Cu")
		(net "GPIO_VCC_U9")
	)
	(segment
		(start 259.21716 -238.76)
		(end 259.21716 -239.6744)
		(width 0.254)
		(layer "F.Cu")
		(net "GPIO_VCC_U9")
	)
	(segment
		(start 258.96316 -238.506)
		(end 259.21716 -238.76)
		(width 0.254)
		(layer "F.Cu")
		(net "GPIO_VCC_U9")
	)
	(segment
		(start 257.2385 -234.02925)
		(end 257.2385 -235.330746)
		(width 0.254)
		(layer "F.Cu")
		(net "GPIO_VCC_U9")
	)
	(segment
		(start 257.2385 -235.330746)
		(end 257.2385 -236.22)
		(width 0.254)
		(layer "F.Cu")
		(net "GPIO_VCC_U9")
	)
	(segment
		(start 257.4163 -237.8075)
		(end 257.7338 -237.49)
		(width 0.254)
		(layer "F.Cu")
		(net "GPIO_VCC_U9")
	)
	(segment
		(start 257.2385 -236.22)
		(end 257.3655 -236.347)
		(width 0.254)
		(layer "F.Cu")
		(net "GPIO_VCC_U9")
	)
	(segment
		(start 257.7338 -237.49)
		(end 257.7338 -236.7153)
		(width 0.254)
		(layer "F.Cu")
		(net "GPIO_VCC_U9")
	)
	(segment
		(start 257.7338 -236.7153)
		(end 257.3655 -236.347)
		(width 0.254)
		(layer "F.Cu")
		(net "GPIO_VCC_U9")
	)
	(segment
		(start 257.4163 -238.506)
		(end 257.4163 -237.8075)
		(width 0.254)
		(layer "F.Cu")
		(net "GPIO_VCC_U9")
	)
	(via
		(at 257.2385 -235.330746)
		(size 0.6604)
		(drill 0.3302)
		(layers "F.Cu" "B.Cu")
		(net "GPIO_VCC_U9")
	)
	(segment
		(start 241.00663 -238.379)
		(end 241.5921 -238.379)
		(width 0.254)
		(layer "F.Cu")
		(net "GPIO_VCC_U8")
	)
	(segment
		(start 240.23066 -241.404648)
		(end 240.23066 -240.238026)
		(width 0.254)
		(layer "F.Cu")
		(net "GPIO_VCC_U8")
	)
	(segment
		(start 240.608104 -238.379)
		(end 239.973104 -239.014)
		(width 0.254)
		(layer "F.Cu")
		(net "GPIO_VCC_U8")
	)
	(segment
		(start 241.00663 -238.379)
		(end 240.608104 -238.379)
		(width 0.254)
		(layer "F.Cu")
		(net "GPIO_VCC_U8")
	)
	(segment
		(start 240.23066 -240.238026)
		(end 240.23066 -239.583722)
		(width 0.254)
		(layer "F.Cu")
		(net "GPIO_VCC_U8")
	)
	(segment
		(start 240.23066 -241.404648)
		(end 238.46409 -239.638078)
		(width 0.254)
		(layer "F.Cu")
		(net "GPIO_VCC_U8")
	)
	(segment
		(start 239.973104 -239.326166)
		(end 239.973104 -239.014)
		(width 0.254)
		(layer "F.Cu")
		(net "GPIO_VCC_U8")
	)
	(segment
		(start 241.5921 -238.379)
		(end 242.16868 -238.95558)
		(width 0.254)
		(layer "F.Cu")
		(net "GPIO_VCC_U8")
	)
	(segment
		(start 242.16868 -238.95558)
		(end 242.16868 -239.8014)
		(width 0.254)
		(layer "F.Cu")
		(net "GPIO_VCC_U8")
	)
	(segment
		(start 240.23066 -239.583722)
		(end 239.973104 -239.326166)
		(width 0.254)
		(layer "F.Cu")
		(net "GPIO_VCC_U8")
	)
	(segment
		(start 238.46409 -239.638078)
		(end 238.46409 -239.19053)
		(width 0.254)
		(layer "F.Cu")
		(net "GPIO_VCC_U8")
	)
	(via
		(at 240.23066 -240.238026)
		(size 0.6604)
		(drill 0.3302)
		(layers "F.Cu" "B.Cu")
		(net "GPIO_VCC_U8")
	)
	(segment
		(start 237.115096 -231.661716)
		(end 237.115096 -232.778046)
		(width 0.254)
		(layer "F.Cu")
		(net "GPIO_VCC_U7")
	)
	(segment
		(start 234.84332 -234.1626)
		(end 236.024928 -234.1626)
		(width 0.254)
		(layer "F.Cu")
		(net "GPIO_VCC_U7")
	)
	(segment
		(start 236.024928 -234.1626)
		(end 237.115096 -234.1626)
		(width 0.254)
		(layer "F.Cu")
		(net "GPIO_VCC_U7")
	)
	(segment
		(start 237.115096 -229.91953)
		(end 237.115096 -231.65816)
		(width 0.254)
		(layer "F.Cu")
		(net "GPIO_VCC_U7")
	)
	(segment
		(start 237.116874 -231.659938)
		(end 237.115096 -231.661716)
		(width 0.254)
		(layer "F.Cu")
		(net "GPIO_VCC_U7")
	)
	(segment
		(start 237.115096 -231.65816)
		(end 237.116874 -231.659938)
		(width 0.254)
		(layer "F.Cu")
		(net "GPIO_VCC_U7")
	)
	(segment
		(start 237.115096 -232.778046)
		(end 237.115096 -234.1626)
		(width 0.254)
		(layer "F.Cu")
		(net "GPIO_VCC_U7")
	)
	(via
		(at 237.115096 -232.778046)
		(size 0.6604)
		(drill 0.3302)
		(layers "F.Cu" "B.Cu")
		(net "GPIO_VCC_U7")
	)
	(segment
		(start 212.085428 -389.445754)
		(end 213.743032 -389.445754)
		(width 0.17145)
		(layer "F.Cu")
		(net "BMC_B_TO_EXP_B_RESET_N")
	)
	(segment
		(start 212.4964 -390.8552)
		(end 213.0933 -390.8552)
		(width 0.17145)
		(layer "F.Cu")
		(net "BMC_B_TO_EXP_B_RESET_N")
	)
	(segment
		(start 212.083396 -389.443722)
		(end 212.083396 -390.442196)
		(width 0.17145)
		(layer "F.Cu")
		(net "BMC_B_TO_EXP_B_RESET_N")
	)
	(segment
		(start 212.083396 -389.443722)
		(end 212.085428 -389.445754)
		(width 0.17145)
		(layer "F.Cu")
		(net "BMC_B_TO_EXP_B_RESET_N")
	)
	(segment
		(start 212.083396 -390.442196)
		(end 212.4964 -390.8552)
		(width 0.17145)
		(layer "F.Cu")
		(net "BMC_B_TO_EXP_B_RESET_N")
	)
	(via
		(at 212.083396 -389.443722)
		(size 0.5588)
		(drill 0.3048)
		(layers "F.Cu" "B.Cu")
		(net "BMC_B_TO_EXP_B_RESET_N")
	)
	(via
		(at 348.873826 -193.5226)
		(size 0.5588)
		(drill 0.3048)
		(layers "F.Cu" "B.Cu")
		(net "BMC_B_TO_EXP_B_RESET_N")
	)
	(via
		(at 239.903 -193.2305)
		(size 0.5588)
		(drill 0.3048)
		(layers "F.Cu" "B.Cu")
		(net "BMC_B_TO_EXP_B_RESET_N")
	)
	(segment
		(start 348.873826 -193.5226)
		(end 332.068932 -193.5226)
		(width 0.13335)
		(layer "In2.Cu")
		(net "BMC_B_TO_EXP_B_RESET_N")
	)
	(segment
		(start 332.068932 -193.5226)
		(end 331.305154 -194.286378)
		(width 0.13335)
		(layer "In2.Cu")
		(net "BMC_B_TO_EXP_B_RESET_N")
	)
	(segment
		(start 244.777514 -193.2305)
		(end 239.903 -193.2305)
		(width 0.13335)
		(layer "In2.Cu")
		(net "BMC_B_TO_EXP_B_RESET_N")
	)
	(segment
		(start 314.461144 -199.231758)
		(end 250.778772 -199.231758)
		(width 0.13335)
		(layer "In2.Cu")
		(net "BMC_B_TO_EXP_B_RESET_N")
	)
	(segment
		(start 331.305154 -194.286378)
		(end 319.406524 -194.286378)
		(width 0.13335)
		(layer "In2.Cu")
		(net "BMC_B_TO_EXP_B_RESET_N")
	)
	(segment
		(start 319.406524 -194.286378)
		(end 314.461144 -199.231758)
		(width 0.13335)
		(layer "In2.Cu")
		(net "BMC_B_TO_EXP_B_RESET_N")
	)
	(segment
		(start 250.778772 -199.231758)
		(end 244.777514 -193.2305)
		(width 0.13335)
		(layer "In2.Cu")
		(net "BMC_B_TO_EXP_B_RESET_N")
	)
	(segment
		(start 218.417902 -208.231486)
		(end 218.417902 -317.516256)
		(width 0.12065)
		(layer "In4.Cu")
		(net "BMC_B_TO_EXP_B_RESET_N")
	)
	(segment
		(start 211.77123 -324.162928)
		(end 211.77123 -387.847332)
		(width 0.12065)
		(layer "In4.Cu")
		(net "BMC_B_TO_EXP_B_RESET_N")
	)
	(segment
		(start 341.572596 -174.44085)
		(end 348.873826 -181.74208)
		(width 0.12065)
		(layer "In4.Cu")
		(net "BMC_B_TO_EXP_B_RESET_N")
	)
	(segment
		(start 233.418888 -193.2305)
		(end 218.417902 -208.231486)
		(width 0.12065)
		(layer "In4.Cu")
		(net "BMC_B_TO_EXP_B_RESET_N")
	)
	(segment
		(start 364.149894 -30.550104)
		(end 364.149894 -39.841424)
		(width 0.12065)
		(layer "In4.Cu")
		(net "BMC_B_TO_EXP_B_RESET_N")
	)
	(segment
		(start 211.967318 -389.443722)
		(end 212.083396 -389.443722)
		(width 0.12065)
		(layer "In4.Cu")
		(net "BMC_B_TO_EXP_B_RESET_N")
	)
	(segment
		(start 340.12505 -169.360596)
		(end 341.572596 -170.808142)
		(width 0.12065)
		(layer "In4.Cu")
		(net "BMC_B_TO_EXP_B_RESET_N")
	)
	(segment
		(start 348.873826 -181.74208)
		(end 348.873826 -193.5226)
		(width 0.12065)
		(layer "In4.Cu")
		(net "BMC_B_TO_EXP_B_RESET_N")
	)
	(segment
		(start 211.54771 -389.024114)
		(end 211.967318 -389.443722)
		(width 0.12065)
		(layer "In4.Cu")
		(net "BMC_B_TO_EXP_B_RESET_N")
	)
	(segment
		(start 360.8578 -43.133518)
		(end 360.8578 -107.188)
		(width 0.12065)
		(layer "In4.Cu")
		(net "BMC_B_TO_EXP_B_RESET_N")
	)
	(segment
		(start 341.572596 -170.808142)
		(end 341.572596 -174.44085)
		(width 0.12065)
		(layer "In4.Cu")
		(net "BMC_B_TO_EXP_B_RESET_N")
	)
	(segment
		(start 340.12505 -163.641278)
		(end 340.12505 -169.360596)
		(width 0.12065)
		(layer "In4.Cu")
		(net "BMC_B_TO_EXP_B_RESET_N")
	)
	(segment
		(start 360.8578 -107.188)
		(end 336.197956 -131.847844)
		(width 0.12065)
		(layer "In4.Cu")
		(net "BMC_B_TO_EXP_B_RESET_N")
	)
	(segment
		(start 211.77123 -387.847332)
		(end 211.54771 -388.070852)
		(width 0.12065)
		(layer "In4.Cu")
		(net "BMC_B_TO_EXP_B_RESET_N")
	)
	(segment
		(start 336.197956 -159.714184)
		(end 340.12505 -163.641278)
		(width 0.12065)
		(layer "In4.Cu")
		(net "BMC_B_TO_EXP_B_RESET_N")
	)
	(segment
		(start 336.197956 -131.847844)
		(end 336.197956 -159.714184)
		(width 0.12065)
		(layer "In4.Cu")
		(net "BMC_B_TO_EXP_B_RESET_N")
	)
	(segment
		(start 239.903 -193.2305)
		(end 233.418888 -193.2305)
		(width 0.12065)
		(layer "In4.Cu")
		(net "BMC_B_TO_EXP_B_RESET_N")
	)
	(segment
		(start 364.149894 -39.841424)
		(end 360.8578 -43.133518)
		(width 0.12065)
		(layer "In4.Cu")
		(net "BMC_B_TO_EXP_B_RESET_N")
	)
	(segment
		(start 211.54771 -388.070852)
		(end 211.54771 -389.024114)
		(width 0.12065)
		(layer "In4.Cu")
		(net "BMC_B_TO_EXP_B_RESET_N")
	)
	(segment
		(start 218.417902 -317.516256)
		(end 211.77123 -324.162928)
		(width 0.12065)
		(layer "In4.Cu")
		(net "BMC_B_TO_EXP_B_RESET_N")
	)
	(segment
		(start 389.349996 -26.950162)
		(end 400.387312 -26.950162)
		(width 0.17145)
		(layer "F.Cu")
		(net "IOM_B_MATED_N")
	)
	(segment
		(start 402.782278 -29.345128)
		(end 402.782278 -30.831028)
		(width 0.17145)
		(layer "F.Cu")
		(net "IOM_B_MATED_N")
	)
	(segment
		(start 400.387312 -26.950162)
		(end 402.782278 -29.345128)
		(width 0.17145)
		(layer "F.Cu")
		(net "IOM_B_MATED_N")
	)
	(segment
		(start 402.782278 -32.068516)
		(end 402.782278 -30.831028)
		(width 0.17145)
		(layer "F.Cu")
		(net "IOM_B_MATED_N")
	)
	(via
		(at 402.782278 -30.831028)
		(size 0.6604)
		(drill 0.3302)
		(layers "F.Cu" "B.Cu")
		(net "IOM_B_MATED_N")
	)
	(segment
		(start 157.898338 -27.338782)
		(end 156.693362 -27.338782)
		(width 0.17145)
		(layer "F.Cu")
		(net "IOM_A_MATED_N")
	)
	(segment
		(start 143.7386 -27.338782)
		(end 156.693362 -27.338782)
		(width 0.17145)
		(layer "F.Cu")
		(net "IOM_A_MATED_N")
	)
	(segment
		(start 143.34998 -26.950162)
		(end 143.7386 -27.338782)
		(width 0.17145)
		(layer "F.Cu")
		(net "IOM_A_MATED_N")
	)
	(via
		(at 156.693362 -27.338782)
		(size 0.6604)
		(drill 0.3302)
		(layers "F.Cu" "B.Cu")
		(net "IOM_A_MATED_N")
	)
	(segment
		(start 277.8506 -282.525216)
		(end 277.556468 -282.819348)
		(width 0.17145)
		(layer "F.Cu")
		(net "FRONT_FAN_LED3")
	)
	(segment
		(start 277.8506 -281.2034)
		(end 277.8506 -282.525216)
		(width 0.17145)
		(layer "F.Cu")
		(net "FRONT_FAN_LED3")
	)
	(via
		(at 277.556468 -282.819348)
		(size 0.5588)
		(drill 0.3048)
		(layers "F.Cu" "B.Cu")
		(net "FRONT_FAN_LED3")
	)
	(via
		(at 245.384574 -312.444638)
		(size 0.6096)
		(drill 0.3048)
		(layers "F.Cu" "B.Cu")
		(net "FRONT_FAN_LED3")
	)
	(segment
		(start 259.354066 -307.901086)
		(end 251.822458 -307.901086)
		(width 0.17145)
		(layer "B.Cu")
		(net "FRONT_FAN_LED3")
	)
	(segment
		(start 278.484076 -288.771076)
		(end 259.354066 -307.901086)
		(width 0.17145)
		(layer "B.Cu")
		(net "FRONT_FAN_LED3")
	)
	(segment
		(start 277.556468 -282.819348)
		(end 277.556468 -284.287468)
		(width 0.17145)
		(layer "B.Cu")
		(net "FRONT_FAN_LED3")
	)
	(segment
		(start 251.822458 -307.901086)
		(end 251.822204 -307.900832)
		(width 0.17145)
		(layer "B.Cu")
		(net "FRONT_FAN_LED3")
	)
	(segment
		(start 232.34396 -408.18816)
		(end 232.34396 -393.527788)
		(width 0.17145)
		(layer "B.Cu")
		(net "FRONT_FAN_LED3")
	)
	(segment
		(start 227.835714 -381.935736)
		(end 227.835714 -374.820688)
		(width 0.17145)
		(layer "B.Cu")
		(net "FRONT_FAN_LED3")
	)
	(segment
		(start 249.92838 -307.900832)
		(end 245.384574 -312.444638)
		(width 0.17145)
		(layer "B.Cu")
		(net "FRONT_FAN_LED3")
	)
	(segment
		(start 232.34396 -393.527788)
		(end 232.524554 -393.347194)
		(width 0.17145)
		(layer "B.Cu")
		(net "FRONT_FAN_LED3")
	)
	(segment
		(start 232.524554 -393.347194)
		(end 232.524554 -386.624322)
		(width 0.17145)
		(layer "B.Cu")
		(net "FRONT_FAN_LED3")
	)
	(segment
		(start 251.822204 -307.900832)
		(end 249.92838 -307.900832)
		(width 0.17145)
		(layer "B.Cu")
		(net "FRONT_FAN_LED3")
	)
	(segment
		(start 232.032048 -408.500072)
		(end 232.34396 -408.18816)
		(width 0.17145)
		(layer "B.Cu")
		(net "FRONT_FAN_LED3")
	)
	(segment
		(start 229.174548 -383.274316)
		(end 229.174294 -383.274316)
		(width 0.17145)
		(layer "B.Cu")
		(net "FRONT_FAN_LED3")
	)
	(segment
		(start 229.174294 -383.274316)
		(end 227.835714 -381.935736)
		(width 0.17145)
		(layer "B.Cu")
		(net "FRONT_FAN_LED3")
	)
	(segment
		(start 218.044776 -365.02975)
		(end 218.044776 -339.784436)
		(width 0.17145)
		(layer "B.Cu")
		(net "FRONT_FAN_LED3")
	)
	(segment
		(start 218.044776 -339.784436)
		(end 245.384574 -312.444638)
		(width 0.17145)
		(layer "B.Cu")
		(net "FRONT_FAN_LED3")
	)
	(segment
		(start 231.599994 -408.500072)
		(end 232.032048 -408.500072)
		(width 0.17145)
		(layer "B.Cu")
		(net "FRONT_FAN_LED3")
	)
	(segment
		(start 278.484076 -285.215076)
		(end 278.484076 -288.771076)
		(width 0.17145)
		(layer "B.Cu")
		(net "FRONT_FAN_LED3")
	)
	(segment
		(start 227.835714 -374.820688)
		(end 218.044776 -365.02975)
		(width 0.17145)
		(layer "B.Cu")
		(net "FRONT_FAN_LED3")
	)
	(segment
		(start 232.524554 -386.624322)
		(end 229.174548 -383.274316)
		(width 0.17145)
		(layer "B.Cu")
		(net "FRONT_FAN_LED3")
	)
	(segment
		(start 277.556468 -284.287468)
		(end 278.484076 -285.215076)
		(width 0.17145)
		(layer "B.Cu")
		(net "FRONT_FAN_LED3")
	)
	(segment
		(start 278.50084 -281.2034)
		(end 278.50084 -283.24175)
		(width 0.17145)
		(layer "F.Cu")
		(net "FRONT_FAN_LED2")
	)
	(via
		(at 278.50084 -283.24175)
		(size 0.5588)
		(drill 0.3048)
		(layers "F.Cu" "B.Cu")
		(net "FRONT_FAN_LED2")
	)
	(via
		(at 239.227614 -319.67932)
		(size 0.6096)
		(drill 0.3048)
		(layers "F.Cu" "B.Cu")
		(net "FRONT_FAN_LED2")
	)
	(segment
		(start 228.597714 -374.504966)
		(end 218.806776 -364.714028)
		(width 0.17145)
		(layer "B.Cu")
		(net "FRONT_FAN_LED2")
	)
	(segment
		(start 233.14152 -408.80284)
		(end 233.14152 -393.80795)
		(width 0.17145)
		(layer "B.Cu")
		(net "FRONT_FAN_LED2")
	)
	(segment
		(start 218.806776 -364.714028)
		(end 218.806776 -340.100158)
		(width 0.17145)
		(layer "B.Cu")
		(net "FRONT_FAN_LED2")
	)
	(segment
		(start 232.344214 -409.600146)
		(end 233.14152 -408.80284)
		(width 0.17145)
		(layer "B.Cu")
		(net "FRONT_FAN_LED2")
	)
	(segment
		(start 233.14152 -393.80795)
		(end 233.934254 -393.015216)
		(width 0.17145)
		(layer "B.Cu")
		(net "FRONT_FAN_LED2")
	)
	(segment
		(start 229.49027 -382.512316)
		(end 229.490016 -382.512316)
		(width 0.17145)
		(layer "B.Cu")
		(net "FRONT_FAN_LED2")
	)
	(segment
		(start 250.244102 -308.662832)
		(end 239.227614 -319.67932)
		(width 0.17145)
		(layer "B.Cu")
		(net "FRONT_FAN_LED2")
	)
	(segment
		(start 278.50084 -283.24175)
		(end 278.50084 -284.34284)
		(width 0.17145)
		(layer "B.Cu")
		(net "FRONT_FAN_LED2")
	)
	(segment
		(start 279.59431 -288.738564)
		(end 260.116066 -308.216808)
		(width 0.17145)
		(layer "B.Cu")
		(net "FRONT_FAN_LED2")
	)
	(segment
		(start 228.597714 -381.620014)
		(end 228.597714 -374.504966)
		(width 0.17145)
		(layer "B.Cu")
		(net "FRONT_FAN_LED2")
	)
	(segment
		(start 278.50084 -284.34284)
		(end 279.59431 -285.43631)
		(width 0.17145)
		(layer "B.Cu")
		(net "FRONT_FAN_LED2")
	)
	(segment
		(start 229.490016 -382.512316)
		(end 228.597714 -381.620014)
		(width 0.17145)
		(layer "B.Cu")
		(net "FRONT_FAN_LED2")
	)
	(segment
		(start 231.599994 -409.600146)
		(end 232.344214 -409.600146)
		(width 0.17145)
		(layer "B.Cu")
		(net "FRONT_FAN_LED2")
	)
	(segment
		(start 218.806776 -340.100158)
		(end 239.227614 -319.67932)
		(width 0.17145)
		(layer "B.Cu")
		(net "FRONT_FAN_LED2")
	)
	(segment
		(start 279.59431 -285.43631)
		(end 279.59431 -288.738564)
		(width 0.17145)
		(layer "B.Cu")
		(net "FRONT_FAN_LED2")
	)
	(segment
		(start 260.116066 -308.217062)
		(end 259.670042 -308.663086)
		(width 0.17145)
		(layer "B.Cu")
		(net "FRONT_FAN_LED2")
	)
	(segment
		(start 259.670042 -308.663086)
		(end 251.506736 -308.663086)
		(width 0.17145)
		(layer "B.Cu")
		(net "FRONT_FAN_LED2")
	)
	(segment
		(start 233.934254 -386.9563)
		(end 229.49027 -382.512316)
		(width 0.17145)
		(layer "B.Cu")
		(net "FRONT_FAN_LED2")
	)
	(segment
		(start 251.506736 -308.663086)
		(end 251.506482 -308.662832)
		(width 0.17145)
		(layer "B.Cu")
		(net "FRONT_FAN_LED2")
	)
	(segment
		(start 260.116066 -308.216808)
		(end 260.116066 -308.217062)
		(width 0.17145)
		(layer "B.Cu")
		(net "FRONT_FAN_LED2")
	)
	(segment
		(start 251.506482 -308.662832)
		(end 250.244102 -308.662832)
		(width 0.17145)
		(layer "B.Cu")
		(net "FRONT_FAN_LED2")
	)
	(segment
		(start 233.934254 -393.015216)
		(end 233.934254 -386.9563)
		(width 0.17145)
		(layer "B.Cu")
		(net "FRONT_FAN_LED2")
	)
	(segment
		(start 279.15108 -281.2034)
		(end 279.15108 -282.518104)
		(width 0.17145)
		(layer "F.Cu")
		(net "FRONT_FAN_LED1")
	)
	(via
		(at 279.15108 -282.518104)
		(size 0.5588)
		(drill 0.3048)
		(layers "F.Cu" "B.Cu")
		(net "FRONT_FAN_LED1")
	)
	(via
		(at 233.820208 -326.164448)
		(size 0.6096)
		(drill 0.3048)
		(layers "F.Cu" "B.Cu")
		(net "FRONT_FAN_LED1")
	)
	(segment
		(start 233.96448 -394.062712)
		(end 234.696254 -393.330938)
		(width 0.17145)
		(layer "B.Cu")
		(net "FRONT_FAN_LED1")
	)
	(segment
		(start 280.450798 -285.276798)
		(end 280.450798 -288.959798)
		(width 0.17145)
		(layer "B.Cu")
		(net "FRONT_FAN_LED1")
	)
	(segment
		(start 229.359714 -374.189244)
		(end 219.568776 -364.398306)
		(width 0.17145)
		(layer "B.Cu")
		(net "FRONT_FAN_LED1")
	)
	(segment
		(start 219.568776 -364.398306)
		(end 219.568776 -340.41588)
		(width 0.17145)
		(layer "B.Cu")
		(net "FRONT_FAN_LED1")
	)
	(segment
		(start 259.986018 -309.424832)
		(end 250.559824 -309.424832)
		(width 0.17145)
		(layer "B.Cu")
		(net "FRONT_FAN_LED1")
	)
	(segment
		(start 280.450798 -288.959798)
		(end 260.878066 -308.53253)
		(width 0.17145)
		(layer "B.Cu")
		(net "FRONT_FAN_LED1")
	)
	(segment
		(start 260.878066 -308.532784)
		(end 259.986018 -309.424832)
		(width 0.17145)
		(layer "B.Cu")
		(net "FRONT_FAN_LED1")
	)
	(segment
		(start 219.568776 -340.41588)
		(end 233.820208 -326.164448)
		(width 0.17145)
		(layer "B.Cu")
		(net "FRONT_FAN_LED1")
	)
	(segment
		(start 233.96448 -409.63596)
		(end 233.96448 -394.062712)
		(width 0.17145)
		(layer "B.Cu")
		(net "FRONT_FAN_LED1")
	)
	(segment
		(start 231.599994 -411.000194)
		(end 232.600246 -411.000194)
		(width 0.17145)
		(layer "B.Cu")
		(net "FRONT_FAN_LED1")
	)
	(segment
		(start 234.696254 -386.640832)
		(end 229.359714 -381.304292)
		(width 0.17145)
		(layer "B.Cu")
		(net "FRONT_FAN_LED1")
	)
	(segment
		(start 229.359714 -381.304292)
		(end 229.359714 -374.189244)
		(width 0.17145)
		(layer "B.Cu")
		(net "FRONT_FAN_LED1")
	)
	(segment
		(start 279.15108 -282.518104)
		(end 279.15108 -283.97708)
		(width 0.17145)
		(layer "B.Cu")
		(net "FRONT_FAN_LED1")
	)
	(segment
		(start 234.696254 -393.330938)
		(end 234.696254 -386.640832)
		(width 0.17145)
		(layer "B.Cu")
		(net "FRONT_FAN_LED1")
	)
	(segment
		(start 250.559824 -309.424832)
		(end 233.820208 -326.164448)
		(width 0.17145)
		(layer "B.Cu")
		(net "FRONT_FAN_LED1")
	)
	(segment
		(start 260.878066 -308.53253)
		(end 260.878066 -308.532784)
		(width 0.17145)
		(layer "B.Cu")
		(net "FRONT_FAN_LED1")
	)
	(segment
		(start 279.15108 -283.97708)
		(end 280.450798 -285.276798)
		(width 0.17145)
		(layer "B.Cu")
		(net "FRONT_FAN_LED1")
	)
	(segment
		(start 232.600246 -411.000194)
		(end 233.96448 -409.63596)
		(width 0.17145)
		(layer "B.Cu")
		(net "FRONT_FAN_LED1")
	)
	(segment
		(start 279.80132 -281.2034)
		(end 279.80132 -282.484068)
		(width 0.17145)
		(layer "F.Cu")
		(net "FRONT_FAN_LED0")
	)
	(segment
		(start 279.80132 -282.484068)
		(end 280.178256 -282.861004)
		(width 0.17145)
		(layer "F.Cu")
		(net "FRONT_FAN_LED0")
	)
	(via
		(at 229.498906 -331.563472)
		(size 0.6096)
		(drill 0.3048)
		(layers "F.Cu" "B.Cu")
		(net "FRONT_FAN_LED0")
	)
	(via
		(at 280.178256 -282.861004)
		(size 0.5588)
		(drill 0.3048)
		(layers "F.Cu" "B.Cu")
		(net "FRONT_FAN_LED0")
	)
	(segment
		(start 260.301486 -310.187086)
		(end 250.875292 -310.187086)
		(width 0.17145)
		(layer "B.Cu")
		(net "FRONT_FAN_LED0")
	)
	(segment
		(start 235.458254 -386.324856)
		(end 230.121714 -380.988316)
		(width 0.17145)
		(layer "B.Cu")
		(net "FRONT_FAN_LED0")
	)
	(segment
		(start 220.309948 -340.75243)
		(end 229.498906 -331.563472)
		(width 0.17145)
		(layer "B.Cu")
		(net "FRONT_FAN_LED0")
	)
	(segment
		(start 230.121714 -380.988316)
		(end 230.121714 -373.873522)
		(width 0.17145)
		(layer "B.Cu")
		(net "FRONT_FAN_LED0")
	)
	(segment
		(start 235.458254 -393.64666)
		(end 235.458254 -386.324856)
		(width 0.17145)
		(layer "B.Cu")
		(net "FRONT_FAN_LED0")
	)
	(segment
		(start 261.640066 -308.848506)
		(end 260.301486 -310.187086)
		(width 0.17145)
		(layer "B.Cu")
		(net "FRONT_FAN_LED0")
	)
	(segment
		(start 280.178256 -282.861004)
		(end 280.178256 -283.861256)
		(width 0.17145)
		(layer "B.Cu")
		(net "FRONT_FAN_LED0")
	)
	(segment
		(start 281.370532 -285.053532)
		(end 281.370532 -289.117786)
		(width 0.17145)
		(layer "B.Cu")
		(net "FRONT_FAN_LED0")
	)
	(segment
		(start 234.7722 -394.332714)
		(end 235.458254 -393.64666)
		(width 0.17145)
		(layer "B.Cu")
		(net "FRONT_FAN_LED0")
	)
	(segment
		(start 231.599994 -412.100014)
		(end 232.709466 -412.100014)
		(width 0.17145)
		(layer "B.Cu")
		(net "FRONT_FAN_LED0")
	)
	(segment
		(start 230.121714 -373.873522)
		(end 220.309948 -364.061756)
		(width 0.17145)
		(layer "B.Cu")
		(net "FRONT_FAN_LED0")
	)
	(segment
		(start 280.178256 -283.861256)
		(end 281.370532 -285.053532)
		(width 0.17145)
		(layer "B.Cu")
		(net "FRONT_FAN_LED0")
	)
	(segment
		(start 234.7722 -410.03728)
		(end 234.7722 -394.332714)
		(width 0.17145)
		(layer "B.Cu")
		(net "FRONT_FAN_LED0")
	)
	(segment
		(start 281.370532 -289.117786)
		(end 261.640066 -308.848252)
		(width 0.17145)
		(layer "B.Cu")
		(net "FRONT_FAN_LED0")
	)
	(segment
		(start 250.875292 -310.187086)
		(end 229.498906 -331.563472)
		(width 0.17145)
		(layer "B.Cu")
		(net "FRONT_FAN_LED0")
	)
	(segment
		(start 261.640066 -308.848252)
		(end 261.640066 -308.848506)
		(width 0.17145)
		(layer "B.Cu")
		(net "FRONT_FAN_LED0")
	)
	(segment
		(start 220.309948 -364.061756)
		(end 220.309948 -340.75243)
		(width 0.17145)
		(layer "B.Cu")
		(net "FRONT_FAN_LED0")
	)
	(segment
		(start 232.709466 -412.100014)
		(end 234.7722 -410.03728)
		(width 0.17145)
		(layer "B.Cu")
		(net "FRONT_FAN_LED0")
	)
	(segment
		(start 215.394032 -388.145274)
		(end 216.940384 -388.145274)
		(width 0.17145)
		(layer "F.Cu")
		(net "SCC_B_RESET_N")
	)
	(segment
		(start 218.15806 -408.758136)
		(end 219.00007 -409.600146)
		(width 0.17145)
		(layer "F.Cu")
		(net "SCC_B_RESET_N")
	)
	(segment
		(start 217.767662 -388.972552)
		(end 217.767662 -391.818368)
		(width 0.17145)
		(layer "F.Cu")
		(net "SCC_B_RESET_N")
	)
	(segment
		(start 218.15806 -392.208766)
		(end 218.15806 -408.758136)
		(width 0.17145)
		(layer "F.Cu")
		(net "SCC_B_RESET_N")
	)
	(segment
		(start 217.767662 -391.818368)
		(end 218.15806 -392.208766)
		(width 0.17145)
		(layer "F.Cu")
		(net "SCC_B_RESET_N")
	)
	(segment
		(start 217.398346 -388.603236)
		(end 217.767662 -388.972552)
		(width 0.17145)
		(layer "F.Cu")
		(net "SCC_B_RESET_N")
	)
	(segment
		(start 216.940384 -388.145274)
		(end 217.398346 -388.603236)
		(width 0.17145)
		(layer "F.Cu")
		(net "SCC_B_RESET_N")
	)
	(via
		(at 217.398346 -388.603236)
		(size 0.6604)
		(drill 0.3302)
		(layers "F.Cu" "B.Cu")
		(net "SCC_B_RESET_N")
	)
	(segment
		(start 247.14073 -295.32453)
		(end 247.14073 -296.075862)
		(width 0.17145)
		(layer "F.Cu")
		(net "BMC_A_TO_EXP_A_RESET_N")
	)
	(segment
		(start 245.212616 -290.983416)
		(end 242.41633 -290.983416)
		(width 0.17145)
		(layer "F.Cu")
		(net "BMC_A_TO_EXP_A_RESET_N")
	)
	(segment
		(start 246.0752 -294.259)
		(end 246.03456 -294.21836)
		(width 0.17145)
		(layer "F.Cu")
		(net "BMC_A_TO_EXP_A_RESET_N")
	)
	(segment
		(start 246.03456 -292.989)
		(end 246.03456 -291.80536)
		(width 0.17145)
		(layer "F.Cu")
		(net "BMC_A_TO_EXP_A_RESET_N")
	)
	(segment
		(start 246.03456 -294.21836)
		(end 246.03456 -292.989)
		(width 0.17145)
		(layer "F.Cu")
		(net "BMC_A_TO_EXP_A_RESET_N")
	)
	(segment
		(start 246.0752 -294.259)
		(end 247.14073 -295.32453)
		(width 0.17145)
		(layer "F.Cu")
		(net "BMC_A_TO_EXP_A_RESET_N")
	)
	(segment
		(start 246.03456 -291.80536)
		(end 245.212616 -290.983416)
		(width 0.17145)
		(layer "F.Cu")
		(net "BMC_A_TO_EXP_A_RESET_N")
	)
	(via
		(at 246.0752 -294.259)
		(size 0.6604)
		(drill 0.3302)
		(layers "F.Cu" "B.Cu")
		(net "BMC_A_TO_EXP_A_RESET_N")
	)
	(via
		(at 204.073252 -289.4838)
		(size 0.5588)
		(drill 0.3048)
		(layers "F.Cu" "B.Cu")
		(net "BMC_A_TO_EXP_A_RESET_N")
	)
	(via
		(at 221.690184 -63.935356)
		(size 0.5588)
		(drill 0.3048)
		(layers "F.Cu" "B.Cu")
		(net "BMC_A_TO_EXP_A_RESET_N")
	)
	(via
		(at 242.41633 -290.983416)
		(size 0.5588)
		(drill 0.3048)
		(layers "F.Cu" "B.Cu")
		(net "BMC_A_TO_EXP_A_RESET_N")
	)
	(segment
		(start 204.073252 -289.4838)
		(end 205.572868 -290.983416)
		(width 0.13335)
		(layer "In2.Cu")
		(net "BMC_A_TO_EXP_A_RESET_N")
	)
	(segment
		(start 205.572868 -290.983416)
		(end 242.41633 -290.983416)
		(width 0.13335)
		(layer "In2.Cu")
		(net "BMC_A_TO_EXP_A_RESET_N")
	)
	(segment
		(start 214.090758 -89.185242)
		(end 215.222836 -88.053164)
		(width 0.12065)
		(layer "In4.Cu")
		(net "BMC_A_TO_EXP_A_RESET_N")
	)
	(segment
		(start 219.391484 -143.851376)
		(end 216.332054 -140.791946)
		(width 0.12065)
		(layer "In4.Cu")
		(net "BMC_A_TO_EXP_A_RESET_N")
	)
	(segment
		(start 219.121736 -71.255128)
		(end 221.690184 -68.68668)
		(width 0.12065)
		(layer "In4.Cu")
		(net "BMC_A_TO_EXP_A_RESET_N")
	)
	(segment
		(start 211.146644 -280.277316)
		(end 211.146644 -204.538326)
		(width 0.12065)
		(layer "In4.Cu")
		(net "BMC_A_TO_EXP_A_RESET_N")
	)
	(segment
		(start 215.222836 -88.053164)
		(end 215.222836 -81.28508)
		(width 0.12065)
		(layer "In4.Cu")
		(net "BMC_A_TO_EXP_A_RESET_N")
	)
	(segment
		(start 215.222836 -81.28508)
		(end 219.121736 -77.38618)
		(width 0.12065)
		(layer "In4.Cu")
		(net "BMC_A_TO_EXP_A_RESET_N")
	)
	(segment
		(start 219.391484 -196.293486)
		(end 219.391484 -143.851376)
		(width 0.12065)
		(layer "In4.Cu")
		(net "BMC_A_TO_EXP_A_RESET_N")
	)
	(segment
		(start 216.332054 -123.52782)
		(end 214.090758 -121.286524)
		(width 0.12065)
		(layer "In4.Cu")
		(net "BMC_A_TO_EXP_A_RESET_N")
	)
	(segment
		(start 204.073252 -289.4838)
		(end 204.073252 -287.350708)
		(width 0.12065)
		(layer "In4.Cu")
		(net "BMC_A_TO_EXP_A_RESET_N")
	)
	(segment
		(start 216.332054 -140.791946)
		(end 216.332054 -123.52782)
		(width 0.12065)
		(layer "In4.Cu")
		(net "BMC_A_TO_EXP_A_RESET_N")
	)
	(segment
		(start 204.073252 -287.350708)
		(end 211.146644 -280.277316)
		(width 0.12065)
		(layer "In4.Cu")
		(net "BMC_A_TO_EXP_A_RESET_N")
	)
	(segment
		(start 211.146644 -204.538326)
		(end 219.391484 -196.293486)
		(width 0.12065)
		(layer "In4.Cu")
		(net "BMC_A_TO_EXP_A_RESET_N")
	)
	(segment
		(start 219.121736 -77.38618)
		(end 219.121736 -71.255128)
		(width 0.12065)
		(layer "In4.Cu")
		(net "BMC_A_TO_EXP_A_RESET_N")
	)
	(segment
		(start 221.690184 -68.68668)
		(end 221.690184 -63.935356)
		(width 0.12065)
		(layer "In4.Cu")
		(net "BMC_A_TO_EXP_A_RESET_N")
	)
	(segment
		(start 214.090758 -121.286524)
		(end 214.090758 -89.185242)
		(width 0.12065)
		(layer "In4.Cu")
		(net "BMC_A_TO_EXP_A_RESET_N")
	)
	(segment
		(start 143.271748 -38.932358)
		(end 144.717008 -40.377618)
		(width 0.12065)
		(layer "In7.Cu")
		(net "BMC_A_TO_EXP_A_RESET_N")
	)
	(segment
		(start 182.701692 -24.946864)
		(end 221.690184 -63.935356)
		(width 0.12065)
		(layer "In7.Cu")
		(net "BMC_A_TO_EXP_A_RESET_N")
	)
	(segment
		(start 144.717008 -40.377618)
		(end 155.47086 -40.377618)
		(width 0.12065)
		(layer "In7.Cu")
		(net "BMC_A_TO_EXP_A_RESET_N")
	)
	(segment
		(start 126.532132 -38.932358)
		(end 143.271748 -38.932358)
		(width 0.12065)
		(layer "In7.Cu")
		(net "BMC_A_TO_EXP_A_RESET_N")
	)
	(segment
		(start 155.47086 -40.377618)
		(end 170.901614 -24.946864)
		(width 0.12065)
		(layer "In7.Cu")
		(net "BMC_A_TO_EXP_A_RESET_N")
	)
	(segment
		(start 170.901614 -24.946864)
		(end 182.701692 -24.946864)
		(width 0.12065)
		(layer "In7.Cu")
		(net "BMC_A_TO_EXP_A_RESET_N")
	)
	(segment
		(start 118.149878 -30.550104)
		(end 126.532132 -38.932358)
		(width 0.12065)
		(layer "In7.Cu")
		(net "BMC_A_TO_EXP_A_RESET_N")
	)
	(via
		(at 472.58478 -237.949486)
		(size 0.6096)
		(drill 0.3048)
		(layers "F.Cu" "B.Cu")
		(net "P12V_A_VIN_U27")
	)
	(via
		(at 441.671202 -250.24715)
		(size 0.5588)
		(drill 0.3048)
		(layers "F.Cu" "B.Cu")
		(net "P12V_A_VIN_U22")
	)
	(via
		(at 441.544202 -249.23115)
		(size 0.6604)
		(drill 0.3302)
		(layers "F.Cu" "B.Cu")
		(net "P12V_A_VIN_U22")
	)
	(via
		(at 442.052202 -251.26315)
		(size 0.5588)
		(drill 0.3048)
		(layers "F.Cu" "B.Cu")
		(net "P12V_A_VIN_U22")
	)
	(via
		(at 41.976802 -143.56715)
		(size 0.5588)
		(drill 0.3048)
		(layers "F.Cu" "B.Cu")
		(net "P12V_A_VIN_U21")
	)
	(via
		(at 41.595802 -142.55115)
		(size 0.5588)
		(drill 0.3048)
		(layers "F.Cu" "B.Cu")
		(net "P12V_A_VIN_U21")
	)
	(via
		(at 41.468802 -141.53515)
		(size 0.6604)
		(drill 0.3302)
		(layers "F.Cu" "B.Cu")
		(net "P12V_A_VIN_U21")
	)
	(via
		(at 25.035002 -248.21515)
		(size 0.5588)
		(drill 0.3048)
		(layers "F.Cu" "B.Cu")
		(net "P12V_A_VIN_U20")
	)
	(via
		(at 24.527002 -246.18315)
		(size 0.6604)
		(drill 0.3302)
		(layers "F.Cu" "B.Cu")
		(net "P12V_A_VIN_U20")
	)
	(via
		(at 24.654002 -247.19915)
		(size 0.5588)
		(drill 0.3048)
		(layers "F.Cu" "B.Cu")
		(net "P12V_A_VIN_U20")
	)
	(via
		(at 480.688142 -239.439196)
		(size 0.6096)
		(drill 0.3048)
		(layers "F.Cu" "B.Cu")
		(net "P12V_A_VDD_U27")
	)
	(segment
		(start 476.951548 -236.971078)
		(end 478.231454 -238.250984)
		(width 0.3048)
		(layer "B.Cu")
		(net "P12V_A_VDD_U27")
	)
	(segment
		(start 480.688142 -239.439196)
		(end 480.688142 -238.900208)
		(width 0.508)
		(layer "B.Cu")
		(net "P12V_A_VDD_U27")
	)
	(segment
		(start 475.542102 -235.997242)
		(end 476.515938 -236.971078)
		(width 0.3048)
		(layer "B.Cu")
		(net "P12V_A_VDD_U27")
	)
	(segment
		(start 480.688142 -238.900208)
		(end 480.038918 -238.250984)
		(width 0.508)
		(layer "B.Cu")
		(net "P12V_A_VDD_U27")
	)
	(segment
		(start 480.688142 -242.397788)
		(end 480.688142 -239.439196)
		(width 0.508)
		(layer "B.Cu")
		(net "P12V_A_VDD_U27")
	)
	(segment
		(start 477.97593 -245.11)
		(end 480.688142 -242.397788)
		(width 0.508)
		(layer "B.Cu")
		(net "P12V_A_VDD_U27")
	)
	(segment
		(start 472.948 -245.11)
		(end 477.97593 -245.11)
		(width 0.508)
		(layer "B.Cu")
		(net "P12V_A_VDD_U27")
	)
	(segment
		(start 476.515938 -236.971078)
		(end 476.951548 -236.971078)
		(width 0.3048)
		(layer "B.Cu")
		(net "P12V_A_VDD_U27")
	)
	(segment
		(start 475.542102 -235.128308)
		(end 475.542102 -235.997242)
		(width 0.3048)
		(layer "B.Cu")
		(net "P12V_A_VDD_U27")
	)
	(segment
		(start 480.038918 -238.250984)
		(end 478.231454 -238.250984)
		(width 0.508)
		(layer "B.Cu")
		(net "P12V_A_VDD_U27")
	)
	(via
		(at 436.798974 -257.886454)
		(size 0.6096)
		(drill 0.3048)
		(layers "F.Cu" "B.Cu")
		(net "P12V_A_VDD_U22")
	)
	(segment
		(start 440.812174 -256.662174)
		(end 439.587894 -257.886454)
		(width 0.508)
		(layer "B.Cu")
		(net "P12V_A_VDD_U22")
	)
	(segment
		(start 440.812174 -256.172716)
		(end 442.01334 -254.97155)
		(width 0.3048)
		(layer "B.Cu")
		(net "P12V_A_VDD_U22")
	)
	(segment
		(start 439.587894 -257.886454)
		(end 436.798974 -257.886454)
		(width 0.508)
		(layer "B.Cu")
		(net "P12V_A_VDD_U22")
	)
	(segment
		(start 442.01334 -254.97155)
		(end 442.01334 -253.452376)
		(width 0.3048)
		(layer "B.Cu")
		(net "P12V_A_VDD_U22")
	)
	(segment
		(start 442.700918 -252.764798)
		(end 443.981078 -252.764798)
		(width 0.3048)
		(layer "B.Cu")
		(net "P12V_A_VDD_U22")
	)
	(segment
		(start 442.01334 -253.452376)
		(end 442.700918 -252.764798)
		(width 0.3048)
		(layer "B.Cu")
		(net "P12V_A_VDD_U22")
	)
	(segment
		(start 436.798974 -257.886454)
		(end 433.88661 -257.886454)
		(width 0.508)
		(layer "B.Cu")
		(net "P12V_A_VDD_U22")
	)
	(segment
		(start 440.812174 -256.172716)
		(end 440.812174 -256.662174)
		(width 0.508)
		(layer "B.Cu")
		(net "P12V_A_VDD_U22")
	)
	(segment
		(start 433.88661 -257.886454)
		(end 432.501294 -256.501138)
		(width 0.508)
		(layer "B.Cu")
		(net "P12V_A_VDD_U22")
	)
	(via
		(at 37.150802 -147.947888)
		(size 0.6096)
		(drill 0.3048)
		(layers "F.Cu" "B.Cu")
		(net "P12V_A_VDD_U21")
	)
	(segment
		(start 37.150802 -147.947888)
		(end 39.882064 -147.947888)
		(width 0.508)
		(layer "B.Cu")
		(net "P12V_A_VDD_U21")
	)
	(segment
		(start 41.164002 -146.66595)
		(end 41.164002 -146.23415)
		(width 0.508)
		(layer "B.Cu")
		(net "P12V_A_VDD_U21")
	)
	(segment
		(start 32.959802 -142.42415)
		(end 32.959802 -144.71015)
		(width 0.508)
		(layer "B.Cu")
		(net "P12V_A_VDD_U21")
	)
	(segment
		(start 42.611802 -145.21815)
		(end 42.887392 -145.21815)
		(width 0.3048)
		(layer "B.Cu")
		(net "P12V_A_VDD_U21")
	)
	(segment
		(start 41.799002 -145.59915)
		(end 42.230802 -145.59915)
		(width 0.3048)
		(layer "B.Cu")
		(net "P12V_A_VDD_U21")
	)
	(segment
		(start 42.887392 -145.21815)
		(end 43.036744 -145.068798)
		(width 0.3048)
		(layer "B.Cu")
		(net "P12V_A_VDD_U21")
	)
	(segment
		(start 32.959802 -144.71015)
		(end 36.19754 -147.947888)
		(width 0.508)
		(layer "B.Cu")
		(net "P12V_A_VDD_U21")
	)
	(segment
		(start 39.882064 -147.947888)
		(end 41.164002 -146.66595)
		(width 0.508)
		(layer "B.Cu")
		(net "P12V_A_VDD_U21")
	)
	(segment
		(start 36.19754 -147.947888)
		(end 37.150802 -147.947888)
		(width 0.508)
		(layer "B.Cu")
		(net "P12V_A_VDD_U21")
	)
	(segment
		(start 42.230802 -145.59915)
		(end 42.611802 -145.21815)
		(width 0.3048)
		(layer "B.Cu")
		(net "P12V_A_VDD_U21")
	)
	(segment
		(start 41.164002 -146.23415)
		(end 41.799002 -145.59915)
		(width 0.3048)
		(layer "B.Cu")
		(net "P12V_A_VDD_U21")
	)
	(segment
		(start 43.036744 -145.068798)
		(end 43.905678 -145.068798)
		(width 0.3048)
		(layer "B.Cu")
		(net "P12V_A_VDD_U21")
	)
	(via
		(at 20.209002 -252.595888)
		(size 0.6096)
		(drill 0.3048)
		(layers "F.Cu" "B.Cu")
		(net "P12V_A_VDD_U20")
	)
	(segment
		(start 17.93494 -252.595888)
		(end 20.209002 -252.595888)
		(width 0.508)
		(layer "B.Cu")
		(net "P12V_A_VDD_U20")
	)
	(segment
		(start 20.209002 -252.595888)
		(end 22.940264 -252.595888)
		(width 0.508)
		(layer "B.Cu")
		(net "P12V_A_VDD_U20")
	)
	(segment
		(start 25.289002 -250.24715)
		(end 25.670002 -249.86615)
		(width 0.3048)
		(layer "B.Cu")
		(net "P12V_A_VDD_U20")
	)
	(segment
		(start 26.094944 -249.716798)
		(end 26.963878 -249.716798)
		(width 0.3048)
		(layer "B.Cu")
		(net "P12V_A_VDD_U20")
	)
	(segment
		(start 24.222202 -250.88215)
		(end 24.857202 -250.24715)
		(width 0.3048)
		(layer "B.Cu")
		(net "P12V_A_VDD_U20")
	)
	(segment
		(start 24.222202 -251.31395)
		(end 24.222202 -250.88215)
		(width 0.508)
		(layer "B.Cu")
		(net "P12V_A_VDD_U20")
	)
	(segment
		(start 22.940264 -252.595888)
		(end 24.222202 -251.31395)
		(width 0.508)
		(layer "B.Cu")
		(net "P12V_A_VDD_U20")
	)
	(segment
		(start 25.670002 -249.86615)
		(end 25.945592 -249.86615)
		(width 0.3048)
		(layer "B.Cu")
		(net "P12V_A_VDD_U20")
	)
	(segment
		(start 16.119602 -250.78055)
		(end 17.93494 -252.595888)
		(width 0.508)
		(layer "B.Cu")
		(net "P12V_A_VDD_U20")
	)
	(segment
		(start 25.945592 -249.86615)
		(end 26.094944 -249.716798)
		(width 0.3048)
		(layer "B.Cu")
		(net "P12V_A_VDD_U20")
	)
	(segment
		(start 24.857202 -250.24715)
		(end 25.289002 -250.24715)
		(width 0.3048)
		(layer "B.Cu")
		(net "P12V_A_VDD_U20")
	)
	(segment
		(start 298.831 -286.258)
		(end 298.831 -291.275262)
		(width 0.17145)
		(layer "F.Cu")
		(net "SCC_A_HS_EN")
	)
	(segment
		(start 298.831 -284.5435)
		(end 298.831 -286.258)
		(width 0.17145)
		(layer "F.Cu")
		(net "SCC_A_HS_EN")
	)
	(segment
		(start 298.831 -291.275262)
		(end 294.531542 -295.57472)
		(width 0.17145)
		(layer "F.Cu")
		(net "SCC_A_HS_EN")
	)
	(segment
		(start 284.106112 -295.57472)
		(end 283.23667 -294.705278)
		(width 0.17145)
		(layer "F.Cu")
		(net "SCC_A_HS_EN")
	)
	(segment
		(start 294.531542 -295.57472)
		(end 284.106112 -295.57472)
		(width 0.17145)
		(layer "F.Cu")
		(net "SCC_A_HS_EN")
	)
	(via
		(at 298.831 -286.258)
		(size 0.6604)
		(drill 0.3302)
		(layers "F.Cu" "B.Cu")
		(net "SCC_A_HS_EN")
	)
	(segment
		(start 280.137362 -144.499838)
		(end 279.137364 -145.499836)
		(width 0.17145)
		(layer "F.Cu")
		(net "TP_SMB_COMP_B_NIC_SDA")
	)
	(segment
		(start 276.771862 -145.858738)
		(end 267.00099 -145.858738)
		(width 0.17145)
		(layer "F.Cu")
		(net "TP_SMB_COMP_B_NIC_SDA")
	)
	(segment
		(start 279.137364 -145.499836)
		(end 277.130764 -145.499836)
		(width 0.17145)
		(layer "F.Cu")
		(net "TP_SMB_COMP_B_NIC_SDA")
	)
	(segment
		(start 285.249874 -144.499838)
		(end 280.137362 -144.499838)
		(width 0.17145)
		(layer "F.Cu")
		(net "TP_SMB_COMP_B_NIC_SDA")
	)
	(segment
		(start 277.130764 -145.499836)
		(end 276.771862 -145.858738)
		(width 0.17145)
		(layer "F.Cu")
		(net "TP_SMB_COMP_B_NIC_SDA")
	)
	(segment
		(start 281.962352 -143.49984)
		(end 281.105102 -142.64259)
		(width 0.17145)
		(layer "F.Cu")
		(net "TP_SMB_COMP_B_NIC_SCL")
	)
	(segment
		(start 281.105102 -142.64259)
		(end 280.297128 -142.64259)
		(width 0.17145)
		(layer "F.Cu")
		(net "TP_SMB_COMP_B_NIC_SCL")
	)
	(segment
		(start 279.419304 -143.520414)
		(end 276.7076 -143.520414)
		(width 0.17145)
		(layer "F.Cu")
		(net "TP_SMB_COMP_B_NIC_SCL")
	)
	(segment
		(start 275.879814 -144.3482)
		(end 267.0048 -144.3482)
		(width 0.17145)
		(layer "F.Cu")
		(net "TP_SMB_COMP_B_NIC_SCL")
	)
	(segment
		(start 276.7076 -143.520414)
		(end 275.879814 -144.3482)
		(width 0.17145)
		(layer "F.Cu")
		(net "TP_SMB_COMP_B_NIC_SCL")
	)
	(segment
		(start 280.297128 -142.64259)
		(end 279.419304 -143.520414)
		(width 0.17145)
		(layer "F.Cu")
		(net "TP_SMB_COMP_B_NIC_SCL")
	)
	(segment
		(start 283.249878 -143.49984)
		(end 281.962352 -143.49984)
		(width 0.17145)
		(layer "F.Cu")
		(net "TP_SMB_COMP_B_NIC_SCL")
	)
	(segment
		(start 278.750014 -142.499842)
		(end 278.408892 -142.840964)
		(width 0.17145)
		(layer "F.Cu")
		(net "TP_SMB_COMP_B_NIC_ALERT_N")
	)
	(segment
		(start 278.408892 -142.840964)
		(end 266.999974 -142.840964)
		(width 0.17145)
		(layer "F.Cu")
		(net "TP_SMB_COMP_B_NIC_ALERT_N")
	)
	(segment
		(start 242.549934 -144.499838)
		(end 237.566962 -144.499838)
		(width 0.17145)
		(layer "F.Cu")
		(net "TP_SMB_COMP_A_NIC_SDA")
	)
	(segment
		(start 237.566962 -144.499838)
		(end 236.5502 -145.5166)
		(width 0.17145)
		(layer "F.Cu")
		(net "TP_SMB_COMP_A_NIC_SDA")
	)
	(segment
		(start 231.164638 -149.120098)
		(end 224.553526 -149.120098)
		(width 0.17145)
		(layer "F.Cu")
		(net "TP_SMB_COMP_A_NIC_SDA")
	)
	(segment
		(start 234.768136 -145.5166)
		(end 231.164638 -149.120098)
		(width 0.17145)
		(layer "F.Cu")
		(net "TP_SMB_COMP_A_NIC_SDA")
	)
	(segment
		(start 236.5502 -145.5166)
		(end 234.768136 -145.5166)
		(width 0.17145)
		(layer "F.Cu")
		(net "TP_SMB_COMP_A_NIC_SDA")
	)
	(segment
		(start 245.989602 -147.639278)
		(end 254.750316 -147.639278)
		(width 0.17145)
		(layer "F.Cu")
		(net "TP_SMB_COMP_A_NIC_SCL")
	)
	(segment
		(start 243.50091 -144.238472)
		(end 243.50091 -145.150586)
		(width 0.17145)
		(layer "F.Cu")
		(net "TP_SMB_COMP_A_NIC_SCL")
	)
	(segment
		(start 240.549938 -143.49984)
		(end 242.762278 -143.49984)
		(width 0.17145)
		(layer "F.Cu")
		(net "TP_SMB_COMP_A_NIC_SCL")
	)
	(segment
		(start 242.762278 -143.49984)
		(end 243.50091 -144.238472)
		(width 0.17145)
		(layer "F.Cu")
		(net "TP_SMB_COMP_A_NIC_SCL")
	)
	(segment
		(start 254.750316 -147.639278)
		(end 255.309878 -147.079716)
		(width 0.17145)
		(layer "F.Cu")
		(net "TP_SMB_COMP_A_NIC_SCL")
	)
	(segment
		(start 243.50091 -145.150586)
		(end 245.989602 -147.639278)
		(width 0.17145)
		(layer "F.Cu")
		(net "TP_SMB_COMP_A_NIC_SCL")
	)
	(segment
		(start 235.423964 -142.499842)
		(end 232.16362 -139.239498)
		(width 0.17145)
		(layer "F.Cu")
		(net "TP_SMB_COMP_A_NIC_ALERT_N")
	)
	(segment
		(start 236.050074 -142.499842)
		(end 235.423964 -142.499842)
		(width 0.17145)
		(layer "F.Cu")
		(net "TP_SMB_COMP_A_NIC_ALERT_N")
	)
	(segment
		(start 232.16362 -139.239498)
		(end 224.528126 -139.239498)
		(width 0.17145)
		(layer "F.Cu")
		(net "TP_SMB_COMP_A_NIC_ALERT_N")
	)
	(segment
		(start 272.299684 -135.979916)
		(end 267.866876 -135.979916)
		(width 0.1651)
		(layer "F.Cu")
		(net "TP_PCIE_COMP_B_CLK_1_DP")
	)
	(segment
		(start 283.249878 -135.499856)
		(end 283.971238 -135.86079)
		(width 0.1651)
		(layer "F.Cu")
		(net "TP_PCIE_COMP_B_CLK_1_DP")
	)
	(segment
		(start 280.24455 -134.645908)
		(end 279.244552 -135.645906)
		(width 0.1651)
		(layer "F.Cu")
		(net "TP_PCIE_COMP_B_CLK_1_DP")
	)
	(segment
		(start 284.162246 -135.829294)
		(end 284.162246 -135.821928)
		(width 0.1651)
		(layer "F.Cu")
		(net "TP_PCIE_COMP_B_CLK_1_DP")
	)
	(segment
		(start 279.244552 -135.645906)
		(end 272.633694 -135.645906)
		(width 0.1651)
		(layer "F.Cu")
		(net "TP_PCIE_COMP_B_CLK_1_DP")
	)
	(segment
		(start 284.376876 -135.248142)
		(end 283.774642 -134.645908)
		(width 0.1651)
		(layer "F.Cu")
		(net "TP_PCIE_COMP_B_CLK_1_DP")
	)
	(segment
		(start 272.633694 -135.645906)
		(end 272.299684 -135.979916)
		(width 0.1651)
		(layer "F.Cu")
		(net "TP_PCIE_COMP_B_CLK_1_DP")
	)
	(segment
		(start 267.866876 -135.979916)
		(end 267.174726 -136.672066)
		(width 0.1651)
		(layer "F.Cu")
		(net "TP_PCIE_COMP_B_CLK_1_DP")
	)
	(segment
		(start 283.774642 -134.645908)
		(end 280.24455 -134.645908)
		(width 0.1651)
		(layer "F.Cu")
		(net "TP_PCIE_COMP_B_CLK_1_DP")
	)
	(segment
		(start 284.162246 -135.821928)
		(end 284.376876 -135.526272)
		(width 0.1651)
		(layer "F.Cu")
		(net "TP_PCIE_COMP_B_CLK_1_DP")
	)
	(arc
		(start 283.971238 -135.86079)
		(mid 284.071817 -135.875941)
		(end 284.162246 -135.829294)
		(width 0.1651)
		(layer "F.Cu")
		(net "TP_PCIE_COMP_B_CLK_1_DP")
	)
	(arc
		(start 284.376876 -135.526272)
		(mid 284.434426 -135.387244)
		(end 284.376876 -135.248142)
		(width 0.1651)
		(layer "F.Cu")
		(net "TP_PCIE_COMP_B_CLK_1_DP")
	)
	(segment
		(start 284.583632 -135.041386)
		(end 284.217872 -134.67588)
		(width 0.1651)
		(layer "F.Cu")
		(net "TP_PCIE_COMP_B_CLK_1_DN")
	)
	(segment
		(start 284.454346 -135.917178)
		(end 284.454346 -135.916924)
		(width 0.1651)
		(layer "F.Cu")
		(net "TP_PCIE_COMP_B_CLK_1_DN")
	)
	(segment
		(start 283.8958 -134.353808)
		(end 280.123392 -134.353808)
		(width 0.1651)
		(layer "F.Cu")
		(net "TP_PCIE_COMP_B_CLK_1_DN")
	)
	(segment
		(start 284.535118 -135.805926)
		(end 284.602936 -135.712454)
		(width 0.1651)
		(layer "F.Cu")
		(net "TP_PCIE_COMP_B_CLK_1_DN")
	)
	(segment
		(start 272.178526 -135.687816)
		(end 267.866876 -135.687816)
		(width 0.1651)
		(layer "F.Cu")
		(net "TP_PCIE_COMP_B_CLK_1_DN")
	)
	(segment
		(start 280.123392 -134.353808)
		(end 279.123394 -135.353806)
		(width 0.1651)
		(layer "F.Cu")
		(net "TP_PCIE_COMP_B_CLK_1_DN")
	)
	(segment
		(start 285.249874 -136.499854)
		(end 284.528006 -136.138666)
		(width 0.1651)
		(layer "F.Cu")
		(net "TP_PCIE_COMP_B_CLK_1_DN")
	)
	(segment
		(start 267.866876 -135.687816)
		(end 267.174726 -134.995666)
		(width 0.1651)
		(layer "F.Cu")
		(net "TP_PCIE_COMP_B_CLK_1_DN")
	)
	(segment
		(start 279.123394 -135.353806)
		(end 272.512536 -135.353806)
		(width 0.1651)
		(layer "F.Cu")
		(net "TP_PCIE_COMP_B_CLK_1_DN")
	)
	(segment
		(start 272.512536 -135.353806)
		(end 272.178526 -135.687816)
		(width 0.1651)
		(layer "F.Cu")
		(net "TP_PCIE_COMP_B_CLK_1_DN")
	)
	(segment
		(start 284.217872 -134.67588)
		(end 283.8958 -134.353808)
		(width 0.1651)
		(layer "F.Cu")
		(net "TP_PCIE_COMP_B_CLK_1_DN")
	)
	(segment
		(start 284.454346 -135.916924)
		(end 284.535118 -135.805926)
		(width 0.1651)
		(layer "F.Cu")
		(net "TP_PCIE_COMP_B_CLK_1_DN")
	)
	(arc
		(start 284.602936 -135.712454)
		(mid 284.726707 -135.373065)
		(end 284.583632 -135.041386)
		(width 0.1651)
		(layer "F.Cu")
		(net "TP_PCIE_COMP_B_CLK_1_DN")
	)
	(arc
		(start 284.528006 -136.138666)
		(mid 284.445304 -136.043177)
		(end 284.454346 -135.917178)
		(width 0.1651)
		(layer "F.Cu")
		(net "TP_PCIE_COMP_B_CLK_1_DN")
	)
	(segment
		(start 254.862584 -19.054064)
		(end 255.498092 -18.418556)
		(width 0.1651)
		(layer "F.Cu")
		(net "TP_PCIE_COMP_A_CLK_P5")
	)
	(segment
		(start 241.196114 -18.054066)
		(end 242.196112 -19.054064)
		(width 0.1651)
		(layer "F.Cu")
		(net "TP_PCIE_COMP_A_CLK_P5")
	)
	(segment
		(start 238.05007 -17.200118)
		(end 237.328202 -17.561306)
		(width 0.1651)
		(layer "F.Cu")
		(net "TP_PCIE_COMP_A_CLK_P5")
	)
	(segment
		(start 242.196112 -19.054064)
		(end 254.862584 -19.054064)
		(width 0.1651)
		(layer "F.Cu")
		(net "TP_PCIE_COMP_A_CLK_P5")
	)
	(segment
		(start 237.254542 -17.783048)
		(end 237.413546 -18.001742)
		(width 0.1651)
		(layer "F.Cu")
		(net "TP_PCIE_COMP_A_CLK_P5")
	)
	(segment
		(start 237.516416 -18.054066)
		(end 241.196114 -18.054066)
		(width 0.1651)
		(layer "F.Cu")
		(net "TP_PCIE_COMP_A_CLK_P5")
	)
	(segment
		(start 237.254542 -17.782794)
		(end 237.254542 -17.783048)
		(width 0.1651)
		(layer "F.Cu")
		(net "TP_PCIE_COMP_A_CLK_P5")
	)
	(arc
		(start 237.328202 -17.561306)
		(mid 237.2455 -17.656795)
		(end 237.254542 -17.782794)
		(width 0.1651)
		(layer "F.Cu")
		(net "TP_PCIE_COMP_A_CLK_P5")
	)
	(arc
		(start 237.413546 -18.001742)
		(mid 237.458702 -18.040225)
		(end 237.516416 -18.054066)
		(width 0.1651)
		(layer "F.Cu")
		(net "TP_PCIE_COMP_A_CLK_P5")
	)
	(segment
		(start 242.074954 -19.346164)
		(end 254.7493 -19.346164)
		(width 0.1651)
		(layer "F.Cu")
		(net "TP_PCIE_COMP_A_CLK_N5")
	)
	(segment
		(start 236.962442 -17.878044)
		(end 237.177072 -18.1737)
		(width 0.1651)
		(layer "F.Cu")
		(net "TP_PCIE_COMP_A_CLK_N5")
	)
	(segment
		(start 236.050074 -18.200116)
		(end 236.771434 -17.839182)
		(width 0.1651)
		(layer "F.Cu")
		(net "TP_PCIE_COMP_A_CLK_N5")
	)
	(segment
		(start 254.7493 -19.346164)
		(end 255.498092 -20.094956)
		(width 0.1651)
		(layer "F.Cu")
		(net "TP_PCIE_COMP_A_CLK_N5")
	)
	(segment
		(start 236.962442 -17.870678)
		(end 236.962442 -17.878044)
		(width 0.1651)
		(layer "F.Cu")
		(net "TP_PCIE_COMP_A_CLK_N5")
	)
	(segment
		(start 237.516416 -18.346166)
		(end 241.074956 -18.346166)
		(width 0.1651)
		(layer "F.Cu")
		(net "TP_PCIE_COMP_A_CLK_N5")
	)
	(segment
		(start 241.074956 -18.346166)
		(end 242.074954 -19.346164)
		(width 0.1651)
		(layer "F.Cu")
		(net "TP_PCIE_COMP_A_CLK_N5")
	)
	(arc
		(start 237.177072 -18.1737)
		(mid 237.326035 -18.300678)
		(end 237.516416 -18.346166)
		(width 0.1651)
		(layer "F.Cu")
		(net "TP_PCIE_COMP_A_CLK_N5")
	)
	(arc
		(start 236.771434 -17.839182)
		(mid 236.872013 -17.824031)
		(end 236.962442 -17.870678)
		(width 0.1651)
		(layer "F.Cu")
		(net "TP_PCIE_COMP_A_CLK_N5")
	)
	(segment
		(start 241.271298 -135.86079)
		(end 240.549938 -135.499856)
		(width 0.1651)
		(layer "F.Cu")
		(net "TP_PCIE_COMP_A_CLK_1_DP")
	)
	(segment
		(start 236.616494 -135.645906)
		(end 237.616492 -134.645908)
		(width 0.1651)
		(layer "F.Cu")
		(net "TP_PCIE_COMP_A_CLK_1_DP")
	)
	(segment
		(start 241.074702 -134.645908)
		(end 241.676936 -135.248142)
		(width 0.1651)
		(layer "F.Cu")
		(net "TP_PCIE_COMP_A_CLK_1_DP")
	)
	(segment
		(start 237.616492 -134.645908)
		(end 241.074702 -134.645908)
		(width 0.1651)
		(layer "F.Cu")
		(net "TP_PCIE_COMP_A_CLK_1_DP")
	)
	(segment
		(start 241.462306 -135.821928)
		(end 241.462306 -135.829294)
		(width 0.1651)
		(layer "F.Cu")
		(net "TP_PCIE_COMP_A_CLK_1_DP")
	)
	(segment
		(start 241.676936 -135.526272)
		(end 241.462306 -135.821928)
		(width 0.1651)
		(layer "F.Cu")
		(net "TP_PCIE_COMP_A_CLK_1_DP")
	)
	(segment
		(start 225.200718 -135.645906)
		(end 236.616494 -135.645906)
		(width 0.1651)
		(layer "F.Cu")
		(net "TP_PCIE_COMP_A_CLK_1_DP")
	)
	(segment
		(start 224.553526 -136.293098)
		(end 225.200718 -135.645906)
		(width 0.1651)
		(layer "F.Cu")
		(net "TP_PCIE_COMP_A_CLK_1_DP")
	)
	(arc
		(start 241.676936 -135.248142)
		(mid 241.734666 -135.387244)
		(end 241.676936 -135.526272)
		(width 0.1651)
		(layer "F.Cu")
		(net "TP_PCIE_COMP_A_CLK_1_DP")
	)
	(arc
		(start 241.462306 -135.829294)
		(mid 241.371897 -135.876062)
		(end 241.271298 -135.86079)
		(width 0.1651)
		(layer "F.Cu")
		(net "TP_PCIE_COMP_A_CLK_1_DP")
	)
	(segment
		(start 241.835178 -135.805926)
		(end 241.754406 -135.916924)
		(width 0.1651)
		(layer "F.Cu")
		(net "TP_PCIE_COMP_A_CLK_1_DN")
	)
	(segment
		(start 225.290634 -135.353806)
		(end 236.495336 -135.353806)
		(width 0.1651)
		(layer "F.Cu")
		(net "TP_PCIE_COMP_A_CLK_1_DN")
	)
	(segment
		(start 236.495336 -135.353806)
		(end 237.495334 -134.353808)
		(width 0.1651)
		(layer "F.Cu")
		(net "TP_PCIE_COMP_A_CLK_1_DN")
	)
	(segment
		(start 241.517932 -134.67588)
		(end 241.883692 -135.041386)
		(width 0.1651)
		(layer "F.Cu")
		(net "TP_PCIE_COMP_A_CLK_1_DN")
	)
	(segment
		(start 241.902996 -135.712454)
		(end 241.835178 -135.805926)
		(width 0.1651)
		(layer "F.Cu")
		(net "TP_PCIE_COMP_A_CLK_1_DN")
	)
	(segment
		(start 241.828066 -136.138666)
		(end 242.549934 -136.499854)
		(width 0.1651)
		(layer "F.Cu")
		(net "TP_PCIE_COMP_A_CLK_1_DN")
	)
	(segment
		(start 241.19586 -134.353808)
		(end 241.517932 -134.67588)
		(width 0.1651)
		(layer "F.Cu")
		(net "TP_PCIE_COMP_A_CLK_1_DN")
	)
	(segment
		(start 241.754406 -135.916924)
		(end 241.754406 -135.917178)
		(width 0.1651)
		(layer "F.Cu")
		(net "TP_PCIE_COMP_A_CLK_1_DN")
	)
	(segment
		(start 224.553526 -134.616698)
		(end 225.290634 -135.353806)
		(width 0.1651)
		(layer "F.Cu")
		(net "TP_PCIE_COMP_A_CLK_1_DN")
	)
	(segment
		(start 237.495334 -134.353808)
		(end 241.19586 -134.353808)
		(width 0.1651)
		(layer "F.Cu")
		(net "TP_PCIE_COMP_A_CLK_1_DN")
	)
	(arc
		(start 241.754406 -135.917178)
		(mid 241.745364 -136.043177)
		(end 241.828066 -136.138666)
		(width 0.1651)
		(layer "F.Cu")
		(net "TP_PCIE_COMP_A_CLK_1_DN")
	)
	(arc
		(start 241.883692 -135.041386)
		(mid 242.026682 -135.373067)
		(end 241.902996 -135.712454)
		(width 0.1651)
		(layer "F.Cu")
		(net "TP_PCIE_COMP_A_CLK_1_DN")
	)
	(segment
		(start 336.052414 -23.657814)
		(end 335.3816 -22.987)
		(width 0.17145)
		(layer "F.Cu")
		(net "BMC_B_MISC_ALERT_N")
	)
	(segment
		(start 333.864204 -22.987)
		(end 333.774034 -23.07717)
		(width 0.17145)
		(layer "F.Cu")
		(net "BMC_B_MISC_ALERT_N")
	)
	(segment
		(start 334.254094 -24.0284)
		(end 334.254094 -24.920448)
		(width 0.17145)
		(layer "F.Cu")
		(net "BMC_B_MISC_ALERT_N")
	)
	(segment
		(start 334.7466 -22.987)
		(end 333.864204 -22.987)
		(width 0.17145)
		(layer "F.Cu")
		(net "BMC_B_MISC_ALERT_N")
	)
	(segment
		(start 335.3816 -22.987)
		(end 334.7466 -22.987)
		(width 0.17145)
		(layer "F.Cu")
		(net "BMC_B_MISC_ALERT_N")
	)
	(segment
		(start 333.774034 -23.54834)
		(end 334.254094 -24.0284)
		(width 0.17145)
		(layer "F.Cu")
		(net "BMC_B_MISC_ALERT_N")
	)
	(segment
		(start 336.052414 -24.41829)
		(end 336.052414 -23.657814)
		(width 0.17145)
		(layer "F.Cu")
		(net "BMC_B_MISC_ALERT_N")
	)
	(segment
		(start 333.774034 -23.07717)
		(end 333.774034 -23.54834)
		(width 0.17145)
		(layer "F.Cu")
		(net "BMC_B_MISC_ALERT_N")
	)
	(via
		(at 334.254094 -24.920448)
		(size 0.5588)
		(drill 0.3048)
		(layers "F.Cu" "B.Cu")
		(net "BMC_B_MISC_ALERT_N")
	)
	(via
		(at 334.7466 -22.987)
		(size 0.6604)
		(drill 0.3302)
		(layers "F.Cu" "B.Cu")
		(net "BMC_B_MISC_ALERT_N")
	)
	(segment
		(start 352.76282 -34.556954)
		(end 346.821506 -28.61564)
		(width 0.13335)
		(layer "In2.Cu")
		(net "BMC_B_MISC_ALERT_N")
	)
	(segment
		(start 336.371438 -24.920448)
		(end 334.254094 -24.920448)
		(width 0.13335)
		(layer "In2.Cu")
		(net "BMC_B_MISC_ALERT_N")
	)
	(segment
		(start 346.821506 -28.61564)
		(end 341.909146 -28.61564)
		(width 0.13335)
		(layer "In2.Cu")
		(net "BMC_B_MISC_ALERT_N")
	)
	(segment
		(start 339.855556 -26.56205)
		(end 338.01304 -26.56205)
		(width 0.13335)
		(layer "In2.Cu")
		(net "BMC_B_MISC_ALERT_N")
	)
	(segment
		(start 362.924852 -30.375098)
		(end 362.924852 -30.888178)
		(width 0.13335)
		(layer "In2.Cu")
		(net "BMC_B_MISC_ALERT_N")
	)
	(segment
		(start 359.256076 -34.556954)
		(end 352.76282 -34.556954)
		(width 0.13335)
		(layer "In2.Cu")
		(net "BMC_B_MISC_ALERT_N")
	)
	(segment
		(start 341.909146 -28.61564)
		(end 339.855556 -26.56205)
		(width 0.13335)
		(layer "In2.Cu")
		(net "BMC_B_MISC_ALERT_N")
	)
	(segment
		(start 364.149894 -29.150056)
		(end 362.924852 -30.375098)
		(width 0.13335)
		(layer "In2.Cu")
		(net "BMC_B_MISC_ALERT_N")
	)
	(segment
		(start 338.01304 -26.56205)
		(end 336.371438 -24.920448)
		(width 0.13335)
		(layer "In2.Cu")
		(net "BMC_B_MISC_ALERT_N")
	)
	(segment
		(start 362.924852 -30.888178)
		(end 359.256076 -34.556954)
		(width 0.13335)
		(layer "In2.Cu")
		(net "BMC_B_MISC_ALERT_N")
	)
	(segment
		(start 82.509614 -21.778214)
		(end 82.509614 -22.22881)
		(width 0.17145)
		(layer "F.Cu")
		(net "BMC_A_MISC_ALERT_N")
	)
	(segment
		(start 78.359 -19.4818)
		(end 78.994 -19.4818)
		(width 0.17145)
		(layer "F.Cu")
		(net "BMC_A_MISC_ALERT_N")
	)
	(segment
		(start 77.96657 -18.269966)
		(end 77.96657 -19.08937)
		(width 0.17145)
		(layer "F.Cu")
		(net "BMC_A_MISC_ALERT_N")
	)
	(segment
		(start 78.994 -19.4818)
		(end 80.2132 -19.4818)
		(width 0.17145)
		(layer "F.Cu")
		(net "BMC_A_MISC_ALERT_N")
	)
	(segment
		(start 76.962 -18.669)
		(end 77.361034 -18.269966)
		(width 0.17145)
		(layer "F.Cu")
		(net "BMC_A_MISC_ALERT_N")
	)
	(segment
		(start 80.2132 -19.4818)
		(end 82.509614 -21.778214)
		(width 0.17145)
		(layer "F.Cu")
		(net "BMC_A_MISC_ALERT_N")
	)
	(segment
		(start 77.361034 -18.269966)
		(end 77.96657 -18.269966)
		(width 0.17145)
		(layer "F.Cu")
		(net "BMC_A_MISC_ALERT_N")
	)
	(segment
		(start 77.96657 -19.08937)
		(end 78.359 -19.4818)
		(width 0.17145)
		(layer "F.Cu")
		(net "BMC_A_MISC_ALERT_N")
	)
	(via
		(at 78.994 -19.4818)
		(size 0.6604)
		(drill 0.3302)
		(layers "F.Cu" "B.Cu")
		(net "BMC_A_MISC_ALERT_N")
	)
	(via
		(at 76.962 -18.669)
		(size 0.5588)
		(drill 0.3048)
		(layers "F.Cu" "B.Cu")
		(net "BMC_A_MISC_ALERT_N")
	)
	(segment
		(start 109.130338 -32.6136)
		(end 93.915738 -17.399)
		(width 0.13335)
		(layer "In2.Cu")
		(net "BMC_A_MISC_ALERT_N")
	)
	(segment
		(start 115.835938 -32.6136)
		(end 109.130338 -32.6136)
		(width 0.13335)
		(layer "In2.Cu")
		(net "BMC_A_MISC_ALERT_N")
	)
	(segment
		(start 83.4644 -19.1262)
		(end 77.4192 -19.1262)
		(width 0.13335)
		(layer "In2.Cu")
		(net "BMC_A_MISC_ALERT_N")
	)
	(segment
		(start 85.1916 -17.399)
		(end 83.4644 -19.1262)
		(width 0.13335)
		(layer "In2.Cu")
		(net "BMC_A_MISC_ALERT_N")
	)
	(segment
		(start 118.149878 -29.150056)
		(end 117.2718 -30.028134)
		(width 0.13335)
		(layer "In2.Cu")
		(net "BMC_A_MISC_ALERT_N")
	)
	(segment
		(start 77.4192 -19.1262)
		(end 76.962 -18.669)
		(width 0.13335)
		(layer "In2.Cu")
		(net "BMC_A_MISC_ALERT_N")
	)
	(segment
		(start 93.915738 -17.399)
		(end 85.1916 -17.399)
		(width 0.13335)
		(layer "In2.Cu")
		(net "BMC_A_MISC_ALERT_N")
	)
	(segment
		(start 117.2718 -30.028134)
		(end 117.2718 -31.177738)
		(width 0.13335)
		(layer "In2.Cu")
		(net "BMC_A_MISC_ALERT_N")
	)
	(segment
		(start 117.2718 -31.177738)
		(end 115.835938 -32.6136)
		(width 0.13335)
		(layer "In2.Cu")
		(net "BMC_A_MISC_ALERT_N")
	)
	(segment
		(start 377.4059 -141.2494)
		(end 379.5776 -141.2494)
		(width 0.17145)
		(layer "F.Cu")
		(net "I2C_BMC_B_MISC_SDA")
	)
	(segment
		(start 335.22539 -33.9979)
		(end 334.03921 -33.9979)
		(width 0.17145)
		(layer "F.Cu")
		(net "I2C_BMC_B_MISC_SDA")
	)
	(segment
		(start 335.228438 -33.994852)
		(end 335.22539 -33.9979)
		(width 0.17145)
		(layer "F.Cu")
		(net "I2C_BMC_B_MISC_SDA")
	)
	(segment
		(start 334.035908 -34.001202)
		(end 334.035908 -35.027362)
		(width 0.17145)
		(layer "F.Cu")
		(net "I2C_BMC_B_MISC_SDA")
	)
	(segment
		(start 334.03921 -33.9979)
		(end 334.035908 -34.001202)
		(width 0.17145)
		(layer "F.Cu")
		(net "I2C_BMC_B_MISC_SDA")
	)
	(via
		(at 383.4892 -131.0894)
		(size 0.5588)
		(drill 0.3048)
		(layers "F.Cu" "B.Cu")
		(net "I2C_BMC_B_MISC_SDA")
	)
	(via
		(at 334.035908 -35.027362)
		(size 0.5588)
		(drill 0.3048)
		(layers "F.Cu" "B.Cu")
		(net "I2C_BMC_B_MISC_SDA")
	)
	(via
		(at 379.5776 -141.2494)
		(size 0.5588)
		(drill 0.3048)
		(layers "F.Cu" "B.Cu")
		(net "I2C_BMC_B_MISC_SDA")
	)
	(segment
		(start 384.452876 -60.398152)
		(end 384.452876 -130.252724)
		(width 0.13335)
		(layer "In2.Cu")
		(net "I2C_BMC_B_MISC_SDA")
	)
	(segment
		(start 388.1247 -32.622998)
		(end 389.336026 -33.834324)
		(width 0.13335)
		(layer "In2.Cu")
		(net "I2C_BMC_B_MISC_SDA")
	)
	(segment
		(start 384.452876 -130.252724)
		(end 383.6162 -131.0894)
		(width 0.13335)
		(layer "In2.Cu")
		(net "I2C_BMC_B_MISC_SDA")
	)
	(segment
		(start 389.336026 -33.834324)
		(end 392.213846 -33.834324)
		(width 0.13335)
		(layer "In2.Cu")
		(net "I2C_BMC_B_MISC_SDA")
	)
	(segment
		(start 392.213846 -33.834324)
		(end 393.297918 -34.918396)
		(width 0.13335)
		(layer "In2.Cu")
		(net "I2C_BMC_B_MISC_SDA")
	)
	(segment
		(start 383.6162 -131.0894)
		(end 383.4892 -131.0894)
		(width 0.13335)
		(layer "In2.Cu")
		(net "I2C_BMC_B_MISC_SDA")
	)
	(segment
		(start 387.549898 -29.550106)
		(end 388.1247 -30.124908)
		(width 0.13335)
		(layer "In2.Cu")
		(net "I2C_BMC_B_MISC_SDA")
	)
	(segment
		(start 388.1247 -30.124908)
		(end 388.1247 -32.622998)
		(width 0.13335)
		(layer "In2.Cu")
		(net "I2C_BMC_B_MISC_SDA")
	)
	(segment
		(start 392.050778 -47.044356)
		(end 392.050778 -52.80025)
		(width 0.13335)
		(layer "In2.Cu")
		(net "I2C_BMC_B_MISC_SDA")
	)
	(segment
		(start 393.297918 -45.797216)
		(end 392.050778 -47.044356)
		(width 0.13335)
		(layer "In2.Cu")
		(net "I2C_BMC_B_MISC_SDA")
	)
	(segment
		(start 392.050778 -52.80025)
		(end 384.452876 -60.398152)
		(width 0.13335)
		(layer "In2.Cu")
		(net "I2C_BMC_B_MISC_SDA")
	)
	(segment
		(start 393.297918 -34.918396)
		(end 393.297918 -45.797216)
		(width 0.13335)
		(layer "In2.Cu")
		(net "I2C_BMC_B_MISC_SDA")
	)
	(segment
		(start 383.4892 -132.8928)
		(end 383.4892 -131.0894)
		(width 0.12065)
		(layer "In4.Cu")
		(net "I2C_BMC_B_MISC_SDA")
	)
	(segment
		(start 383.498852 -132.902452)
		(end 383.4892 -132.8928)
		(width 0.12065)
		(layer "In4.Cu")
		(net "I2C_BMC_B_MISC_SDA")
	)
	(segment
		(start 379.5776 -141.2494)
		(end 383.498852 -137.328148)
		(width 0.12065)
		(layer "In4.Cu")
		(net "I2C_BMC_B_MISC_SDA")
	)
	(segment
		(start 383.498852 -137.328148)
		(end 383.498852 -132.902452)
		(width 0.12065)
		(layer "In4.Cu")
		(net "I2C_BMC_B_MISC_SDA")
	)
	(segment
		(start 340.813136 -41.80459)
		(end 334.035908 -35.027362)
		(width 0.12065)
		(layer "In7.Cu")
		(net "I2C_BMC_B_MISC_SDA")
	)
	(segment
		(start 386.96265 -30.137354)
		(end 386.96265 -33.179004)
		(width 0.12065)
		(layer "In7.Cu")
		(net "I2C_BMC_B_MISC_SDA")
	)
	(segment
		(start 361.504992 -39.49065)
		(end 358.278938 -42.716704)
		(width 0.12065)
		(layer "In7.Cu")
		(net "I2C_BMC_B_MISC_SDA")
	)
	(segment
		(start 354.9142 -42.716704)
		(end 354.002086 -41.80459)
		(width 0.12065)
		(layer "In7.Cu")
		(net "I2C_BMC_B_MISC_SDA")
	)
	(segment
		(start 387.549898 -29.550106)
		(end 386.96265 -30.137354)
		(width 0.12065)
		(layer "In7.Cu")
		(net "I2C_BMC_B_MISC_SDA")
	)
	(segment
		(start 358.278938 -42.716704)
		(end 354.9142 -42.716704)
		(width 0.12065)
		(layer "In7.Cu")
		(net "I2C_BMC_B_MISC_SDA")
	)
	(segment
		(start 386.96265 -33.179004)
		(end 380.651004 -39.49065)
		(width 0.12065)
		(layer "In7.Cu")
		(net "I2C_BMC_B_MISC_SDA")
	)
	(segment
		(start 380.651004 -39.49065)
		(end 361.504992 -39.49065)
		(width 0.12065)
		(layer "In7.Cu")
		(net "I2C_BMC_B_MISC_SDA")
	)
	(segment
		(start 354.002086 -41.80459)
		(end 340.813136 -41.80459)
		(width 0.12065)
		(layer "In7.Cu")
		(net "I2C_BMC_B_MISC_SDA")
	)
	(segment
		(start 377.4059 -142.3416)
		(end 379.5776 -142.3416)
		(width 0.17145)
		(layer "F.Cu")
		(net "I2C_BMC_B_MISC_SCL")
	)
	(segment
		(start 336.348578 -35.244024)
		(end 336.348578 -33.998662)
		(width 0.17145)
		(layer "F.Cu")
		(net "I2C_BMC_B_MISC_SCL")
	)
	(segment
		(start 336.352388 -33.994852)
		(end 337.447636 -33.994852)
		(width 0.17145)
		(layer "F.Cu")
		(net "I2C_BMC_B_MISC_SCL")
	)
	(segment
		(start 336.348578 -33.998662)
		(end 336.352388 -33.994852)
		(width 0.17145)
		(layer "F.Cu")
		(net "I2C_BMC_B_MISC_SCL")
	)
	(via
		(at 379.5776 -142.3416)
		(size 0.5588)
		(drill 0.3048)
		(layers "F.Cu" "B.Cu")
		(net "I2C_BMC_B_MISC_SCL")
	)
	(via
		(at 384.3528 -132.0038)
		(size 0.5588)
		(drill 0.3048)
		(layers "F.Cu" "B.Cu")
		(net "I2C_BMC_B_MISC_SCL")
	)
	(via
		(at 336.348578 -35.244024)
		(size 0.5588)
		(drill 0.3048)
		(layers "F.Cu" "B.Cu")
		(net "I2C_BMC_B_MISC_SCL")
	)
	(segment
		(start 385.094226 -60.663836)
		(end 385.094226 -131.262374)
		(width 0.13335)
		(layer "In2.Cu")
		(net "I2C_BMC_B_MISC_SCL")
	)
	(segment
		(start 392.47953 -33.192974)
		(end 393.939268 -34.652712)
		(width 0.13335)
		(layer "In2.Cu")
		(net "I2C_BMC_B_MISC_SCL")
	)
	(segment
		(start 389.814562 -33.192974)
		(end 392.47953 -33.192974)
		(width 0.13335)
		(layer "In2.Cu")
		(net "I2C_BMC_B_MISC_SCL")
	)
	(segment
		(start 385.094226 -131.262374)
		(end 384.3528 -132.0038)
		(width 0.13335)
		(layer "In2.Cu")
		(net "I2C_BMC_B_MISC_SCL")
	)
	(segment
		(start 388.61365 -31.992062)
		(end 389.814562 -33.192974)
		(width 0.13335)
		(layer "In2.Cu")
		(net "I2C_BMC_B_MISC_SCL")
	)
	(segment
		(start 388.61365 -29.21381)
		(end 388.61365 -31.992062)
		(width 0.13335)
		(layer "In2.Cu")
		(net "I2C_BMC_B_MISC_SCL")
	)
	(segment
		(start 392.692128 -47.31004)
		(end 392.692128 -53.065934)
		(width 0.13335)
		(layer "In2.Cu")
		(net "I2C_BMC_B_MISC_SCL")
	)
	(segment
		(start 393.939268 -46.0629)
		(end 392.692128 -47.31004)
		(width 0.13335)
		(layer "In2.Cu")
		(net "I2C_BMC_B_MISC_SCL")
	)
	(segment
		(start 387.549898 -28.150058)
		(end 388.61365 -29.21381)
		(width 0.13335)
		(layer "In2.Cu")
		(net "I2C_BMC_B_MISC_SCL")
	)
	(segment
		(start 393.939268 -34.652712)
		(end 393.939268 -46.0629)
		(width 0.13335)
		(layer "In2.Cu")
		(net "I2C_BMC_B_MISC_SCL")
	)
	(segment
		(start 392.692128 -53.065934)
		(end 385.094226 -60.663836)
		(width 0.13335)
		(layer "In2.Cu")
		(net "I2C_BMC_B_MISC_SCL")
	)
	(segment
		(start 384.3528 -132.0038)
		(end 384.3528 -138.694414)
		(width 0.12065)
		(layer "In4.Cu")
		(net "I2C_BMC_B_MISC_SCL")
	)
	(segment
		(start 380.705614 -142.3416)
		(end 379.5776 -142.3416)
		(width 0.12065)
		(layer "In4.Cu")
		(net "I2C_BMC_B_MISC_SCL")
	)
	(segment
		(start 384.3528 -138.694414)
		(end 380.705614 -142.3416)
		(width 0.12065)
		(layer "In4.Cu")
		(net "I2C_BMC_B_MISC_SCL")
	)
	(segment
		(start 386.334 -32.149796)
		(end 386.334 -32.9184)
		(width 0.12065)
		(layer "In7.Cu")
		(net "I2C_BMC_B_MISC_SCL")
	)
	(segment
		(start 342.280494 -41.17594)
		(end 336.348578 -35.244024)
		(width 0.12065)
		(layer "In7.Cu")
		(net "I2C_BMC_B_MISC_SCL")
	)
	(segment
		(start 354.26269 -41.17594)
		(end 342.280494 -41.17594)
		(width 0.12065)
		(layer "In7.Cu")
		(net "I2C_BMC_B_MISC_SCL")
	)
	(segment
		(start 386.466842 -29.204158)
		(end 386.466842 -32.016954)
		(width 0.12065)
		(layer "In7.Cu")
		(net "I2C_BMC_B_MISC_SCL")
	)
	(segment
		(start 387.520942 -28.150058)
		(end 386.466842 -29.204158)
		(width 0.12065)
		(layer "In7.Cu")
		(net "I2C_BMC_B_MISC_SCL")
	)
	(segment
		(start 380.3904 -38.862)
		(end 361.244388 -38.862)
		(width 0.12065)
		(layer "In7.Cu")
		(net "I2C_BMC_B_MISC_SCL")
	)
	(segment
		(start 386.466842 -32.016954)
		(end 386.334 -32.149796)
		(width 0.12065)
		(layer "In7.Cu")
		(net "I2C_BMC_B_MISC_SCL")
	)
	(segment
		(start 354.36175 -41.275)
		(end 354.26269 -41.17594)
		(width 0.12065)
		(layer "In7.Cu")
		(net "I2C_BMC_B_MISC_SCL")
	)
	(segment
		(start 387.549898 -28.150058)
		(end 387.520942 -28.150058)
		(width 0.12065)
		(layer "In7.Cu")
		(net "I2C_BMC_B_MISC_SCL")
	)
	(segment
		(start 361.244388 -38.862)
		(end 358.831388 -41.275)
		(width 0.12065)
		(layer "In7.Cu")
		(net "I2C_BMC_B_MISC_SCL")
	)
	(segment
		(start 358.831388 -41.275)
		(end 354.36175 -41.275)
		(width 0.12065)
		(layer "In7.Cu")
		(net "I2C_BMC_B_MISC_SCL")
	)
	(segment
		(start 386.334 -32.9184)
		(end 380.3904 -38.862)
		(width 0.12065)
		(layer "In7.Cu")
		(net "I2C_BMC_B_MISC_SCL")
	)
	(segment
		(start 136.370314 -135.339074)
		(end 136.088374 -135.621014)
		(width 0.17145)
		(layer "F.Cu")
		(net "I2C_BMC_A_MISC_SDA")
	)
	(segment
		(start 79.861918 -33.946338)
		(end 79.861918 -32.946594)
		(width 0.17145)
		(layer "F.Cu")
		(net "I2C_BMC_A_MISC_SDA")
	)
	(segment
		(start 79.861918 -32.946594)
		(end 79.84998 -32.934656)
		(width 0.17145)
		(layer "F.Cu")
		(net "I2C_BMC_A_MISC_SDA")
	)
	(segment
		(start 81.002886 -31.849822)
		(end 79.850488 -31.849822)
		(width 0.17145)
		(layer "F.Cu")
		(net "I2C_BMC_A_MISC_SDA")
	)
	(segment
		(start 137.573766 -135.339074)
		(end 136.370314 -135.339074)
		(width 0.17145)
		(layer "F.Cu")
		(net "I2C_BMC_A_MISC_SDA")
	)
	(segment
		(start 136.088374 -135.621014)
		(end 127.513842 -135.621014)
		(width 0.17145)
		(layer "F.Cu")
		(net "I2C_BMC_A_MISC_SDA")
	)
	(segment
		(start 79.850488 -31.849822)
		(end 79.84998 -31.849314)
		(width 0.17145)
		(layer "F.Cu")
		(net "I2C_BMC_A_MISC_SDA")
	)
	(segment
		(start 79.867506 -33.951926)
		(end 79.861918 -33.946338)
		(width 0.17145)
		(layer "F.Cu")
		(net "I2C_BMC_A_MISC_SDA")
	)
	(segment
		(start 127.513842 -135.621014)
		(end 127.259842 -135.875014)
		(width 0.17145)
		(layer "F.Cu")
		(net "I2C_BMC_A_MISC_SDA")
	)
	(segment
		(start 79.84998 -32.934656)
		(end 79.84998 -31.849314)
		(width 0.17145)
		(layer "F.Cu")
		(net "I2C_BMC_A_MISC_SDA")
	)
	(via
		(at 137.70737 -47.635922)
		(size 0.5588)
		(drill 0.3048)
		(layers "F.Cu" "B.Cu")
		(net "I2C_BMC_A_MISC_SDA")
	)
	(via
		(at 127.259842 -135.875014)
		(size 0.5588)
		(drill 0.3048)
		(layers "F.Cu" "B.Cu")
		(net "I2C_BMC_A_MISC_SDA")
	)
	(via
		(at 136.370314 -135.339074)
		(size 0.6604)
		(drill 0.3302)
		(layers "F.Cu" "B.Cu")
		(net "I2C_BMC_A_MISC_SDA")
	)
	(via
		(at 79.867506 -33.951926)
		(size 0.5588)
		(drill 0.3048)
		(layers "F.Cu" "B.Cu")
		(net "I2C_BMC_A_MISC_SDA")
	)
	(segment
		(start 140.895578 -30.20441)
		(end 140.895578 -44.447714)
		(width 0.12065)
		(layer "In4.Cu")
		(net "I2C_BMC_A_MISC_SDA")
	)
	(segment
		(start 137.380218 -47.963074)
		(end 137.70737 -47.635922)
		(width 0.12065)
		(layer "In4.Cu")
		(net "I2C_BMC_A_MISC_SDA")
	)
	(segment
		(start 137.380218 -85.077554)
		(end 137.380218 -47.963074)
		(width 0.12065)
		(layer "In4.Cu")
		(net "I2C_BMC_A_MISC_SDA")
	)
	(segment
		(start 127.259842 -130.393186)
		(end 132.013198 -125.63983)
		(width 0.12065)
		(layer "In4.Cu")
		(net "I2C_BMC_A_MISC_SDA")
	)
	(segment
		(start 140.895578 -44.447714)
		(end 137.70737 -47.635922)
		(width 0.12065)
		(layer "In4.Cu")
		(net "I2C_BMC_A_MISC_SDA")
	)
	(segment
		(start 132.013198 -90.444574)
		(end 137.380218 -85.077554)
		(width 0.12065)
		(layer "In4.Cu")
		(net "I2C_BMC_A_MISC_SDA")
	)
	(segment
		(start 132.013198 -125.63983)
		(end 132.013198 -90.444574)
		(width 0.12065)
		(layer "In4.Cu")
		(net "I2C_BMC_A_MISC_SDA")
	)
	(segment
		(start 141.549882 -29.550106)
		(end 140.895578 -30.20441)
		(width 0.12065)
		(layer "In4.Cu")
		(net "I2C_BMC_A_MISC_SDA")
	)
	(segment
		(start 127.259842 -135.875014)
		(end 127.259842 -130.393186)
		(width 0.12065)
		(layer "In4.Cu")
		(net "I2C_BMC_A_MISC_SDA")
	)
	(segment
		(start 99.604068 -35.130994)
		(end 107.839002 -43.365928)
		(width 0.12065)
		(layer "In7.Cu")
		(net "I2C_BMC_A_MISC_SDA")
	)
	(segment
		(start 129.733802 -43.365928)
		(end 134.003796 -47.635922)
		(width 0.12065)
		(layer "In7.Cu")
		(net "I2C_BMC_A_MISC_SDA")
	)
	(segment
		(start 79.867506 -33.951926)
		(end 81.046574 -35.130994)
		(width 0.12065)
		(layer "In7.Cu")
		(net "I2C_BMC_A_MISC_SDA")
	)
	(segment
		(start 134.003796 -47.635922)
		(end 137.70737 -47.635922)
		(width 0.12065)
		(layer "In7.Cu")
		(net "I2C_BMC_A_MISC_SDA")
	)
	(segment
		(start 107.839002 -43.365928)
		(end 129.733802 -43.365928)
		(width 0.12065)
		(layer "In7.Cu")
		(net "I2C_BMC_A_MISC_SDA")
	)
	(segment
		(start 81.046574 -35.130994)
		(end 99.604068 -35.130994)
		(width 0.12065)
		(layer "In7.Cu")
		(net "I2C_BMC_A_MISC_SDA")
	)
	(segment
		(start 83.387692 -31.844488)
		(end 83.393534 -31.838646)
		(width 0.17145)
		(layer "F.Cu")
		(net "I2C_BMC_A_MISC_SCL")
	)
	(segment
		(start 135.729726 -134.881874)
		(end 126.454154 -134.881874)
		(width 0.17145)
		(layer "F.Cu")
		(net "I2C_BMC_A_MISC_SCL")
	)
	(segment
		(start 82.248502 -31.844488)
		(end 83.387692 -31.844488)
		(width 0.17145)
		(layer "F.Cu")
		(net "I2C_BMC_A_MISC_SCL")
	)
	(segment
		(start 136.380474 -134.246874)
		(end 136.3726 -134.239)
		(width 0.17145)
		(layer "F.Cu")
		(net "I2C_BMC_A_MISC_SCL")
	)
	(segment
		(start 136.3726 -134.239)
		(end 135.729726 -134.881874)
		(width 0.17145)
		(layer "F.Cu")
		(net "I2C_BMC_A_MISC_SCL")
	)
	(segment
		(start 137.573766 -134.246874)
		(end 136.380474 -134.246874)
		(width 0.17145)
		(layer "F.Cu")
		(net "I2C_BMC_A_MISC_SCL")
	)
	(segment
		(start 126.454154 -134.881874)
		(end 126.327154 -135.008874)
		(width 0.17145)
		(layer "F.Cu")
		(net "I2C_BMC_A_MISC_SCL")
	)
	(segment
		(start 82.248502 -33.965388)
		(end 82.248502 -31.844488)
		(width 0.17145)
		(layer "F.Cu")
		(net "I2C_BMC_A_MISC_SCL")
	)
	(via
		(at 136.3726 -134.239)
		(size 0.6604)
		(drill 0.3302)
		(layers "F.Cu" "B.Cu")
		(net "I2C_BMC_A_MISC_SCL")
	)
	(via
		(at 126.327154 -135.008874)
		(size 0.5588)
		(drill 0.3048)
		(layers "F.Cu" "B.Cu")
		(net "I2C_BMC_A_MISC_SCL")
	)
	(via
		(at 82.248502 -33.965388)
		(size 0.5588)
		(drill 0.3048)
		(layers "F.Cu" "B.Cu")
		(net "I2C_BMC_A_MISC_SCL")
	)
	(via
		(at 137.054336 -46.912276)
		(size 0.5588)
		(drill 0.3048)
		(layers "F.Cu" "B.Cu")
		(net "I2C_BMC_A_MISC_SCL")
	)
	(segment
		(start 126.631192 -130.132582)
		(end 131.384548 -125.379226)
		(width 0.12065)
		(layer "In4.Cu")
		(net "I2C_BMC_A_MISC_SCL")
	)
	(segment
		(start 141.549882 -28.150058)
		(end 140.399516 -29.300424)
		(width 0.12065)
		(layer "In4.Cu")
		(net "I2C_BMC_A_MISC_SCL")
	)
	(segment
		(start 131.384548 -90.168222)
		(end 136.751568 -84.801202)
		(width 0.12065)
		(layer "In4.Cu")
		(net "I2C_BMC_A_MISC_SCL")
	)
	(segment
		(start 136.751568 -47.215044)
		(end 137.054336 -46.912276)
		(width 0.12065)
		(layer "In4.Cu")
		(net "I2C_BMC_A_MISC_SCL")
	)
	(segment
		(start 131.384548 -125.379226)
		(end 131.384548 -90.168222)
		(width 0.12065)
		(layer "In4.Cu")
		(net "I2C_BMC_A_MISC_SCL")
	)
	(segment
		(start 126.327154 -135.008874)
		(end 126.631192 -134.704836)
		(width 0.12065)
		(layer "In4.Cu")
		(net "I2C_BMC_A_MISC_SCL")
	)
	(segment
		(start 136.751568 -84.801202)
		(end 136.751568 -47.215044)
		(width 0.12065)
		(layer "In4.Cu")
		(net "I2C_BMC_A_MISC_SCL")
	)
	(segment
		(start 140.068554 -32.333184)
		(end 140.068554 -43.898058)
		(width 0.12065)
		(layer "In4.Cu")
		(net "I2C_BMC_A_MISC_SCL")
	)
	(segment
		(start 140.399516 -32.002222)
		(end 140.068554 -32.333184)
		(width 0.12065)
		(layer "In4.Cu")
		(net "I2C_BMC_A_MISC_SCL")
	)
	(segment
		(start 126.631192 -134.704836)
		(end 126.631192 -130.132582)
		(width 0.12065)
		(layer "In4.Cu")
		(net "I2C_BMC_A_MISC_SCL")
	)
	(segment
		(start 140.399516 -29.300424)
		(end 140.399516 -32.002222)
		(width 0.12065)
		(layer "In4.Cu")
		(net "I2C_BMC_A_MISC_SCL")
	)
	(segment
		(start 140.068554 -43.898058)
		(end 137.054336 -46.912276)
		(width 0.12065)
		(layer "In4.Cu")
		(net "I2C_BMC_A_MISC_SCL")
	)
	(segment
		(start 109.732064 -42.703242)
		(end 131.285234 -42.703242)
		(width 0.12065)
		(layer "In7.Cu")
		(net "I2C_BMC_A_MISC_SCL")
	)
	(segment
		(start 82.674714 -34.3916)
		(end 101.420422 -34.3916)
		(width 0.12065)
		(layer "In7.Cu")
		(net "I2C_BMC_A_MISC_SCL")
	)
	(segment
		(start 82.248502 -33.965388)
		(end 82.674714 -34.3916)
		(width 0.12065)
		(layer "In7.Cu")
		(net "I2C_BMC_A_MISC_SCL")
	)
	(segment
		(start 135.494268 -46.912276)
		(end 137.054336 -46.912276)
		(width 0.12065)
		(layer "In7.Cu")
		(net "I2C_BMC_A_MISC_SCL")
	)
	(segment
		(start 131.285234 -42.703242)
		(end 135.494268 -46.912276)
		(width 0.12065)
		(layer "In7.Cu")
		(net "I2C_BMC_A_MISC_SCL")
	)
	(segment
		(start 101.420422 -34.3916)
		(end 109.732064 -42.703242)
		(width 0.12065)
		(layer "In7.Cu")
		(net "I2C_BMC_A_MISC_SCL")
	)
	(segment
		(start 277.9268 13.4112)
		(end 277.9268 12.3444)
		(width 0.508)
		(layer "F.Cu")
		(net "VCCP")
	)
	(segment
		(start 278.892 13.6144)
		(end 278.511 13.6144)
		(width 0.508)
		(layer "F.Cu")
		(net "VCCP")
	)
	(segment
		(start 276.2758 13.0048)
		(end 276.9362 12.3444)
		(width 0.508)
		(layer "F.Cu")
		(net "VCCP")
	)
	(segment
		(start 276.9362 12.3444)
		(end 277.9268 12.3444)
		(width 0.508)
		(layer "F.Cu")
		(net "VCCP")
	)
	(segment
		(start 279.0952 12.2936)
		(end 279.0952 13.4112)
		(width 0.508)
		(layer "F.Cu")
		(net "VCCP")
	)
	(segment
		(start 279.0952 13.4112)
		(end 278.892 13.6144)
		(width 0.508)
		(layer "F.Cu")
		(net "VCCP")
	)
	(segment
		(start 278.13 13.6144)
		(end 277.9268 13.4112)
		(width 0.508)
		(layer "F.Cu")
		(net "VCCP")
	)
	(segment
		(start 278.511 13.6144)
		(end 278.511 13.589)
		(width 0.508)
		(layer "F.Cu")
		(net "VCCP")
	)
	(segment
		(start 278.511 13.6144)
		(end 278.13 13.6144)
		(width 0.508)
		(layer "F.Cu")
		(net "VCCP")
	)
	(via
		(at 278.511 13.589)
		(size 0.6604)
		(drill 0.3302)
		(layers "F.Cu" "B.Cu")
		(net "VCCP")
	)
	(segment
		(start 272.8976 17.570196)
		(end 272.8976 16.213328)
		(width 0.17145)
		(layer "F.Cu")
		(net "SCC_B_FAULT_LED")
	)
	(segment
		(start 272.013172 18.698972)
		(end 272.8976 18.698972)
		(width 0.17145)
		(layer "F.Cu")
		(net "SCC_B_FAULT_LED")
	)
	(segment
		(start 272.8976 18.698972)
		(end 272.8976 17.570196)
		(width 0.17145)
		(layer "F.Cu")
		(net "SCC_B_FAULT_LED")
	)
	(via
		(at 251.2187 17.9959)
		(size 0.5588)
		(drill 0.3048)
		(layers "F.Cu" "B.Cu")
		(net "SCC_B_FAULT_LED")
	)
	(via
		(at 272.013172 18.698972)
		(size 0.5588)
		(drill 0.3048)
		(layers "F.Cu" "B.Cu")
		(net "SCC_B_FAULT_LED")
	)
	(via
		(at 272.8976 17.570196)
		(size 0.6604)
		(drill 0.3302)
		(layers "F.Cu" "B.Cu")
		(net "SCC_B_FAULT_LED")
	)
	(segment
		(start 252.5903 17.9959)
		(end 251.2187 17.9959)
		(width 0.13335)
		(layer "In2.Cu")
		(net "SCC_B_FAULT_LED")
	)
	(segment
		(start 260.4262 17.8562)
		(end 259.715 17.145)
		(width 0.13335)
		(layer "In2.Cu")
		(net "SCC_B_FAULT_LED")
	)
	(segment
		(start 253.4412 17.145)
		(end 252.5903 17.9959)
		(width 0.13335)
		(layer "In2.Cu")
		(net "SCC_B_FAULT_LED")
	)
	(segment
		(start 259.715 17.145)
		(end 253.4412 17.145)
		(width 0.13335)
		(layer "In2.Cu")
		(net "SCC_B_FAULT_LED")
	)
	(segment
		(start 271.1704 17.8562)
		(end 260.4262 17.8562)
		(width 0.13335)
		(layer "In2.Cu")
		(net "SCC_B_FAULT_LED")
	)
	(segment
		(start 272.013172 18.698972)
		(end 271.1704 17.8562)
		(width 0.13335)
		(layer "In2.Cu")
		(net "SCC_B_FAULT_LED")
	)
	(segment
		(start 254.55372 -26.797)
		(end 254.036322 -26.279602)
		(width 0.12065)
		(layer "In4.Cu")
		(net "SCC_B_FAULT_LED")
	)
	(segment
		(start 252.710442 13.934186)
		(end 251.2187 15.425928)
		(width 0.12065)
		(layer "In4.Cu")
		(net "SCC_B_FAULT_LED")
	)
	(segment
		(start 222.025972 -319.091564)
		(end 222.025972 -319.09131)
		(width 0.12065)
		(layer "In4.Cu")
		(net "SCC_B_FAULT_LED")
	)
	(segment
		(start 252.583696 -158.185104)
		(end 252.583696 -137.367518)
		(width 0.12065)
		(layer "In4.Cu")
		(net "SCC_B_FAULT_LED")
	)
	(segment
		(start 216.110312 -390.583928)
		(end 216.110312 -385.072128)
		(width 0.12065)
		(layer "In4.Cu")
		(net "SCC_B_FAULT_LED")
	)
	(segment
		(start 222.025972 -319.09131)
		(end 222.082106 -319.035176)
		(width 0.12065)
		(layer "In4.Cu")
		(net "SCC_B_FAULT_LED")
	)
	(segment
		(start 247.269 -193.3448)
		(end 247.269 -163.4998)
		(width 0.12065)
		(layer "In4.Cu")
		(net "SCC_B_FAULT_LED")
	)
	(segment
		(start 254.55372 -89.713562)
		(end 254.55372 -26.797)
		(width 0.12065)
		(layer "In4.Cu")
		(net "SCC_B_FAULT_LED")
	)
	(segment
		(start 224.278952 -217.053922)
		(end 225.295206 -216.037668)
		(width 0.12065)
		(layer "In4.Cu")
		(net "SCC_B_FAULT_LED")
	)
	(segment
		(start 254.036322 -11.043158)
		(end 254.55372 -10.52576)
		(width 0.12065)
		(layer "In4.Cu")
		(net "SCC_B_FAULT_LED")
	)
	(segment
		(start 216.110312 -385.072128)
		(end 215.69172 -384.653536)
		(width 0.12065)
		(layer "In4.Cu")
		(net "SCC_B_FAULT_LED")
	)
	(segment
		(start 224.278952 -220.271848)
		(end 224.278952 -217.053922)
		(width 0.12065)
		(layer "In4.Cu")
		(net "SCC_B_FAULT_LED")
	)
	(segment
		(start 225.129852 -402.24837)
		(end 216.786206 -393.904724)
		(width 0.12065)
		(layer "In4.Cu")
		(net "SCC_B_FAULT_LED")
	)
	(segment
		(start 254.55372 7.694168)
		(end 252.710442 9.537446)
		(width 0.12065)
		(layer "In4.Cu")
		(net "SCC_B_FAULT_LED")
	)
	(segment
		(start 252.583696 -137.367518)
		(end 249.760232 -134.544054)
		(width 0.12065)
		(layer "In4.Cu")
		(net "SCC_B_FAULT_LED")
	)
	(segment
		(start 225.295206 -216.037668)
		(end 225.295206 -214.619332)
		(width 0.12065)
		(layer "In4.Cu")
		(net "SCC_B_FAULT_LED")
	)
	(segment
		(start 247.269 -163.4998)
		(end 252.583696 -158.185104)
		(width 0.12065)
		(layer "In4.Cu")
		(net "SCC_B_FAULT_LED")
	)
	(segment
		(start 222.082106 -222.468694)
		(end 224.278952 -220.271848)
		(width 0.12065)
		(layer "In4.Cu")
		(net "SCC_B_FAULT_LED")
	)
	(segment
		(start 249.760232 -134.544054)
		(end 249.760232 -94.50705)
		(width 0.12065)
		(layer "In4.Cu")
		(net "SCC_B_FAULT_LED")
	)
	(segment
		(start 225.294952 -210.91779)
		(end 238.79429 -197.418452)
		(width 0.12065)
		(layer "In4.Cu")
		(net "SCC_B_FAULT_LED")
	)
	(segment
		(start 222.082106 -319.035176)
		(end 222.082106 -222.468694)
		(width 0.12065)
		(layer "In4.Cu")
		(net "SCC_B_FAULT_LED")
	)
	(segment
		(start 215.69172 -325.425816)
		(end 222.025972 -319.091564)
		(width 0.12065)
		(layer "In4.Cu")
		(net "SCC_B_FAULT_LED")
	)
	(segment
		(start 215.69172 -384.653536)
		(end 215.69172 -325.425816)
		(width 0.12065)
		(layer "In4.Cu")
		(net "SCC_B_FAULT_LED")
	)
	(segment
		(start 225.129852 -407.32964)
		(end 225.129852 -402.24837)
		(width 0.12065)
		(layer "In4.Cu")
		(net "SCC_B_FAULT_LED")
	)
	(segment
		(start 254.55372 -10.52576)
		(end 254.55372 7.694168)
		(width 0.12065)
		(layer "In4.Cu")
		(net "SCC_B_FAULT_LED")
	)
	(segment
		(start 225.295206 -214.619332)
		(end 225.294952 -214.619078)
		(width 0.12065)
		(layer "In4.Cu")
		(net "SCC_B_FAULT_LED")
	)
	(segment
		(start 252.710442 9.537446)
		(end 252.710442 13.934186)
		(width 0.12065)
		(layer "In4.Cu")
		(net "SCC_B_FAULT_LED")
	)
	(segment
		(start 216.786206 -391.259822)
		(end 216.110312 -390.583928)
		(width 0.12065)
		(layer "In4.Cu")
		(net "SCC_B_FAULT_LED")
	)
	(segment
		(start 243.195348 -197.418452)
		(end 247.269 -193.3448)
		(width 0.12065)
		(layer "In4.Cu")
		(net "SCC_B_FAULT_LED")
	)
	(segment
		(start 226.200208 -408.399996)
		(end 225.129852 -407.32964)
		(width 0.12065)
		(layer "In4.Cu")
		(net "SCC_B_FAULT_LED")
	)
	(segment
		(start 225.294952 -214.619078)
		(end 225.294952 -210.91779)
		(width 0.12065)
		(layer "In4.Cu")
		(net "SCC_B_FAULT_LED")
	)
	(segment
		(start 249.760232 -94.50705)
		(end 254.55372 -89.713562)
		(width 0.12065)
		(layer "In4.Cu")
		(net "SCC_B_FAULT_LED")
	)
	(segment
		(start 254.036322 -26.279602)
		(end 254.036322 -11.043158)
		(width 0.12065)
		(layer "In4.Cu")
		(net "SCC_B_FAULT_LED")
	)
	(segment
		(start 251.2187 15.425928)
		(end 251.2187 17.9959)
		(width 0.12065)
		(layer "In4.Cu")
		(net "SCC_B_FAULT_LED")
	)
	(segment
		(start 216.786206 -393.904724)
		(end 216.786206 -391.259822)
		(width 0.12065)
		(layer "In4.Cu")
		(net "SCC_B_FAULT_LED")
	)
	(segment
		(start 238.79429 -197.418452)
		(end 243.195348 -197.418452)
		(width 0.12065)
		(layer "In4.Cu")
		(net "SCC_B_FAULT_LED")
	)
	(segment
		(start 258.8514 15.748)
		(end 258.8514 14.409928)
		(width 0.17145)
		(layer "F.Cu")
		(net "SCC_A_FAULT_LED")
	)
	(segment
		(start 258.8514 16.810228)
		(end 258.8514 15.748)
		(width 0.17145)
		(layer "F.Cu")
		(net "SCC_A_FAULT_LED")
	)
	(segment
		(start 258.846828 16.8148)
		(end 258.8514 16.810228)
		(width 0.17145)
		(layer "F.Cu")
		(net "SCC_A_FAULT_LED")
	)
	(segment
		(start 258.846828 16.8148)
		(end 258.846828 18.034)
		(width 0.17145)
		(layer "F.Cu")
		(net "SCC_A_FAULT_LED")
	)
	(via
		(at 258.846828 18.034)
		(size 0.5588)
		(drill 0.3048)
		(layers "F.Cu" "B.Cu")
		(net "SCC_A_FAULT_LED")
	)
	(via
		(at 258.8514 15.748)
		(size 0.6604)
		(drill 0.3302)
		(layers "F.Cu" "B.Cu")
		(net "SCC_A_FAULT_LED")
	)
	(segment
		(start 250.33732 -318.764666)
		(end 250.33732 -286.588454)
		(width 0.12065)
		(layer "In4.Cu")
		(net "SCC_A_FAULT_LED")
	)
	(segment
		(start 251.331476 -246.046498)
		(end 251.331476 -211.630514)
		(width 0.12065)
		(layer "In4.Cu")
		(net "SCC_A_FAULT_LED")
	)
	(segment
		(start 246.03329 -256.98577)
		(end 246.03329 -251.344684)
		(width 0.12065)
		(layer "In4.Cu")
		(net "SCC_A_FAULT_LED")
	)
	(segment
		(start 258.846828 15.591028)
		(end 258.846828 18.034)
		(width 0.12065)
		(layer "In4.Cu")
		(net "SCC_A_FAULT_LED")
	)
	(segment
		(start 250.33732 -286.588454)
		(end 252.980698 -283.945076)
		(width 0.12065)
		(layer "In4.Cu")
		(net "SCC_A_FAULT_LED")
	)
	(segment
		(start 257.184652 -131.37007)
		(end 257.184652 -19.104356)
		(width 0.12065)
		(layer "In4.Cu")
		(net "SCC_A_FAULT_LED")
	)
	(segment
		(start 257.8608 14.605)
		(end 258.846828 15.591028)
		(width 0.12065)
		(layer "In4.Cu")
		(net "SCC_A_FAULT_LED")
	)
	(segment
		(start 246.712232 -263.209278)
		(end 246.712232 -257.664712)
		(width 0.12065)
		(layer "In4.Cu")
		(net "SCC_A_FAULT_LED")
	)
	(segment
		(start 257.8608 -18.428208)
		(end 257.8608 14.605)
		(width 0.12065)
		(layer "In4.Cu")
		(net "SCC_A_FAULT_LED")
	)
	(segment
		(start 259.513324 -133.698742)
		(end 257.184652 -131.37007)
		(width 0.12065)
		(layer "In4.Cu")
		(net "SCC_A_FAULT_LED")
	)
	(segment
		(start 252.980698 -283.945076)
		(end 252.980698 -269.477744)
		(width 0.12065)
		(layer "In4.Cu")
		(net "SCC_A_FAULT_LED")
	)
	(segment
		(start 246.712232 -257.664712)
		(end 246.03329 -256.98577)
		(width 0.12065)
		(layer "In4.Cu")
		(net "SCC_A_FAULT_LED")
	)
	(segment
		(start 283.23667 -341.330788)
		(end 282.349448 -340.443566)
		(width 0.12065)
		(layer "In4.Cu")
		(net "SCC_A_FAULT_LED")
	)
	(segment
		(start 246.03329 -251.344684)
		(end 251.331476 -246.046498)
		(width 0.12065)
		(layer "In4.Cu")
		(net "SCC_A_FAULT_LED")
	)
	(segment
		(start 282.349448 -340.443566)
		(end 272.01622 -340.443566)
		(width 0.12065)
		(layer "In4.Cu")
		(net "SCC_A_FAULT_LED")
	)
	(segment
		(start 257.184652 -19.104356)
		(end 257.8608 -18.428208)
		(width 0.12065)
		(layer "In4.Cu")
		(net "SCC_A_FAULT_LED")
	)
	(segment
		(start 283.23667 -341.505032)
		(end 283.23667 -341.330788)
		(width 0.12065)
		(layer "In4.Cu")
		(net "SCC_A_FAULT_LED")
	)
	(segment
		(start 272.01622 -340.443566)
		(end 250.33732 -318.764666)
		(width 0.12065)
		(layer "In4.Cu")
		(net "SCC_A_FAULT_LED")
	)
	(segment
		(start 252.980698 -269.477744)
		(end 246.712232 -263.209278)
		(width 0.12065)
		(layer "In4.Cu")
		(net "SCC_A_FAULT_LED")
	)
	(segment
		(start 259.513324 -203.448666)
		(end 259.513324 -133.698742)
		(width 0.12065)
		(layer "In4.Cu")
		(net "SCC_A_FAULT_LED")
	)
	(segment
		(start 251.331476 -211.630514)
		(end 259.513324 -203.448666)
		(width 0.12065)
		(layer "In4.Cu")
		(net "SCC_A_FAULT_LED")
	)
	(segment
		(start 334.03921 -32.25038)
		(end 334.039972 -32.249618)
		(width 0.508)
		(layer "F.Cu")
		(net "P3V3_STBY_B")
	)
	(segment
		(start 336.348578 -32.26816)
		(end 336.330036 -32.249618)
		(width 0.508)
		(layer "F.Cu")
		(net "P3V3_STBY_B")
	)
	(segment
		(start 301.01159 -66.29527)
		(end 301.01159 -67.2846)
		(width 0.3048)
		(layer "F.Cu")
		(net "P3V3_STBY_B")
	)
	(segment
		(start 313.4106 -58.608468)
		(end 313.4106 -58.60796)
		(width 0.381)
		(layer "F.Cu")
		(net "P3V3_STBY_B")
	)
	(segment
		(start 275.797772 22.906228)
		(end 275.6662 23.0378)
		(width 0.508)
		(layer "F.Cu")
		(net "P3V3_STBY_B")
	)
	(segment
		(start 334.03921 -33.1089)
		(end 334.03921 -32.25038)
		(width 0.508)
		(layer "F.Cu")
		(net "P3V3_STBY_B")
	)
	(segment
		(start 332.885034 -21.88337)
		(end 332.885034 -23.07717)
		(width 0.508)
		(layer "F.Cu")
		(net "P3V3_STBY_B")
	)
	(segment
		(start 301.26686 -65.452752)
		(end 301.26686 -66.04)
		(width 0.3048)
		(layer "F.Cu")
		(net "P3V3_STBY_B")
	)
	(segment
		(start 300.99 -71.461122)
		(end 300.10481 -71.461122)
		(width 0.508)
		(layer "F.Cu")
		(net "P3V3_STBY_B")
	)
	(segment
		(start 225.7044 -378.265944)
		(end 225.806508 -378.368052)
		(width 0.508)
		(layer "F.Cu")
		(net "P3V3_STBY_B")
	)
	(segment
		(start 340.931246 -33.994852)
		(end 339.759036 -33.994852)
		(width 0.508)
		(layer "F.Cu")
		(net "P3V3_STBY_B")
	)
	(segment
		(start 298.7294 -67.6275)
		(end 298.7294 -68.733162)
		(width 0.508)
		(layer "F.Cu")
		(net "P3V3_STBY_B")
	)
	(segment
		(start 335.29397 -18.206466)
		(end 335.29397 -17.272)
		(width 0.508)
		(layer "F.Cu")
		(net "P3V3_STBY_B")
	)
	(segment
		(start 220.599 -364.4646)
		(end 221.213934 -363.849666)
		(width 0.508)
		(layer "F.Cu")
		(net "P3V3_STBY_B")
	)
	(segment
		(start 221.213934 -363.849666)
		(end 221.213934 -363.8042)
		(width 0.508)
		(layer "F.Cu")
		(net "P3V3_STBY_B")
	)
	(segment
		(start 215.354916 -389.48487)
		(end 215.354916 -390.80186)
		(width 0.3556)
		(layer "F.Cu")
		(net "P3V3_STBY_B")
	)
	(segment
		(start 308.748938 -59.830462)
		(end 309.970932 -58.608468)
		(width 0.508)
		(layer "F.Cu")
		(net "P3V3_STBY_B")
	)
	(segment
		(start 339.759036 -33.994852)
		(end 339.759036 -34.646362)
		(width 0.508)
		(layer "F.Cu")
		(net "P3V3_STBY_B")
	)
	(segment
		(start 309.970932 -58.608468)
		(end 310.71185 -58.608468)
		(width 0.508)
		(layer "F.Cu")
		(net "P3V3_STBY_B")
	)
	(segment
		(start 215.354916 -391.097516)
		(end 215.354916 -390.80186)
		(width 0.3556)
		(layer "F.Cu")
		(net "P3V3_STBY_B")
	)
	(segment
		(start 221.742 -364.332266)
		(end 221.742 -364.6805)
		(width 0.508)
		(layer "F.Cu")
		(net "P3V3_STBY_B")
	)
	(segment
		(start 265.7475 -112.268)
		(end 264.8712 -112.268)
		(width 0.508)
		(layer "F.Cu")
		(net "P3V3_STBY_B")
	)
	(segment
		(start 215.531954 -391.77976)
		(end 215.531954 -391.274554)
		(width 0.3556)
		(layer "F.Cu")
		(net "P3V3_STBY_B")
	)
	(segment
		(start 275.797772 22.225)
		(end 275.797772 22.906228)
		(width 0.508)
		(layer "F.Cu")
		(net "P3V3_STBY_B")
	)
	(segment
		(start 300.10481 -70.91299)
		(end 300.10481 -71.461122)
		(width 0.3048)
		(layer "F.Cu")
		(net "P3V3_STBY_B")
	)
	(segment
		(start 215.394032 -389.445754)
		(end 215.354916 -389.48487)
		(width 0.3556)
		(layer "F.Cu")
		(net "P3V3_STBY_B")
	)
	(segment
		(start 332.885034 -23.07717)
		(end 332.885034 -23.128224)
		(width 0.508)
		(layer "F.Cu")
		(net "P3V3_STBY_B")
	)
	(segment
		(start 332.885034 -23.128224)
		(end 332.289912 -23.723346)
		(width 0.508)
		(layer "F.Cu")
		(net "P3V3_STBY_B")
	)
	(segment
		(start 335.30667 -18.193766)
		(end 335.29397 -18.206466)
		(width 0.381)
		(layer "F.Cu")
		(net "P3V3_STBY_B")
	)
	(segment
		(start 224.028 -364.6805)
		(end 224.028 -363.8804)
		(width 0.508)
		(layer "F.Cu")
		(net "P3V3_STBY_B")
	)
	(segment
		(start 300.51121 -70.50659)
		(end 300.10481 -70.91299)
		(width 0.3048)
		(layer "F.Cu")
		(net "P3V3_STBY_B")
	)
	(segment
		(start 298.7802 -74.3331)
		(end 298.7802 -73.3044)
		(width 0.508)
		(layer "F.Cu")
		(net "P3V3_STBY_B")
	)
	(segment
		(start 301.3964 -64.3128)
		(end 301.3964 -65.323212)
		(width 0.508)
		(layer "F.Cu")
		(net "P3V3_STBY_B")
	)
	(segment
		(start 301.26686 -66.04)
		(end 301.01159 -66.29527)
		(width 0.3048)
		(layer "F.Cu")
		(net "P3V3_STBY_B")
	)
	(segment
		(start 313.4106 -58.60796)
		(end 315.0616 -58.60796)
		(width 0.381)
		(layer "F.Cu")
		(net "P3V3_STBY_B")
	)
	(segment
		(start 339.759036 -34.646362)
		(end 339.766148 -34.646362)
		(width 0.508)
		(layer "F.Cu")
		(net "P3V3_STBY_B")
	)
	(segment
		(start 214.20836 -391.77976)
		(end 213.9823 -391.5537)
		(width 0.3556)
		(layer "F.Cu")
		(net "P3V3_STBY_B")
	)
	(segment
		(start 220.599 -364.6805)
		(end 220.599 -364.4646)
		(width 0.508)
		(layer "F.Cu")
		(net "P3V3_STBY_B")
	)
	(segment
		(start 225.7044 -377.444)
		(end 225.7044 -378.265944)
		(width 0.508)
		(layer "F.Cu")
		(net "P3V3_STBY_B")
	)
	(segment
		(start 337.291934 -21.00707)
		(end 337.291934 -20.0406)
		(width 0.508)
		(layer "F.Cu")
		(net "P3V3_STBY_B")
	)
	(segment
		(start 215.531954 -391.274554)
		(end 215.354916 -391.097516)
		(width 0.3556)
		(layer "F.Cu")
		(net "P3V3_STBY_B")
	)
	(segment
		(start 263.325102 31.074868)
		(end 263.325102 29.337)
		(width 0.508)
		(layer "F.Cu")
		(net "P3V3_STBY_B")
	)
	(segment
		(start 336.73669 -18.193766)
		(end 335.30667 -18.193766)
		(width 0.381)
		(layer "F.Cu")
		(net "P3V3_STBY_B")
	)
	(segment
		(start 340.932262 -33.995868)
		(end 340.931246 -33.994852)
		(width 0.508)
		(layer "F.Cu")
		(net "P3V3_STBY_B")
	)
	(segment
		(start 303.4284 -72.3265)
		(end 303.4284 -73.212198)
		(width 0.508)
		(layer "F.Cu")
		(net "P3V3_STBY_B")
	)
	(segment
		(start 298.7294 -69.6341)
		(end 298.7294 -68.733162)
		(width 0.508)
		(layer "F.Cu")
		(net "P3V3_STBY_B")
	)
	(segment
		(start 336.348578 -33.109662)
		(end 336.348578 -32.26816)
		(width 0.508)
		(layer "F.Cu")
		(net "P3V3_STBY_B")
	)
	(segment
		(start 308.748938 -64.32931)
		(end 308.748938 -62.57417)
		(width 0.508)
		(layer "F.Cu")
		(net "P3V3_STBY_B")
	)
	(segment
		(start 303.4284 -74.3331)
		(end 303.4284 -73.212198)
		(width 0.508)
		(layer "F.Cu")
		(net "P3V3_STBY_B")
	)
	(segment
		(start 301.3964 -65.323212)
		(end 301.26686 -65.452752)
		(width 0.508)
		(layer "F.Cu")
		(net "P3V3_STBY_B")
	)
	(segment
		(start 215.531954 -391.77976)
		(end 214.20836 -391.77976)
		(width 0.3556)
		(layer "F.Cu")
		(net "P3V3_STBY_B")
	)
	(segment
		(start 300.51121 -69.6214)
		(end 300.51121 -70.50659)
		(width 0.3048)
		(layer "F.Cu")
		(net "P3V3_STBY_B")
	)
	(segment
		(start 221.213934 -363.8042)
		(end 221.742 -364.332266)
		(width 0.508)
		(layer "F.Cu")
		(net "P3V3_STBY_B")
	)
	(segment
		(start 310.71185 -58.608468)
		(end 313.4106 -58.608468)
		(width 0.381)
		(layer "F.Cu")
		(net "P3V3_STBY_B")
	)
	(segment
		(start 339.766148 -34.646362)
		(end 339.766148 -34.845752)
		(width 0.508)
		(layer "F.Cu")
		(net "P3V3_STBY_B")
	)
	(segment
		(start 275.7932 15.3162)
		(end 275.7932 14.5034)
		(width 0.508)
		(layer "F.Cu")
		(net "P3V3_STBY_B")
	)
	(segment
		(start 270.806672 -5.69087)
		(end 267.9192 -5.69087)
		(width 0.508)
		(layer "F.Cu")
		(net "P3V3_STBY_B")
	)
	(segment
		(start 213.9823 -391.5537)
		(end 213.9823 -390.8552)
		(width 0.3556)
		(layer "F.Cu")
		(net "P3V3_STBY_B")
	)
	(segment
		(start 308.748938 -62.57417)
		(end 308.748938 -59.830462)
		(width 0.508)
		(layer "F.Cu")
		(net "P3V3_STBY_B")
	)
	(via
		(at 337.291934 -20.0406)
		(size 0.5588)
		(drill 0.3048)
		(layers "F.Cu" "B.Cu")
		(net "P3V3_STBY_B")
	)
	(via
		(at 336.330036 -32.249618)
		(size 0.5588)
		(drill 0.3048)
		(layers "F.Cu" "B.Cu")
		(net "P3V3_STBY_B")
	)
	(via
		(at 301.3964 -64.3128)
		(size 0.5588)
		(drill 0.3048)
		(layers "F.Cu" "B.Cu")
		(net "P3V3_STBY_B")
	)
	(via
		(at 263.325102 29.337)
		(size 0.5588)
		(drill 0.3048)
		(layers "F.Cu" "B.Cu")
		(net "P3V3_STBY_B")
	)
	(via
		(at 334.039972 -32.249618)
		(size 0.5588)
		(drill 0.3048)
		(layers "F.Cu" "B.Cu")
		(net "P3V3_STBY_B")
	)
	(via
		(at 335.29397 -17.272)
		(size 0.5588)
		(drill 0.3048)
		(layers "F.Cu" "B.Cu")
		(net "P3V3_STBY_B")
	)
	(via
		(at 221.988888 -374.006618)
		(size 0.5588)
		(drill 0.3048)
		(layers "F.Cu" "B.Cu")
		(net "P3V3_STBY_B")
	)
	(via
		(at 334.63103 -30.71368)
		(size 0.6604)
		(drill 0.3302)
		(layers "F.Cu" "B.Cu")
		(net "P3V3_STBY_B")
	)
	(via
		(at 303.4284 -73.212198)
		(size 0.5588)
		(drill 0.3048)
		(layers "F.Cu" "B.Cu")
		(net "P3V3_STBY_B")
	)
	(via
		(at 221.976188 -375.352564)
		(size 0.5588)
		(drill 0.3048)
		(layers "F.Cu" "B.Cu")
		(net "P3V3_STBY_B")
	)
	(via
		(at 339.766148 -34.845752)
		(size 0.5588)
		(drill 0.3048)
		(layers "F.Cu" "B.Cu")
		(net "P3V3_STBY_B")
	)
	(via
		(at 298.7294 -68.733162)
		(size 0.5588)
		(drill 0.3048)
		(layers "F.Cu" "B.Cu")
		(net "P3V3_STBY_B")
	)
	(via
		(at 267.9192 -5.69087)
		(size 0.5588)
		(drill 0.3048)
		(layers "F.Cu" "B.Cu")
		(net "P3V3_STBY_B")
	)
	(via
		(at 275.7932 14.5034)
		(size 0.5588)
		(drill 0.3048)
		(layers "F.Cu" "B.Cu")
		(net "P3V3_STBY_B")
	)
	(via
		(at 275.6662 23.0378)
		(size 0.5588)
		(drill 0.3048)
		(layers "F.Cu" "B.Cu")
		(net "P3V3_STBY_B")
	)
	(via
		(at 298.7802 -73.3044)
		(size 0.5588)
		(drill 0.3048)
		(layers "F.Cu" "B.Cu")
		(net "P3V3_STBY_B")
	)
	(via
		(at 264.8712 -112.268)
		(size 0.5588)
		(drill 0.3048)
		(layers "F.Cu" "B.Cu")
		(net "P3V3_STBY_B")
	)
	(via
		(at 332.289912 -23.723346)
		(size 0.5588)
		(drill 0.3048)
		(layers "F.Cu" "B.Cu")
		(net "P3V3_STBY_B")
	)
	(via
		(at 300.99 -71.461122)
		(size 0.5588)
		(drill 0.3048)
		(layers "F.Cu" "B.Cu")
		(net "P3V3_STBY_B")
	)
	(via
		(at 308.748938 -62.57417)
		(size 0.5588)
		(drill 0.3048)
		(layers "F.Cu" "B.Cu")
		(net "P3V3_STBY_B")
	)
	(via
		(at 221.213934 -363.8042)
		(size 0.5588)
		(drill 0.3048)
		(layers "F.Cu" "B.Cu")
		(net "P3V3_STBY_B")
	)
	(via
		(at 333.534258 -30.693106)
		(size 0.5588)
		(drill 0.3048)
		(layers "F.Cu" "B.Cu")
		(net "P3V3_STBY_B")
	)
	(via
		(at 225.806508 -378.368052)
		(size 0.5588)
		(drill 0.3048)
		(layers "F.Cu" "B.Cu")
		(net "P3V3_STBY_B")
	)
	(via
		(at 215.531954 -391.77976)
		(size 0.5588)
		(drill 0.3048)
		(layers "F.Cu" "B.Cu")
		(net "P3V3_STBY_B")
	)
	(via
		(at 224.028 -363.8804)
		(size 0.5588)
		(drill 0.3048)
		(layers "F.Cu" "B.Cu")
		(net "P3V3_STBY_B")
	)
	(segment
		(start 336.330036 -32.249618)
		(end 337.170014 -32.249618)
		(width 0.508)
		(layer "In2.Cu")
		(net "P3V3_STBY_B")
	)
	(segment
		(start 221.976188 -379.891544)
		(end 215.531954 -386.335778)
		(width 0.508)
		(layer "In2.Cu")
		(net "P3V3_STBY_B")
	)
	(segment
		(start 221.976188 -375.352564)
		(end 221.976188 -379.891544)
		(width 0.508)
		(layer "In2.Cu")
		(net "P3V3_STBY_B")
	)
	(segment
		(start 215.531954 -386.335778)
		(end 215.531954 -391.77976)
		(width 0.508)
		(layer "In2.Cu")
		(net "P3V3_STBY_B")
	)
	(segment
		(start 337.170014 -32.249618)
		(end 339.766148 -34.845752)
		(width 0.508)
		(layer "In2.Cu")
		(net "P3V3_STBY_B")
	)
	(segment
		(start 281.2542 12.2936)
		(end 281.263852 12.303252)
		(width 0.508)
		(layer "F.Cu")
		(net "P3V3_BIAS")
	)
	(segment
		(start 280.1112 12.2936)
		(end 281.2542 12.2936)
		(width 0.508)
		(layer "F.Cu")
		(net "P3V3_BIAS")
	)
	(segment
		(start 281.263852 14.138148)
		(end 281.269948 14.144244)
		(width 0.508)
		(layer "F.Cu")
		(net "P3V3_BIAS")
	)
	(segment
		(start 281.263852 12.303252)
		(end 281.263852 14.138148)
		(width 0.508)
		(layer "F.Cu")
		(net "P3V3_BIAS")
	)
	(segment
		(start 281.269948 15.560548)
		(end 281.269948 16.540734)
		(width 0.381)
		(layer "F.Cu")
		(net "P3V3_BIAS")
	)
	(segment
		(start 281.269948 15.113)
		(end 281.269948 15.560548)
		(width 0.508)
		(layer "F.Cu")
		(net "P3V3_BIAS")
	)
	(segment
		(start 281.269948 14.144244)
		(end 281.269948 15.113)
		(width 0.508)
		(layer "F.Cu")
		(net "P3V3_BIAS")
	)
	(via
		(at 281.269948 15.113)
		(size 0.6604)
		(drill 0.3302)
		(layers "F.Cu" "B.Cu")
		(net "P3V3_BIAS")
	)
	(segment
		(start 272.8976 12.876276)
		(end 272.8976 11.628628)
		(width 0.17145)
		(layer "F.Cu")
		(net "IOM_B_FAULT_LED")
	)
	(segment
		(start 274.0406 11.628628)
		(end 272.8976 11.628628)
		(width 0.17145)
		(layer "F.Cu")
		(net "IOM_B_FAULT_LED")
	)
	(segment
		(start 272.8976 14.333728)
		(end 272.8976 12.876276)
		(width 0.17145)
		(layer "F.Cu")
		(net "IOM_B_FAULT_LED")
	)
	(via
		(at 274.0406 11.628628)
		(size 0.5588)
		(drill 0.3048)
		(layers "F.Cu" "B.Cu")
		(net "IOM_B_FAULT_LED")
	)
	(via
		(at 272.8976 12.876276)
		(size 0.6604)
		(drill 0.3302)
		(layers "F.Cu" "B.Cu")
		(net "IOM_B_FAULT_LED")
	)
	(segment
		(start 316.573154 -14.795246)
		(end 316.065408 -14.2875)
		(width 0.13335)
		(layer "In2.Cu")
		(net "IOM_B_FAULT_LED")
	)
	(segment
		(start 356.2096 -30.451298)
		(end 355.435916 -31.224982)
		(width 0.13335)
		(layer "In2.Cu")
		(net "IOM_B_FAULT_LED")
	)
	(segment
		(start 284.11297 10.491724)
		(end 275.177504 10.491724)
		(width 0.13335)
		(layer "In2.Cu")
		(net "IOM_B_FAULT_LED")
	)
	(segment
		(start 316.065408 -9.449308)
		(end 309.403496 -2.787396)
		(width 0.13335)
		(layer "In2.Cu")
		(net "IOM_B_FAULT_LED")
	)
	(segment
		(start 348.0562 -16.913098)
		(end 344.8177 -13.674598)
		(width 0.13335)
		(layer "In2.Cu")
		(net "IOM_B_FAULT_LED")
	)
	(segment
		(start 309.403496 -2.787396)
		(end 297.39209 -2.787396)
		(width 0.13335)
		(layer "In2.Cu")
		(net "IOM_B_FAULT_LED")
	)
	(segment
		(start 354.57511 -30.799532)
		(end 348.0562 -24.280622)
		(width 0.13335)
		(layer "In2.Cu")
		(net "IOM_B_FAULT_LED")
	)
	(segment
		(start 354.57511 -30.888178)
		(end 354.57511 -30.799532)
		(width 0.13335)
		(layer "In2.Cu")
		(net "IOM_B_FAULT_LED")
	)
	(segment
		(start 356.2096 -26.290524)
		(end 356.2096 -30.451298)
		(width 0.13335)
		(layer "In2.Cu")
		(net "IOM_B_FAULT_LED")
	)
	(segment
		(start 355.435916 -31.224982)
		(end 354.911914 -31.224982)
		(width 0.13335)
		(layer "In2.Cu")
		(net "IOM_B_FAULT_LED")
	)
	(segment
		(start 297.39209 -2.787396)
		(end 284.11297 10.491724)
		(width 0.13335)
		(layer "In2.Cu")
		(net "IOM_B_FAULT_LED")
	)
	(segment
		(start 356.95001 -25.550114)
		(end 356.2096 -26.290524)
		(width 0.13335)
		(layer "In2.Cu")
		(net "IOM_B_FAULT_LED")
	)
	(segment
		(start 344.8177 -13.674598)
		(end 333.962248 -13.674598)
		(width 0.13335)
		(layer "In2.Cu")
		(net "IOM_B_FAULT_LED")
	)
	(segment
		(start 275.177504 10.491724)
		(end 274.0406 11.628628)
		(width 0.13335)
		(layer "In2.Cu")
		(net "IOM_B_FAULT_LED")
	)
	(segment
		(start 354.911914 -31.224982)
		(end 354.57511 -30.888178)
		(width 0.13335)
		(layer "In2.Cu")
		(net "IOM_B_FAULT_LED")
	)
	(segment
		(start 333.962248 -13.674598)
		(end 332.8416 -14.795246)
		(width 0.13335)
		(layer "In2.Cu")
		(net "IOM_B_FAULT_LED")
	)
	(segment
		(start 348.0562 -24.280622)
		(end 348.0562 -16.913098)
		(width 0.13335)
		(layer "In2.Cu")
		(net "IOM_B_FAULT_LED")
	)
	(segment
		(start 316.065408 -14.2875)
		(end 316.065408 -9.449308)
		(width 0.13335)
		(layer "In2.Cu")
		(net "IOM_B_FAULT_LED")
	)
	(segment
		(start 332.8416 -14.795246)
		(end 316.573154 -14.795246)
		(width 0.13335)
		(layer "In2.Cu")
		(net "IOM_B_FAULT_LED")
	)
	(segment
		(start 258.855972 11.170412)
		(end 258.855972 10.1854)
		(width 0.17145)
		(layer "F.Cu")
		(net "IOM_A_FAULT_LED")
	)
	(segment
		(start 258.855972 8.733028)
		(end 258.855972 10.1854)
		(width 0.17145)
		(layer "F.Cu")
		(net "IOM_A_FAULT_LED")
	)
	(segment
		(start 258.8514 11.174984)
		(end 258.855972 11.170412)
		(width 0.17145)
		(layer "F.Cu")
		(net "IOM_A_FAULT_LED")
	)
	(segment
		(start 258.8514 12.530328)
		(end 258.8514 11.174984)
		(width 0.17145)
		(layer "F.Cu")
		(net "IOM_A_FAULT_LED")
	)
	(via
		(at 259.1435 -90.725752)
		(size 0.5588)
		(drill 0.3048)
		(layers "F.Cu" "B.Cu")
		(net "IOM_A_FAULT_LED")
	)
	(via
		(at 193.849752 -43.815)
		(size 0.5588)
		(drill 0.3048)
		(layers "F.Cu" "B.Cu")
		(net "IOM_A_FAULT_LED")
	)
	(via
		(at 200.593706 -92.835222)
		(size 0.5588)
		(drill 0.3048)
		(layers "F.Cu" "B.Cu")
		(net "IOM_A_FAULT_LED")
	)
	(via
		(at 258.8514 11.174984)
		(size 0.6604)
		(drill 0.3302)
		(layers "F.Cu" "B.Cu")
		(net "IOM_A_FAULT_LED")
	)
	(via
		(at 258.855972 8.733028)
		(size 0.5588)
		(drill 0.3048)
		(layers "F.Cu" "B.Cu")
		(net "IOM_A_FAULT_LED")
	)
	(segment
		(start 257.196082 -90.725752)
		(end 259.1435 -90.725752)
		(width 0.13335)
		(layer "In2.Cu")
		(net "IOM_A_FAULT_LED")
	)
	(segment
		(start 200.593706 -92.835222)
		(end 200.722484 -92.964)
		(width 0.13335)
		(layer "In2.Cu")
		(net "IOM_A_FAULT_LED")
	)
	(segment
		(start 200.722484 -92.964)
		(end 226.474274 -92.964)
		(width 0.13335)
		(layer "In2.Cu")
		(net "IOM_A_FAULT_LED")
	)
	(segment
		(start 253.045722 -94.876112)
		(end 257.196082 -90.725752)
		(width 0.13335)
		(layer "In2.Cu")
		(net "IOM_A_FAULT_LED")
	)
	(segment
		(start 228.386386 -94.876112)
		(end 253.045722 -94.876112)
		(width 0.13335)
		(layer "In2.Cu")
		(net "IOM_A_FAULT_LED")
	)
	(segment
		(start 226.474274 -92.964)
		(end 228.386386 -94.876112)
		(width 0.13335)
		(layer "In2.Cu")
		(net "IOM_A_FAULT_LED")
	)
	(segment
		(start 196.542406 -45.500798)
		(end 196.542406 -53.802026)
		(width 0.12065)
		(layer "In4.Cu")
		(net "IOM_A_FAULT_LED")
	)
	(segment
		(start 258.855972 8.733028)
		(end 258.855972 5.937758)
		(width 0.12065)
		(layer "In4.Cu")
		(net "IOM_A_FAULT_LED")
	)
	(segment
		(start 193.324226 -85.565742)
		(end 200.593706 -92.835222)
		(width 0.12065)
		(layer "In4.Cu")
		(net "IOM_A_FAULT_LED")
	)
	(segment
		(start 193.324226 -57.020206)
		(end 193.324226 -85.565742)
		(width 0.12065)
		(layer "In4.Cu")
		(net "IOM_A_FAULT_LED")
	)
	(segment
		(start 261.773162 3.020568)
		(end 261.773162 -17.619726)
		(width 0.12065)
		(layer "In4.Cu")
		(net "IOM_A_FAULT_LED")
	)
	(segment
		(start 193.849752 -43.815)
		(end 194.856608 -43.815)
		(width 0.12065)
		(layer "In4.Cu")
		(net "IOM_A_FAULT_LED")
	)
	(segment
		(start 194.856608 -43.815)
		(end 196.542406 -45.500798)
		(width 0.12065)
		(layer "In4.Cu")
		(net "IOM_A_FAULT_LED")
	)
	(segment
		(start 259.1435 -20.249388)
		(end 259.1435 -90.725752)
		(width 0.12065)
		(layer "In4.Cu")
		(net "IOM_A_FAULT_LED")
	)
	(segment
		(start 196.542406 -53.802026)
		(end 193.324226 -57.020206)
		(width 0.12065)
		(layer "In4.Cu")
		(net "IOM_A_FAULT_LED")
	)
	(segment
		(start 261.773162 -17.619726)
		(end 259.1435 -20.249388)
		(width 0.12065)
		(layer "In4.Cu")
		(net "IOM_A_FAULT_LED")
	)
	(segment
		(start 258.855972 5.937758)
		(end 261.773162 3.020568)
		(width 0.12065)
		(layer "In4.Cu")
		(net "IOM_A_FAULT_LED")
	)
	(segment
		(start 111.7092 -33.092644)
		(end 120.475502 -41.858946)
		(width 0.12065)
		(layer "In7.Cu")
		(net "IOM_A_FAULT_LED")
	)
	(segment
		(start 110.949994 -25.550114)
		(end 111.7092 -26.30932)
		(width 0.12065)
		(layer "In7.Cu")
		(net "IOM_A_FAULT_LED")
	)
	(segment
		(start 120.475502 -41.858946)
		(end 127.1778 -41.858946)
		(width 0.12065)
		(layer "In7.Cu")
		(net "IOM_A_FAULT_LED")
	)
	(segment
		(start 153.182066 -42.263568)
		(end 183.563768 -42.263568)
		(width 0.12065)
		(layer "In7.Cu")
		(net "IOM_A_FAULT_LED")
	)
	(segment
		(start 111.7092 -26.30932)
		(end 111.7092 -33.092644)
		(width 0.12065)
		(layer "In7.Cu")
		(net "IOM_A_FAULT_LED")
	)
	(segment
		(start 151.577802 -43.867832)
		(end 153.182066 -42.263568)
		(width 0.12065)
		(layer "In7.Cu")
		(net "IOM_A_FAULT_LED")
	)
	(segment
		(start 136.85647 -41.473374)
		(end 139.250928 -43.867832)
		(width 0.12065)
		(layer "In7.Cu")
		(net "IOM_A_FAULT_LED")
	)
	(segment
		(start 127.563372 -41.473374)
		(end 136.85647 -41.473374)
		(width 0.12065)
		(layer "In7.Cu")
		(net "IOM_A_FAULT_LED")
	)
	(segment
		(start 127.1778 -41.858946)
		(end 127.563372 -41.473374)
		(width 0.12065)
		(layer "In7.Cu")
		(net "IOM_A_FAULT_LED")
	)
	(segment
		(start 183.563768 -42.263568)
		(end 185.1152 -43.815)
		(width 0.12065)
		(layer "In7.Cu")
		(net "IOM_A_FAULT_LED")
	)
	(segment
		(start 139.250928 -43.867832)
		(end 151.577802 -43.867832)
		(width 0.12065)
		(layer "In7.Cu")
		(net "IOM_A_FAULT_LED")
	)
	(segment
		(start 185.1152 -43.815)
		(end 193.849752 -43.815)
		(width 0.12065)
		(layer "In7.Cu")
		(net "IOM_A_FAULT_LED")
	)
	(segment
		(start 273.54784 17.26184)
		(end 273.54784 16.213328)
		(width 0.17145)
		(layer "F.Cu")
		(net "ENCL_FAULT_LED_B")
	)
	(segment
		(start 272.3896 15.24)
		(end 272.24736 15.09776)
		(width 0.17145)
		(layer "F.Cu")
		(net "ENCL_FAULT_LED_B")
	)
	(segment
		(start 273.7866 17.5006)
		(end 273.54784 17.26184)
		(width 0.17145)
		(layer "F.Cu")
		(net "ENCL_FAULT_LED_B")
	)
	(segment
		(start 273.0754 21.8948)
		(end 273.7866 21.1836)
		(width 0.17145)
		(layer "F.Cu")
		(net "ENCL_FAULT_LED_B")
	)
	(segment
		(start 263.7536 26.7208)
		(end 268.2494 26.7208)
		(width 0.17145)
		(layer "F.Cu")
		(net "ENCL_FAULT_LED_B")
	)
	(segment
		(start 260.785102 29.689298)
		(end 263.7536 26.7208)
		(width 0.17145)
		(layer "F.Cu")
		(net "ENCL_FAULT_LED_B")
	)
	(segment
		(start 273.54784 15.53464)
		(end 273.2532 15.24)
		(width 0.17145)
		(layer "F.Cu")
		(net "ENCL_FAULT_LED_B")
	)
	(segment
		(start 260.785102 31.074868)
		(end 260.785102 29.689298)
		(width 0.17145)
		(layer "F.Cu")
		(net "ENCL_FAULT_LED_B")
	)
	(segment
		(start 268.2494 26.7208)
		(end 273.0754 21.8948)
		(width 0.17145)
		(layer "F.Cu")
		(net "ENCL_FAULT_LED_B")
	)
	(segment
		(start 273.7866 21.1836)
		(end 273.7866 17.5006)
		(width 0.17145)
		(layer "F.Cu")
		(net "ENCL_FAULT_LED_B")
	)
	(segment
		(start 273.54784 16.213328)
		(end 273.54784 15.53464)
		(width 0.17145)
		(layer "F.Cu")
		(net "ENCL_FAULT_LED_B")
	)
	(segment
		(start 273.2532 15.24)
		(end 272.3896 15.24)
		(width 0.17145)
		(layer "F.Cu")
		(net "ENCL_FAULT_LED_B")
	)
	(segment
		(start 272.24736 15.09776)
		(end 272.24736 14.333728)
		(width 0.17145)
		(layer "F.Cu")
		(net "ENCL_FAULT_LED_B")
	)
	(via
		(at 273.0754 21.8948)
		(size 0.6604)
		(drill 0.3302)
		(layers "F.Cu" "B.Cu")
		(net "ENCL_FAULT_LED_B")
	)
	(segment
		(start 256.670048 23.955248)
		(end 256.670048 26.404824)
		(width 0.17145)
		(layer "F.Cu")
		(net "ENCL_FAULT_LED_A")
	)
	(segment
		(start 259.39115 13.4366)
		(end 258.4704 13.4366)
		(width 0.17145)
		(layer "F.Cu")
		(net "ENCL_FAULT_LED_A")
	)
	(segment
		(start 256.286 23.5712)
		(end 256.670048 23.955248)
		(width 0.17145)
		(layer "F.Cu")
		(net "ENCL_FAULT_LED_A")
	)
	(segment
		(start 259.50164 14.409928)
		(end 259.50164 13.54709)
		(width 0.17145)
		(layer "F.Cu")
		(net "ENCL_FAULT_LED_A")
	)
	(segment
		(start 257.9878 19.6596)
		(end 256.7432 19.6596)
		(width 0.17145)
		(layer "F.Cu")
		(net "ENCL_FAULT_LED_A")
	)
	(segment
		(start 256.7432 19.6596)
		(end 256.286 20.1168)
		(width 0.17145)
		(layer "F.Cu")
		(net "ENCL_FAULT_LED_A")
	)
	(segment
		(start 256.286 20.1168)
		(end 256.286 23.5712)
		(width 0.17145)
		(layer "F.Cu")
		(net "ENCL_FAULT_LED_A")
	)
	(segment
		(start 259.50164 14.409928)
		(end 259.50164 18.14576)
		(width 0.17145)
		(layer "F.Cu")
		(net "ENCL_FAULT_LED_A")
	)
	(segment
		(start 259.50164 13.54709)
		(end 259.39115 13.4366)
		(width 0.17145)
		(layer "F.Cu")
		(net "ENCL_FAULT_LED_A")
	)
	(segment
		(start 258.20116 13.16736)
		(end 258.20116 12.530328)
		(width 0.17145)
		(layer "F.Cu")
		(net "ENCL_FAULT_LED_A")
	)
	(segment
		(start 259.50164 18.14576)
		(end 257.9878 19.6596)
		(width 0.17145)
		(layer "F.Cu")
		(net "ENCL_FAULT_LED_A")
	)
	(segment
		(start 258.4704 13.4366)
		(end 258.20116 13.16736)
		(width 0.17145)
		(layer "F.Cu")
		(net "ENCL_FAULT_LED_A")
	)
	(via
		(at 256.7432 19.6596)
		(size 0.6604)
		(drill 0.3302)
		(layers "F.Cu" "B.Cu")
		(net "ENCL_FAULT_LED_A")
	)
	(segment
		(start 224.155 -389.094472)
		(end 224.5614 -389.094472)
		(width 0.508)
		(layer "F.Cu")
		(net "VCCP_IN")
	)
	(segment
		(start 226.7204 -389.640572)
		(end 225.65106 -389.640572)
		(width 0.508)
		(layer "F.Cu")
		(net "VCCP_IN")
	)
	(segment
		(start 225.1075 -389.640572)
		(end 225.65106 -389.640572)
		(width 0.508)
		(layer "F.Cu")
		(net "VCCP_IN")
	)
	(segment
		(start 226.7458 -389.615172)
		(end 226.7204 -389.640572)
		(width 0.508)
		(layer "F.Cu")
		(net "VCCP_IN")
	)
	(segment
		(start 224.5614 -389.094472)
		(end 225.1075 -389.640572)
		(width 0.508)
		(layer "F.Cu")
		(net "VCCP_IN")
	)
	(segment
		(start 226.756468 -389.62584)
		(end 226.7458 -389.615172)
		(width 0.508)
		(layer "F.Cu")
		(net "VCCP_IN")
	)
	(segment
		(start 227.911152 -389.62584)
		(end 226.756468 -389.62584)
		(width 0.508)
		(layer "F.Cu")
		(net "VCCP_IN")
	)
	(via
		(at 225.65106 -389.640572)
		(size 0.6604)
		(drill 0.3302)
		(layers "F.Cu" "B.Cu")
		(net "VCCP_IN")
	)
	(segment
		(start 382.787398 -135.611362)
		(end 384.28676 -135.611362)
		(width 0.508)
		(layer "F.Cu")
		(net "VCCP_B")
	)
	(segment
		(start 382.753362 -135.577326)
		(end 382.787398 -135.611362)
		(width 0.508)
		(layer "F.Cu")
		(net "VCCP_B")
	)
	(segment
		(start 381.64516 -135.577326)
		(end 382.753362 -135.577326)
		(width 0.508)
		(layer "F.Cu")
		(net "VCCP_B")
	)
	(segment
		(start 384.631438 -138.305794)
		(end 384.631438 -135.95604)
		(width 0.508)
		(layer "F.Cu")
		(net "VCCP_B")
	)
	(segment
		(start 384.631438 -135.95604)
		(end 384.28676 -135.611362)
		(width 0.508)
		(layer "F.Cu")
		(net "VCCP_B")
	)
	(via
		(at 384.28676 -135.611362)
		(size 0.6604)
		(drill 0.3302)
		(layers "F.Cu" "B.Cu")
		(net "VCCP_B")
	)
	(segment
		(start 132.201666 -141.913102)
		(end 131.938014 -141.64945)
		(width 0.508)
		(layer "F.Cu")
		(net "VCCP_A")
	)
	(segment
		(start 131.938014 -141.64945)
		(end 130.487166 -141.64945)
		(width 0.508)
		(layer "F.Cu")
		(net "VCCP_A")
	)
	(segment
		(start 130.433318 -141.703298)
		(end 130.487166 -141.64945)
		(width 0.508)
		(layer "F.Cu")
		(net "VCCP_A")
	)
	(segment
		(start 133.375908 -141.913102)
		(end 132.201666 -141.913102)
		(width 0.508)
		(layer "F.Cu")
		(net "VCCP_A")
	)
	(segment
		(start 133.38683 -141.90218)
		(end 133.375908 -141.913102)
		(width 0.508)
		(layer "F.Cu")
		(net "VCCP_A")
	)
	(segment
		(start 130.433318 -144.254474)
		(end 130.433318 -141.703298)
		(width 0.508)
		(layer "F.Cu")
		(net "VCCP_A")
	)
	(via
		(at 130.487166 -141.64945)
		(size 0.6604)
		(drill 0.3302)
		(layers "F.Cu" "B.Cu")
		(net "VCCP_A")
	)
	(segment
		(start 229.064312 -389.763)
		(end 229.8446 -389.763)
		(width 0.508)
		(layer "F.Cu")
		(net "P3V3_IN_BIAS")
	)
	(segment
		(start 232.2703 -387.6675)
		(end 232.2703 -387.36524)
		(width 0.381)
		(layer "F.Cu")
		(net "P3V3_IN_BIAS")
	)
	(segment
		(start 231.469184 -388.72287)
		(end 231.469184 -388.468616)
		(width 0.381)
		(layer "F.Cu")
		(net "P3V3_IN_BIAS")
	)
	(segment
		(start 228.927152 -389.62584)
		(end 229.064312 -389.763)
		(width 0.508)
		(layer "F.Cu")
		(net "P3V3_IN_BIAS")
	)
	(segment
		(start 231.469184 -388.468616)
		(end 232.2703 -387.6675)
		(width 0.381)
		(layer "F.Cu")
		(net "P3V3_IN_BIAS")
	)
	(segment
		(start 230.906828 -389.763)
		(end 231.469184 -389.200644)
		(width 0.508)
		(layer "F.Cu")
		(net "P3V3_IN_BIAS")
	)
	(segment
		(start 229.8446 -389.763)
		(end 230.906828 -389.763)
		(width 0.508)
		(layer "F.Cu")
		(net "P3V3_IN_BIAS")
	)
	(segment
		(start 231.469184 -389.200644)
		(end 231.469184 -388.72287)
		(width 0.508)
		(layer "F.Cu")
		(net "P3V3_IN_BIAS")
	)
	(via
		(at 229.8446 -389.763)
		(size 0.6604)
		(drill 0.3302)
		(layers "F.Cu" "B.Cu")
		(net "P3V3_IN_BIAS")
	)
	(segment
		(start 377.090432 -138.48461)
		(end 377.090432 -137.67943)
		(width 0.381)
		(layer "F.Cu")
		(net "P3V3_B_BIAS")
	)
	(segment
		(start 379.355096 -136.9314)
		(end 379.352048 -136.934448)
		(width 0.508)
		(layer "F.Cu")
		(net "P3V3_B_BIAS")
	)
	(segment
		(start 377.090432 -137.67943)
		(end 377.835414 -136.934448)
		(width 0.381)
		(layer "F.Cu")
		(net "P3V3_B_BIAS")
	)
	(segment
		(start 379.352048 -136.934448)
		(end 379.1458 -136.934448)
		(width 0.508)
		(layer "F.Cu")
		(net "P3V3_B_BIAS")
	)
	(segment
		(start 380.462028 -135.744458)
		(end 380.462028 -136.9314)
		(width 0.508)
		(layer "F.Cu")
		(net "P3V3_B_BIAS")
	)
	(segment
		(start 380.462028 -136.9314)
		(end 379.355096 -136.9314)
		(width 0.508)
		(layer "F.Cu")
		(net "P3V3_B_BIAS")
	)
	(segment
		(start 377.835414 -136.934448)
		(end 379.1458 -136.934448)
		(width 0.508)
		(layer "F.Cu")
		(net "P3V3_B_BIAS")
	)
	(segment
		(start 380.62916 -135.577326)
		(end 380.462028 -135.744458)
		(width 0.508)
		(layer "F.Cu")
		(net "P3V3_B_BIAS")
	)
	(via
		(at 379.1458 -136.934448)
		(size 0.6604)
		(drill 0.3302)
		(layers "F.Cu" "B.Cu")
		(net "P3V3_B_BIAS")
	)
	(segment
		(start 138.016234 -138.992864)
		(end 138.016234 -140.509244)
		(width 0.381)
		(layer "F.Cu")
		(net "P3V3_A_BIAS")
	)
	(segment
		(start 134.40283 -140.813282)
		(end 134.695438 -140.520674)
		(width 0.508)
		(layer "F.Cu")
		(net "P3V3_A_BIAS")
	)
	(segment
		(start 134.695438 -140.520674)
		(end 134.698486 -140.517626)
		(width 0.508)
		(layer "F.Cu")
		(net "P3V3_A_BIAS")
	)
	(segment
		(start 138.016234 -140.509244)
		(end 138.007852 -140.517626)
		(width 0.381)
		(layer "F.Cu")
		(net "P3V3_A_BIAS")
	)
	(segment
		(start 134.40283 -141.90218)
		(end 134.40283 -140.813282)
		(width 0.508)
		(layer "F.Cu")
		(net "P3V3_A_BIAS")
	)
	(segment
		(start 138.007852 -140.517626)
		(end 136.392666 -140.517626)
		(width 0.508)
		(layer "F.Cu")
		(net "P3V3_A_BIAS")
	)
	(segment
		(start 134.698486 -140.517626)
		(end 136.392666 -140.517626)
		(width 0.508)
		(layer "F.Cu")
		(net "P3V3_A_BIAS")
	)
	(via
		(at 136.392666 -140.517626)
		(size 0.6604)
		(drill 0.3302)
		(layers "F.Cu" "B.Cu")
		(net "P3V3_A_BIAS")
	)
	(via
		(at 246.651526 -379.84811)
		(size 0.6604)
		(drill 0.3302)
		(layers "F.Cu" "B.Cu")
		(net "MB3_CM_GATE_C")
	)
	(via
		(at 368.728244 -151.082756)
		(size 0.6604)
		(drill 0.3302)
		(layers "F.Cu" "B.Cu")
		(net "MB1_CM_GATE_C")
	)
	(via
		(at 146.204178 -126.986538)
		(size 0.6604)
		(drill 0.3302)
		(layers "F.Cu" "B.Cu")
		(net "MB0_CM_GATE_C")
	)
	(segment
		(start 301.139352 -74.3458)
		(end 301.139352 -73.401174)
		(width 0.17145)
		(layer "F.Cu")
		(net "COMP_B_BMC_B_SPARE_1")
	)
	(segment
		(start 301.139352 -73.401174)
		(end 301.139352 -72.39889)
		(width 0.17145)
		(layer "F.Cu")
		(net "COMP_B_BMC_B_SPARE_1")
	)
	(via
		(at 301.139352 -72.39889)
		(size 0.5588)
		(drill 0.3048)
		(layers "F.Cu" "B.Cu")
		(net "COMP_B_BMC_B_SPARE_1")
	)
	(via
		(at 301.139352 -73.401174)
		(size 0.6604)
		(drill 0.3302)
		(layers "F.Cu" "B.Cu")
		(net "COMP_B_BMC_B_SPARE_1")
	)
	(via
		(at 345.077542 -73.8886)
		(size 0.5588)
		(drill 0.3048)
		(layers "F.Cu" "B.Cu")
		(net "COMP_B_BMC_B_SPARE_1")
	)
	(segment
		(start 302.629062 -73.8886)
		(end 301.139352 -72.39889)
		(width 0.13335)
		(layer "In2.Cu")
		(net "COMP_B_BMC_B_SPARE_1")
	)
	(segment
		(start 345.077542 -73.8886)
		(end 302.629062 -73.8886)
		(width 0.13335)
		(layer "In2.Cu")
		(net "COMP_B_BMC_B_SPARE_1")
	)
	(segment
		(start 354.029264 -33.168336)
		(end 345.077542 -42.120058)
		(width 0.12065)
		(layer "In4.Cu")
		(net "COMP_B_BMC_B_SPARE_1")
	)
	(segment
		(start 355.149912 -29.550106)
		(end 354.029264 -30.670754)
		(width 0.12065)
		(layer "In4.Cu")
		(net "COMP_B_BMC_B_SPARE_1")
	)
	(segment
		(start 345.077542 -42.120058)
		(end 345.077542 -73.8886)
		(width 0.12065)
		(layer "In4.Cu")
		(net "COMP_B_BMC_B_SPARE_1")
	)
	(segment
		(start 354.029264 -30.670754)
		(end 354.029264 -33.168336)
		(width 0.12065)
		(layer "In4.Cu")
		(net "COMP_B_BMC_B_SPARE_1")
	)
	(segment
		(start 222.1611 -114.3508)
		(end 221.036134 -114.3508)
		(width 0.17145)
		(layer "F.Cu")
		(net "COMP_A_BMC_A_SPARE_1")
	)
	(segment
		(start 221.036134 -114.3508)
		(end 220.324934 -114.3508)
		(width 0.17145)
		(layer "F.Cu")
		(net "COMP_A_BMC_A_SPARE_1")
	)
	(segment
		(start 220.324934 -114.3508)
		(end 220.045534 -114.6302)
		(width 0.17145)
		(layer "F.Cu")
		(net "COMP_A_BMC_A_SPARE_1")
	)
	(via
		(at 220.045534 -114.6302)
		(size 0.5588)
		(drill 0.3048)
		(layers "F.Cu" "B.Cu")
		(net "COMP_A_BMC_A_SPARE_1")
	)
	(via
		(at 221.036134 -114.3508)
		(size 0.6604)
		(drill 0.3302)
		(layers "F.Cu" "B.Cu")
		(net "COMP_A_BMC_A_SPARE_1")
	)
	(via
		(at 107.1118 -114.3508)
		(size 0.5588)
		(drill 0.3048)
		(layers "F.Cu" "B.Cu")
		(net "COMP_A_BMC_A_SPARE_1")
	)
	(segment
		(start 219.766134 -114.3508)
		(end 220.045534 -114.6302)
		(width 0.13335)
		(layer "In2.Cu")
		(net "COMP_A_BMC_A_SPARE_1")
	)
	(segment
		(start 107.1118 -114.3508)
		(end 219.766134 -114.3508)
		(width 0.13335)
		(layer "In2.Cu")
		(net "COMP_A_BMC_A_SPARE_1")
	)
	(segment
		(start 108.365798 -37.97046)
		(end 102.63886 -43.697398)
		(width 0.12065)
		(layer "In4.Cu")
		(net "COMP_A_BMC_A_SPARE_1")
	)
	(segment
		(start 102.63886 -43.697398)
		(end 102.63886 -83.606894)
		(width 0.12065)
		(layer "In4.Cu")
		(net "COMP_A_BMC_A_SPARE_1")
	)
	(segment
		(start 102.63886 -83.606894)
		(end 107.1118 -88.079834)
		(width 0.12065)
		(layer "In4.Cu")
		(net "COMP_A_BMC_A_SPARE_1")
	)
	(segment
		(start 109.149896 -29.550106)
		(end 108.365798 -30.334204)
		(width 0.12065)
		(layer "In4.Cu")
		(net "COMP_A_BMC_A_SPARE_1")
	)
	(segment
		(start 107.1118 -88.079834)
		(end 107.1118 -114.3508)
		(width 0.12065)
		(layer "In4.Cu")
		(net "COMP_A_BMC_A_SPARE_1")
	)
	(segment
		(start 108.365798 -30.334204)
		(end 108.365798 -37.97046)
		(width 0.12065)
		(layer "In4.Cu")
		(net "COMP_A_BMC_A_SPARE_1")
	)
	(segment
		(start 470.021158 -294.839644)
		(end 470.021158 -311.652158)
		(width 0.17145)
		(layer "F.Cu")
		(net "FLT_HDD35_N")
	)
	(segment
		(start 472.399614 -323.66966)
		(end 472.399614 -314.030614)
		(width 0.17145)
		(layer "F.Cu")
		(net "FLT_HDD35_N")
	)
	(segment
		(start 472.399614 -314.030614)
		(end 471.587068 -313.218068)
		(width 0.17145)
		(layer "F.Cu")
		(net "FLT_HDD35_N")
	)
	(segment
		(start 470.021158 -311.652158)
		(end 471.587068 -313.218068)
		(width 0.17145)
		(layer "F.Cu")
		(net "FLT_HDD35_N")
	)
	(via
		(at 471.587068 -313.218068)
		(size 0.6604)
		(drill 0.3302)
		(layers "F.Cu" "B.Cu")
		(net "FLT_HDD35_N")
	)
	(segment
		(start 440.849512 -323.66966)
		(end 440.849512 -311.6072)
		(width 0.17145)
		(layer "F.Cu")
		(net "FLT_HDD34_N")
	)
	(segment
		(start 440.180984 -308.07914)
		(end 440.849512 -308.747668)
		(width 0.17145)
		(layer "F.Cu")
		(net "FLT_HDD34_N")
	)
	(segment
		(start 440.180984 -294.794432)
		(end 440.180984 -308.07914)
		(width 0.17145)
		(layer "F.Cu")
		(net "FLT_HDD34_N")
	)
	(segment
		(start 440.849512 -308.747668)
		(end 440.849512 -311.6072)
		(width 0.17145)
		(layer "F.Cu")
		(net "FLT_HDD34_N")
	)
	(via
		(at 440.849512 -311.6072)
		(size 0.6604)
		(drill 0.3302)
		(layers "F.Cu" "B.Cu")
		(net "FLT_HDD34_N")
	)
	(segment
		(start 411.46476 -313.83224)
		(end 411.46476 -311.2516)
		(width 0.17145)
		(layer "F.Cu")
		(net "FLT_HDD33_N")
	)
	(segment
		(start 409.1686 -323.538596)
		(end 409.1686 -316.1284)
		(width 0.17145)
		(layer "F.Cu")
		(net "FLT_HDD33_N")
	)
	(segment
		(start 412.323534 -291.101018)
		(end 412.653988 -291.431472)
		(width 0.17145)
		(layer "F.Cu")
		(net "FLT_HDD33_N")
	)
	(segment
		(start 409.299664 -323.66966)
		(end 409.1686 -323.538596)
		(width 0.17145)
		(layer "F.Cu")
		(net "FLT_HDD33_N")
	)
	(segment
		(start 411.46476 -297.822112)
		(end 411.46476 -311.2516)
		(width 0.17145)
		(layer "F.Cu")
		(net "FLT_HDD33_N")
	)
	(segment
		(start 412.653988 -291.431472)
		(end 412.653988 -296.632884)
		(width 0.17145)
		(layer "F.Cu")
		(net "FLT_HDD33_N")
	)
	(segment
		(start 409.1686 -316.1284)
		(end 411.46476 -313.83224)
		(width 0.17145)
		(layer "F.Cu")
		(net "FLT_HDD33_N")
	)
	(segment
		(start 412.653988 -296.632884)
		(end 411.46476 -297.822112)
		(width 0.17145)
		(layer "F.Cu")
		(net "FLT_HDD33_N")
	)
	(via
		(at 411.46476 -311.2516)
		(size 0.6604)
		(drill 0.3302)
		(layers "F.Cu" "B.Cu")
		(net "FLT_HDD33_N")
	)
	(segment
		(start 377.749562 -300.000162)
		(end 377.749562 -313.5122)
		(width 0.17145)
		(layer "F.Cu")
		(net "FLT_HDD32_N")
	)
	(segment
		(start 377.308872 -294.845232)
		(end 377.308872 -299.559472)
		(width 0.17145)
		(layer "F.Cu")
		(net "FLT_HDD32_N")
	)
	(segment
		(start 377.308872 -299.559472)
		(end 377.749562 -300.000162)
		(width 0.17145)
		(layer "F.Cu")
		(net "FLT_HDD32_N")
	)
	(segment
		(start 377.749562 -323.66966)
		(end 377.749562 -313.5122)
		(width 0.17145)
		(layer "F.Cu")
		(net "FLT_HDD32_N")
	)
	(via
		(at 377.749562 -313.5122)
		(size 0.6604)
		(drill 0.3302)
		(layers "F.Cu" "B.Cu")
		(net "FLT_HDD32_N")
	)
	(segment
		(start 346.199714 -299.705268)
		(end 346.199714 -318.6176)
		(width 0.17145)
		(layer "F.Cu")
		(net "FLT_HDD31_N")
	)
	(segment
		(start 345.641676 -294.823896)
		(end 345.641676 -299.14723)
		(width 0.17145)
		(layer "F.Cu")
		(net "FLT_HDD31_N")
	)
	(segment
		(start 345.641676 -299.14723)
		(end 346.199714 -299.705268)
		(width 0.17145)
		(layer "F.Cu")
		(net "FLT_HDD31_N")
	)
	(segment
		(start 346.199714 -323.66966)
		(end 346.199714 -318.6176)
		(width 0.17145)
		(layer "F.Cu")
		(net "FLT_HDD31_N")
	)
	(via
		(at 346.199714 -318.6176)
		(size 0.6604)
		(drill 0.3302)
		(layers "F.Cu" "B.Cu")
		(net "FLT_HDD31_N")
	)
	(segment
		(start 311.36463 -303.816004)
		(end 314.649612 -307.100986)
		(width 0.17145)
		(layer "F.Cu")
		(net "FLT_HDD30_N")
	)
	(segment
		(start 311.36463 -294.866314)
		(end 311.36463 -303.816004)
		(width 0.17145)
		(layer "F.Cu")
		(net "FLT_HDD30_N")
	)
	(segment
		(start 314.649612 -323.66966)
		(end 314.649612 -310.4388)
		(width 0.17145)
		(layer "F.Cu")
		(net "FLT_HDD30_N")
	)
	(segment
		(start 314.649612 -307.100986)
		(end 314.649612 -310.4388)
		(width 0.17145)
		(layer "F.Cu")
		(net "FLT_HDD30_N")
	)
	(via
		(at 314.649612 -310.4388)
		(size 0.6604)
		(drill 0.3302)
		(layers "F.Cu" "B.Cu")
		(net "FLT_HDD30_N")
	)
	(segment
		(start 167.208962 -308.94782)
		(end 175.227488 -316.966346)
		(width 0.17145)
		(layer "F.Cu")
		(net "FLT_HDD29_N")
	)
	(segment
		(start 164.279326 -306.018184)
		(end 167.208962 -308.94782)
		(width 0.17145)
		(layer "F.Cu")
		(net "FLT_HDD29_N")
	)
	(segment
		(start 175.049688 -323.03466)
		(end 175.049688 -323.66966)
		(width 0.17145)
		(layer "F.Cu")
		(net "FLT_HDD29_N")
	)
	(segment
		(start 164.279326 -304.83556)
		(end 164.279326 -306.018184)
		(width 0.17145)
		(layer "F.Cu")
		(net "FLT_HDD29_N")
	)
	(segment
		(start 175.227488 -316.966346)
		(end 175.227488 -322.85686)
		(width 0.17145)
		(layer "F.Cu")
		(net "FLT_HDD29_N")
	)
	(segment
		(start 175.227488 -322.85686)
		(end 175.049688 -323.03466)
		(width 0.17145)
		(layer "F.Cu")
		(net "FLT_HDD29_N")
	)
	(via
		(at 167.208962 -308.94782)
		(size 0.6604)
		(drill 0.3302)
		(layers "F.Cu" "B.Cu")
		(net "FLT_HDD29_N")
	)
	(segment
		(start 143.499586 -323.03466)
		(end 143.499586 -323.66966)
		(width 0.17145)
		(layer "F.Cu")
		(net "FLT_HDD28_N")
	)
	(segment
		(start 143.677386 -320.464688)
		(end 143.677386 -322.85686)
		(width 0.17145)
		(layer "F.Cu")
		(net "FLT_HDD28_N")
	)
	(segment
		(start 132.718302 -309.505604)
		(end 140.912088 -317.69939)
		(width 0.17145)
		(layer "F.Cu")
		(net "FLT_HDD28_N")
	)
	(segment
		(start 143.677386 -322.85686)
		(end 143.499586 -323.03466)
		(width 0.17145)
		(layer "F.Cu")
		(net "FLT_HDD28_N")
	)
	(segment
		(start 132.718302 -304.846228)
		(end 132.718302 -309.505604)
		(width 0.17145)
		(layer "F.Cu")
		(net "FLT_HDD28_N")
	)
	(segment
		(start 140.912088 -317.69939)
		(end 143.677386 -320.464688)
		(width 0.17145)
		(layer "F.Cu")
		(net "FLT_HDD28_N")
	)
	(via
		(at 140.912088 -317.69939)
		(size 0.6604)
		(drill 0.3302)
		(layers "F.Cu" "B.Cu")
		(net "FLT_HDD28_N")
	)
	(segment
		(start 108.0008 -317.807848)
		(end 108.0008 -313.756548)
		(width 0.17145)
		(layer "F.Cu")
		(net "FLT_HDD27_N")
	)
	(segment
		(start 112.127538 -321.934586)
		(end 108.0008 -317.807848)
		(width 0.17145)
		(layer "F.Cu")
		(net "FLT_HDD27_N")
	)
	(segment
		(start 112.127538 -322.999862)
		(end 112.127538 -321.934586)
		(width 0.17145)
		(layer "F.Cu")
		(net "FLT_HDD27_N")
	)
	(segment
		(start 111.949738 -323.177662)
		(end 112.127538 -322.999862)
		(width 0.17145)
		(layer "F.Cu")
		(net "FLT_HDD27_N")
	)
	(segment
		(start 102.485698 -308.241446)
		(end 101.190044 -306.945792)
		(width 0.17145)
		(layer "F.Cu")
		(net "FLT_HDD27_N")
	)
	(segment
		(start 101.190044 -306.945792)
		(end 101.190044 -304.856896)
		(width 0.17145)
		(layer "F.Cu")
		(net "FLT_HDD27_N")
	)
	(segment
		(start 108.0008 -313.756548)
		(end 102.485698 -308.241446)
		(width 0.17145)
		(layer "F.Cu")
		(net "FLT_HDD27_N")
	)
	(segment
		(start 111.949738 -323.66966)
		(end 111.949738 -323.177662)
		(width 0.17145)
		(layer "F.Cu")
		(net "FLT_HDD27_N")
	)
	(via
		(at 102.485698 -308.241446)
		(size 0.6604)
		(drill 0.3302)
		(layers "F.Cu" "B.Cu")
		(net "FLT_HDD27_N")
	)
	(segment
		(start 76.073 -317.1698)
		(end 77.72781 -318.82461)
		(width 0.17145)
		(layer "F.Cu")
		(net "FLT_HDD26_N")
	)
	(segment
		(start 77.825346 -319.267586)
		(end 77.72781 -319.17005)
		(width 0.17145)
		(layer "F.Cu")
		(net "FLT_HDD26_N")
	)
	(segment
		(start 77.72781 -318.82461)
		(end 77.72781 -319.17005)
		(width 0.17145)
		(layer "F.Cu")
		(net "FLT_HDD26_N")
	)
	(segment
		(start 80.399636 -323.66966)
		(end 80.399636 -321.982084)
		(width 0.17145)
		(layer "F.Cu")
		(net "FLT_HDD26_N")
	)
	(segment
		(start 77.825346 -319.407794)
		(end 77.825346 -319.267586)
		(width 0.17145)
		(layer "F.Cu")
		(net "FLT_HDD26_N")
	)
	(segment
		(start 69.65061 -304.856896)
		(end 69.65061 -309.52821)
		(width 0.17145)
		(layer "F.Cu")
		(net "FLT_HDD26_N")
	)
	(segment
		(start 69.65061 -309.52821)
		(end 76.073 -315.9506)
		(width 0.17145)
		(layer "F.Cu")
		(net "FLT_HDD26_N")
	)
	(segment
		(start 76.073 -315.9506)
		(end 76.073 -317.1698)
		(width 0.17145)
		(layer "F.Cu")
		(net "FLT_HDD26_N")
	)
	(segment
		(start 80.399636 -321.982084)
		(end 77.825346 -319.407794)
		(width 0.17145)
		(layer "F.Cu")
		(net "FLT_HDD26_N")
	)
	(via
		(at 77.72781 -319.17005)
		(size 0.6604)
		(drill 0.3302)
		(layers "F.Cu" "B.Cu")
		(net "FLT_HDD26_N")
	)
	(segment
		(start 39.236142 -308.335426)
		(end 38.100254 -307.199538)
		(width 0.17145)
		(layer "F.Cu")
		(net "FLT_HDD25_N")
	)
	(segment
		(start 49.027334 -318.126618)
		(end 39.236142 -308.335426)
		(width 0.17145)
		(layer "F.Cu")
		(net "FLT_HDD25_N")
	)
	(segment
		(start 48.849534 -323.66966)
		(end 48.849534 -323.133466)
		(width 0.17145)
		(layer "F.Cu")
		(net "FLT_HDD25_N")
	)
	(segment
		(start 38.100254 -307.199538)
		(end 38.100254 -304.856896)
		(width 0.17145)
		(layer "F.Cu")
		(net "FLT_HDD25_N")
	)
	(segment
		(start 48.849534 -323.133466)
		(end 49.027334 -322.955666)
		(width 0.17145)
		(layer "F.Cu")
		(net "FLT_HDD25_N")
	)
	(segment
		(start 49.027334 -322.955666)
		(end 49.027334 -318.126618)
		(width 0.17145)
		(layer "F.Cu")
		(net "FLT_HDD25_N")
	)
	(via
		(at 39.236142 -308.335426)
		(size 0.6604)
		(drill 0.3302)
		(layers "F.Cu" "B.Cu")
		(net "FLT_HDD25_N")
	)
	(segment
		(start 17.299686 -323.03466)
		(end 17.299686 -323.66966)
		(width 0.17145)
		(layer "F.Cu")
		(net "FLT_HDD24_N")
	)
	(segment
		(start 12.247626 -303.967134)
		(end 12.247626 -310.03494)
		(width 0.17145)
		(layer "F.Cu")
		(net "FLT_HDD24_N")
	)
	(segment
		(start 12.247626 -310.03494)
		(end 17.477486 -315.2648)
		(width 0.17145)
		(layer "F.Cu")
		(net "FLT_HDD24_N")
	)
	(segment
		(start 6.799326 -298.518834)
		(end 12.247626 -303.967134)
		(width 0.17145)
		(layer "F.Cu")
		(net "FLT_HDD24_N")
	)
	(segment
		(start 6.799326 -294.830754)
		(end 6.799326 -298.518834)
		(width 0.17145)
		(layer "F.Cu")
		(net "FLT_HDD24_N")
	)
	(segment
		(start 17.477486 -315.2648)
		(end 17.477486 -322.85686)
		(width 0.17145)
		(layer "F.Cu")
		(net "FLT_HDD24_N")
	)
	(segment
		(start 17.477486 -322.85686)
		(end 17.299686 -323.03466)
		(width 0.17145)
		(layer "F.Cu")
		(net "FLT_HDD24_N")
	)
	(via
		(at 12.247626 -303.967134)
		(size 0.6604)
		(drill 0.3302)
		(layers "F.Cu" "B.Cu")
		(net "FLT_HDD24_N")
	)
	(segment
		(start 473.593668 -294.845232)
		(end 473.593668 -295.754552)
		(width 0.17145)
		(layer "F.Cu")
		(net "DRV_ACT_35_N")
	)
	(segment
		(start 471.2716 -311.0992)
		(end 472.556078 -312.383678)
		(width 0.17145)
		(layer "F.Cu")
		(net "DRV_ACT_35_N")
	)
	(segment
		(start 471.2716 -298.07662)
		(end 471.2716 -311.0992)
		(width 0.17145)
		(layer "F.Cu")
		(net "DRV_ACT_35_N")
	)
	(segment
		(start 473.400374 -313.227974)
		(end 472.556078 -312.383678)
		(width 0.17145)
		(layer "F.Cu")
		(net "DRV_ACT_35_N")
	)
	(segment
		(start 473.400374 -323.66966)
		(end 473.400374 -313.227974)
		(width 0.17145)
		(layer "F.Cu")
		(net "DRV_ACT_35_N")
	)
	(segment
		(start 473.593668 -295.754552)
		(end 471.2716 -298.07662)
		(width 0.17145)
		(layer "F.Cu")
		(net "DRV_ACT_35_N")
	)
	(via
		(at 472.556078 -312.383678)
		(size 0.6604)
		(drill 0.3302)
		(layers "F.Cu" "B.Cu")
		(net "DRV_ACT_35_N")
	)
	(segment
		(start 440.144662 -288.40049)
		(end 440.698128 -288.40049)
		(width 0.17145)
		(layer "F.Cu")
		(net "DRV_ACT_34_N")
	)
	(segment
		(start 441.850272 -299.093128)
		(end 441.850272 -307.1622)
		(width 0.17145)
		(layer "F.Cu")
		(net "DRV_ACT_34_N")
	)
	(segment
		(start 441.850272 -307.1622)
		(end 441.850272 -323.66966)
		(width 0.17145)
		(layer "F.Cu")
		(net "DRV_ACT_34_N")
	)
	(segment
		(start 442.4934 -290.195762)
		(end 442.4934 -298.45)
		(width 0.17145)
		(layer "F.Cu")
		(net "DRV_ACT_34_N")
	)
	(segment
		(start 440.698128 -288.40049)
		(end 442.4934 -290.195762)
		(width 0.17145)
		(layer "F.Cu")
		(net "DRV_ACT_34_N")
	)
	(segment
		(start 442.4934 -298.45)
		(end 441.850272 -299.093128)
		(width 0.17145)
		(layer "F.Cu")
		(net "DRV_ACT_34_N")
	)
	(via
		(at 441.850272 -307.1622)
		(size 0.6604)
		(drill 0.3302)
		(layers "F.Cu" "B.Cu")
		(net "DRV_ACT_34_N")
	)
	(segment
		(start 412.242 -315.0108)
		(end 410.300424 -316.952376)
		(width 0.17145)
		(layer "F.Cu")
		(net "DRV_ACT_33_N")
	)
	(segment
		(start 414.4518 -291.821616)
		(end 413.7152 -292.558216)
		(width 0.17145)
		(layer "F.Cu")
		(net "DRV_ACT_33_N")
	)
	(segment
		(start 413.7152 -292.558216)
		(end 413.7152 -296.5958)
		(width 0.17145)
		(layer "F.Cu")
		(net "DRV_ACT_33_N")
	)
	(segment
		(start 412.242 -298.069)
		(end 412.242 -315.0108)
		(width 0.17145)
		(layer "F.Cu")
		(net "DRV_ACT_33_N")
	)
	(segment
		(start 410.300424 -323.66966)
		(end 410.300424 -319.1764)
		(width 0.17145)
		(layer "F.Cu")
		(net "DRV_ACT_33_N")
	)
	(segment
		(start 413.7152 -296.5958)
		(end 412.242 -298.069)
		(width 0.17145)
		(layer "F.Cu")
		(net "DRV_ACT_33_N")
	)
	(segment
		(start 410.300424 -316.952376)
		(end 410.300424 -319.1764)
		(width 0.17145)
		(layer "F.Cu")
		(net "DRV_ACT_33_N")
	)
	(segment
		(start 412.477458 -284.975046)
		(end 413.724598 -284.975046)
		(width 0.17145)
		(layer "F.Cu")
		(net "DRV_ACT_33_N")
	)
	(segment
		(start 414.4518 -285.702248)
		(end 414.4518 -291.821616)
		(width 0.17145)
		(layer "F.Cu")
		(net "DRV_ACT_33_N")
	)
	(segment
		(start 413.724598 -284.975046)
		(end 414.4518 -285.702248)
		(width 0.17145)
		(layer "F.Cu")
		(net "DRV_ACT_33_N")
	)
	(via
		(at 410.300424 -319.1764)
		(size 0.6604)
		(drill 0.3302)
		(layers "F.Cu" "B.Cu")
		(net "DRV_ACT_33_N")
	)
	(segment
		(start 378.445014 -288.122614)
		(end 379.2982 -288.9758)
		(width 0.17145)
		(layer "F.Cu")
		(net "DRV_ACT_32_N")
	)
	(segment
		(start 378.750322 -295.061132)
		(end 378.750322 -307.7464)
		(width 0.17145)
		(layer "F.Cu")
		(net "DRV_ACT_32_N")
	)
	(segment
		(start 377.246134 -288.122614)
		(end 378.445014 -288.122614)
		(width 0.17145)
		(layer "F.Cu")
		(net "DRV_ACT_32_N")
	)
	(segment
		(start 379.2982 -288.9758)
		(end 379.2982 -294.513254)
		(width 0.17145)
		(layer "F.Cu")
		(net "DRV_ACT_32_N")
	)
	(segment
		(start 378.750322 -307.7464)
		(end 378.750322 -323.66966)
		(width 0.17145)
		(layer "F.Cu")
		(net "DRV_ACT_32_N")
	)
	(segment
		(start 379.2982 -294.513254)
		(end 378.750322 -295.061132)
		(width 0.17145)
		(layer "F.Cu")
		(net "DRV_ACT_32_N")
	)
	(via
		(at 378.750322 -307.7464)
		(size 0.6604)
		(drill 0.3302)
		(layers "F.Cu" "B.Cu")
		(net "DRV_ACT_32_N")
	)
	(segment
		(start 346.67317 -289.34537)
		(end 345.842844 -289.34537)
		(width 0.17145)
		(layer "F.Cu")
		(net "DRV_ACT_31_N")
	)
	(segment
		(start 347.200474 -304.4698)
		(end 347.200474 -299.380402)
		(width 0.17145)
		(layer "F.Cu")
		(net "DRV_ACT_31_N")
	)
	(segment
		(start 347.200474 -304.4698)
		(end 347.200474 -323.66966)
		(width 0.17145)
		(layer "F.Cu")
		(net "DRV_ACT_31_N")
	)
	(segment
		(start 347.564202 -290.236402)
		(end 346.67317 -289.34537)
		(width 0.17145)
		(layer "F.Cu")
		(net "DRV_ACT_31_N")
	)
	(segment
		(start 347.564202 -299.016674)
		(end 347.564202 -290.236402)
		(width 0.17145)
		(layer "F.Cu")
		(net "DRV_ACT_31_N")
	)
	(segment
		(start 347.200474 -299.380402)
		(end 347.564202 -299.016674)
		(width 0.17145)
		(layer "F.Cu")
		(net "DRV_ACT_31_N")
	)
	(via
		(at 347.200474 -304.4698)
		(size 0.6604)
		(drill 0.3302)
		(layers "F.Cu" "B.Cu")
		(net "DRV_ACT_31_N")
	)
	(segment
		(start 315.650372 -299.486828)
		(end 315.650372 -302.4886)
		(width 0.17145)
		(layer "F.Cu")
		(net "DRV_ACT_30_N")
	)
	(segment
		(start 314.94603 -298.782486)
		(end 315.650372 -299.486828)
		(width 0.17145)
		(layer "F.Cu")
		(net "DRV_ACT_30_N")
	)
	(segment
		(start 315.650372 -302.4886)
		(end 315.650372 -323.66966)
		(width 0.17145)
		(layer "F.Cu")
		(net "DRV_ACT_30_N")
	)
	(segment
		(start 314.94603 -294.859456)
		(end 314.94603 -298.782486)
		(width 0.17145)
		(layer "F.Cu")
		(net "DRV_ACT_30_N")
	)
	(via
		(at 315.650372 -302.4886)
		(size 0.6604)
		(drill 0.3302)
		(layers "F.Cu" "B.Cu")
		(net "DRV_ACT_30_N")
	)
	(segment
		(start 176.050448 -323.08546)
		(end 175.786288 -322.8213)
		(width 0.17145)
		(layer "F.Cu")
		(net "DRV_ACT_29_N")
	)
	(segment
		(start 165.8112 -299.696886)
		(end 166.4462 -300.331886)
		(width 0.17145)
		(layer "F.Cu")
		(net "DRV_ACT_29_N")
	)
	(segment
		(start 175.786288 -316.172088)
		(end 172.696378 -313.082178)
		(width 0.17145)
		(layer "F.Cu")
		(net "DRV_ACT_29_N")
	)
	(segment
		(start 175.786288 -322.8213)
		(end 175.786288 -316.172088)
		(width 0.17145)
		(layer "F.Cu")
		(net "DRV_ACT_29_N")
	)
	(segment
		(start 164.303456 -299.696886)
		(end 165.8112 -299.696886)
		(width 0.17145)
		(layer "F.Cu")
		(net "DRV_ACT_29_N")
	)
	(segment
		(start 166.4462 -306.832)
		(end 172.696378 -313.082178)
		(width 0.17145)
		(layer "F.Cu")
		(net "DRV_ACT_29_N")
	)
	(segment
		(start 166.4462 -300.331886)
		(end 166.4462 -306.832)
		(width 0.17145)
		(layer "F.Cu")
		(net "DRV_ACT_29_N")
	)
	(segment
		(start 176.050448 -323.66966)
		(end 176.050448 -323.08546)
		(width 0.17145)
		(layer "F.Cu")
		(net "DRV_ACT_29_N")
	)
	(via
		(at 172.696378 -313.082178)
		(size 0.6604)
		(drill 0.3302)
		(layers "F.Cu" "B.Cu")
		(net "DRV_ACT_29_N")
	)
	(segment
		(start 144.500346 -323.08546)
		(end 144.500346 -323.66966)
		(width 0.17145)
		(layer "F.Cu")
		(net "DRV_ACT_28_N")
	)
	(segment
		(start 134.962138 -309.053738)
		(end 138.9634 -313.055)
		(width 0.17145)
		(layer "F.Cu")
		(net "DRV_ACT_28_N")
	)
	(segment
		(start 134.649464 -299.749464)
		(end 134.962138 -300.062138)
		(width 0.17145)
		(layer "F.Cu")
		(net "DRV_ACT_28_N")
	)
	(segment
		(start 132.752592 -299.749464)
		(end 134.649464 -299.749464)
		(width 0.17145)
		(layer "F.Cu")
		(net "DRV_ACT_28_N")
	)
	(segment
		(start 138.9634 -313.055)
		(end 138.9634 -314.8838)
		(width 0.17145)
		(layer "F.Cu")
		(net "DRV_ACT_28_N")
	)
	(segment
		(start 138.9634 -314.8838)
		(end 144.236186 -320.156586)
		(width 0.17145)
		(layer "F.Cu")
		(net "DRV_ACT_28_N")
	)
	(segment
		(start 134.962138 -300.062138)
		(end 134.962138 -309.053738)
		(width 0.17145)
		(layer "F.Cu")
		(net "DRV_ACT_28_N")
	)
	(segment
		(start 144.236186 -322.8213)
		(end 144.500346 -323.08546)
		(width 0.17145)
		(layer "F.Cu")
		(net "DRV_ACT_28_N")
	)
	(segment
		(start 144.236186 -320.156586)
		(end 144.236186 -322.8213)
		(width 0.17145)
		(layer "F.Cu")
		(net "DRV_ACT_28_N")
	)
	(via
		(at 138.9634 -313.055)
		(size 0.6604)
		(drill 0.3302)
		(layers "F.Cu" "B.Cu")
		(net "DRV_ACT_28_N")
	)
	(segment
		(start 108.5596 -317.5762)
		(end 108.5596 -312.155586)
		(width 0.17145)
		(layer "F.Cu")
		(net "DRV_ACT_27_N")
	)
	(segment
		(start 101.878384 -299.47743)
		(end 104.017572 -301.616618)
		(width 0.17145)
		(layer "F.Cu")
		(net "DRV_ACT_27_N")
	)
	(segment
		(start 112.686338 -321.702938)
		(end 108.5596 -317.5762)
		(width 0.17145)
		(layer "F.Cu")
		(net "DRV_ACT_27_N")
	)
	(segment
		(start 108.5596 -312.155586)
		(end 105.51922 -309.115206)
		(width 0.17145)
		(layer "F.Cu")
		(net "DRV_ACT_27_N")
	)
	(segment
		(start 101.163374 -299.47743)
		(end 101.878384 -299.47743)
		(width 0.17145)
		(layer "F.Cu")
		(net "DRV_ACT_27_N")
	)
	(segment
		(start 104.017572 -301.616618)
		(end 104.017572 -307.613558)
		(width 0.17145)
		(layer "F.Cu")
		(net "DRV_ACT_27_N")
	)
	(segment
		(start 104.017572 -307.613558)
		(end 105.51922 -309.115206)
		(width 0.17145)
		(layer "F.Cu")
		(net "DRV_ACT_27_N")
	)
	(segment
		(start 112.686338 -322.922138)
		(end 112.686338 -321.702938)
		(width 0.17145)
		(layer "F.Cu")
		(net "DRV_ACT_27_N")
	)
	(segment
		(start 112.950498 -323.186298)
		(end 112.686338 -322.922138)
		(width 0.17145)
		(layer "F.Cu")
		(net "DRV_ACT_27_N")
	)
	(segment
		(start 112.950498 -323.66966)
		(end 112.950498 -323.186298)
		(width 0.17145)
		(layer "F.Cu")
		(net "DRV_ACT_27_N")
	)
	(via
		(at 105.51922 -309.115206)
		(size 0.6604)
		(drill 0.3302)
		(layers "F.Cu" "B.Cu")
		(net "DRV_ACT_27_N")
	)
	(segment
		(start 69.60997 -299.171868)
		(end 70.978268 -299.171868)
		(width 0.17145)
		(layer "F.Cu")
		(net "DRV_ACT_26_N")
	)
	(segment
		(start 71.977758 -310.610758)
		(end 77.057504 -315.690504)
		(width 0.17145)
		(layer "F.Cu")
		(net "DRV_ACT_26_N")
	)
	(segment
		(start 78.3844 -318.498728)
		(end 77.057504 -317.171832)
		(width 0.17145)
		(layer "F.Cu")
		(net "DRV_ACT_26_N")
	)
	(segment
		(start 78.3844 -319.1764)
		(end 78.3844 -318.498728)
		(width 0.17145)
		(layer "F.Cu")
		(net "DRV_ACT_26_N")
	)
	(segment
		(start 71.977758 -300.171358)
		(end 71.977758 -310.610758)
		(width 0.17145)
		(layer "F.Cu")
		(net "DRV_ACT_26_N")
	)
	(segment
		(start 81.400396 -323.132196)
		(end 81.136236 -322.868036)
		(width 0.17145)
		(layer "F.Cu")
		(net "DRV_ACT_26_N")
	)
	(segment
		(start 77.057504 -315.690504)
		(end 77.057504 -317.171832)
		(width 0.17145)
		(layer "F.Cu")
		(net "DRV_ACT_26_N")
	)
	(segment
		(start 70.978268 -299.171868)
		(end 71.977758 -300.171358)
		(width 0.17145)
		(layer "F.Cu")
		(net "DRV_ACT_26_N")
	)
	(segment
		(start 81.400396 -323.66966)
		(end 81.400396 -323.132196)
		(width 0.17145)
		(layer "F.Cu")
		(net "DRV_ACT_26_N")
	)
	(segment
		(start 81.136236 -321.928236)
		(end 78.3844 -319.1764)
		(width 0.17145)
		(layer "F.Cu")
		(net "DRV_ACT_26_N")
	)
	(segment
		(start 81.136236 -322.868036)
		(end 81.136236 -321.928236)
		(width 0.17145)
		(layer "F.Cu")
		(net "DRV_ACT_26_N")
	)
	(via
		(at 77.057504 -317.171832)
		(size 0.6604)
		(drill 0.3302)
		(layers "F.Cu" "B.Cu")
		(net "DRV_ACT_26_N")
	)
	(segment
		(start 49.586134 -322.890134)
		(end 49.586134 -317.733934)
		(width 0.17145)
		(layer "F.Cu")
		(net "DRV_ACT_25_N")
	)
	(segment
		(start 49.586134 -317.733934)
		(end 42.03446 -310.18226)
		(width 0.17145)
		(layer "F.Cu")
		(net "DRV_ACT_25_N")
	)
	(segment
		(start 39.424356 -299.171868)
		(end 40.0812 -299.828712)
		(width 0.17145)
		(layer "F.Cu")
		(net "DRV_ACT_25_N")
	)
	(segment
		(start 49.850294 -323.154294)
		(end 49.586134 -322.890134)
		(width 0.17145)
		(layer "F.Cu")
		(net "DRV_ACT_25_N")
	)
	(segment
		(start 40.0812 -307.293772)
		(end 42.03446 -309.247032)
		(width 0.17145)
		(layer "F.Cu")
		(net "DRV_ACT_25_N")
	)
	(segment
		(start 38.059614 -299.171868)
		(end 39.424356 -299.171868)
		(width 0.17145)
		(layer "F.Cu")
		(net "DRV_ACT_25_N")
	)
	(segment
		(start 49.850294 -323.66966)
		(end 49.850294 -323.154294)
		(width 0.17145)
		(layer "F.Cu")
		(net "DRV_ACT_25_N")
	)
	(segment
		(start 40.0812 -299.828712)
		(end 40.0812 -307.293772)
		(width 0.17145)
		(layer "F.Cu")
		(net "DRV_ACT_25_N")
	)
	(segment
		(start 42.03446 -310.18226)
		(end 42.03446 -309.247032)
		(width 0.17145)
		(layer "F.Cu")
		(net "DRV_ACT_25_N")
	)
	(via
		(at 42.03446 -309.247032)
		(size 0.6604)
		(drill 0.3302)
		(layers "F.Cu" "B.Cu")
		(net "DRV_ACT_25_N")
	)
	(segment
		(start 7.6454 -288.3916)
		(end 8.685784 -289.431984)
		(width 0.17145)
		(layer "F.Cu")
		(net "DRV_ACT_24_N")
	)
	(segment
		(start 8.685784 -299.466)
		(end 13.3604 -304.140616)
		(width 0.17145)
		(layer "F.Cu")
		(net "DRV_ACT_24_N")
	)
	(segment
		(start 18.300446 -323.66966)
		(end 18.300446 -323.024246)
		(width 0.17145)
		(layer "F.Cu")
		(net "DRV_ACT_24_N")
	)
	(segment
		(start 13.3604 -304.140616)
		(end 13.3604 -305.1302)
		(width 0.17145)
		(layer "F.Cu")
		(net "DRV_ACT_24_N")
	)
	(segment
		(start 6.80593 -288.3916)
		(end 7.6454 -288.3916)
		(width 0.17145)
		(layer "F.Cu")
		(net "DRV_ACT_24_N")
	)
	(segment
		(start 8.685784 -289.431984)
		(end 8.685784 -299.466)
		(width 0.17145)
		(layer "F.Cu")
		(net "DRV_ACT_24_N")
	)
	(segment
		(start 18.036286 -322.760086)
		(end 18.036286 -314.708286)
		(width 0.17145)
		(layer "F.Cu")
		(net "DRV_ACT_24_N")
	)
	(segment
		(start 18.300446 -323.024246)
		(end 18.036286 -322.760086)
		(width 0.17145)
		(layer "F.Cu")
		(net "DRV_ACT_24_N")
	)
	(segment
		(start 18.036286 -314.708286)
		(end 13.3604 -310.0324)
		(width 0.17145)
		(layer "F.Cu")
		(net "DRV_ACT_24_N")
	)
	(segment
		(start 13.3604 -310.0324)
		(end 13.3604 -305.1302)
		(width 0.17145)
		(layer "F.Cu")
		(net "DRV_ACT_24_N")
	)
	(via
		(at 13.3604 -305.1302)
		(size 0.6604)
		(drill 0.3302)
		(layers "F.Cu" "B.Cu")
		(net "DRV_ACT_24_N")
	)
	(segment
		(start 408.31643 -206.38897)
		(end 407.661618 -207.043782)
		(width 0.17145)
		(layer "F.Cu")
		(net "FLT_HDD9_N")
	)
	(segment
		(start 409.299664 -208.085436)
		(end 409.525978 -207.859122)
		(width 0.17145)
		(layer "F.Cu")
		(net "FLT_HDD9_N")
	)
	(segment
		(start 407.661618 -237.416848)
		(end 407.661618 -230.0986)
		(width 0.17145)
		(layer "F.Cu")
		(net "FLT_HDD9_N")
	)
	(segment
		(start 409.525978 -207.02397)
		(end 408.890978 -206.38897)
		(width 0.17145)
		(layer "F.Cu")
		(net "FLT_HDD9_N")
	)
	(segment
		(start 409.299664 -208.669636)
		(end 409.299664 -208.085436)
		(width 0.17145)
		(layer "F.Cu")
		(net "FLT_HDD9_N")
	)
	(segment
		(start 407.661618 -207.043782)
		(end 407.661618 -230.0986)
		(width 0.17145)
		(layer "F.Cu")
		(net "FLT_HDD9_N")
	)
	(segment
		(start 409.525978 -207.859122)
		(end 409.525978 -207.02397)
		(width 0.17145)
		(layer "F.Cu")
		(net "FLT_HDD9_N")
	)
	(segment
		(start 406.711912 -241.878612)
		(end 406.711912 -238.366554)
		(width 0.17145)
		(layer "F.Cu")
		(net "FLT_HDD9_N")
	)
	(segment
		(start 406.711912 -238.366554)
		(end 407.661618 -237.416848)
		(width 0.17145)
		(layer "F.Cu")
		(net "FLT_HDD9_N")
	)
	(segment
		(start 408.890978 -206.38897)
		(end 408.31643 -206.38897)
		(width 0.17145)
		(layer "F.Cu")
		(net "FLT_HDD9_N")
	)
	(via
		(at 407.661618 -230.0986)
		(size 0.6604)
		(drill 0.3302)
		(layers "F.Cu" "B.Cu")
		(net "FLT_HDD9_N")
	)
	(segment
		(start 377.975876 -207.859122)
		(end 377.749562 -208.085436)
		(width 0.17145)
		(layer "F.Cu")
		(net "FLT_HDD8_N")
	)
	(segment
		(start 377.19 -206.7814)
		(end 377.733306 -206.7814)
		(width 0.17145)
		(layer "F.Cu")
		(net "FLT_HDD8_N")
	)
	(segment
		(start 377.733306 -206.7814)
		(end 377.975876 -207.02397)
		(width 0.17145)
		(layer "F.Cu")
		(net "FLT_HDD8_N")
	)
	(segment
		(start 375.16181 -241.846608)
		(end 375.16181 -239.376712)
		(width 0.17145)
		(layer "F.Cu")
		(net "FLT_HDD8_N")
	)
	(segment
		(start 375.16181 -239.376712)
		(end 376.949716 -237.588806)
		(width 0.17145)
		(layer "F.Cu")
		(net "FLT_HDD8_N")
	)
	(segment
		(start 376.949716 -207.021684)
		(end 377.19 -206.7814)
		(width 0.17145)
		(layer "F.Cu")
		(net "FLT_HDD8_N")
	)
	(segment
		(start 376.949716 -231.6226)
		(end 376.949716 -207.021684)
		(width 0.17145)
		(layer "F.Cu")
		(net "FLT_HDD8_N")
	)
	(segment
		(start 377.975876 -207.02397)
		(end 377.975876 -207.859122)
		(width 0.17145)
		(layer "F.Cu")
		(net "FLT_HDD8_N")
	)
	(segment
		(start 376.949716 -237.588806)
		(end 376.949716 -231.6226)
		(width 0.17145)
		(layer "F.Cu")
		(net "FLT_HDD8_N")
	)
	(segment
		(start 377.749562 -208.085436)
		(end 377.749562 -208.669636)
		(width 0.17145)
		(layer "F.Cu")
		(net "FLT_HDD8_N")
	)
	(via
		(at 376.949716 -231.6226)
		(size 0.6604)
		(drill 0.3302)
		(layers "F.Cu" "B.Cu")
		(net "FLT_HDD8_N")
	)
	(segment
		(start 345.156028 -207.02397)
		(end 346.008452 -207.02397)
		(width 0.17145)
		(layer "F.Cu")
		(net "FLT_HDD7_N")
	)
	(segment
		(start 343.992454 -237.59287)
		(end 344.561668 -237.023656)
		(width 0.17145)
		(layer "F.Cu")
		(net "FLT_HDD7_N")
	)
	(segment
		(start 344.561668 -207.61833)
		(end 345.156028 -207.02397)
		(width 0.17145)
		(layer "F.Cu")
		(net "FLT_HDD7_N")
	)
	(segment
		(start 343.611962 -241.857276)
		(end 343.611962 -237.973362)
		(width 0.17145)
		(layer "F.Cu")
		(net "FLT_HDD7_N")
	)
	(segment
		(start 346.199714 -208.085436)
		(end 346.199714 -208.669636)
		(width 0.17145)
		(layer "F.Cu")
		(net "FLT_HDD7_N")
	)
	(segment
		(start 346.426028 -207.441546)
		(end 346.426028 -207.859122)
		(width 0.17145)
		(layer "F.Cu")
		(net "FLT_HDD7_N")
	)
	(segment
		(start 346.426028 -207.859122)
		(end 346.199714 -208.085436)
		(width 0.17145)
		(layer "F.Cu")
		(net "FLT_HDD7_N")
	)
	(segment
		(start 344.561668 -237.023656)
		(end 344.561668 -207.61833)
		(width 0.17145)
		(layer "F.Cu")
		(net "FLT_HDD7_N")
	)
	(segment
		(start 343.611962 -237.973362)
		(end 343.992454 -237.59287)
		(width 0.17145)
		(layer "F.Cu")
		(net "FLT_HDD7_N")
	)
	(segment
		(start 346.008452 -207.02397)
		(end 346.426028 -207.441546)
		(width 0.17145)
		(layer "F.Cu")
		(net "FLT_HDD7_N")
	)
	(via
		(at 343.992454 -237.59287)
		(size 0.6604)
		(drill 0.3302)
		(layers "F.Cu" "B.Cu")
		(net "FLT_HDD7_N")
	)
	(segment
		(start 314.875926 -207.859122)
		(end 314.875926 -207.02397)
		(width 0.17145)
		(layer "F.Cu")
		(net "FLT_HDD6_N")
	)
	(segment
		(start 312.412126 -223.61017)
		(end 318.600074 -229.798118)
		(width 0.17145)
		(layer "F.Cu")
		(net "FLT_HDD6_N")
	)
	(segment
		(start 312.412126 -207.27797)
		(end 312.412126 -223.61017)
		(width 0.17145)
		(layer "F.Cu")
		(net "FLT_HDD6_N")
	)
	(segment
		(start 314.240926 -206.38897)
		(end 313.301126 -206.38897)
		(width 0.17145)
		(layer "F.Cu")
		(net "FLT_HDD6_N")
	)
	(segment
		(start 314.649612 -208.669636)
		(end 314.649612 -208.085436)
		(width 0.17145)
		(layer "F.Cu")
		(net "FLT_HDD6_N")
	)
	(segment
		(start 314.649612 -208.085436)
		(end 314.875926 -207.859122)
		(width 0.17145)
		(layer "F.Cu")
		(net "FLT_HDD6_N")
	)
	(segment
		(start 313.301126 -206.38897)
		(end 312.412126 -207.27797)
		(width 0.17145)
		(layer "F.Cu")
		(net "FLT_HDD6_N")
	)
	(segment
		(start 314.875926 -207.02397)
		(end 314.240926 -206.38897)
		(width 0.17145)
		(layer "F.Cu")
		(net "FLT_HDD6_N")
	)
	(segment
		(start 318.600074 -229.798118)
		(end 318.600074 -237.678468)
		(width 0.17145)
		(layer "F.Cu")
		(net "FLT_HDD6_N")
	)
	(segment
		(start 318.600074 -241.793014)
		(end 318.600074 -237.678468)
		(width 0.17145)
		(layer "F.Cu")
		(net "FLT_HDD6_N")
	)
	(via
		(at 318.600074 -237.678468)
		(size 0.6604)
		(drill 0.3302)
		(layers "F.Cu" "B.Cu")
		(net "FLT_HDD6_N")
	)
	(segment
		(start 175.049688 -208.669636)
		(end 175.049688 -208.083912)
		(width 0.17145)
		(layer "F.Cu")
		(net "FLT_HDD5_N")
	)
	(segment
		(start 164.283136 -192.10274)
		(end 164.283136 -189.827662)
		(width 0.17145)
		(layer "F.Cu")
		(net "FLT_HDD5_N")
	)
	(segment
		(start 175.049688 -208.083912)
		(end 175.276002 -207.857598)
		(width 0.17145)
		(layer "F.Cu")
		(net "FLT_HDD5_N")
	)
	(segment
		(start 175.276002 -207.02397)
		(end 164.283136 -196.031104)
		(width 0.17145)
		(layer "F.Cu")
		(net "FLT_HDD5_N")
	)
	(segment
		(start 164.283136 -196.031104)
		(end 164.283136 -192.10274)
		(width 0.17145)
		(layer "F.Cu")
		(net "FLT_HDD5_N")
	)
	(segment
		(start 175.276002 -207.857598)
		(end 175.276002 -207.02397)
		(width 0.17145)
		(layer "F.Cu")
		(net "FLT_HDD5_N")
	)
	(via
		(at 164.283136 -192.10274)
		(size 0.6604)
		(drill 0.3302)
		(layers "F.Cu" "B.Cu")
		(net "FLT_HDD5_N")
	)
	(segment
		(start 140.974572 -205.218538)
		(end 140.974572 -203.785724)
		(width 0.17145)
		(layer "F.Cu")
		(net "FLT_HDD4_N")
	)
	(segment
		(start 143.499586 -207.743552)
		(end 140.974572 -205.218538)
		(width 0.17145)
		(layer "F.Cu")
		(net "FLT_HDD4_N")
	)
	(segment
		(start 140.974572 -203.785724)
		(end 132.6769 -195.488052)
		(width 0.17145)
		(layer "F.Cu")
		(net "FLT_HDD4_N")
	)
	(segment
		(start 132.6769 -192.123822)
		(end 132.6769 -189.848744)
		(width 0.17145)
		(layer "F.Cu")
		(net "FLT_HDD4_N")
	)
	(segment
		(start 143.499586 -208.669636)
		(end 143.499586 -207.743552)
		(width 0.17145)
		(layer "F.Cu")
		(net "FLT_HDD4_N")
	)
	(segment
		(start 132.6769 -195.488052)
		(end 132.6769 -192.123822)
		(width 0.17145)
		(layer "F.Cu")
		(net "FLT_HDD4_N")
	)
	(via
		(at 132.6769 -192.123822)
		(size 0.6604)
		(drill 0.3302)
		(layers "F.Cu" "B.Cu")
		(net "FLT_HDD4_N")
	)
	(segment
		(start 101.156516 -189.784482)
		(end 101.156516 -192.294764)
		(width 0.17145)
		(layer "F.Cu")
		(net "FLT_HDD3_N")
	)
	(segment
		(start 101.156516 -192.294764)
		(end 101.156516 -193.933318)
		(width 0.17145)
		(layer "F.Cu")
		(net "FLT_HDD3_N")
	)
	(segment
		(start 111.949738 -208.669636)
		(end 111.949738 -207.45831)
		(width 0.17145)
		(layer "F.Cu")
		(net "FLT_HDD3_N")
	)
	(via
		(at 101.156516 -192.294764)
		(size 0.6604)
		(drill 0.3302)
		(layers "F.Cu" "B.Cu")
		(net "FLT_HDD3_N")
	)
	(via
		(at 111.949738 -207.45831)
		(size 0.5588)
		(drill 0.3048)
		(layers "F.Cu" "B.Cu")
		(net "FLT_HDD3_N")
	)
	(via
		(at 101.156516 -193.933318)
		(size 0.5588)
		(drill 0.3048)
		(layers "F.Cu" "B.Cu")
		(net "FLT_HDD3_N")
	)
	(segment
		(start 111.949738 -204.72654)
		(end 101.156516 -193.933318)
		(width 0.13335)
		(layer "In9.Cu")
		(net "FLT_HDD3_N")
	)
	(segment
		(start 111.949738 -207.45831)
		(end 111.949738 -204.72654)
		(width 0.13335)
		(layer "In9.Cu")
		(net "FLT_HDD3_N")
	)
	(segment
		(start 469.747854 -126.804166)
		(end 469.747854 -123.826524)
		(width 0.17145)
		(layer "F.Cu")
		(net "FLT_HDD23_N")
	)
	(segment
		(start 469.747854 -123.826524)
		(end 470.761568 -122.81281)
		(width 0.17145)
		(layer "F.Cu")
		(net "FLT_HDD23_N")
	)
	(segment
		(start 471.3478 -91.3892)
		(end 470.761568 -91.975432)
		(width 0.17145)
		(layer "F.Cu")
		(net "FLT_HDD23_N")
	)
	(segment
		(start 471.990928 -91.3892)
		(end 471.3478 -91.3892)
		(width 0.17145)
		(layer "F.Cu")
		(net "FLT_HDD23_N")
	)
	(segment
		(start 472.625928 -92.859352)
		(end 472.625928 -92.0242)
		(width 0.17145)
		(layer "F.Cu")
		(net "FLT_HDD23_N")
	)
	(segment
		(start 472.625928 -92.0242)
		(end 471.990928 -91.3892)
		(width 0.17145)
		(layer "F.Cu")
		(net "FLT_HDD23_N")
	)
	(segment
		(start 472.399614 -93.085666)
		(end 472.625928 -92.859352)
		(width 0.17145)
		(layer "F.Cu")
		(net "FLT_HDD23_N")
	)
	(segment
		(start 470.761568 -91.975432)
		(end 470.761568 -121.031)
		(width 0.17145)
		(layer "F.Cu")
		(net "FLT_HDD23_N")
	)
	(segment
		(start 470.761568 -122.81281)
		(end 470.761568 -121.031)
		(width 0.17145)
		(layer "F.Cu")
		(net "FLT_HDD23_N")
	)
	(segment
		(start 472.399614 -93.669866)
		(end 472.399614 -93.085666)
		(width 0.17145)
		(layer "F.Cu")
		(net "FLT_HDD23_N")
	)
	(via
		(at 470.761568 -121.031)
		(size 0.6604)
		(drill 0.3302)
		(layers "F.Cu" "B.Cu")
		(net "FLT_HDD23_N")
	)
	(segment
		(start 441.075826 -92.0242)
		(end 440.440826 -91.3892)
		(width 0.17145)
		(layer "F.Cu")
		(net "FLT_HDD22_N")
	)
	(segment
		(start 440.849512 -93.669866)
		(end 440.849512 -93.085666)
		(width 0.17145)
		(layer "F.Cu")
		(net "FLT_HDD22_N")
	)
	(segment
		(start 439.8518 -91.3892)
		(end 439.211466 -92.029534)
		(width 0.17145)
		(layer "F.Cu")
		(net "FLT_HDD22_N")
	)
	(segment
		(start 438.293764 -126.771908)
		(end 438.293764 -121.949464)
		(width 0.17145)
		(layer "F.Cu")
		(net "FLT_HDD22_N")
	)
	(segment
		(start 438.293764 -121.949464)
		(end 439.211466 -121.031762)
		(width 0.17145)
		(layer "F.Cu")
		(net "FLT_HDD22_N")
	)
	(segment
		(start 439.211466 -92.029534)
		(end 439.211466 -99.9998)
		(width 0.17145)
		(layer "F.Cu")
		(net "FLT_HDD22_N")
	)
	(segment
		(start 440.440826 -91.3892)
		(end 439.8518 -91.3892)
		(width 0.17145)
		(layer "F.Cu")
		(net "FLT_HDD22_N")
	)
	(segment
		(start 439.211466 -121.031762)
		(end 439.211466 -99.9998)
		(width 0.17145)
		(layer "F.Cu")
		(net "FLT_HDD22_N")
	)
	(segment
		(start 440.849512 -93.085666)
		(end 441.075826 -92.859352)
		(width 0.17145)
		(layer "F.Cu")
		(net "FLT_HDD22_N")
	)
	(segment
		(start 441.075826 -92.859352)
		(end 441.075826 -92.0242)
		(width 0.17145)
		(layer "F.Cu")
		(net "FLT_HDD22_N")
	)
	(via
		(at 439.211466 -99.9998)
		(size 0.6604)
		(drill 0.3302)
		(layers "F.Cu" "B.Cu")
		(net "FLT_HDD22_N")
	)
	(segment
		(start 408.890978 -91.3892)
		(end 408.2288 -91.3892)
		(width 0.17145)
		(layer "F.Cu")
		(net "FLT_HDD21_N")
	)
	(segment
		(start 409.299664 -93.669866)
		(end 409.299664 -93.085666)
		(width 0.17145)
		(layer "F.Cu")
		(net "FLT_HDD21_N")
	)
	(segment
		(start 409.525978 -92.859352)
		(end 409.525978 -92.0242)
		(width 0.17145)
		(layer "F.Cu")
		(net "FLT_HDD21_N")
	)
	(segment
		(start 408.2288 -91.3892)
		(end 406.679654 -92.938346)
		(width 0.17145)
		(layer "F.Cu")
		(net "FLT_HDD21_N")
	)
	(segment
		(start 409.525978 -92.0242)
		(end 408.890978 -91.3892)
		(width 0.17145)
		(layer "F.Cu")
		(net "FLT_HDD21_N")
	)
	(segment
		(start 406.679654 -126.83617)
		(end 406.679654 -117.949218)
		(width 0.17145)
		(layer "F.Cu")
		(net "FLT_HDD21_N")
	)
	(segment
		(start 409.299664 -93.085666)
		(end 409.525978 -92.859352)
		(width 0.17145)
		(layer "F.Cu")
		(net "FLT_HDD21_N")
	)
	(segment
		(start 406.679654 -92.938346)
		(end 406.679654 -117.949218)
		(width 0.17145)
		(layer "F.Cu")
		(net "FLT_HDD21_N")
	)
	(via
		(at 406.679654 -117.949218)
		(size 0.6604)
		(drill 0.3302)
		(layers "F.Cu" "B.Cu")
		(net "FLT_HDD21_N")
	)
	(segment
		(start 376.111516 -92.010484)
		(end 376.7328 -91.3892)
		(width 0.17145)
		(layer "F.Cu")
		(net "FLT_HDD20_N")
	)
	(segment
		(start 377.975876 -92.859352)
		(end 377.749562 -93.085666)
		(width 0.17145)
		(layer "F.Cu")
		(net "FLT_HDD20_N")
	)
	(segment
		(start 377.340876 -91.3892)
		(end 377.975876 -92.0242)
		(width 0.17145)
		(layer "F.Cu")
		(net "FLT_HDD20_N")
	)
	(segment
		(start 376.7328 -91.3892)
		(end 377.340876 -91.3892)
		(width 0.17145)
		(layer "F.Cu")
		(net "FLT_HDD20_N")
	)
	(segment
		(start 377.749562 -93.085666)
		(end 377.749562 -93.669866)
		(width 0.17145)
		(layer "F.Cu")
		(net "FLT_HDD20_N")
	)
	(segment
		(start 374.00992 -126.750572)
		(end 374.00992 -123.259088)
		(width 0.17145)
		(layer "F.Cu")
		(net "FLT_HDD20_N")
	)
	(segment
		(start 374.00992 -123.259088)
		(end 375.352564 -121.916444)
		(width 0.17145)
		(layer "F.Cu")
		(net "FLT_HDD20_N")
	)
	(segment
		(start 376.111516 -121.157492)
		(end 376.111516 -92.010484)
		(width 0.17145)
		(layer "F.Cu")
		(net "FLT_HDD20_N")
	)
	(segment
		(start 377.975876 -92.0242)
		(end 377.975876 -92.859352)
		(width 0.17145)
		(layer "F.Cu")
		(net "FLT_HDD20_N")
	)
	(segment
		(start 375.352564 -121.916444)
		(end 376.111516 -121.157492)
		(width 0.17145)
		(layer "F.Cu")
		(net "FLT_HDD20_N")
	)
	(via
		(at 375.352564 -121.916444)
		(size 0.6604)
		(drill 0.3302)
		(layers "F.Cu" "B.Cu")
		(net "FLT_HDD20_N")
	)
	(segment
		(start 69.620638 -189.80277)
		(end 69.620638 -193.578226)
		(width 0.17145)
		(layer "F.Cu")
		(net "FLT_HDD2_N")
	)
	(segment
		(start 69.620638 -196.595238)
		(end 80.62595 -207.60055)
		(width 0.17145)
		(layer "F.Cu")
		(net "FLT_HDD2_N")
	)
	(segment
		(start 69.620638 -193.578226)
		(end 69.620638 -196.595238)
		(width 0.17145)
		(layer "F.Cu")
		(net "FLT_HDD2_N")
	)
	(segment
		(start 80.399636 -208.085436)
		(end 80.399636 -208.669636)
		(width 0.17145)
		(layer "F.Cu")
		(net "FLT_HDD2_N")
	)
	(segment
		(start 80.62595 -207.60055)
		(end 80.62595 -207.859122)
		(width 0.17145)
		(layer "F.Cu")
		(net "FLT_HDD2_N")
	)
	(segment
		(start 80.62595 -207.859122)
		(end 80.399636 -208.085436)
		(width 0.17145)
		(layer "F.Cu")
		(net "FLT_HDD2_N")
	)
	(via
		(at 69.620638 -193.578226)
		(size 0.6604)
		(drill 0.3302)
		(layers "F.Cu" "B.Cu")
		(net "FLT_HDD2_N")
	)
	(segment
		(start 345.791028 -91.3892)
		(end 345.1606 -91.3892)
		(width 0.17145)
		(layer "F.Cu")
		(net "FLT_HDD19_N")
	)
	(segment
		(start 342.955626 -126.814834)
		(end 342.955626 -124.410216)
		(width 0.17145)
		(layer "F.Cu")
		(net "FLT_HDD19_N")
	)
	(segment
		(start 344.561668 -122.804174)
		(end 344.561668 -116.5606)
		(width 0.17145)
		(layer "F.Cu")
		(net "FLT_HDD19_N")
	)
	(segment
		(start 342.955626 -124.410216)
		(end 344.561668 -122.804174)
		(width 0.17145)
		(layer "F.Cu")
		(net "FLT_HDD19_N")
	)
	(segment
		(start 346.426028 -92.859352)
		(end 346.426028 -92.0242)
		(width 0.17145)
		(layer "F.Cu")
		(net "FLT_HDD19_N")
	)
	(segment
		(start 346.199714 -93.669866)
		(end 346.199714 -93.085666)
		(width 0.17145)
		(layer "F.Cu")
		(net "FLT_HDD19_N")
	)
	(segment
		(start 346.426028 -92.0242)
		(end 345.791028 -91.3892)
		(width 0.17145)
		(layer "F.Cu")
		(net "FLT_HDD19_N")
	)
	(segment
		(start 344.561668 -91.988132)
		(end 344.561668 -116.5606)
		(width 0.17145)
		(layer "F.Cu")
		(net "FLT_HDD19_N")
	)
	(segment
		(start 346.199714 -93.085666)
		(end 346.426028 -92.859352)
		(width 0.17145)
		(layer "F.Cu")
		(net "FLT_HDD19_N")
	)
	(segment
		(start 345.1606 -91.3892)
		(end 344.561668 -91.988132)
		(width 0.17145)
		(layer "F.Cu")
		(net "FLT_HDD19_N")
	)
	(via
		(at 344.561668 -116.5606)
		(size 0.6604)
		(drill 0.3302)
		(layers "F.Cu" "B.Cu")
		(net "FLT_HDD19_N")
	)
	(segment
		(start 162.118802 -126.750572)
		(end 162.118802 -127.887476)
		(width 0.17145)
		(layer "F.Cu")
		(net "FLT_HDD17_N")
	)
	(segment
		(start 175.049688 -92.170504)
		(end 175.049688 -93.669866)
		(width 0.17145)
		(layer "F.Cu")
		(net "FLT_HDD17_N")
	)
	(segment
		(start 175.049688 -91.180412)
		(end 175.049688 -92.170504)
		(width 0.17145)
		(layer "F.Cu")
		(net "FLT_HDD17_N")
	)
	(via
		(at 175.049688 -92.170504)
		(size 0.6604)
		(drill 0.3302)
		(layers "F.Cu" "B.Cu")
		(net "FLT_HDD17_N")
	)
	(via
		(at 175.049688 -91.180412)
		(size 0.5588)
		(drill 0.3048)
		(layers "F.Cu" "B.Cu")
		(net "FLT_HDD17_N")
	)
	(via
		(at 162.118802 -127.887476)
		(size 0.5588)
		(drill 0.3048)
		(layers "F.Cu" "B.Cu")
		(net "FLT_HDD17_N")
	)
	(segment
		(start 173.043088 -109.79785)
		(end 173.043088 -93.187012)
		(width 0.13335)
		(layer "In9.Cu")
		(net "FLT_HDD17_N")
	)
	(segment
		(start 162.118802 -127.887476)
		(end 162.118802 -120.722136)
		(width 0.13335)
		(layer "In9.Cu")
		(net "FLT_HDD17_N")
	)
	(segment
		(start 162.118802 -120.722136)
		(end 173.043088 -109.79785)
		(width 0.13335)
		(layer "In9.Cu")
		(net "FLT_HDD17_N")
	)
	(segment
		(start 173.043088 -93.187012)
		(end 175.049688 -91.180412)
		(width 0.13335)
		(layer "In9.Cu")
		(net "FLT_HDD17_N")
	)
	(segment
		(start 143.499586 -93.669866)
		(end 143.499586 -92.261436)
		(width 0.17145)
		(layer "F.Cu")
		(net "FLT_HDD16_N")
	)
	(segment
		(start 133.313424 -123.449588)
		(end 133.313424 -124.916438)
		(width 0.17145)
		(layer "F.Cu")
		(net "FLT_HDD16_N")
	)
	(segment
		(start 133.313424 -126.83617)
		(end 133.313424 -124.916438)
		(width 0.17145)
		(layer "F.Cu")
		(net "FLT_HDD16_N")
	)
	(via
		(at 143.499586 -92.261436)
		(size 0.5588)
		(drill 0.3048)
		(layers "F.Cu" "B.Cu")
		(net "FLT_HDD16_N")
	)
	(via
		(at 133.313424 -124.916438)
		(size 0.6604)
		(drill 0.3302)
		(layers "F.Cu" "B.Cu")
		(net "FLT_HDD16_N")
	)
	(via
		(at 133.313424 -123.449588)
		(size 0.5588)
		(drill 0.3048)
		(layers "F.Cu" "B.Cu")
		(net "FLT_HDD16_N")
	)
	(segment
		(start 133.313424 -123.449588)
		(end 133.313424 -111.990124)
		(width 0.13335)
		(layer "In9.Cu")
		(net "FLT_HDD16_N")
	)
	(segment
		(start 133.313424 -111.990124)
		(end 141.746986 -103.556562)
		(width 0.13335)
		(layer "In9.Cu")
		(net "FLT_HDD16_N")
	)
	(segment
		(start 141.746986 -94.014036)
		(end 143.499586 -92.261436)
		(width 0.13335)
		(layer "In9.Cu")
		(net "FLT_HDD16_N")
	)
	(segment
		(start 141.746986 -103.556562)
		(end 141.746986 -94.014036)
		(width 0.13335)
		(layer "In9.Cu")
		(net "FLT_HDD16_N")
	)
	(segment
		(start 111.949738 -93.669866)
		(end 111.949738 -92.261436)
		(width 0.17145)
		(layer "F.Cu")
		(net "FLT_HDD15_N")
	)
	(segment
		(start 109.356652 -126.826772)
		(end 109.356652 -124.90704)
		(width 0.17145)
		(layer "F.Cu")
		(net "FLT_HDD15_N")
	)
	(segment
		(start 109.356652 -123.44019)
		(end 109.356652 -124.90704)
		(width 0.17145)
		(layer "F.Cu")
		(net "FLT_HDD15_N")
	)
	(via
		(at 109.356652 -123.44019)
		(size 0.5588)
		(drill 0.3048)
		(layers "F.Cu" "B.Cu")
		(net "FLT_HDD15_N")
	)
	(via
		(at 111.949738 -92.261436)
		(size 0.5588)
		(drill 0.3048)
		(layers "F.Cu" "B.Cu")
		(net "FLT_HDD15_N")
	)
	(via
		(at 109.356652 -124.90704)
		(size 0.6604)
		(drill 0.3302)
		(layers "F.Cu" "B.Cu")
		(net "FLT_HDD15_N")
	)
	(segment
		(start 109.356652 -123.44019)
		(end 110.311692 -122.48515)
		(width 0.13335)
		(layer "In9.Cu")
		(net "FLT_HDD15_N")
	)
	(segment
		(start 110.311692 -93.899482)
		(end 111.949738 -92.261436)
		(width 0.13335)
		(layer "In9.Cu")
		(net "FLT_HDD15_N")
	)
	(segment
		(start 110.311692 -122.48515)
		(end 110.311692 -93.899482)
		(width 0.13335)
		(layer "In9.Cu")
		(net "FLT_HDD15_N")
	)
	(segment
		(start 77.822552 -124.916438)
		(end 77.822552 -123.449588)
		(width 0.17145)
		(layer "F.Cu")
		(net "FLT_HDD14_N")
	)
	(segment
		(start 80.399636 -93.669866)
		(end 80.399636 -92.261436)
		(width 0.17145)
		(layer "F.Cu")
		(net "FLT_HDD14_N")
	)
	(segment
		(start 77.822552 -126.83617)
		(end 77.822552 -124.916438)
		(width 0.17145)
		(layer "F.Cu")
		(net "FLT_HDD14_N")
	)
	(via
		(at 77.822552 -123.449588)
		(size 0.5588)
		(drill 0.3048)
		(layers "F.Cu" "B.Cu")
		(net "FLT_HDD14_N")
	)
	(via
		(at 80.399636 -92.261436)
		(size 0.5588)
		(drill 0.3048)
		(layers "F.Cu" "B.Cu")
		(net "FLT_HDD14_N")
	)
	(via
		(at 77.822552 -124.916438)
		(size 0.6604)
		(drill 0.3302)
		(layers "F.Cu" "B.Cu")
		(net "FLT_HDD14_N")
	)
	(segment
		(start 78.76159 -93.899482)
		(end 80.399636 -92.261436)
		(width 0.13335)
		(layer "In9.Cu")
		(net "FLT_HDD14_N")
	)
	(segment
		(start 77.822552 -123.449588)
		(end 78.76159 -122.51055)
		(width 0.13335)
		(layer "In9.Cu")
		(net "FLT_HDD14_N")
	)
	(segment
		(start 78.76159 -122.51055)
		(end 78.76159 -93.899482)
		(width 0.13335)
		(layer "In9.Cu")
		(net "FLT_HDD14_N")
	)
	(segment
		(start 48.162718 -91.474798)
		(end 47.55007 -91.474798)
		(width 0.17145)
		(layer "F.Cu")
		(net "FLT_HDD13_N")
	)
	(segment
		(start 46.283118 -92.74175)
		(end 46.283118 -101.473)
		(width 0.17145)
		(layer "F.Cu")
		(net "FLT_HDD13_N")
	)
	(segment
		(start 48.849534 -92.161614)
		(end 48.162718 -91.474798)
		(width 0.17145)
		(layer "F.Cu")
		(net "FLT_HDD13_N")
	)
	(segment
		(start 46.283118 -101.473)
		(end 46.283118 -126.83617)
		(width 0.17145)
		(layer "F.Cu")
		(net "FLT_HDD13_N")
	)
	(segment
		(start 48.849534 -93.669866)
		(end 48.849534 -92.161614)
		(width 0.17145)
		(layer "F.Cu")
		(net "FLT_HDD13_N")
	)
	(segment
		(start 47.55007 -91.474798)
		(end 46.283118 -92.74175)
		(width 0.17145)
		(layer "F.Cu")
		(net "FLT_HDD13_N")
	)
	(via
		(at 46.283118 -101.473)
		(size 0.6604)
		(drill 0.3302)
		(layers "F.Cu" "B.Cu")
		(net "FLT_HDD13_N")
	)
	(segment
		(start 17.526 -92.408248)
		(end 17.526 -92.859352)
		(width 0.17145)
		(layer "F.Cu")
		(net "FLT_HDD12_N")
	)
	(segment
		(start 14.722602 -126.846838)
		(end 14.722602 -116.189506)
		(width 0.17145)
		(layer "F.Cu")
		(net "FLT_HDD12_N")
	)
	(segment
		(start 17.299686 -93.085666)
		(end 17.299686 -93.669866)
		(width 0.17145)
		(layer "F.Cu")
		(net "FLT_HDD12_N")
	)
	(segment
		(start 16.309848 -92.1258)
		(end 17.243552 -92.1258)
		(width 0.17145)
		(layer "F.Cu")
		(net "FLT_HDD12_N")
	)
	(segment
		(start 14.722602 -116.189506)
		(end 14.722602 -93.713046)
		(width 0.17145)
		(layer "F.Cu")
		(net "FLT_HDD12_N")
	)
	(segment
		(start 17.243552 -92.1258)
		(end 17.526 -92.408248)
		(width 0.17145)
		(layer "F.Cu")
		(net "FLT_HDD12_N")
	)
	(segment
		(start 17.526 -92.859352)
		(end 17.299686 -93.085666)
		(width 0.17145)
		(layer "F.Cu")
		(net "FLT_HDD12_N")
	)
	(segment
		(start 14.722602 -93.713046)
		(end 16.309848 -92.1258)
		(width 0.17145)
		(layer "F.Cu")
		(net "FLT_HDD12_N")
	)
	(via
		(at 14.722602 -116.189506)
		(size 0.6604)
		(drill 0.3302)
		(layers "F.Cu" "B.Cu")
		(net "FLT_HDD12_N")
	)
	(segment
		(start 458.838808 -228.222048)
		(end 475.088458 -211.972398)
		(width 0.17145)
		(layer "F.Cu")
		(net "FLT_HDD11_N")
	)
	(segment
		(start 472.625928 -207.859122)
		(end 472.399614 -208.085436)
		(width 0.17145)
		(layer "F.Cu")
		(net "FLT_HDD11_N")
	)
	(segment
		(start 472.399614 -208.085436)
		(end 472.399614 -208.669636)
		(width 0.17145)
		(layer "F.Cu")
		(net "FLT_HDD11_N")
	)
	(segment
		(start 472.625928 -206.560674)
		(end 472.625928 -207.859122)
		(width 0.17145)
		(layer "F.Cu")
		(net "FLT_HDD11_N")
	)
	(segment
		(start 475.088458 -207.056228)
		(end 474.060266 -206.028036)
		(width 0.17145)
		(layer "F.Cu")
		(net "FLT_HDD11_N")
	)
	(segment
		(start 458.838808 -239.43945)
		(end 458.838808 -228.222048)
		(width 0.17145)
		(layer "F.Cu")
		(net "FLT_HDD11_N")
	)
	(segment
		(start 474.060266 -206.028036)
		(end 473.158566 -206.028036)
		(width 0.17145)
		(layer "F.Cu")
		(net "FLT_HDD11_N")
	)
	(segment
		(start 473.158566 -206.028036)
		(end 472.625928 -206.560674)
		(width 0.17145)
		(layer "F.Cu")
		(net "FLT_HDD11_N")
	)
	(segment
		(start 475.088458 -211.972398)
		(end 475.088458 -207.056228)
		(width 0.17145)
		(layer "F.Cu")
		(net "FLT_HDD11_N")
	)
	(segment
		(start 458.838808 -241.83594)
		(end 458.838808 -239.43945)
		(width 0.17145)
		(layer "F.Cu")
		(net "FLT_HDD11_N")
	)
	(via
		(at 458.838808 -239.43945)
		(size 0.6604)
		(drill 0.3302)
		(layers "F.Cu" "B.Cu")
		(net "FLT_HDD11_N")
	)
	(segment
		(start 441.075826 -207.859122)
		(end 440.849512 -208.085436)
		(width 0.17145)
		(layer "F.Cu")
		(net "FLT_HDD10_N")
	)
	(segment
		(start 447.99631 -240.199164)
		(end 444.28283 -236.485684)
		(width 0.17145)
		(layer "F.Cu")
		(net "FLT_HDD10_N")
	)
	(segment
		(start 441.826904 -206.15529)
		(end 441.075826 -206.906368)
		(width 0.17145)
		(layer "F.Cu")
		(net "FLT_HDD10_N")
	)
	(segment
		(start 444.28283 -236.485684)
		(end 444.28283 -233.382058)
		(width 0.17145)
		(layer "F.Cu")
		(net "FLT_HDD10_N")
	)
	(segment
		(start 441.075826 -206.906368)
		(end 441.075826 -207.859122)
		(width 0.17145)
		(layer "F.Cu")
		(net "FLT_HDD10_N")
	)
	(segment
		(start 444.28283 -207.01)
		(end 443.42812 -206.15529)
		(width 0.17145)
		(layer "F.Cu")
		(net "FLT_HDD10_N")
	)
	(segment
		(start 440.849512 -208.085436)
		(end 440.849512 -208.669636)
		(width 0.17145)
		(layer "F.Cu")
		(net "FLT_HDD10_N")
	)
	(segment
		(start 443.42812 -206.15529)
		(end 441.826904 -206.15529)
		(width 0.17145)
		(layer "F.Cu")
		(net "FLT_HDD10_N")
	)
	(segment
		(start 444.28283 -233.382058)
		(end 444.28283 -207.01)
		(width 0.17145)
		(layer "F.Cu")
		(net "FLT_HDD10_N")
	)
	(segment
		(start 447.99631 -241.867436)
		(end 447.99631 -240.199164)
		(width 0.17145)
		(layer "F.Cu")
		(net "FLT_HDD10_N")
	)
	(via
		(at 444.28283 -233.382058)
		(size 0.6604)
		(drill 0.3302)
		(layers "F.Cu" "B.Cu")
		(net "FLT_HDD10_N")
	)
	(segment
		(start 38.05682 -195.45681)
		(end 48.849534 -206.249524)
		(width 0.17145)
		(layer "F.Cu")
		(net "FLT_HDD1_N")
	)
	(segment
		(start 38.05682 -189.867794)
		(end 38.05682 -193.75501)
		(width 0.17145)
		(layer "F.Cu")
		(net "FLT_HDD1_N")
	)
	(segment
		(start 38.05682 -193.75501)
		(end 38.05682 -195.45681)
		(width 0.17145)
		(layer "F.Cu")
		(net "FLT_HDD1_N")
	)
	(segment
		(start 48.849534 -206.249524)
		(end 48.849534 -208.669636)
		(width 0.17145)
		(layer "F.Cu")
		(net "FLT_HDD1_N")
	)
	(via
		(at 38.05682 -193.75501)
		(size 0.6604)
		(drill 0.3302)
		(layers "F.Cu" "B.Cu")
		(net "FLT_HDD1_N")
	)
	(segment
		(start 318.482218 -126.8476)
		(end 318.482218 -122.353578)
		(width 0.17145)
		(layer "F.Cu")
		(net "FLT_HDD018_N")
	)
	(segment
		(start 314.240926 -91.3892)
		(end 314.875926 -92.0242)
		(width 0.17145)
		(layer "F.Cu")
		(net "FLT_HDD018_N")
	)
	(segment
		(start 312.793126 -116.664486)
		(end 312.793126 -91.8972)
		(width 0.17145)
		(layer "F.Cu")
		(net "FLT_HDD018_N")
	)
	(segment
		(start 314.875926 -92.859352)
		(end 314.649612 -93.085666)
		(width 0.17145)
		(layer "F.Cu")
		(net "FLT_HDD018_N")
	)
	(segment
		(start 313.301126 -91.3892)
		(end 314.240926 -91.3892)
		(width 0.17145)
		(layer "F.Cu")
		(net "FLT_HDD018_N")
	)
	(segment
		(start 314.649612 -93.085666)
		(end 314.649612 -93.669866)
		(width 0.17145)
		(layer "F.Cu")
		(net "FLT_HDD018_N")
	)
	(segment
		(start 318.482218 -122.353578)
		(end 317.66764 -121.539)
		(width 0.17145)
		(layer "F.Cu")
		(net "FLT_HDD018_N")
	)
	(segment
		(start 314.875926 -92.0242)
		(end 314.875926 -92.859352)
		(width 0.17145)
		(layer "F.Cu")
		(net "FLT_HDD018_N")
	)
	(segment
		(start 312.793126 -91.8972)
		(end 313.301126 -91.3892)
		(width 0.17145)
		(layer "F.Cu")
		(net "FLT_HDD018_N")
	)
	(segment
		(start 317.66764 -121.539)
		(end 312.793126 -116.664486)
		(width 0.17145)
		(layer "F.Cu")
		(net "FLT_HDD018_N")
	)
	(via
		(at 317.66764 -121.539)
		(size 0.6604)
		(drill 0.3302)
		(layers "F.Cu" "B.Cu")
		(net "FLT_HDD018_N")
	)
	(segment
		(start 7.2136 -194.228212)
		(end 7.2136 -193.9544)
		(width 0.17145)
		(layer "F.Cu")
		(net "FLT_HDD0_N")
	)
	(segment
		(start 7.239 -180.594)
		(end 7.239 -193.587624)
		(width 0.17145)
		(layer "F.Cu")
		(net "FLT_HDD0_N")
	)
	(segment
		(start 7.2136 -193.613024)
		(end 7.2136 -193.9544)
		(width 0.17145)
		(layer "F.Cu")
		(net "FLT_HDD0_N")
	)
	(segment
		(start 17.299686 -208.669636)
		(end 17.299686 -204.314298)
		(width 0.17145)
		(layer "F.Cu")
		(net "FLT_HDD0_N")
	)
	(segment
		(start 17.299686 -204.314298)
		(end 7.2136 -194.228212)
		(width 0.17145)
		(layer "F.Cu")
		(net "FLT_HDD0_N")
	)
	(segment
		(start 6.906006 -179.777136)
		(end 6.906006 -180.261006)
		(width 0.17145)
		(layer "F.Cu")
		(net "FLT_HDD0_N")
	)
	(segment
		(start 6.906006 -180.261006)
		(end 7.239 -180.594)
		(width 0.17145)
		(layer "F.Cu")
		(net "FLT_HDD0_N")
	)
	(segment
		(start 7.239 -193.587624)
		(end 7.2136 -193.613024)
		(width 0.17145)
		(layer "F.Cu")
		(net "FLT_HDD0_N")
	)
	(via
		(at 7.2136 -193.9544)
		(size 0.6604)
		(drill 0.3302)
		(layers "F.Cu" "B.Cu")
		(net "FLT_HDD0_N")
	)
	(segment
		(start 407.71953 -205.83017)
		(end 409.122626 -205.83017)
		(width 0.17145)
		(layer "F.Cu")
		(net "DRV_ACT_9_N")
	)
	(segment
		(start 409.122626 -205.83017)
		(end 410.084778 -206.792322)
		(width 0.17145)
		(layer "F.Cu")
		(net "DRV_ACT_9_N")
	)
	(segment
		(start 410.300424 -208.085436)
		(end 410.300424 -208.669636)
		(width 0.17145)
		(layer "F.Cu")
		(net "DRV_ACT_9_N")
	)
	(segment
		(start 404.400512 -238.443262)
		(end 406.7302 -236.113574)
		(width 0.17145)
		(layer "F.Cu")
		(net "DRV_ACT_9_N")
	)
	(segment
		(start 403.107144 -239.73663)
		(end 404.400512 -238.443262)
		(width 0.17145)
		(layer "F.Cu")
		(net "DRV_ACT_9_N")
	)
	(segment
		(start 406.7302 -206.8195)
		(end 407.71953 -205.83017)
		(width 0.17145)
		(layer "F.Cu")
		(net "DRV_ACT_9_N")
	)
	(segment
		(start 406.7302 -236.113574)
		(end 406.7302 -206.8195)
		(width 0.17145)
		(layer "F.Cu")
		(net "DRV_ACT_9_N")
	)
	(segment
		(start 403.107144 -241.868198)
		(end 403.107144 -239.73663)
		(width 0.17145)
		(layer "F.Cu")
		(net "DRV_ACT_9_N")
	)
	(segment
		(start 410.084778 -207.86979)
		(end 410.300424 -208.085436)
		(width 0.17145)
		(layer "F.Cu")
		(net "DRV_ACT_9_N")
	)
	(segment
		(start 410.084778 -206.792322)
		(end 410.084778 -207.86979)
		(width 0.17145)
		(layer "F.Cu")
		(net "DRV_ACT_9_N")
	)
	(via
		(at 404.400512 -238.443262)
		(size 0.6604)
		(drill 0.3302)
		(layers "F.Cu" "B.Cu")
		(net "DRV_ACT_9_N")
	)
	(segment
		(start 378.534676 -206.792322)
		(end 377.863354 -206.121)
		(width 0.17145)
		(layer "F.Cu")
		(net "DRV_ACT_8_N")
	)
	(segment
		(start 378.750322 -208.085436)
		(end 378.534676 -207.86979)
		(width 0.17145)
		(layer "F.Cu")
		(net "DRV_ACT_8_N")
	)
	(segment
		(start 371.557042 -241.836194)
		(end 371.557042 -238.943642)
		(width 0.17145)
		(layer "F.Cu")
		(net "DRV_ACT_8_N")
	)
	(segment
		(start 377.863354 -206.121)
		(end 376.8344 -206.121)
		(width 0.17145)
		(layer "F.Cu")
		(net "DRV_ACT_8_N")
	)
	(segment
		(start 375.848118 -234.652566)
		(end 372.373144 -238.12754)
		(width 0.17145)
		(layer "F.Cu")
		(net "DRV_ACT_8_N")
	)
	(segment
		(start 375.848118 -207.107282)
		(end 375.848118 -234.652566)
		(width 0.17145)
		(layer "F.Cu")
		(net "DRV_ACT_8_N")
	)
	(segment
		(start 371.557042 -238.943642)
		(end 372.373144 -238.12754)
		(width 0.17145)
		(layer "F.Cu")
		(net "DRV_ACT_8_N")
	)
	(segment
		(start 378.750322 -208.669636)
		(end 378.750322 -208.085436)
		(width 0.17145)
		(layer "F.Cu")
		(net "DRV_ACT_8_N")
	)
	(segment
		(start 376.8344 -206.121)
		(end 375.848118 -207.107282)
		(width 0.17145)
		(layer "F.Cu")
		(net "DRV_ACT_8_N")
	)
	(segment
		(start 378.534676 -207.86979)
		(end 378.534676 -206.792322)
		(width 0.17145)
		(layer "F.Cu")
		(net "DRV_ACT_8_N")
	)
	(via
		(at 372.373144 -238.12754)
		(size 0.6604)
		(drill 0.3302)
		(layers "F.Cu" "B.Cu")
		(net "DRV_ACT_8_N")
	)
	(segment
		(start 340.007194 -236.699806)
		(end 341.8332 -234.8738)
		(width 0.17145)
		(layer "F.Cu")
		(net "DRV_ACT_7_N")
	)
	(segment
		(start 347.200474 -208.669636)
		(end 347.200474 -208.033874)
		(width 0.17145)
		(layer "F.Cu")
		(net "DRV_ACT_7_N")
	)
	(segment
		(start 346.984828 -207.818228)
		(end 346.984828 -206.792322)
		(width 0.17145)
		(layer "F.Cu")
		(net "DRV_ACT_7_N")
	)
	(segment
		(start 346.022676 -205.83017)
		(end 344.61958 -205.83017)
		(width 0.17145)
		(layer "F.Cu")
		(net "DRV_ACT_7_N")
	)
	(segment
		(start 340.007194 -241.846862)
		(end 340.007194 -236.699806)
		(width 0.17145)
		(layer "F.Cu")
		(net "DRV_ACT_7_N")
	)
	(segment
		(start 344.61958 -205.83017)
		(end 343.403428 -207.046322)
		(width 0.17145)
		(layer "F.Cu")
		(net "DRV_ACT_7_N")
	)
	(segment
		(start 343.403428 -233.303572)
		(end 341.8332 -234.8738)
		(width 0.17145)
		(layer "F.Cu")
		(net "DRV_ACT_7_N")
	)
	(segment
		(start 343.403428 -207.046322)
		(end 343.403428 -233.303572)
		(width 0.17145)
		(layer "F.Cu")
		(net "DRV_ACT_7_N")
	)
	(segment
		(start 346.984828 -206.792322)
		(end 346.022676 -205.83017)
		(width 0.17145)
		(layer "F.Cu")
		(net "DRV_ACT_7_N")
	)
	(segment
		(start 347.200474 -208.033874)
		(end 346.984828 -207.818228)
		(width 0.17145)
		(layer "F.Cu")
		(net "DRV_ACT_7_N")
	)
	(via
		(at 341.8332 -234.8738)
		(size 0.6604)
		(drill 0.3302)
		(layers "F.Cu" "B.Cu")
		(net "DRV_ACT_7_N")
	)
	(segment
		(start 315.434726 -207.86979)
		(end 315.434726 -206.792322)
		(width 0.17145)
		(layer "F.Cu")
		(net "DRV_ACT_6_N")
	)
	(segment
		(start 315.650372 -208.669636)
		(end 315.650372 -208.085436)
		(width 0.17145)
		(layer "F.Cu")
		(net "DRV_ACT_6_N")
	)
	(segment
		(start 315.016388 -227.00488)
		(end 315.016388 -231.625902)
		(width 0.17145)
		(layer "F.Cu")
		(net "DRV_ACT_6_N")
	)
	(segment
		(start 315.434726 -206.792322)
		(end 314.472574 -205.83017)
		(width 0.17145)
		(layer "F.Cu")
		(net "DRV_ACT_6_N")
	)
	(segment
		(start 313.069478 -205.83017)
		(end 311.853326 -207.046322)
		(width 0.17145)
		(layer "F.Cu")
		(net "DRV_ACT_6_N")
	)
	(segment
		(start 315.016388 -241.793268)
		(end 315.016388 -231.625902)
		(width 0.17145)
		(layer "F.Cu")
		(net "DRV_ACT_6_N")
	)
	(segment
		(start 315.650372 -208.085436)
		(end 315.434726 -207.86979)
		(width 0.17145)
		(layer "F.Cu")
		(net "DRV_ACT_6_N")
	)
	(segment
		(start 311.853326 -207.046322)
		(end 311.853326 -223.841818)
		(width 0.17145)
		(layer "F.Cu")
		(net "DRV_ACT_6_N")
	)
	(segment
		(start 311.853326 -223.841818)
		(end 315.016388 -227.00488)
		(width 0.17145)
		(layer "F.Cu")
		(net "DRV_ACT_6_N")
	)
	(segment
		(start 314.472574 -205.83017)
		(end 313.069478 -205.83017)
		(width 0.17145)
		(layer "F.Cu")
		(net "DRV_ACT_6_N")
	)
	(via
		(at 315.016388 -231.625902)
		(size 0.6604)
		(drill 0.3302)
		(layers "F.Cu" "B.Cu")
		(net "DRV_ACT_6_N")
	)
	(segment
		(start 164.28212 -186.037982)
		(end 165.47973 -186.037982)
		(width 0.17145)
		(layer "F.Cu")
		(net "DRV_ACT_5_N")
	)
	(segment
		(start 166.685976 -187.244228)
		(end 166.685976 -191.8462)
		(width 0.17145)
		(layer "F.Cu")
		(net "DRV_ACT_5_N")
	)
	(segment
		(start 176.050448 -208.079848)
		(end 175.834802 -207.864202)
		(width 0.17145)
		(layer "F.Cu")
		(net "DRV_ACT_5_N")
	)
	(segment
		(start 175.834802 -207.864202)
		(end 175.834802 -206.792322)
		(width 0.17145)
		(layer "F.Cu")
		(net "DRV_ACT_5_N")
	)
	(segment
		(start 166.685976 -197.643496)
		(end 166.685976 -191.8462)
		(width 0.17145)
		(layer "F.Cu")
		(net "DRV_ACT_5_N")
	)
	(segment
		(start 176.050448 -208.669636)
		(end 176.050448 -208.079848)
		(width 0.17145)
		(layer "F.Cu")
		(net "DRV_ACT_5_N")
	)
	(segment
		(start 175.834802 -206.792322)
		(end 166.685976 -197.643496)
		(width 0.17145)
		(layer "F.Cu")
		(net "DRV_ACT_5_N")
	)
	(segment
		(start 165.47973 -186.037982)
		(end 166.685976 -187.244228)
		(width 0.17145)
		(layer "F.Cu")
		(net "DRV_ACT_5_N")
	)
	(via
		(at 166.685976 -191.8462)
		(size 0.6604)
		(drill 0.3302)
		(layers "F.Cu" "B.Cu")
		(net "DRV_ACT_5_N")
	)
	(segment
		(start 144.500346 -208.669636)
		(end 144.154906 -208.324196)
		(width 0.17145)
		(layer "F.Cu")
		(net "DRV_ACT_4_N")
	)
	(segment
		(start 144.154906 -207.671416)
		(end 141.488922 -205.005432)
		(width 0.17145)
		(layer "F.Cu")
		(net "DRV_ACT_4_N")
	)
	(segment
		(start 141.488922 -205.005432)
		(end 141.488922 -203.572618)
		(width 0.17145)
		(layer "F.Cu")
		(net "DRV_ACT_4_N")
	)
	(segment
		(start 144.154906 -208.324196)
		(end 144.154906 -207.671416)
		(width 0.17145)
		(layer "F.Cu")
		(net "DRV_ACT_4_N")
	)
	(segment
		(start 133.873494 -186.059064)
		(end 135.07974 -187.26531)
		(width 0.17145)
		(layer "F.Cu")
		(net "DRV_ACT_4_N")
	)
	(segment
		(start 135.07974 -197.163436)
		(end 135.07974 -191.867282)
		(width 0.17145)
		(layer "F.Cu")
		(net "DRV_ACT_4_N")
	)
	(segment
		(start 135.07974 -187.26531)
		(end 135.07974 -191.867282)
		(width 0.17145)
		(layer "F.Cu")
		(net "DRV_ACT_4_N")
	)
	(segment
		(start 141.488922 -203.572618)
		(end 135.07974 -197.163436)
		(width 0.17145)
		(layer "F.Cu")
		(net "DRV_ACT_4_N")
	)
	(segment
		(start 132.675884 -186.059064)
		(end 133.873494 -186.059064)
		(width 0.17145)
		(layer "F.Cu")
		(net "DRV_ACT_4_N")
	)
	(via
		(at 135.07974 -191.867282)
		(size 0.6604)
		(drill 0.3302)
		(layers "F.Cu" "B.Cu")
		(net "DRV_ACT_4_N")
	)
	(segment
		(start 103.559356 -186.922156)
		(end 103.559356 -192.038224)
		(width 0.17145)
		(layer "F.Cu")
		(net "DRV_ACT_3_N")
	)
	(segment
		(start 101.1555 -185.994802)
		(end 102.632002 -185.994802)
		(width 0.17145)
		(layer "F.Cu")
		(net "DRV_ACT_3_N")
	)
	(segment
		(start 112.950498 -208.669636)
		(end 112.950498 -207.45831)
		(width 0.17145)
		(layer "F.Cu")
		(net "DRV_ACT_3_N")
	)
	(segment
		(start 103.559356 -192.038224)
		(end 103.559356 -193.367914)
		(width 0.17145)
		(layer "F.Cu")
		(net "DRV_ACT_3_N")
	)
	(segment
		(start 102.632002 -185.994802)
		(end 103.559356 -186.922156)
		(width 0.17145)
		(layer "F.Cu")
		(net "DRV_ACT_3_N")
	)
	(via
		(at 103.559356 -193.367914)
		(size 0.5588)
		(drill 0.3048)
		(layers "F.Cu" "B.Cu")
		(net "DRV_ACT_3_N")
	)
	(via
		(at 103.559356 -192.038224)
		(size 0.6604)
		(drill 0.3302)
		(layers "F.Cu" "B.Cu")
		(net "DRV_ACT_3_N")
	)
	(via
		(at 112.950498 -207.45831)
		(size 0.5588)
		(drill 0.3048)
		(layers "F.Cu" "B.Cu")
		(net "DRV_ACT_3_N")
	)
	(segment
		(start 112.950498 -205.04023)
		(end 103.559356 -195.649088)
		(width 0.13335)
		(layer "In9.Cu")
		(net "DRV_ACT_3_N")
	)
	(segment
		(start 103.559356 -195.649088)
		(end 103.559356 -193.367914)
		(width 0.13335)
		(layer "In9.Cu")
		(net "DRV_ACT_3_N")
	)
	(segment
		(start 112.950498 -207.45831)
		(end 112.950498 -205.04023)
		(width 0.13335)
		(layer "In9.Cu")
		(net "DRV_ACT_3_N")
	)
	(segment
		(start 473.184728 -92.87002)
		(end 473.184728 -91.792552)
		(width 0.17145)
		(layer "F.Cu")
		(net "DRV_ACT_23_N")
	)
	(segment
		(start 470.81948 -90.8304)
		(end 468.587328 -93.062552)
		(width 0.17145)
		(layer "F.Cu")
		(net "DRV_ACT_23_N")
	)
	(segment
		(start 473.400374 -93.085666)
		(end 473.184728 -92.87002)
		(width 0.17145)
		(layer "F.Cu")
		(net "DRV_ACT_23_N")
	)
	(segment
		(start 472.222576 -90.8304)
		(end 470.81948 -90.8304)
		(width 0.17145)
		(layer "F.Cu")
		(net "DRV_ACT_23_N")
	)
	(segment
		(start 468.587328 -123.232672)
		(end 468.587328 -113.3856)
		(width 0.17145)
		(layer "F.Cu")
		(net "DRV_ACT_23_N")
	)
	(segment
		(start 473.400374 -93.669866)
		(end 473.400374 -93.085666)
		(width 0.17145)
		(layer "F.Cu")
		(net "DRV_ACT_23_N")
	)
	(segment
		(start 468.587328 -93.062552)
		(end 468.587328 -113.3856)
		(width 0.17145)
		(layer "F.Cu")
		(net "DRV_ACT_23_N")
	)
	(segment
		(start 466.164168 -125.655832)
		(end 468.587328 -123.232672)
		(width 0.17145)
		(layer "F.Cu")
		(net "DRV_ACT_23_N")
	)
	(segment
		(start 473.184728 -91.792552)
		(end 472.222576 -90.8304)
		(width 0.17145)
		(layer "F.Cu")
		(net "DRV_ACT_23_N")
	)
	(segment
		(start 466.164168 -126.80442)
		(end 466.164168 -125.655832)
		(width 0.17145)
		(layer "F.Cu")
		(net "DRV_ACT_23_N")
	)
	(via
		(at 468.587328 -113.3856)
		(size 0.6604)
		(drill 0.3302)
		(layers "F.Cu" "B.Cu")
		(net "DRV_ACT_23_N")
	)
	(segment
		(start 437.799226 -121.000774)
		(end 434.710078 -124.089922)
		(width 0.17145)
		(layer "F.Cu")
		(net "DRV_ACT_22_N")
	)
	(segment
		(start 440.672474 -90.8304)
		(end 441.634626 -91.792552)
		(width 0.17145)
		(layer "F.Cu")
		(net "DRV_ACT_22_N")
	)
	(segment
		(start 437.799226 -110.9218)
		(end 437.799226 -92.300552)
		(width 0.17145)
		(layer "F.Cu")
		(net "DRV_ACT_22_N")
	)
	(segment
		(start 441.634626 -92.87002)
		(end 441.850272 -93.085666)
		(width 0.17145)
		(layer "F.Cu")
		(net "DRV_ACT_22_N")
	)
	(segment
		(start 441.634626 -91.792552)
		(end 441.634626 -92.87002)
		(width 0.17145)
		(layer "F.Cu")
		(net "DRV_ACT_22_N")
	)
	(segment
		(start 437.799226 -110.9218)
		(end 437.799226 -121.000774)
		(width 0.17145)
		(layer "F.Cu")
		(net "DRV_ACT_22_N")
	)
	(segment
		(start 437.799226 -92.300552)
		(end 439.269378 -90.8304)
		(width 0.17145)
		(layer "F.Cu")
		(net "DRV_ACT_22_N")
	)
	(segment
		(start 434.710078 -124.089922)
		(end 434.710078 -126.772162)
		(width 0.17145)
		(layer "F.Cu")
		(net "DRV_ACT_22_N")
	)
	(segment
		(start 441.850272 -93.085666)
		(end 441.850272 -93.669866)
		(width 0.17145)
		(layer "F.Cu")
		(net "DRV_ACT_22_N")
	)
	(segment
		(start 439.269378 -90.8304)
		(end 440.672474 -90.8304)
		(width 0.17145)
		(layer "F.Cu")
		(net "DRV_ACT_22_N")
	)
	(via
		(at 437.799226 -110.9218)
		(size 0.6604)
		(drill 0.3302)
		(layers "F.Cu" "B.Cu")
		(net "DRV_ACT_22_N")
	)
	(segment
		(start 403.095968 -126.836424)
		(end 405.487378 -124.445014)
		(width 0.17145)
		(layer "F.Cu")
		(net "DRV_ACT_21_N")
	)
	(segment
		(start 410.300424 -93.669866)
		(end 410.300424 -93.085666)
		(width 0.17145)
		(layer "F.Cu")
		(net "DRV_ACT_21_N")
	)
	(segment
		(start 409.122626 -90.8304)
		(end 407.71953 -90.8304)
		(width 0.17145)
		(layer "F.Cu")
		(net "DRV_ACT_21_N")
	)
	(segment
		(start 410.084778 -91.792552)
		(end 409.122626 -90.8304)
		(width 0.17145)
		(layer "F.Cu")
		(net "DRV_ACT_21_N")
	)
	(segment
		(start 410.300424 -93.085666)
		(end 410.084778 -92.87002)
		(width 0.17145)
		(layer "F.Cu")
		(net "DRV_ACT_21_N")
	)
	(segment
		(start 405.487378 -124.445014)
		(end 405.487378 -120.0658)
		(width 0.17145)
		(layer "F.Cu")
		(net "DRV_ACT_21_N")
	)
	(segment
		(start 407.71953 -90.8304)
		(end 405.487378 -93.062552)
		(width 0.17145)
		(layer "F.Cu")
		(net "DRV_ACT_21_N")
	)
	(segment
		(start 410.084778 -92.87002)
		(end 410.084778 -91.792552)
		(width 0.17145)
		(layer "F.Cu")
		(net "DRV_ACT_21_N")
	)
	(segment
		(start 405.487378 -93.062552)
		(end 405.487378 -120.0658)
		(width 0.17145)
		(layer "F.Cu")
		(net "DRV_ACT_21_N")
	)
	(via
		(at 405.487378 -120.0658)
		(size 0.6604)
		(drill 0.3302)
		(layers "F.Cu" "B.Cu")
		(net "DRV_ACT_21_N")
	)
	(segment
		(start 373.937276 -120.50014)
		(end 373.937276 -113.919)
		(width 0.17145)
		(layer "F.Cu")
		(net "DRV_ACT_20_N")
	)
	(segment
		(start 377.572524 -90.8304)
		(end 376.169428 -90.8304)
		(width 0.17145)
		(layer "F.Cu")
		(net "DRV_ACT_20_N")
	)
	(segment
		(start 378.534676 -92.87002)
		(end 378.534676 -91.792552)
		(width 0.17145)
		(layer "F.Cu")
		(net "DRV_ACT_20_N")
	)
	(segment
		(start 369.176554 -126.776734)
		(end 369.176554 -125.260862)
		(width 0.17145)
		(layer "F.Cu")
		(net "DRV_ACT_20_N")
	)
	(segment
		(start 378.750322 -93.085666)
		(end 378.534676 -92.87002)
		(width 0.17145)
		(layer "F.Cu")
		(net "DRV_ACT_20_N")
	)
	(segment
		(start 378.750322 -93.669866)
		(end 378.750322 -93.085666)
		(width 0.17145)
		(layer "F.Cu")
		(net "DRV_ACT_20_N")
	)
	(segment
		(start 378.534676 -91.792552)
		(end 377.572524 -90.8304)
		(width 0.17145)
		(layer "F.Cu")
		(net "DRV_ACT_20_N")
	)
	(segment
		(start 373.937276 -93.062552)
		(end 373.937276 -113.919)
		(width 0.17145)
		(layer "F.Cu")
		(net "DRV_ACT_20_N")
	)
	(segment
		(start 376.169428 -90.8304)
		(end 373.937276 -93.062552)
		(width 0.17145)
		(layer "F.Cu")
		(net "DRV_ACT_20_N")
	)
	(segment
		(start 369.176554 -125.260862)
		(end 373.937276 -120.50014)
		(width 0.17145)
		(layer "F.Cu")
		(net "DRV_ACT_20_N")
	)
	(via
		(at 373.937276 -113.919)
		(size 0.6604)
		(drill 0.3302)
		(layers "F.Cu" "B.Cu")
		(net "DRV_ACT_20_N")
	)
	(segment
		(start 72.013064 -187.151264)
		(end 72.013064 -195.182236)
		(width 0.17145)
		(layer "F.Cu")
		(net "DRV_ACT_2_N")
	)
	(segment
		(start 72.013064 -198.255636)
		(end 72.013064 -195.182236)
		(width 0.17145)
		(layer "F.Cu")
		(net "DRV_ACT_2_N")
	)
	(segment
		(start 69.619622 -186.01309)
		(end 70.87489 -186.01309)
		(width 0.17145)
		(layer "F.Cu")
		(net "DRV_ACT_2_N")
	)
	(segment
		(start 70.87489 -186.01309)
		(end 72.013064 -187.151264)
		(width 0.17145)
		(layer "F.Cu")
		(net "DRV_ACT_2_N")
	)
	(segment
		(start 81.400396 -208.120996)
		(end 81.18475 -207.90535)
		(width 0.17145)
		(layer "F.Cu")
		(net "DRV_ACT_2_N")
	)
	(segment
		(start 81.400396 -208.669636)
		(end 81.400396 -208.120996)
		(width 0.17145)
		(layer "F.Cu")
		(net "DRV_ACT_2_N")
	)
	(segment
		(start 81.18475 -207.90535)
		(end 81.18475 -207.427322)
		(width 0.17145)
		(layer "F.Cu")
		(net "DRV_ACT_2_N")
	)
	(segment
		(start 81.18475 -207.427322)
		(end 72.013064 -198.255636)
		(width 0.17145)
		(layer "F.Cu")
		(net "DRV_ACT_2_N")
	)
	(via
		(at 72.013064 -195.182236)
		(size 0.6604)
		(drill 0.3302)
		(layers "F.Cu" "B.Cu")
		(net "DRV_ACT_2_N")
	)
	(segment
		(start 346.984828 -92.87002)
		(end 346.984828 -91.792552)
		(width 0.17145)
		(layer "F.Cu")
		(net "DRV_ACT_19_N")
	)
	(segment
		(start 347.200474 -93.669866)
		(end 347.200474 -93.085666)
		(width 0.17145)
		(layer "F.Cu")
		(net "DRV_ACT_19_N")
	)
	(segment
		(start 347.200474 -93.085666)
		(end 346.984828 -92.87002)
		(width 0.17145)
		(layer "F.Cu")
		(net "DRV_ACT_19_N")
	)
	(segment
		(start 339.37194 -126.815088)
		(end 339.37194 -125.468888)
		(width 0.17145)
		(layer "F.Cu")
		(net "DRV_ACT_19_N")
	)
	(segment
		(start 339.37194 -125.468888)
		(end 342.387428 -122.4534)
		(width 0.17145)
		(layer "F.Cu")
		(net "DRV_ACT_19_N")
	)
	(segment
		(start 344.61958 -90.8304)
		(end 342.387428 -93.062552)
		(width 0.17145)
		(layer "F.Cu")
		(net "DRV_ACT_19_N")
	)
	(segment
		(start 346.022676 -90.8304)
		(end 344.61958 -90.8304)
		(width 0.17145)
		(layer "F.Cu")
		(net "DRV_ACT_19_N")
	)
	(segment
		(start 342.387428 -93.062552)
		(end 342.387428 -122.4534)
		(width 0.17145)
		(layer "F.Cu")
		(net "DRV_ACT_19_N")
	)
	(segment
		(start 346.984828 -91.792552)
		(end 346.022676 -90.8304)
		(width 0.17145)
		(layer "F.Cu")
		(net "DRV_ACT_19_N")
	)
	(via
		(at 342.387428 -122.4534)
		(size 0.6604)
		(drill 0.3302)
		(layers "F.Cu" "B.Cu")
		(net "DRV_ACT_19_N")
	)
	(segment
		(start 315.434726 -91.792552)
		(end 315.434726 -92.87002)
		(width 0.17145)
		(layer "F.Cu")
		(net "DRV_ACT_18_N")
	)
	(segment
		(start 314.898532 -119.56034)
		(end 312.234326 -116.896134)
		(width 0.17145)
		(layer "F.Cu")
		(net "DRV_ACT_18_N")
	)
	(segment
		(start 315.434726 -92.87002)
		(end 315.650372 -93.085666)
		(width 0.17145)
		(layer "F.Cu")
		(net "DRV_ACT_18_N")
	)
	(segment
		(start 314.898532 -124.42952)
		(end 314.898532 -119.56034)
		(width 0.17145)
		(layer "F.Cu")
		(net "DRV_ACT_18_N")
	)
	(segment
		(start 315.650372 -93.085666)
		(end 315.650372 -93.669866)
		(width 0.17145)
		(layer "F.Cu")
		(net "DRV_ACT_18_N")
	)
	(segment
		(start 314.472574 -90.8304)
		(end 315.434726 -91.792552)
		(width 0.17145)
		(layer "F.Cu")
		(net "DRV_ACT_18_N")
	)
	(segment
		(start 314.898532 -126.847854)
		(end 314.898532 -124.42952)
		(width 0.17145)
		(layer "F.Cu")
		(net "DRV_ACT_18_N")
	)
	(segment
		(start 313.069478 -90.8304)
		(end 314.472574 -90.8304)
		(width 0.17145)
		(layer "F.Cu")
		(net "DRV_ACT_18_N")
	)
	(segment
		(start 312.234326 -91.665552)
		(end 313.069478 -90.8304)
		(width 0.17145)
		(layer "F.Cu")
		(net "DRV_ACT_18_N")
	)
	(segment
		(start 312.234326 -116.896134)
		(end 312.234326 -91.665552)
		(width 0.17145)
		(layer "F.Cu")
		(net "DRV_ACT_18_N")
	)
	(via
		(at 314.898532 -124.42952)
		(size 0.6604)
		(drill 0.3302)
		(layers "F.Cu" "B.Cu")
		(net "DRV_ACT_18_N")
	)
	(segment
		(start 176.050448 -91.795854)
		(end 176.050448 -93.669866)
		(width 0.17145)
		(layer "F.Cu")
		(net "DRV_ACT_17_N")
	)
	(segment
		(start 175.064928 -90.233754)
		(end 176.050448 -91.219274)
		(width 0.17145)
		(layer "F.Cu")
		(net "DRV_ACT_17_N")
	)
	(segment
		(start 176.050448 -91.219274)
		(end 176.050448 -91.795854)
		(width 0.17145)
		(layer "F.Cu")
		(net "DRV_ACT_17_N")
	)
	(segment
		(start 158.503112 -127.903732)
		(end 158.503112 -126.75997)
		(width 0.17145)
		(layer "F.Cu")
		(net "DRV_ACT_17_N")
	)
	(via
		(at 175.064928 -90.233754)
		(size 0.5588)
		(drill 0.3048)
		(layers "F.Cu" "B.Cu")
		(net "DRV_ACT_17_N")
	)
	(via
		(at 176.050448 -91.795854)
		(size 0.6604)
		(drill 0.3302)
		(layers "F.Cu" "B.Cu")
		(net "DRV_ACT_17_N")
	)
	(via
		(at 158.503112 -127.903732)
		(size 0.5588)
		(drill 0.3048)
		(layers "F.Cu" "B.Cu")
		(net "DRV_ACT_17_N")
	)
	(segment
		(start 172.173646 -107.559348)
		(end 172.173646 -92.722954)
		(width 0.13335)
		(layer "In9.Cu")
		(net "DRV_ACT_17_N")
	)
	(segment
		(start 158.503112 -121.229882)
		(end 172.173646 -107.559348)
		(width 0.13335)
		(layer "In9.Cu")
		(net "DRV_ACT_17_N")
	)
	(segment
		(start 158.503112 -127.903732)
		(end 158.503112 -121.229882)
		(width 0.13335)
		(layer "In9.Cu")
		(net "DRV_ACT_17_N")
	)
	(segment
		(start 174.662846 -90.233754)
		(end 175.064928 -90.233754)
		(width 0.13335)
		(layer "In9.Cu")
		(net "DRV_ACT_17_N")
	)
	(segment
		(start 172.173646 -92.722954)
		(end 174.662846 -90.233754)
		(width 0.13335)
		(layer "In9.Cu")
		(net "DRV_ACT_17_N")
	)
	(segment
		(start 129.697734 -126.845568)
		(end 129.697734 -124.925836)
		(width 0.17145)
		(layer "F.Cu")
		(net "DRV_ACT_16_N")
	)
	(segment
		(start 129.697734 -124.925836)
		(end 129.697734 -123.458986)
		(width 0.17145)
		(layer "F.Cu")
		(net "DRV_ACT_16_N")
	)
	(segment
		(start 144.500346 -93.669866)
		(end 144.500346 -92.261436)
		(width 0.17145)
		(layer "F.Cu")
		(net "DRV_ACT_16_N")
	)
	(via
		(at 129.697734 -123.458986)
		(size 0.5588)
		(drill 0.3048)
		(layers "F.Cu" "B.Cu")
		(net "DRV_ACT_16_N")
	)
	(via
		(at 129.697734 -124.925836)
		(size 0.6604)
		(drill 0.3302)
		(layers "F.Cu" "B.Cu")
		(net "DRV_ACT_16_N")
	)
	(via
		(at 144.500346 -92.261436)
		(size 0.5588)
		(drill 0.3048)
		(layers "F.Cu" "B.Cu")
		(net "DRV_ACT_16_N")
	)
	(segment
		(start 139.820396 -94.653354)
		(end 142.93215 -91.5416)
		(width 0.13335)
		(layer "In9.Cu")
		(net "DRV_ACT_16_N")
	)
	(segment
		(start 139.820396 -103.867204)
		(end 139.820396 -94.653354)
		(width 0.13335)
		(layer "In9.Cu")
		(net "DRV_ACT_16_N")
	)
	(segment
		(start 129.697734 -113.989866)
		(end 139.820396 -103.867204)
		(width 0.13335)
		(layer "In9.Cu")
		(net "DRV_ACT_16_N")
	)
	(segment
		(start 142.93215 -91.5416)
		(end 143.78051 -91.5416)
		(width 0.13335)
		(layer "In9.Cu")
		(net "DRV_ACT_16_N")
	)
	(segment
		(start 129.697734 -123.458986)
		(end 129.697734 -113.989866)
		(width 0.13335)
		(layer "In9.Cu")
		(net "DRV_ACT_16_N")
	)
	(segment
		(start 143.78051 -91.5416)
		(end 144.500346 -92.261436)
		(width 0.13335)
		(layer "In9.Cu")
		(net "DRV_ACT_16_N")
	)
	(segment
		(start 105.740962 -124.916438)
		(end 105.740962 -123.449588)
		(width 0.17145)
		(layer "F.Cu")
		(net "DRV_ACT_15_N")
	)
	(segment
		(start 105.740962 -126.83617)
		(end 105.740962 -124.916438)
		(width 0.17145)
		(layer "F.Cu")
		(net "DRV_ACT_15_N")
	)
	(segment
		(start 112.950498 -93.669866)
		(end 112.950498 -92.261436)
		(width 0.17145)
		(layer "F.Cu")
		(net "DRV_ACT_15_N")
	)
	(via
		(at 112.950498 -92.261436)
		(size 0.5588)
		(drill 0.3048)
		(layers "F.Cu" "B.Cu")
		(net "DRV_ACT_15_N")
	)
	(via
		(at 105.740962 -123.449588)
		(size 0.5588)
		(drill 0.3048)
		(layers "F.Cu" "B.Cu")
		(net "DRV_ACT_15_N")
	)
	(via
		(at 105.740962 -124.916438)
		(size 0.6604)
		(drill 0.3302)
		(layers "F.Cu" "B.Cu")
		(net "DRV_ACT_15_N")
	)
	(segment
		(start 112.230662 -91.5416)
		(end 112.950498 -92.261436)
		(width 0.13335)
		(layer "In9.Cu")
		(net "DRV_ACT_15_N")
	)
	(segment
		(start 111.382302 -91.5416)
		(end 112.230662 -91.5416)
		(width 0.13335)
		(layer "In9.Cu")
		(net "DRV_ACT_15_N")
	)
	(segment
		(start 108.385102 -94.5388)
		(end 111.382302 -91.5416)
		(width 0.13335)
		(layer "In9.Cu")
		(net "DRV_ACT_15_N")
	)
	(segment
		(start 108.385102 -120.805448)
		(end 108.385102 -94.5388)
		(width 0.13335)
		(layer "In9.Cu")
		(net "DRV_ACT_15_N")
	)
	(segment
		(start 105.740962 -123.449588)
		(end 108.385102 -120.805448)
		(width 0.13335)
		(layer "In9.Cu")
		(net "DRV_ACT_15_N")
	)
	(segment
		(start 81.400396 -93.669866)
		(end 81.400396 -92.261436)
		(width 0.17145)
		(layer "F.Cu")
		(net "DRV_ACT_14_N")
	)
	(segment
		(start 74.206862 -124.925836)
		(end 74.206862 -123.458986)
		(width 0.17145)
		(layer "F.Cu")
		(net "DRV_ACT_14_N")
	)
	(segment
		(start 74.206862 -126.845568)
		(end 74.206862 -124.925836)
		(width 0.17145)
		(layer "F.Cu")
		(net "DRV_ACT_14_N")
	)
	(via
		(at 81.400396 -92.261436)
		(size 0.5588)
		(drill 0.3048)
		(layers "F.Cu" "B.Cu")
		(net "DRV_ACT_14_N")
	)
	(via
		(at 74.206862 -124.925836)
		(size 0.6604)
		(drill 0.3302)
		(layers "F.Cu" "B.Cu")
		(net "DRV_ACT_14_N")
	)
	(via
		(at 74.206862 -123.458986)
		(size 0.5588)
		(drill 0.3048)
		(layers "F.Cu" "B.Cu")
		(net "DRV_ACT_14_N")
	)
	(segment
		(start 74.206862 -123.458986)
		(end 76.835 -120.830848)
		(width 0.13335)
		(layer "In9.Cu")
		(net "DRV_ACT_14_N")
	)
	(segment
		(start 76.835 -120.830848)
		(end 76.835 -94.5388)
		(width 0.13335)
		(layer "In9.Cu")
		(net "DRV_ACT_14_N")
	)
	(segment
		(start 80.70596 -91.567)
		(end 81.400396 -92.261436)
		(width 0.13335)
		(layer "In9.Cu")
		(net "DRV_ACT_14_N")
	)
	(segment
		(start 76.835 -94.5388)
		(end 79.8068 -91.567)
		(width 0.13335)
		(layer "In9.Cu")
		(net "DRV_ACT_14_N")
	)
	(segment
		(start 79.8068 -91.567)
		(end 80.70596 -91.567)
		(width 0.13335)
		(layer "In9.Cu")
		(net "DRV_ACT_14_N")
	)
	(segment
		(start 49.634648 -92.128848)
		(end 49.634648 -92.87002)
		(width 0.17145)
		(layer "F.Cu")
		(net "DRV_ACT_13_N")
	)
	(segment
		(start 48.3362 -90.8304)
		(end 49.634648 -92.128848)
		(width 0.17145)
		(layer "F.Cu")
		(net "DRV_ACT_13_N")
	)
	(segment
		(start 47.2694 -90.8304)
		(end 48.3362 -90.8304)
		(width 0.17145)
		(layer "F.Cu")
		(net "DRV_ACT_13_N")
	)
	(segment
		(start 42.669968 -95.429832)
		(end 47.2694 -90.8304)
		(width 0.17145)
		(layer "F.Cu")
		(net "DRV_ACT_13_N")
	)
	(segment
		(start 49.850294 -93.085666)
		(end 49.850294 -93.669866)
		(width 0.17145)
		(layer "F.Cu")
		(net "DRV_ACT_13_N")
	)
	(segment
		(start 49.634648 -92.87002)
		(end 49.850294 -93.085666)
		(width 0.17145)
		(layer "F.Cu")
		(net "DRV_ACT_13_N")
	)
	(segment
		(start 42.667428 -101.72954)
		(end 42.669968 -101.727)
		(width 0.17145)
		(layer "F.Cu")
		(net "DRV_ACT_13_N")
	)
	(segment
		(start 42.667428 -126.845568)
		(end 42.667428 -101.72954)
		(width 0.17145)
		(layer "F.Cu")
		(net "DRV_ACT_13_N")
	)
	(segment
		(start 42.669968 -101.727)
		(end 42.669968 -95.429832)
		(width 0.17145)
		(layer "F.Cu")
		(net "DRV_ACT_13_N")
	)
	(via
		(at 42.669968 -101.727)
		(size 0.6604)
		(drill 0.3302)
		(layers "F.Cu" "B.Cu")
		(net "DRV_ACT_13_N")
	)
	(segment
		(start 18.300446 -93.085666)
		(end 18.300446 -93.669866)
		(width 0.17145)
		(layer "F.Cu")
		(net "DRV_ACT_12_N")
	)
	(segment
		(start 10.9474 -117.8814)
		(end 13.9954 -114.8334)
		(width 0.17145)
		(layer "F.Cu")
		(net "DRV_ACT_12_N")
	)
	(segment
		(start 13.9954 -93.6498)
		(end 16.0782 -91.567)
		(width 0.17145)
		(layer "F.Cu")
		(net "DRV_ACT_12_N")
	)
	(segment
		(start 18.0848 -92.87002)
		(end 18.300446 -93.085666)
		(width 0.17145)
		(layer "F.Cu")
		(net "DRV_ACT_12_N")
	)
	(segment
		(start 16.0782 -91.567)
		(end 17.4752 -91.567)
		(width 0.17145)
		(layer "F.Cu")
		(net "DRV_ACT_12_N")
	)
	(segment
		(start 10.9474 -118.716552)
		(end 10.9474 -117.8814)
		(width 0.17145)
		(layer "F.Cu")
		(net "DRV_ACT_12_N")
	)
	(segment
		(start 11.106912 -126.856236)
		(end 11.106912 -124.8664)
		(width 0.17145)
		(layer "F.Cu")
		(net "DRV_ACT_12_N")
	)
	(segment
		(start 13.9954 -114.8334)
		(end 13.9954 -93.6498)
		(width 0.17145)
		(layer "F.Cu")
		(net "DRV_ACT_12_N")
	)
	(segment
		(start 18.0848 -92.1766)
		(end 18.0848 -92.87002)
		(width 0.17145)
		(layer "F.Cu")
		(net "DRV_ACT_12_N")
	)
	(segment
		(start 10.922 -118.741952)
		(end 10.9474 -118.716552)
		(width 0.17145)
		(layer "F.Cu")
		(net "DRV_ACT_12_N")
	)
	(segment
		(start 17.4752 -91.567)
		(end 18.0848 -92.1766)
		(width 0.17145)
		(layer "F.Cu")
		(net "DRV_ACT_12_N")
	)
	(segment
		(start 10.922 -124.681488)
		(end 10.922 -118.741952)
		(width 0.17145)
		(layer "F.Cu")
		(net "DRV_ACT_12_N")
	)
	(segment
		(start 11.106912 -124.8664)
		(end 10.922 -124.681488)
		(width 0.17145)
		(layer "F.Cu")
		(net "DRV_ACT_12_N")
	)
	(via
		(at 10.9474 -117.8814)
		(size 0.6604)
		(drill 0.3302)
		(layers "F.Cu" "B.Cu")
		(net "DRV_ACT_12_N")
	)
	(segment
		(start 473.390214 -206.586836)
		(end 473.184728 -206.792322)
		(width 0.17145)
		(layer "F.Cu")
		(net "DRV_ACT_11_N")
	)
	(segment
		(start 473.400374 -208.085436)
		(end 473.400374 -208.669636)
		(width 0.17145)
		(layer "F.Cu")
		(net "DRV_ACT_11_N")
	)
	(segment
		(start 473.184728 -207.86979)
		(end 473.400374 -208.085436)
		(width 0.17145)
		(layer "F.Cu")
		(net "DRV_ACT_11_N")
	)
	(segment
		(start 455.227944 -231.050084)
		(end 474.464888 -211.81314)
		(width 0.17145)
		(layer "F.Cu")
		(net "DRV_ACT_11_N")
	)
	(segment
		(start 474.464888 -207.175862)
		(end 473.875862 -206.586836)
		(width 0.17145)
		(layer "F.Cu")
		(net "DRV_ACT_11_N")
	)
	(segment
		(start 455.227944 -239.38992)
		(end 455.227944 -231.050084)
		(width 0.17145)
		(layer "F.Cu")
		(net "DRV_ACT_11_N")
	)
	(segment
		(start 455.227944 -241.770154)
		(end 455.227944 -239.38992)
		(width 0.17145)
		(layer "F.Cu")
		(net "DRV_ACT_11_N")
	)
	(segment
		(start 473.875862 -206.586836)
		(end 473.390214 -206.586836)
		(width 0.17145)
		(layer "F.Cu")
		(net "DRV_ACT_11_N")
	)
	(segment
		(start 474.464888 -211.81314)
		(end 474.464888 -207.175862)
		(width 0.17145)
		(layer "F.Cu")
		(net "DRV_ACT_11_N")
	)
	(segment
		(start 473.184728 -206.792322)
		(end 473.184728 -207.86979)
		(width 0.17145)
		(layer "F.Cu")
		(net "DRV_ACT_11_N")
	)
	(via
		(at 455.227944 -239.38992)
		(size 0.6604)
		(drill 0.3302)
		(layers "F.Cu" "B.Cu")
		(net "DRV_ACT_11_N")
	)
	(segment
		(start 444.391542 -238.50981)
		(end 444.391542 -237.321852)
		(width 0.17145)
		(layer "F.Cu")
		(net "DRV_ACT_10_N")
	)
	(segment
		(start 443.215014 -206.66964)
		(end 442.04001 -206.66964)
		(width 0.17145)
		(layer "F.Cu")
		(net "DRV_ACT_10_N")
	)
	(segment
		(start 441.850272 -208.085436)
		(end 441.850272 -208.669636)
		(width 0.17145)
		(layer "F.Cu")
		(net "DRV_ACT_10_N")
	)
	(segment
		(start 441.634626 -207.86979)
		(end 441.850272 -208.085436)
		(width 0.17145)
		(layer "F.Cu")
		(net "DRV_ACT_10_N")
	)
	(segment
		(start 443.615572 -207.070198)
		(end 443.215014 -206.66964)
		(width 0.17145)
		(layer "F.Cu")
		(net "DRV_ACT_10_N")
	)
	(segment
		(start 441.634626 -207.075024)
		(end 441.634626 -207.86979)
		(width 0.17145)
		(layer "F.Cu")
		(net "DRV_ACT_10_N")
	)
	(segment
		(start 444.391542 -238.50981)
		(end 444.391542 -241.857022)
		(width 0.17145)
		(layer "F.Cu")
		(net "DRV_ACT_10_N")
	)
	(segment
		(start 442.04001 -206.66964)
		(end 441.634626 -207.075024)
		(width 0.17145)
		(layer "F.Cu")
		(net "DRV_ACT_10_N")
	)
	(segment
		(start 444.391542 -237.321852)
		(end 443.615572 -236.545882)
		(width 0.17145)
		(layer "F.Cu")
		(net "DRV_ACT_10_N")
	)
	(segment
		(start 443.615572 -236.545882)
		(end 443.615572 -207.070198)
		(width 0.17145)
		(layer "F.Cu")
		(net "DRV_ACT_10_N")
	)
	(via
		(at 444.391542 -238.50981)
		(size 0.6604)
		(drill 0.3302)
		(layers "F.Cu" "B.Cu")
		(net "DRV_ACT_10_N")
	)
	(segment
		(start 39.469314 -186.078114)
		(end 40.5384 -187.1472)
		(width 0.17145)
		(layer "F.Cu")
		(net "DRV_ACT_1_N")
	)
	(segment
		(start 40.5384 -192.771268)
		(end 40.5384 -196.5452)
		(width 0.17145)
		(layer "F.Cu")
		(net "DRV_ACT_1_N")
	)
	(segment
		(start 49.850294 -205.857094)
		(end 49.850294 -208.669636)
		(width 0.17145)
		(layer "F.Cu")
		(net "DRV_ACT_1_N")
	)
	(segment
		(start 40.5384 -187.1472)
		(end 40.5384 -192.771268)
		(width 0.17145)
		(layer "F.Cu")
		(net "DRV_ACT_1_N")
	)
	(segment
		(start 40.5384 -196.5452)
		(end 49.850294 -205.857094)
		(width 0.17145)
		(layer "F.Cu")
		(net "DRV_ACT_1_N")
	)
	(segment
		(start 38.055804 -186.078114)
		(end 39.469314 -186.078114)
		(width 0.17145)
		(layer "F.Cu")
		(net "DRV_ACT_1_N")
	)
	(via
		(at 40.5384 -192.771268)
		(size 0.6604)
		(drill 0.3302)
		(layers "F.Cu" "B.Cu")
		(net "DRV_ACT_1_N")
	)
	(segment
		(start 9.9314 -178.1556)
		(end 8.0772 -180.0098)
		(width 0.17145)
		(layer "F.Cu")
		(net "DRV_ACT_0_N")
	)
	(segment
		(start 6.812788 -173.337982)
		(end 8.212582 -173.337982)
		(width 0.17145)
		(layer "F.Cu")
		(net "DRV_ACT_0_N")
	)
	(segment
		(start 18.300446 -208.669636)
		(end 18.300446 -204.507846)
		(width 0.17145)
		(layer "F.Cu")
		(net "DRV_ACT_0_N")
	)
	(segment
		(start 8.0772 -180.0098)
		(end 8.0772 -193.5734)
		(width 0.17145)
		(layer "F.Cu")
		(net "DRV_ACT_0_N")
	)
	(segment
		(start 8.6106 -194.818)
		(end 8.6106 -194.1068)
		(width 0.17145)
		(layer "F.Cu")
		(net "DRV_ACT_0_N")
	)
	(segment
		(start 8.0772 -193.5734)
		(end 8.6106 -194.1068)
		(width 0.17145)
		(layer "F.Cu")
		(net "DRV_ACT_0_N")
	)
	(segment
		(start 9.9314 -175.0568)
		(end 9.9314 -178.1556)
		(width 0.17145)
		(layer "F.Cu")
		(net "DRV_ACT_0_N")
	)
	(segment
		(start 18.300446 -204.507846)
		(end 8.6106 -194.818)
		(width 0.17145)
		(layer "F.Cu")
		(net "DRV_ACT_0_N")
	)
	(segment
		(start 8.212582 -173.337982)
		(end 9.9314 -175.0568)
		(width 0.17145)
		(layer "F.Cu")
		(net "DRV_ACT_0_N")
	)
	(via
		(at 8.6106 -194.1068)
		(size 0.6604)
		(drill 0.3302)
		(layers "F.Cu" "B.Cu")
		(net "DRV_ACT_0_N")
	)
	(segment
		(start 248.44121 -297.726862)
		(end 248.44121 -298.60621)
		(width 0.17145)
		(layer "F.Cu")
		(net "SCC_A_RESET_N")
	)
	(segment
		(start 249.526298 -300.633892)
		(end 249.301 -300.408594)
		(width 0.17145)
		(layer "F.Cu")
		(net "SCC_A_RESET_N")
	)
	(segment
		(start 249.301 -300.408594)
		(end 249.301 -299.466)
		(width 0.17145)
		(layer "F.Cu")
		(net "SCC_A_RESET_N")
	)
	(segment
		(start 248.44121 -298.60621)
		(end 249.301 -299.466)
		(width 0.17145)
		(layer "F.Cu")
		(net "SCC_A_RESET_N")
	)
	(via
		(at 249.526298 -300.633892)
		(size 0.5588)
		(drill 0.3048)
		(layers "F.Cu" "B.Cu")
		(net "SCC_A_RESET_N")
	)
	(via
		(at 249.301 -299.466)
		(size 0.6604)
		(drill 0.3302)
		(layers "F.Cu" "B.Cu")
		(net "SCC_A_RESET_N")
	)
	(segment
		(start 272.064734 -341.381334)
		(end 249.526298 -318.842898)
		(width 0.12065)
		(layer "In4.Cu")
		(net "SCC_A_RESET_N")
	)
	(segment
		(start 249.526298 -318.842898)
		(end 249.526298 -300.633892)
		(width 0.12065)
		(layer "In4.Cu")
		(net "SCC_A_RESET_N")
	)
	(segment
		(start 274.93722 -341.381334)
		(end 272.064734 -341.381334)
		(width 0.12065)
		(layer "In4.Cu")
		(net "SCC_A_RESET_N")
	)
	(segment
		(start 275.72081 -342.164924)
		(end 274.93722 -341.381334)
		(width 0.12065)
		(layer "In4.Cu")
		(net "SCC_A_RESET_N")
	)
	(segment
		(start 281.17673 -342.164924)
		(end 275.72081 -342.164924)
		(width 0.12065)
		(layer "In4.Cu")
		(net "SCC_A_RESET_N")
	)
	(segment
		(start 281.836622 -341.505032)
		(end 281.17673 -342.164924)
		(width 0.12065)
		(layer "In4.Cu")
		(net "SCC_A_RESET_N")
	)
	(segment
		(start 300.01083 -66.343784)
		(end 299.4406 -65.773554)
		(width 0.17145)
		(layer "F.Cu")
		(net "I2C_BMC_B_COMP_B_SDA")
	)
	(segment
		(start 285.249874 -104.499918)
		(end 285.487618 -104.499918)
		(width 0.17145)
		(layer "F.Cu")
		(net "I2C_BMC_B_COMP_B_SDA")
	)
	(segment
		(start 291.4142 -91.578684)
		(end 299.232574 -83.76031)
		(width 0.17145)
		(layer "F.Cu")
		(net "I2C_BMC_B_COMP_B_SDA")
	)
	(segment
		(start 304.3174 -78.675484)
		(end 304.3174 -77.941932)
		(width 0.17145)
		(layer "F.Cu")
		(net "I2C_BMC_B_COMP_B_SDA")
	)
	(segment
		(start 291.4142 -98.573336)
		(end 291.4142 -91.578684)
		(width 0.17145)
		(layer "F.Cu")
		(net "I2C_BMC_B_COMP_B_SDA")
	)
	(segment
		(start 299.4406 -65.773554)
		(end 299.4406 -63.6143)
		(width 0.17145)
		(layer "F.Cu")
		(net "I2C_BMC_B_COMP_B_SDA")
	)
	(segment
		(start 298.9961 -66.7385)
		(end 298.7294 -66.7385)
		(width 0.17145)
		(layer "F.Cu")
		(net "I2C_BMC_B_COMP_B_SDA")
	)
	(segment
		(start 299.4406 -63.6143)
		(end 299.6057 -63.4492)
		(width 0.17145)
		(layer "F.Cu")
		(net "I2C_BMC_B_COMP_B_SDA")
	)
	(segment
		(start 299.232574 -83.76031)
		(end 304.3174 -78.675484)
		(width 0.17145)
		(layer "F.Cu")
		(net "I2C_BMC_B_COMP_B_SDA")
	)
	(segment
		(start 299.5422 -67.2846)
		(end 298.9961 -66.7385)
		(width 0.17145)
		(layer "F.Cu")
		(net "I2C_BMC_B_COMP_B_SDA")
	)
	(segment
		(start 285.487618 -104.499918)
		(end 291.4142 -98.573336)
		(width 0.17145)
		(layer "F.Cu")
		(net "I2C_BMC_B_COMP_B_SDA")
	)
	(segment
		(start 298.7294 -65.913)
		(end 298.5516 -65.7352)
		(width 0.17145)
		(layer "F.Cu")
		(net "I2C_BMC_B_COMP_B_SDA")
	)
	(segment
		(start 300.01083 -67.2846)
		(end 300.01083 -66.343784)
		(width 0.17145)
		(layer "F.Cu")
		(net "I2C_BMC_B_COMP_B_SDA")
	)
	(segment
		(start 298.7294 -66.7385)
		(end 298.7294 -65.913)
		(width 0.17145)
		(layer "F.Cu")
		(net "I2C_BMC_B_COMP_B_SDA")
	)
	(segment
		(start 300.01083 -67.2846)
		(end 299.5422 -67.2846)
		(width 0.17145)
		(layer "F.Cu")
		(net "I2C_BMC_B_COMP_B_SDA")
	)
	(via
		(at 304.3174 -77.941932)
		(size 0.5588)
		(drill 0.3048)
		(layers "F.Cu" "B.Cu")
		(net "I2C_BMC_B_COMP_B_SDA")
	)
	(via
		(at 299.232574 -83.76031)
		(size 0.6604)
		(drill 0.3302)
		(layers "F.Cu" "B.Cu")
		(net "I2C_BMC_B_COMP_B_SDA")
	)
	(via
		(at 298.5516 -65.7352)
		(size 0.5588)
		(drill 0.3048)
		(layers "F.Cu" "B.Cu")
		(net "I2C_BMC_B_COMP_B_SDA")
	)
	(segment
		(start 298.5516 -65.7352)
		(end 298.7294 -65.913)
		(width 0.12065)
		(layer "In4.Cu")
		(net "I2C_BMC_B_COMP_B_SDA")
	)
	(segment
		(start 298.7294 -65.913)
		(end 298.7294 -66.866262)
		(width 0.12065)
		(layer "In4.Cu")
		(net "I2C_BMC_B_COMP_B_SDA")
	)
	(segment
		(start 304.05578 -77.680312)
		(end 304.3174 -77.941932)
		(width 0.12065)
		(layer "In4.Cu")
		(net "I2C_BMC_B_COMP_B_SDA")
	)
	(segment
		(start 304.05578 -72.192642)
		(end 304.05578 -77.680312)
		(width 0.12065)
		(layer "In4.Cu")
		(net "I2C_BMC_B_COMP_B_SDA")
	)
	(segment
		(start 298.7294 -66.866262)
		(end 304.05578 -72.192642)
		(width 0.12065)
		(layer "In4.Cu")
		(net "I2C_BMC_B_COMP_B_SDA")
	)
	(segment
		(start 300.487842 -68.3514)
		(end 301.832772 -68.3514)
		(width 0.17145)
		(layer "F.Cu")
		(net "I2C_BMC_B_COMP_B_SCL")
	)
	(segment
		(start 297.935142 -70.5231)
		(end 298.7294 -70.5231)
		(width 0.17145)
		(layer "F.Cu")
		(net "I2C_BMC_B_COMP_B_SCL")
	)
	(segment
		(start 302.240696 -79.775304)
		(end 303.2252 -78.7908)
		(width 0.17145)
		(layer "F.Cu")
		(net "I2C_BMC_B_COMP_B_SCL")
	)
	(segment
		(start 303.2252 -78.7908)
		(end 303.2252 -78.195678)
		(width 0.17145)
		(layer "F.Cu")
		(net "I2C_BMC_B_COMP_B_SCL")
	)
	(segment
		(start 298.7294 -70.5231)
		(end 299.3009 -70.5231)
		(width 0.17145)
		(layer "F.Cu")
		(net "I2C_BMC_B_COMP_B_SCL")
	)
	(segment
		(start 290.73475 -91.28125)
		(end 302.240696 -79.775304)
		(width 0.17145)
		(layer "F.Cu")
		(net "I2C_BMC_B_COMP_B_SCL")
	)
	(segment
		(start 301.832772 -68.3514)
		(end 302.8442 -67.339972)
		(width 0.17145)
		(layer "F.Cu")
		(net "I2C_BMC_B_COMP_B_SCL")
	)
	(segment
		(start 297.624246 -65.827402)
		(end 297.624246 -70.212204)
		(width 0.17145)
		(layer "F.Cu")
		(net "I2C_BMC_B_COMP_B_SCL")
	)
	(segment
		(start 285.52648 -103.49992)
		(end 290.73475 -98.29165)
		(width 0.17145)
		(layer "F.Cu")
		(net "I2C_BMC_B_COMP_B_SCL")
	)
	(segment
		(start 300.01083 -68.828412)
		(end 300.487842 -68.3514)
		(width 0.17145)
		(layer "F.Cu")
		(net "I2C_BMC_B_COMP_B_SCL")
	)
	(segment
		(start 300.01083 -69.81317)
		(end 300.01083 -69.6214)
		(width 0.17145)
		(layer "F.Cu")
		(net "I2C_BMC_B_COMP_B_SCL")
	)
	(segment
		(start 299.3009 -70.5231)
		(end 300.01083 -69.81317)
		(width 0.17145)
		(layer "F.Cu")
		(net "I2C_BMC_B_COMP_B_SCL")
	)
	(segment
		(start 297.624246 -70.212204)
		(end 297.935142 -70.5231)
		(width 0.17145)
		(layer "F.Cu")
		(net "I2C_BMC_B_COMP_B_SCL")
	)
	(segment
		(start 300.01083 -69.6214)
		(end 300.01083 -68.828412)
		(width 0.17145)
		(layer "F.Cu")
		(net "I2C_BMC_B_COMP_B_SCL")
	)
	(segment
		(start 290.73475 -98.29165)
		(end 290.73475 -91.28125)
		(width 0.17145)
		(layer "F.Cu")
		(net "I2C_BMC_B_COMP_B_SCL")
	)
	(segment
		(start 283.249878 -103.49992)
		(end 285.52648 -103.49992)
		(width 0.17145)
		(layer "F.Cu")
		(net "I2C_BMC_B_COMP_B_SCL")
	)
	(via
		(at 297.624246 -65.827402)
		(size 0.5588)
		(drill 0.3048)
		(layers "F.Cu" "B.Cu")
		(net "I2C_BMC_B_COMP_B_SCL")
	)
	(via
		(at 302.240696 -79.775304)
		(size 0.6604)
		(drill 0.3302)
		(layers "F.Cu" "B.Cu")
		(net "I2C_BMC_B_COMP_B_SCL")
	)
	(via
		(at 303.2252 -78.195678)
		(size 0.5588)
		(drill 0.3048)
		(layers "F.Cu" "B.Cu")
		(net "I2C_BMC_B_COMP_B_SCL")
	)
	(segment
		(start 297.624246 -65.827402)
		(end 297.624246 -66.650362)
		(width 0.12065)
		(layer "In4.Cu")
		(net "I2C_BMC_B_COMP_B_SCL")
	)
	(segment
		(start 297.624246 -66.650362)
		(end 302.870362 -71.896478)
		(width 0.12065)
		(layer "In4.Cu")
		(net "I2C_BMC_B_COMP_B_SCL")
	)
	(segment
		(start 302.870362 -77.84084)
		(end 303.2252 -78.195678)
		(width 0.12065)
		(layer "In4.Cu")
		(net "I2C_BMC_B_COMP_B_SCL")
	)
	(segment
		(start 302.870362 -71.896478)
		(end 302.870362 -77.84084)
		(width 0.12065)
		(layer "In4.Cu")
		(net "I2C_BMC_B_COMP_B_SCL")
	)
	(segment
		(start 236.290612 -99.642676)
		(end 235.694982 -99.642676)
		(width 0.17145)
		(layer "F.Cu")
		(net "I2C_BMC_A_COMP_A_SDA")
	)
	(segment
		(start 238.369602 -100.567998)
		(end 237.518448 -100.567998)
		(width 0.17145)
		(layer "F.Cu")
		(net "I2C_BMC_A_COMP_A_SDA")
	)
	(segment
		(start 235.192824 -100.144834)
		(end 235.192824 -100.740464)
		(width 0.17145)
		(layer "F.Cu")
		(net "I2C_BMC_A_COMP_A_SDA")
	)
	(segment
		(start 235.192824 -100.740464)
		(end 225.439478 -110.49381)
		(width 0.17145)
		(layer "F.Cu")
		(net "I2C_BMC_A_COMP_A_SDA")
	)
	(segment
		(start 220.06179 -110.49381)
		(end 217.3986 -113.157)
		(width 0.17145)
		(layer "F.Cu")
		(net "I2C_BMC_A_COMP_A_SDA")
	)
	(segment
		(start 241.050064 -102.489254)
		(end 240.290858 -102.489254)
		(width 0.17145)
		(layer "F.Cu")
		(net "I2C_BMC_A_COMP_A_SDA")
	)
	(segment
		(start 217.3986 -113.157)
		(end 217.3986 -114.3762)
		(width 0.17145)
		(layer "F.Cu")
		(net "I2C_BMC_A_COMP_A_SDA")
	)
	(segment
		(start 235.694982 -99.642676)
		(end 235.192824 -100.144834)
		(width 0.17145)
		(layer "F.Cu")
		(net "I2C_BMC_A_COMP_A_SDA")
	)
	(segment
		(start 225.439478 -110.49381)
		(end 220.06179 -110.49381)
		(width 0.17145)
		(layer "F.Cu")
		(net "I2C_BMC_A_COMP_A_SDA")
	)
	(segment
		(start 242.549934 -104.499918)
		(end 242.549934 -103.989124)
		(width 0.17145)
		(layer "F.Cu")
		(net "I2C_BMC_A_COMP_A_SDA")
	)
	(segment
		(start 237.518448 -100.567998)
		(end 236.530642 -99.580192)
		(width 0.17145)
		(layer "F.Cu")
		(net "I2C_BMC_A_COMP_A_SDA")
	)
	(segment
		(start 217.3986 -114.3762)
		(end 216.408 -115.3668)
		(width 0.17145)
		(layer "F.Cu")
		(net "I2C_BMC_A_COMP_A_SDA")
	)
	(segment
		(start 240.290858 -102.489254)
		(end 238.369602 -100.567998)
		(width 0.17145)
		(layer "F.Cu")
		(net "I2C_BMC_A_COMP_A_SDA")
	)
	(segment
		(start 236.353096 -99.580192)
		(end 236.290612 -99.642676)
		(width 0.17145)
		(layer "F.Cu")
		(net "I2C_BMC_A_COMP_A_SDA")
	)
	(segment
		(start 236.530642 -99.580192)
		(end 236.353096 -99.580192)
		(width 0.17145)
		(layer "F.Cu")
		(net "I2C_BMC_A_COMP_A_SDA")
	)
	(segment
		(start 242.549934 -103.989124)
		(end 241.050064 -102.489254)
		(width 0.17145)
		(layer "F.Cu")
		(net "I2C_BMC_A_COMP_A_SDA")
	)
	(via
		(at 215.47455 -121.98985)
		(size 0.6096)
		(drill 0.3048)
		(layers "F.Cu" "B.Cu")
		(net "I2C_BMC_A_COMP_A_SDA")
	)
	(via
		(at 216.408 -115.3668)
		(size 0.5588)
		(drill 0.3048)
		(layers "F.Cu" "B.Cu")
		(net "I2C_BMC_A_COMP_A_SDA")
	)
	(segment
		(start 217.02903 -119.01043)
		(end 217.6526 -119.01043)
		(width 0.17145)
		(layer "B.Cu")
		(net "I2C_BMC_A_COMP_A_SDA")
	)
	(segment
		(start 214.7316 -118.2624)
		(end 216.281 -118.2624)
		(width 0.17145)
		(layer "B.Cu")
		(net "I2C_BMC_A_COMP_A_SDA")
	)
	(segment
		(start 217.6526 -118.2624)
		(end 217.6526 -119.01043)
		(width 0.17145)
		(layer "B.Cu")
		(net "I2C_BMC_A_COMP_A_SDA")
	)
	(segment
		(start 216.3953 -115.3795)
		(end 216.408 -115.3668)
		(width 0.17145)
		(layer "B.Cu")
		(net "I2C_BMC_A_COMP_A_SDA")
	)
	(segment
		(start 214.376 -120.8913)
		(end 214.376 -118.618)
		(width 0.17145)
		(layer "B.Cu")
		(net "I2C_BMC_A_COMP_A_SDA")
	)
	(segment
		(start 216.3953 -116.459)
		(end 216.3953 -117.0051)
		(width 0.17145)
		(layer "B.Cu")
		(net "I2C_BMC_A_COMP_A_SDA")
	)
	(segment
		(start 216.3953 -117.0051)
		(end 217.6526 -118.2624)
		(width 0.17145)
		(layer "B.Cu")
		(net "I2C_BMC_A_COMP_A_SDA")
	)
	(segment
		(start 216.535 -123.0503)
		(end 215.47455 -121.98985)
		(width 0.17145)
		(layer "B.Cu")
		(net "I2C_BMC_A_COMP_A_SDA")
	)
	(segment
		(start 216.281 -118.2624)
		(end 217.02903 -119.01043)
		(width 0.17145)
		(layer "B.Cu")
		(net "I2C_BMC_A_COMP_A_SDA")
	)
	(segment
		(start 214.376 -118.618)
		(end 214.7316 -118.2624)
		(width 0.17145)
		(layer "B.Cu")
		(net "I2C_BMC_A_COMP_A_SDA")
	)
	(segment
		(start 215.47455 -121.98985)
		(end 214.376 -120.8913)
		(width 0.17145)
		(layer "B.Cu")
		(net "I2C_BMC_A_COMP_A_SDA")
	)
	(segment
		(start 216.3953 -116.459)
		(end 216.3953 -115.3795)
		(width 0.17145)
		(layer "B.Cu")
		(net "I2C_BMC_A_COMP_A_SDA")
	)
	(segment
		(start 240.011712 -103.49992)
		(end 239.001046 -102.489254)
		(width 0.17145)
		(layer "F.Cu")
		(net "I2C_BMC_A_COMP_A_SCL")
	)
	(segment
		(start 220.476318 -111.17326)
		(end 218.3003 -113.349278)
		(width 0.17145)
		(layer "F.Cu")
		(net "I2C_BMC_A_COMP_A_SCL")
	)
	(segment
		(start 237.729522 -102.489254)
		(end 236.695488 -101.45522)
		(width 0.17145)
		(layer "F.Cu")
		(net "I2C_BMC_A_COMP_A_SCL")
	)
	(segment
		(start 218.3003 -113.349278)
		(end 218.3003 -114.5667)
		(width 0.17145)
		(layer "F.Cu")
		(net "I2C_BMC_A_COMP_A_SCL")
	)
	(segment
		(start 240.549938 -103.49992)
		(end 240.011712 -103.49992)
		(width 0.17145)
		(layer "F.Cu")
		(net "I2C_BMC_A_COMP_A_SCL")
	)
	(segment
		(start 239.001046 -102.489254)
		(end 237.729522 -102.489254)
		(width 0.17145)
		(layer "F.Cu")
		(net "I2C_BMC_A_COMP_A_SCL")
	)
	(segment
		(start 225.721164 -111.17326)
		(end 220.476318 -111.17326)
		(width 0.17145)
		(layer "F.Cu")
		(net "I2C_BMC_A_COMP_A_SCL")
	)
	(segment
		(start 235.439204 -101.45522)
		(end 225.721164 -111.17326)
		(width 0.17145)
		(layer "F.Cu")
		(net "I2C_BMC_A_COMP_A_SCL")
	)
	(segment
		(start 236.695488 -101.45522)
		(end 235.439204 -101.45522)
		(width 0.17145)
		(layer "F.Cu")
		(net "I2C_BMC_A_COMP_A_SCL")
	)
	(segment
		(start 218.3003 -114.5667)
		(end 218.948 -115.2144)
		(width 0.17145)
		(layer "F.Cu")
		(net "I2C_BMC_A_COMP_A_SCL")
	)
	(via
		(at 219.4306 -117.6274)
		(size 0.6096)
		(drill 0.3048)
		(layers "F.Cu" "B.Cu")
		(net "I2C_BMC_A_COMP_A_SCL")
	)
	(via
		(at 218.948 -115.2144)
		(size 0.5588)
		(drill 0.3048)
		(layers "F.Cu" "B.Cu")
		(net "I2C_BMC_A_COMP_A_SCL")
	)
	(segment
		(start 219.11437 -119.01043)
		(end 219.9894 -119.01043)
		(width 0.17145)
		(layer "B.Cu")
		(net "I2C_BMC_A_COMP_A_SCL")
	)
	(segment
		(start 219.2147 -116.4844)
		(end 219.2147 -115.4811)
		(width 0.17145)
		(layer "B.Cu")
		(net "I2C_BMC_A_COMP_A_SCL")
	)
	(segment
		(start 219.2147 -117.4115)
		(end 219.4306 -117.6274)
		(width 0.17145)
		(layer "B.Cu")
		(net "I2C_BMC_A_COMP_A_SCL")
	)
	(segment
		(start 219.4306 -117.6274)
		(end 219.9894 -118.1862)
		(width 0.17145)
		(layer "B.Cu")
		(net "I2C_BMC_A_COMP_A_SCL")
	)
	(segment
		(start 219.9894 -118.1862)
		(end 219.9894 -119.01043)
		(width 0.17145)
		(layer "B.Cu")
		(net "I2C_BMC_A_COMP_A_SCL")
	)
	(segment
		(start 218.9226 -119.2022)
		(end 219.11437 -119.01043)
		(width 0.17145)
		(layer "B.Cu")
		(net "I2C_BMC_A_COMP_A_SCL")
	)
	(segment
		(start 219.2147 -115.4811)
		(end 218.948 -115.2144)
		(width 0.17145)
		(layer "B.Cu")
		(net "I2C_BMC_A_COMP_A_SCL")
	)
	(segment
		(start 218.9226 -123.0249)
		(end 218.9226 -119.2022)
		(width 0.17145)
		(layer "B.Cu")
		(net "I2C_BMC_A_COMP_A_SCL")
	)
	(segment
		(start 219.2147 -116.4844)
		(end 219.2147 -117.4115)
		(width 0.17145)
		(layer "B.Cu")
		(net "I2C_BMC_A_COMP_A_SCL")
	)
	(segment
		(start 299.962062 -73.3044)
		(end 299.962062 -72.3392)
		(width 0.17145)
		(layer "F.Cu")
		(net "COMP_B_TO_BMC_B_RESET_N")
	)
	(segment
		(start 299.962062 -74.35469)
		(end 299.962062 -73.3044)
		(width 0.17145)
		(layer "F.Cu")
		(net "COMP_B_TO_BMC_B_RESET_N")
	)
	(via
		(at 299.962062 -73.3044)
		(size 0.6604)
		(drill 0.3302)
		(layers "F.Cu" "B.Cu")
		(net "COMP_B_TO_BMC_B_RESET_N")
	)
	(via
		(at 299.962062 -72.3392)
		(size 0.5588)
		(drill 0.3048)
		(layers "F.Cu" "B.Cu")
		(net "COMP_B_TO_BMC_B_RESET_N")
	)
	(via
		(at 349.081852 -74.3966)
		(size 0.5588)
		(drill 0.3048)
		(layers "F.Cu" "B.Cu")
		(net "COMP_B_TO_BMC_B_RESET_N")
	)
	(segment
		(start 349.081852 -74.3966)
		(end 348.948502 -74.52995)
		(width 0.13335)
		(layer "In2.Cu")
		(net "COMP_B_TO_BMC_B_RESET_N")
	)
	(segment
		(start 302.152812 -74.52995)
		(end 299.962062 -72.3392)
		(width 0.13335)
		(layer "In2.Cu")
		(net "COMP_B_TO_BMC_B_RESET_N")
	)
	(segment
		(start 348.948502 -74.52995)
		(end 302.152812 -74.52995)
		(width 0.13335)
		(layer "In2.Cu")
		(net "COMP_B_TO_BMC_B_RESET_N")
	)
	(segment
		(start 360.549952 -37.730176)
		(end 349.319342 -48.960786)
		(width 0.12065)
		(layer "In4.Cu")
		(net "COMP_B_TO_BMC_B_RESET_N")
	)
	(segment
		(start 360.549952 -30.550104)
		(end 360.549952 -37.730176)
		(width 0.12065)
		(layer "In4.Cu")
		(net "COMP_B_TO_BMC_B_RESET_N")
	)
	(segment
		(start 349.319342 -74.15911)
		(end 349.081852 -74.3966)
		(width 0.12065)
		(layer "In4.Cu")
		(net "COMP_B_TO_BMC_B_RESET_N")
	)
	(segment
		(start 349.319342 -48.960786)
		(end 349.319342 -74.15911)
		(width 0.12065)
		(layer "In4.Cu")
		(net "COMP_B_TO_BMC_B_RESET_N")
	)
	(segment
		(start 276.07006 -115.61826)
		(end 279.29586 -115.61826)
		(width 0.17145)
		(layer "F.Cu")
		(net "COMP_B_BMC_B_ALERT_N")
	)
	(segment
		(start 285.249874 -112.712246)
		(end 285.249874 -112.499902)
		(width 0.17145)
		(layer "F.Cu")
		(net "COMP_B_BMC_B_ALERT_N")
	)
	(segment
		(start 283.0576 -114.427)
		(end 283.53512 -114.427)
		(width 0.17145)
		(layer "F.Cu")
		(net "COMP_B_BMC_B_ALERT_N")
	)
	(segment
		(start 265.049 -113.4364)
		(end 266.154662 -113.4364)
		(width 0.17145)
		(layer "F.Cu")
		(net "COMP_B_BMC_B_ALERT_N")
	)
	(segment
		(start 272.7198 -112.268)
		(end 276.07006 -115.61826)
		(width 0.17145)
		(layer "F.Cu")
		(net "COMP_B_BMC_B_ALERT_N")
	)
	(segment
		(start 266.6365 -112.268)
		(end 272.7198 -112.268)
		(width 0.17145)
		(layer "F.Cu")
		(net "COMP_B_BMC_B_ALERT_N")
	)
	(segment
		(start 279.29586 -115.61826)
		(end 280.034746 -116.357146)
		(width 0.17145)
		(layer "F.Cu")
		(net "COMP_B_BMC_B_ALERT_N")
	)
	(segment
		(start 266.154662 -113.4364)
		(end 266.319 -113.4364)
		(width 0.17145)
		(layer "F.Cu")
		(net "COMP_B_BMC_B_ALERT_N")
	)
	(segment
		(start 266.319 -113.4364)
		(end 266.6365 -113.1189)
		(width 0.17145)
		(layer "F.Cu")
		(net "COMP_B_BMC_B_ALERT_N")
	)
	(segment
		(start 280.034746 -116.357146)
		(end 281.127454 -116.357146)
		(width 0.17145)
		(layer "F.Cu")
		(net "COMP_B_BMC_B_ALERT_N")
	)
	(segment
		(start 281.127454 -116.357146)
		(end 283.0576 -114.427)
		(width 0.17145)
		(layer "F.Cu")
		(net "COMP_B_BMC_B_ALERT_N")
	)
	(segment
		(start 283.53512 -114.427)
		(end 285.249874 -112.712246)
		(width 0.17145)
		(layer "F.Cu")
		(net "COMP_B_BMC_B_ALERT_N")
	)
	(segment
		(start 266.6365 -113.1189)
		(end 266.6365 -112.268)
		(width 0.17145)
		(layer "F.Cu")
		(net "COMP_B_BMC_B_ALERT_N")
	)
	(via
		(at 346.460318 -31.312358)
		(size 0.5588)
		(drill 0.3048)
		(layers "F.Cu" "B.Cu")
		(net "COMP_B_BMC_B_ALERT_N")
	)
	(via
		(at 265.049 -113.4364)
		(size 0.5588)
		(drill 0.3048)
		(layers "F.Cu" "B.Cu")
		(net "COMP_B_BMC_B_ALERT_N")
	)
	(via
		(at 265.052302 5.510784)
		(size 0.5588)
		(drill 0.3048)
		(layers "F.Cu" "B.Cu")
		(net "COMP_B_BMC_B_ALERT_N")
	)
	(via
		(at 266.154662 -113.4364)
		(size 0.6604)
		(drill 0.3302)
		(layers "F.Cu" "B.Cu")
		(net "COMP_B_BMC_B_ALERT_N")
	)
	(via
		(at 345.2749 -16.8529)
		(size 0.5588)
		(drill 0.3048)
		(layers "F.Cu" "B.Cu")
		(net "COMP_B_BMC_B_ALERT_N")
	)
	(segment
		(start 344.719148 -16.297148)
		(end 345.2749 -16.8529)
		(width 0.13335)
		(layer "In2.Cu")
		(net "COMP_B_BMC_B_ALERT_N")
	)
	(segment
		(start 367.09985 -27.600402)
		(end 367.09985 -33.692338)
		(width 0.13335)
		(layer "In2.Cu")
		(net "COMP_B_BMC_B_ALERT_N")
	)
	(segment
		(start 352.367596 -37.219636)
		(end 346.460318 -31.312358)
		(width 0.13335)
		(layer "In2.Cu")
		(net "COMP_B_BMC_B_ALERT_N")
	)
	(segment
		(start 357.830374 -37.219636)
		(end 352.367596 -37.219636)
		(width 0.13335)
		(layer "In2.Cu")
		(net "COMP_B_BMC_B_ALERT_N")
	)
	(segment
		(start 367.75009 -26.950162)
		(end 367.09985 -27.600402)
		(width 0.13335)
		(layer "In2.Cu")
		(net "COMP_B_BMC_B_ALERT_N")
	)
	(segment
		(start 334.616044 -16.34363)
		(end 334.662526 -16.297148)
		(width 0.13335)
		(layer "In2.Cu")
		(net "COMP_B_BMC_B_ALERT_N")
	)
	(segment
		(start 334.662526 -16.297148)
		(end 344.719148 -16.297148)
		(width 0.13335)
		(layer "In2.Cu")
		(net "COMP_B_BMC_B_ALERT_N")
	)
	(segment
		(start 334.240632 -16.719296)
		(end 334.616044 -16.343884)
		(width 0.13335)
		(layer "In2.Cu")
		(net "COMP_B_BMC_B_ALERT_N")
	)
	(segment
		(start 286.523938 5.359654)
		(end 296.601642 -4.71805)
		(width 0.13335)
		(layer "In2.Cu")
		(net "COMP_B_BMC_B_ALERT_N")
	)
	(segment
		(start 315.579252 -16.719296)
		(end 334.240632 -16.719296)
		(width 0.13335)
		(layer "In2.Cu")
		(net "COMP_B_BMC_B_ALERT_N")
	)
	(segment
		(start 314.141104 -10.246106)
		(end 314.141104 -15.281148)
		(width 0.13335)
		(layer "In2.Cu")
		(net "COMP_B_BMC_B_ALERT_N")
	)
	(segment
		(start 367.09985 -33.692338)
		(end 362.934758 -37.85743)
		(width 0.13335)
		(layer "In2.Cu")
		(net "COMP_B_BMC_B_ALERT_N")
	)
	(segment
		(start 358.468168 -37.85743)
		(end 357.830374 -37.219636)
		(width 0.13335)
		(layer "In2.Cu")
		(net "COMP_B_BMC_B_ALERT_N")
	)
	(segment
		(start 265.203432 5.359654)
		(end 286.523938 5.359654)
		(width 0.13335)
		(layer "In2.Cu")
		(net "COMP_B_BMC_B_ALERT_N")
	)
	(segment
		(start 334.616044 -16.343884)
		(end 334.616044 -16.34363)
		(width 0.13335)
		(layer "In2.Cu")
		(net "COMP_B_BMC_B_ALERT_N")
	)
	(segment
		(start 296.601642 -4.71805)
		(end 308.613048 -4.71805)
		(width 0.13335)
		(layer "In2.Cu")
		(net "COMP_B_BMC_B_ALERT_N")
	)
	(segment
		(start 308.613048 -4.71805)
		(end 314.141104 -10.246106)
		(width 0.13335)
		(layer "In2.Cu")
		(net "COMP_B_BMC_B_ALERT_N")
	)
	(segment
		(start 314.141104 -15.281148)
		(end 315.579252 -16.719296)
		(width 0.13335)
		(layer "In2.Cu")
		(net "COMP_B_BMC_B_ALERT_N")
	)
	(segment
		(start 362.934758 -37.85743)
		(end 358.468168 -37.85743)
		(width 0.13335)
		(layer "In2.Cu")
		(net "COMP_B_BMC_B_ALERT_N")
	)
	(segment
		(start 265.052302 5.510784)
		(end 265.203432 5.359654)
		(width 0.13335)
		(layer "In2.Cu")
		(net "COMP_B_BMC_B_ALERT_N")
	)
	(segment
		(start 265.7348 -109.183932)
		(end 264.033 -107.482132)
		(width 0.12065)
		(layer "In4.Cu")
		(net "COMP_B_BMC_B_ALERT_N")
	)
	(segment
		(start 346.394532 -17.972532)
		(end 346.394532 -31.246572)
		(width 0.12065)
		(layer "In4.Cu")
		(net "COMP_B_BMC_B_ALERT_N")
	)
	(segment
		(start 268.59992 -36.341812)
		(end 268.59992 -20.557236)
		(width 0.12065)
		(layer "In4.Cu")
		(net "COMP_B_BMC_B_ALERT_N")
	)
	(segment
		(start 268.59992 -20.557236)
		(end 265.655044 -17.61236)
		(width 0.12065)
		(layer "In4.Cu")
		(net "COMP_B_BMC_B_ALERT_N")
	)
	(segment
		(start 264.033 -40.908732)
		(end 268.59992 -36.341812)
		(width 0.12065)
		(layer "In4.Cu")
		(net "COMP_B_BMC_B_ALERT_N")
	)
	(segment
		(start 265.655044 -17.61236)
		(end 265.655044 4.908042)
		(width 0.12065)
		(layer "In4.Cu")
		(net "COMP_B_BMC_B_ALERT_N")
	)
	(segment
		(start 265.049 -113.4364)
		(end 265.7348 -112.7506)
		(width 0.12065)
		(layer "In4.Cu")
		(net "COMP_B_BMC_B_ALERT_N")
	)
	(segment
		(start 265.7348 -112.7506)
		(end 265.7348 -109.183932)
		(width 0.12065)
		(layer "In4.Cu")
		(net "COMP_B_BMC_B_ALERT_N")
	)
	(segment
		(start 264.033 -107.482132)
		(end 264.033 -40.908732)
		(width 0.12065)
		(layer "In4.Cu")
		(net "COMP_B_BMC_B_ALERT_N")
	)
	(segment
		(start 265.655044 4.908042)
		(end 265.052302 5.510784)
		(width 0.12065)
		(layer "In4.Cu")
		(net "COMP_B_BMC_B_ALERT_N")
	)
	(segment
		(start 345.2749 -16.8529)
		(end 346.394532 -17.972532)
		(width 0.12065)
		(layer "In4.Cu")
		(net "COMP_B_BMC_B_ALERT_N")
	)
	(segment
		(start 346.394532 -31.246572)
		(end 346.460318 -31.312358)
		(width 0.12065)
		(layer "In4.Cu")
		(net "COMP_B_BMC_B_ALERT_N")
	)
	(segment
		(start 222.174816 -116.728748)
		(end 221.046802 -116.728748)
		(width 0.17145)
		(layer "F.Cu")
		(net "COMP_A_TO_BMC_A_RESET_N")
	)
	(segment
		(start 221.046802 -116.728748)
		(end 220.034612 -116.728748)
		(width 0.17145)
		(layer "F.Cu")
		(net "COMP_A_TO_BMC_A_RESET_N")
	)
	(via
		(at 114.427 -116.728748)
		(size 0.5588)
		(drill 0.3048)
		(layers "F.Cu" "B.Cu")
		(net "COMP_A_TO_BMC_A_RESET_N")
	)
	(via
		(at 221.046802 -116.728748)
		(size 0.6604)
		(drill 0.3302)
		(layers "F.Cu" "B.Cu")
		(net "COMP_A_TO_BMC_A_RESET_N")
	)
	(via
		(at 220.034612 -116.728748)
		(size 0.5588)
		(drill 0.3048)
		(layers "F.Cu" "B.Cu")
		(net "COMP_A_TO_BMC_A_RESET_N")
	)
	(segment
		(start 212.81771 -116.04879)
		(end 115.106958 -116.04879)
		(width 0.13335)
		(layer "In2.Cu")
		(net "COMP_A_TO_BMC_A_RESET_N")
	)
	(segment
		(start 115.106958 -116.04879)
		(end 114.427 -116.728748)
		(width 0.13335)
		(layer "In2.Cu")
		(net "COMP_A_TO_BMC_A_RESET_N")
	)
	(segment
		(start 213.497668 -116.728748)
		(end 212.81771 -116.04879)
		(width 0.13335)
		(layer "In2.Cu")
		(net "COMP_A_TO_BMC_A_RESET_N")
	)
	(segment
		(start 220.034612 -116.728748)
		(end 213.497668 -116.728748)
		(width 0.13335)
		(layer "In2.Cu")
		(net "COMP_A_TO_BMC_A_RESET_N")
	)
	(segment
		(start 106.143298 -82.386424)
		(end 114.38255 -90.625676)
		(width 0.12065)
		(layer "In4.Cu")
		(net "COMP_A_TO_BMC_A_RESET_N")
	)
	(segment
		(start 106.143298 -45.418502)
		(end 106.143298 -82.386424)
		(width 0.12065)
		(layer "In4.Cu")
		(net "COMP_A_TO_BMC_A_RESET_N")
	)
	(segment
		(start 114.38255 -107.172252)
		(end 114.427 -107.216702)
		(width 0.12065)
		(layer "In4.Cu")
		(net "COMP_A_TO_BMC_A_RESET_N")
	)
	(segment
		(start 114.427 -107.216702)
		(end 114.427 -116.728748)
		(width 0.12065)
		(layer "In4.Cu")
		(net "COMP_A_TO_BMC_A_RESET_N")
	)
	(segment
		(start 113.947194 -37.614606)
		(end 106.143298 -45.418502)
		(width 0.12065)
		(layer "In4.Cu")
		(net "COMP_A_TO_BMC_A_RESET_N")
	)
	(segment
		(start 114.549936 -30.550104)
		(end 113.947194 -31.152846)
		(width 0.12065)
		(layer "In4.Cu")
		(net "COMP_A_TO_BMC_A_RESET_N")
	)
	(segment
		(start 113.947194 -31.152846)
		(end 113.947194 -37.614606)
		(width 0.12065)
		(layer "In4.Cu")
		(net "COMP_A_TO_BMC_A_RESET_N")
	)
	(segment
		(start 114.38255 -90.625676)
		(end 114.38255 -107.172252)
		(width 0.12065)
		(layer "In4.Cu")
		(net "COMP_A_TO_BMC_A_RESET_N")
	)
	(segment
		(start 233.543348 -111.642652)
		(end 237.434374 -111.642652)
		(width 0.17145)
		(layer "F.Cu")
		(net "COMP_A_BMC_A_ALERT_N")
	)
	(segment
		(start 237.434374 -111.642652)
		(end 238.599472 -112.80775)
		(width 0.17145)
		(layer "F.Cu")
		(net "COMP_A_BMC_A_ALERT_N")
	)
	(segment
		(start 238.599472 -112.80775)
		(end 240.029746 -112.80775)
		(width 0.17145)
		(layer "F.Cu")
		(net "COMP_A_BMC_A_ALERT_N")
	)
	(segment
		(start 223.0755 -119.6594)
		(end 225.5266 -119.6594)
		(width 0.17145)
		(layer "F.Cu")
		(net "COMP_A_BMC_A_ALERT_N")
	)
	(segment
		(start 240.337594 -112.499902)
		(end 242.549934 -112.499902)
		(width 0.17145)
		(layer "F.Cu")
		(net "COMP_A_BMC_A_ALERT_N")
	)
	(segment
		(start 240.029746 -112.80775)
		(end 240.337594 -112.499902)
		(width 0.17145)
		(layer "F.Cu")
		(net "COMP_A_BMC_A_ALERT_N")
	)
	(segment
		(start 225.5266 -119.6594)
		(end 233.543348 -111.642652)
		(width 0.17145)
		(layer "F.Cu")
		(net "COMP_A_BMC_A_ALERT_N")
	)
	(via
		(at 122.309382 -122.14225)
		(size 0.5588)
		(drill 0.3048)
		(layers "F.Cu" "B.Cu")
		(net "COMP_A_BMC_A_ALERT_N")
	)
	(segment
		(start 232.259378 -116.762022)
		(end 223.12249 -125.89891)
		(width 0.13335)
		(layer "In2.Cu")
		(net "COMP_A_BMC_A_ALERT_N")
	)
	(segment
		(start 240.059718 -112.786668)
		(end 238.589566 -112.786668)
		(width 0.13335)
		(layer "In2.Cu")
		(net "COMP_A_BMC_A_ALERT_N")
	)
	(segment
		(start 235.571792 -111.649002)
		(end 232.259378 -114.961416)
		(width 0.13335)
		(layer "In2.Cu")
		(net "COMP_A_BMC_A_ALERT_N")
	)
	(segment
		(start 232.259378 -114.961416)
		(end 232.259378 -116.762022)
		(width 0.13335)
		(layer "In2.Cu")
		(net "COMP_A_BMC_A_ALERT_N")
	)
	(segment
		(start 223.12249 -125.89891)
		(end 126.066042 -125.89891)
		(width 0.13335)
		(layer "In2.Cu")
		(net "COMP_A_BMC_A_ALERT_N")
	)
	(segment
		(start 126.066042 -125.89891)
		(end 122.309382 -122.14225)
		(width 0.13335)
		(layer "In2.Cu")
		(net "COMP_A_BMC_A_ALERT_N")
	)
	(segment
		(start 242.549934 -112.499902)
		(end 240.346484 -112.499902)
		(width 0.13335)
		(layer "In2.Cu")
		(net "COMP_A_BMC_A_ALERT_N")
	)
	(segment
		(start 237.4519 -111.649002)
		(end 235.571792 -111.649002)
		(width 0.13335)
		(layer "In2.Cu")
		(net "COMP_A_BMC_A_ALERT_N")
	)
	(segment
		(start 240.346484 -112.499902)
		(end 240.059718 -112.786668)
		(width 0.13335)
		(layer "In2.Cu")
		(net "COMP_A_BMC_A_ALERT_N")
	)
	(segment
		(start 238.589566 -112.786668)
		(end 237.4519 -111.649002)
		(width 0.13335)
		(layer "In2.Cu")
		(net "COMP_A_BMC_A_ALERT_N")
	)
	(segment
		(start 120.9294 -35.143948)
		(end 120.347232 -35.726116)
		(width 0.12065)
		(layer "In4.Cu")
		(net "COMP_A_BMC_A_ALERT_N")
	)
	(segment
		(start 113.795048 -62.982856)
		(end 112.864138 -63.913766)
		(width 0.12065)
		(layer "In4.Cu")
		(net "COMP_A_BMC_A_ALERT_N")
	)
	(segment
		(start 112.864138 -63.913766)
		(end 112.864138 -78.980538)
		(width 0.12065)
		(layer "In4.Cu")
		(net "COMP_A_BMC_A_ALERT_N")
	)
	(segment
		(start 122.309382 -88.425782)
		(end 122.309382 -122.14225)
		(width 0.12065)
		(layer "In4.Cu")
		(net "COMP_A_BMC_A_ALERT_N")
	)
	(segment
		(start 120.347232 -35.726116)
		(end 120.347232 -38.656768)
		(width 0.12065)
		(layer "In4.Cu")
		(net "COMP_A_BMC_A_ALERT_N")
	)
	(segment
		(start 120.9294 -27.770836)
		(end 120.9294 -35.143948)
		(width 0.12065)
		(layer "In4.Cu")
		(net "COMP_A_BMC_A_ALERT_N")
	)
	(segment
		(start 113.795048 -59.399932)
		(end 113.795048 -62.982856)
		(width 0.12065)
		(layer "In4.Cu")
		(net "COMP_A_BMC_A_ALERT_N")
	)
	(segment
		(start 121.750074 -26.950162)
		(end 120.9294 -27.770836)
		(width 0.12065)
		(layer "In4.Cu")
		(net "COMP_A_BMC_A_ALERT_N")
	)
	(segment
		(start 112.864138 -46.139862)
		(end 112.864138 -58.469022)
		(width 0.12065)
		(layer "In4.Cu")
		(net "COMP_A_BMC_A_ALERT_N")
	)
	(segment
		(start 112.864138 -58.469022)
		(end 113.795048 -59.399932)
		(width 0.12065)
		(layer "In4.Cu")
		(net "COMP_A_BMC_A_ALERT_N")
	)
	(segment
		(start 120.347232 -38.656768)
		(end 112.864138 -46.139862)
		(width 0.12065)
		(layer "In4.Cu")
		(net "COMP_A_BMC_A_ALERT_N")
	)
	(segment
		(start 112.864138 -78.980538)
		(end 122.309382 -88.425782)
		(width 0.12065)
		(layer "In4.Cu")
		(net "COMP_A_BMC_A_ALERT_N")
	)
	(segment
		(start 312.173874 -59.90844)
		(end 313.4106 -59.90844)
		(width 0.17145)
		(layer "F.Cu")
		(net "SYS_B_RESET_BUFFER_N")
	)
	(segment
		(start 312.0644 -60.017914)
		(end 312.173874 -59.90844)
		(width 0.17145)
		(layer "F.Cu")
		(net "SYS_B_RESET_BUFFER_N")
	)
	(segment
		(start 311.13984 -60.017914)
		(end 312.0644 -60.017914)
		(width 0.17145)
		(layer "F.Cu")
		(net "SYS_B_RESET_BUFFER_N")
	)
	(segment
		(start 310.7944 -61.239654)
		(end 309.870348 -62.163706)
		(width 0.17145)
		(layer "F.Cu")
		(net "SYS_B_RESET_BUFFER_N")
	)
	(segment
		(start 311.152032 -60.881768)
		(end 310.7944 -61.2394)
		(width 0.17145)
		(layer "F.Cu")
		(net "SYS_B_RESET_BUFFER_N")
	)
	(segment
		(start 310.7944 -61.2394)
		(end 310.7944 -61.239654)
		(width 0.17145)
		(layer "F.Cu")
		(net "SYS_B_RESET_BUFFER_N")
	)
	(segment
		(start 311.152032 -60.030106)
		(end 311.152032 -60.881768)
		(width 0.17145)
		(layer "F.Cu")
		(net "SYS_B_RESET_BUFFER_N")
	)
	(segment
		(start 311.13984 -60.017914)
		(end 311.152032 -60.030106)
		(width 0.17145)
		(layer "F.Cu")
		(net "SYS_B_RESET_BUFFER_N")
	)
	(via
		(at 310.7944 -61.2394)
		(size 0.6604)
		(drill 0.3302)
		(layers "F.Cu" "B.Cu")
		(net "SYS_B_RESET_BUFFER_N")
	)
	(via
		(at 309.870348 -62.163706)
		(size 0.5588)
		(drill 0.3048)
		(layers "F.Cu" "B.Cu")
		(net "SYS_B_RESET_BUFFER_N")
	)
	(via
		(at 311.41543 -109.499908)
		(size 0.5588)
		(drill 0.3048)
		(layers "F.Cu" "B.Cu")
		(net "SYS_B_RESET_BUFFER_N")
	)
	(segment
		(start 311.41543 -109.499908)
		(end 283.249878 -109.499908)
		(width 0.13335)
		(layer "In2.Cu")
		(net "SYS_B_RESET_BUFFER_N")
	)
	(segment
		(start 311.41543 -109.499908)
		(end 311.41543 -100.629974)
		(width 0.12065)
		(layer "In4.Cu")
		(net "SYS_B_RESET_BUFFER_N")
	)
	(segment
		(start 307.628036 -64.406018)
		(end 309.870348 -62.163706)
		(width 0.12065)
		(layer "In4.Cu")
		(net "SYS_B_RESET_BUFFER_N")
	)
	(segment
		(start 307.628036 -96.84258)
		(end 307.628036 -64.406018)
		(width 0.12065)
		(layer "In4.Cu")
		(net "SYS_B_RESET_BUFFER_N")
	)
	(segment
		(start 311.41543 -100.629974)
		(end 307.628036 -96.84258)
		(width 0.12065)
		(layer "In4.Cu")
		(net "SYS_B_RESET_BUFFER_N")
	)
	(segment
		(start 175.464978 -27.240738)
		(end 175.464978 -26.237692)
		(width 0.17145)
		(layer "F.Cu")
		(net "SYS_A_RESET_BUFFER_N")
	)
	(segment
		(start 173.342808 -26.240232)
		(end 173.342808 -27.3431)
		(width 0.17145)
		(layer "F.Cu")
		(net "SYS_A_RESET_BUFFER_N")
	)
	(segment
		(start 175.11776 -25.890474)
		(end 174.170594 -25.890474)
		(width 0.17145)
		(layer "F.Cu")
		(net "SYS_A_RESET_BUFFER_N")
	)
	(segment
		(start 174.170594 -25.890474)
		(end 173.692566 -25.890474)
		(width 0.17145)
		(layer "F.Cu")
		(net "SYS_A_RESET_BUFFER_N")
	)
	(segment
		(start 173.692566 -25.890474)
		(end 173.342808 -26.240232)
		(width 0.17145)
		(layer "F.Cu")
		(net "SYS_A_RESET_BUFFER_N")
	)
	(segment
		(start 175.464978 -26.237692)
		(end 175.11776 -25.890474)
		(width 0.17145)
		(layer "F.Cu")
		(net "SYS_A_RESET_BUFFER_N")
	)
	(via
		(at 179.158392 -121.51995)
		(size 0.5588)
		(drill 0.3048)
		(layers "F.Cu" "B.Cu")
		(net "SYS_A_RESET_BUFFER_N")
	)
	(via
		(at 175.464978 -26.237692)
		(size 0.5588)
		(drill 0.3048)
		(layers "F.Cu" "B.Cu")
		(net "SYS_A_RESET_BUFFER_N")
	)
	(via
		(at 174.170594 -25.890474)
		(size 0.6604)
		(drill 0.3302)
		(layers "F.Cu" "B.Cu")
		(net "SYS_A_RESET_BUFFER_N")
	)
	(segment
		(start 236.961426 -109.147356)
		(end 237.19917 -109.147356)
		(width 0.13335)
		(layer "In2.Cu")
		(net "SYS_A_RESET_BUFFER_N")
	)
	(segment
		(start 238.054896 -108.649008)
		(end 238.069882 -108.634022)
		(width 0.13335)
		(layer "In2.Cu")
		(net "SYS_A_RESET_BUFFER_N")
	)
	(segment
		(start 240.505996 -109.499908)
		(end 240.549938 -109.499908)
		(width 0.13335)
		(layer "In2.Cu")
		(net "SYS_A_RESET_BUFFER_N")
	)
	(segment
		(start 222.84944 -125.25756)
		(end 231.618028 -116.488972)
		(width 0.13335)
		(layer "In2.Cu")
		(net "SYS_A_RESET_BUFFER_N")
	)
	(segment
		(start 182.896002 -125.25756)
		(end 222.84944 -125.25756)
		(width 0.13335)
		(layer "In2.Cu")
		(net "SYS_A_RESET_BUFFER_N")
	)
	(segment
		(start 235.28655 -111.059722)
		(end 235.28655 -110.822232)
		(width 0.13335)
		(layer "In2.Cu")
		(net "SYS_A_RESET_BUFFER_N")
	)
	(segment
		(start 235.28655 -110.822232)
		(end 236.961426 -109.147356)
		(width 0.13335)
		(layer "In2.Cu")
		(net "SYS_A_RESET_BUFFER_N")
	)
	(segment
		(start 237.19917 -109.147356)
		(end 237.697518 -108.649008)
		(width 0.13335)
		(layer "In2.Cu")
		(net "SYS_A_RESET_BUFFER_N")
	)
	(segment
		(start 238.069882 -108.634022)
		(end 239.64011 -108.634022)
		(width 0.13335)
		(layer "In2.Cu")
		(net "SYS_A_RESET_BUFFER_N")
	)
	(segment
		(start 231.618028 -116.488972)
		(end 231.618028 -114.695732)
		(width 0.13335)
		(layer "In2.Cu")
		(net "SYS_A_RESET_BUFFER_N")
	)
	(segment
		(start 235.254038 -111.059722)
		(end 235.28655 -111.059722)
		(width 0.13335)
		(layer "In2.Cu")
		(net "SYS_A_RESET_BUFFER_N")
	)
	(segment
		(start 239.64011 -108.634022)
		(end 240.505996 -109.499908)
		(width 0.13335)
		(layer "In2.Cu")
		(net "SYS_A_RESET_BUFFER_N")
	)
	(segment
		(start 231.618028 -114.695732)
		(end 235.254038 -111.059722)
		(width 0.13335)
		(layer "In2.Cu")
		(net "SYS_A_RESET_BUFFER_N")
	)
	(segment
		(start 179.158392 -121.51995)
		(end 182.896002 -125.25756)
		(width 0.13335)
		(layer "In2.Cu")
		(net "SYS_A_RESET_BUFFER_N")
	)
	(segment
		(start 237.697518 -108.649008)
		(end 238.054896 -108.649008)
		(width 0.13335)
		(layer "In2.Cu")
		(net "SYS_A_RESET_BUFFER_N")
	)
	(segment
		(start 176.969166 -79.08798)
		(end 176.969166 -53.988208)
		(width 0.12065)
		(layer "In4.Cu")
		(net "SYS_A_RESET_BUFFER_N")
	)
	(segment
		(start 179.171346 -121.506996)
		(end 179.171346 -81.29016)
		(width 0.12065)
		(layer "In4.Cu")
		(net "SYS_A_RESET_BUFFER_N")
	)
	(segment
		(start 175.889158 -52.9082)
		(end 175.889158 -26.661872)
		(width 0.12065)
		(layer "In4.Cu")
		(net "SYS_A_RESET_BUFFER_N")
	)
	(segment
		(start 175.889158 -26.661872)
		(end 175.464978 -26.237692)
		(width 0.12065)
		(layer "In4.Cu")
		(net "SYS_A_RESET_BUFFER_N")
	)
	(segment
		(start 179.171346 -81.29016)
		(end 176.969166 -79.08798)
		(width 0.12065)
		(layer "In4.Cu")
		(net "SYS_A_RESET_BUFFER_N")
	)
	(segment
		(start 179.158392 -121.51995)
		(end 179.171346 -121.506996)
		(width 0.12065)
		(layer "In4.Cu")
		(net "SYS_A_RESET_BUFFER_N")
	)
	(segment
		(start 176.969166 -53.988208)
		(end 175.889158 -52.9082)
		(width 0.12065)
		(layer "In4.Cu")
		(net "SYS_A_RESET_BUFFER_N")
	)
	(segment
		(start 341.16518 -32.765238)
		(end 341.16518 -31.800038)
		(width 0.254)
		(layer "F.Cu")
		(net "SCC_B_STBY_PGOOD")
	)
	(segment
		(start 341.150448 -32.765238)
		(end 341.16518 -32.765238)
		(width 0.254)
		(layer "F.Cu")
		(net "SCC_B_STBY_PGOOD")
	)
	(segment
		(start 340.604094 -31.238952)
		(end 341.16518 -31.800038)
		(width 0.254)
		(layer "F.Cu")
		(net "SCC_B_STBY_PGOOD")
	)
	(segment
		(start 340.604094 -30.05709)
		(end 340.604094 -31.238952)
		(width 0.254)
		(layer "F.Cu")
		(net "SCC_B_STBY_PGOOD")
	)
	(via
		(at 341.150448 -32.765238)
		(size 0.5588)
		(drill 0.3048)
		(layers "F.Cu" "B.Cu")
		(net "SCC_B_STBY_PGOOD")
	)
	(via
		(at 242.01628 -195.457572)
		(size 0.5588)
		(drill 0.3048)
		(layers "F.Cu" "B.Cu")
		(net "SCC_B_STBY_PGOOD")
	)
	(via
		(at 341.16518 -31.800038)
		(size 0.6604)
		(drill 0.3302)
		(layers "F.Cu" "B.Cu")
		(net "SCC_B_STBY_PGOOD")
	)
	(via
		(at 332.867 -196.7738)
		(size 0.5588)
		(drill 0.3048)
		(layers "F.Cu" "B.Cu")
		(net "SCC_B_STBY_PGOOD")
	)
	(segment
		(start 315.595508 -201.72426)
		(end 248.282968 -201.72426)
		(width 0.254)
		(layer "In2.Cu")
		(net "SCC_B_STBY_PGOOD")
	)
	(segment
		(start 332.372208 -197.268592)
		(end 320.051176 -197.268592)
		(width 0.254)
		(layer "In2.Cu")
		(net "SCC_B_STBY_PGOOD")
	)
	(segment
		(start 320.051176 -197.268592)
		(end 315.595508 -201.72426)
		(width 0.254)
		(layer "In2.Cu")
		(net "SCC_B_STBY_PGOOD")
	)
	(segment
		(start 332.867 -196.7738)
		(end 332.372208 -197.268592)
		(width 0.254)
		(layer "In2.Cu")
		(net "SCC_B_STBY_PGOOD")
	)
	(segment
		(start 248.282968 -201.72426)
		(end 242.01628 -195.457572)
		(width 0.254)
		(layer "In2.Cu")
		(net "SCC_B_STBY_PGOOD")
	)
	(segment
		(start 213.980268 -385.362958)
		(end 213.980268 -324.71614)
		(width 0.254)
		(layer "In4.Cu")
		(net "SCC_B_STBY_PGOOD")
	)
	(segment
		(start 223.5835 -215.3285)
		(end 223.5835 -209.0547)
		(width 0.254)
		(layer "In4.Cu")
		(net "SCC_B_STBY_PGOOD")
	)
	(segment
		(start 220.370654 -218.541346)
		(end 223.5835 -215.3285)
		(width 0.254)
		(layer "In4.Cu")
		(net "SCC_B_STBY_PGOOD")
	)
	(segment
		(start 241.792252 -195.6816)
		(end 242.01628 -195.457572)
		(width 0.254)
		(layer "In4.Cu")
		(net "SCC_B_STBY_PGOOD")
	)
	(segment
		(start 324.414134 -178.084734)
		(end 332.867 -186.5376)
		(width 0.254)
		(layer "In4.Cu")
		(net "SCC_B_STBY_PGOOD")
	)
	(segment
		(start 339.60816 -75.277472)
		(end 341.156544 -76.825856)
		(width 0.254)
		(layer "In4.Cu")
		(net "SCC_B_STBY_PGOOD")
	)
	(segment
		(start 214.39886 -385.78155)
		(end 213.980268 -385.362958)
		(width 0.254)
		(layer "In4.Cu")
		(net "SCC_B_STBY_PGOOD")
	)
	(segment
		(start 226.200208 -419.200076)
		(end 223.347534 -416.347402)
		(width 0.254)
		(layer "In4.Cu")
		(net "SCC_B_STBY_PGOOD")
	)
	(segment
		(start 341.150448 -32.765238)
		(end 341.150448 -37.131752)
		(width 0.254)
		(layer "In4.Cu")
		(net "SCC_B_STBY_PGOOD")
	)
	(segment
		(start 332.867 -186.5376)
		(end 332.867 -196.7738)
		(width 0.254)
		(layer "In4.Cu")
		(net "SCC_B_STBY_PGOOD")
	)
	(segment
		(start 223.347534 -404.098506)
		(end 214.39886 -395.149832)
		(width 0.254)
		(layer "In4.Cu")
		(net "SCC_B_STBY_PGOOD")
	)
	(segment
		(start 323.394324 -170.993562)
		(end 324.414134 -172.013372)
		(width 0.254)
		(layer "In4.Cu")
		(net "SCC_B_STBY_PGOOD")
	)
	(segment
		(start 236.9566 -195.6816)
		(end 241.792252 -195.6816)
		(width 0.254)
		(layer "In4.Cu")
		(net "SCC_B_STBY_PGOOD")
	)
	(segment
		(start 220.370654 -318.325754)
		(end 220.370654 -218.541346)
		(width 0.254)
		(layer "In4.Cu")
		(net "SCC_B_STBY_PGOOD")
	)
	(segment
		(start 341.150448 -37.131752)
		(end 339.60816 -38.67404)
		(width 0.254)
		(layer "In4.Cu")
		(net "SCC_B_STBY_PGOOD")
	)
	(segment
		(start 326.424798 -120.705372)
		(end 326.424798 -147.481544)
		(width 0.254)
		(layer "In4.Cu")
		(net "SCC_B_STBY_PGOOD")
	)
	(segment
		(start 223.347534 -416.347402)
		(end 223.347534 -404.098506)
		(width 0.254)
		(layer "In4.Cu")
		(net "SCC_B_STBY_PGOOD")
	)
	(segment
		(start 341.156544 -105.973626)
		(end 326.424798 -120.705372)
		(width 0.254)
		(layer "In4.Cu")
		(net "SCC_B_STBY_PGOOD")
	)
	(segment
		(start 326.424798 -147.481544)
		(end 323.394324 -150.512018)
		(width 0.254)
		(layer "In4.Cu")
		(net "SCC_B_STBY_PGOOD")
	)
	(segment
		(start 223.5835 -209.0547)
		(end 236.9566 -195.6816)
		(width 0.254)
		(layer "In4.Cu")
		(net "SCC_B_STBY_PGOOD")
	)
	(segment
		(start 324.414134 -172.013372)
		(end 324.414134 -178.084734)
		(width 0.254)
		(layer "In4.Cu")
		(net "SCC_B_STBY_PGOOD")
	)
	(segment
		(start 339.60816 -38.67404)
		(end 339.60816 -75.277472)
		(width 0.254)
		(layer "In4.Cu")
		(net "SCC_B_STBY_PGOOD")
	)
	(segment
		(start 341.156544 -76.825856)
		(end 341.156544 -105.973626)
		(width 0.254)
		(layer "In4.Cu")
		(net "SCC_B_STBY_PGOOD")
	)
	(segment
		(start 213.980268 -324.71614)
		(end 220.370654 -318.325754)
		(width 0.254)
		(layer "In4.Cu")
		(net "SCC_B_STBY_PGOOD")
	)
	(segment
		(start 214.39886 -395.149832)
		(end 214.39886 -385.78155)
		(width 0.254)
		(layer "In4.Cu")
		(net "SCC_B_STBY_PGOOD")
	)
	(segment
		(start 323.394324 -150.512018)
		(end 323.394324 -170.993562)
		(width 0.254)
		(layer "In4.Cu")
		(net "SCC_B_STBY_PGOOD")
	)
	(segment
		(start 87.061294 -27.86761)
		(end 87.061294 -29.174694)
		(width 0.254)
		(layer "F.Cu")
		(net "SCC_A_STBY_PGOOD")
	)
	(via
		(at 87.061294 -29.174694)
		(size 0.5588)
		(drill 0.3048)
		(layers "F.Cu" "B.Cu")
		(net "SCC_A_STBY_PGOOD")
	)
	(via
		(at 73.53554 -340.933786)
		(size 0.5588)
		(drill 0.3048)
		(layers "F.Cu" "B.Cu")
		(net "SCC_A_STBY_PGOOD")
	)
	(segment
		(start 139.579604 -341.890604)
		(end 131.959604 -341.890604)
		(width 0.254)
		(layer "In2.Cu")
		(net "SCC_A_STBY_PGOOD")
	)
	(segment
		(start 270.11884 -358.58704)
		(end 260.4516 -348.9198)
		(width 0.254)
		(layer "In2.Cu")
		(net "SCC_A_STBY_PGOOD")
	)
	(segment
		(start 234.4166 -346.8116)
		(end 224.8662 -346.8116)
		(width 0.254)
		(layer "In2.Cu")
		(net "SCC_A_STBY_PGOOD")
	)
	(segment
		(start 131.002786 -340.933786)
		(end 73.53554 -340.933786)
		(width 0.254)
		(layer "In2.Cu")
		(net "SCC_A_STBY_PGOOD")
	)
	(segment
		(start 224.8662 -346.8116)
		(end 223.3422 -345.2876)
		(width 0.254)
		(layer "In2.Cu")
		(net "SCC_A_STBY_PGOOD")
	)
	(segment
		(start 209.51444 -340.058502)
		(end 168.84777 -340.058502)
		(width 0.254)
		(layer "In2.Cu")
		(net "SCC_A_STBY_PGOOD")
	)
	(segment
		(start 283.35478 -358.58704)
		(end 270.11884 -358.58704)
		(width 0.254)
		(layer "In2.Cu")
		(net "SCC_A_STBY_PGOOD")
	)
	(segment
		(start 214.743538 -345.2876)
		(end 209.51444 -340.058502)
		(width 0.254)
		(layer "In2.Cu")
		(net "SCC_A_STBY_PGOOD")
	)
	(segment
		(start 131.959604 -341.890604)
		(end 131.002786 -340.933786)
		(width 0.254)
		(layer "In2.Cu")
		(net "SCC_A_STBY_PGOOD")
	)
	(segment
		(start 236.5248 -348.9198)
		(end 234.4166 -346.8116)
		(width 0.254)
		(layer "In2.Cu")
		(net "SCC_A_STBY_PGOOD")
	)
	(segment
		(start 260.4516 -348.9198)
		(end 236.5248 -348.9198)
		(width 0.254)
		(layer "In2.Cu")
		(net "SCC_A_STBY_PGOOD")
	)
	(segment
		(start 223.3422 -345.2876)
		(end 214.743538 -345.2876)
		(width 0.254)
		(layer "In2.Cu")
		(net "SCC_A_STBY_PGOOD")
	)
	(segment
		(start 165.879272 -343.027)
		(end 140.716 -343.027)
		(width 0.254)
		(layer "In2.Cu")
		(net "SCC_A_STBY_PGOOD")
	)
	(segment
		(start 168.84777 -340.058502)
		(end 165.879272 -343.027)
		(width 0.254)
		(layer "In2.Cu")
		(net "SCC_A_STBY_PGOOD")
	)
	(segment
		(start 284.236668 -357.705152)
		(end 283.35478 -358.58704)
		(width 0.254)
		(layer "In2.Cu")
		(net "SCC_A_STBY_PGOOD")
	)
	(segment
		(start 140.716 -343.027)
		(end 139.579604 -341.890604)
		(width 0.254)
		(layer "In2.Cu")
		(net "SCC_A_STBY_PGOOD")
	)
	(segment
		(start 73.637648 -305.54041)
		(end 73.637648 -191.479678)
		(width 0.254)
		(layer "In4.Cu")
		(net "SCC_A_STBY_PGOOD")
	)
	(segment
		(start 75.08367 -160.627568)
		(end 79.623158 -156.08808)
		(width 0.254)
		(layer "In4.Cu")
		(net "SCC_A_STBY_PGOOD")
	)
	(segment
		(start 70.525386 -54.577234)
		(end 70.5358 -54.56682)
		(width 0.254)
		(layer "In4.Cu")
		(net "SCC_A_STBY_PGOOD")
	)
	(segment
		(start 73.637648 -191.479678)
		(end 75.08367 -190.033656)
		(width 0.254)
		(layer "In4.Cu")
		(net "SCC_A_STBY_PGOOD")
	)
	(segment
		(start 75.08367 -190.033656)
		(end 75.08367 -160.627568)
		(width 0.254)
		(layer "In4.Cu")
		(net "SCC_A_STBY_PGOOD")
	)
	(segment
		(start 87.24519 -37.75583)
		(end 87.24519 -30.818836)
		(width 0.254)
		(layer "In4.Cu")
		(net "SCC_A_STBY_PGOOD")
	)
	(segment
		(start 79.623158 -141.44879)
		(end 70.525386 -132.351018)
		(width 0.254)
		(layer "In4.Cu")
		(net "SCC_A_STBY_PGOOD")
	)
	(segment
		(start 79.623158 -156.08808)
		(end 79.623158 -141.44879)
		(width 0.254)
		(layer "In4.Cu")
		(net "SCC_A_STBY_PGOOD")
	)
	(segment
		(start 73.53554 -340.933786)
		(end 73.3806 -340.778846)
		(width 0.254)
		(layer "In4.Cu")
		(net "SCC_A_STBY_PGOOD")
	)
	(segment
		(start 70.5358 -54.46522)
		(end 87.24519 -37.75583)
		(width 0.254)
		(layer "In4.Cu")
		(net "SCC_A_STBY_PGOOD")
	)
	(segment
		(start 70.525386 -132.351018)
		(end 70.525386 -54.577234)
		(width 0.254)
		(layer "In4.Cu")
		(net "SCC_A_STBY_PGOOD")
	)
	(segment
		(start 87.061294 -30.63494)
		(end 87.061294 -29.174694)
		(width 0.254)
		(layer "In4.Cu")
		(net "SCC_A_STBY_PGOOD")
	)
	(segment
		(start 73.3806 -305.797458)
		(end 73.637648 -305.54041)
		(width 0.254)
		(layer "In4.Cu")
		(net "SCC_A_STBY_PGOOD")
	)
	(segment
		(start 70.5358 -54.56682)
		(end 70.5358 -54.46522)
		(width 0.254)
		(layer "In4.Cu")
		(net "SCC_A_STBY_PGOOD")
	)
	(segment
		(start 87.24519 -30.818836)
		(end 87.061294 -30.63494)
		(width 0.254)
		(layer "In4.Cu")
		(net "SCC_A_STBY_PGOOD")
	)
	(segment
		(start 73.3806 -340.778846)
		(end 73.3806 -305.797458)
		(width 0.254)
		(layer "In4.Cu")
		(net "SCC_A_STBY_PGOOD")
	)
	(segment
		(start 241.9858 -388.1374)
		(end 241.956336 -388.166864)
		(width 0.254)
		(layer "F.Cu")
		(net "MB3_HS_SENSE_P")
	)
	(segment
		(start 244.094 -388.3533)
		(end 243.8781 -388.1374)
		(width 0.254)
		(layer "F.Cu")
		(net "MB3_HS_SENSE_P")
	)
	(segment
		(start 243.8781 -388.1374)
		(end 241.9858 -388.1374)
		(width 0.254)
		(layer "F.Cu")
		(net "MB3_HS_SENSE_P")
	)
	(segment
		(start 244.3099 -388.1374)
		(end 244.094 -388.3533)
		(width 0.254)
		(layer "F.Cu")
		(net "MB3_HS_SENSE_P")
	)
	(segment
		(start 245.5291 -388.1374)
		(end 244.3099 -388.1374)
		(width 0.254)
		(layer "F.Cu")
		(net "MB3_HS_SENSE_P")
	)
	(segment
		(start 245.8085 -388.4168)
		(end 245.5291 -388.1374)
		(width 0.254)
		(layer "F.Cu")
		(net "MB3_HS_SENSE_P")
	)
	(segment
		(start 241.956336 -388.166864)
		(end 241.2365 -388.166864)
		(width 0.254)
		(layer "F.Cu")
		(net "MB3_HS_SENSE_P")
	)
	(segment
		(start 241.946938 -387.666738)
		(end 241.2365 -387.666738)
		(width 0.254)
		(layer "F.Cu")
		(net "MB3_HS_SENSE_N")
	)
	(segment
		(start 243.8781 -387.6802)
		(end 241.9604 -387.6802)
		(width 0.254)
		(layer "F.Cu")
		(net "MB3_HS_SENSE_N")
	)
	(segment
		(start 244.094 -387.4643)
		(end 243.8781 -387.6802)
		(width 0.254)
		(layer "F.Cu")
		(net "MB3_HS_SENSE_N")
	)
	(segment
		(start 241.9604 -387.6802)
		(end 241.946938 -387.666738)
		(width 0.254)
		(layer "F.Cu")
		(net "MB3_HS_SENSE_N")
	)
	(segment
		(start 244.3099 -387.6802)
		(end 244.094 -387.4643)
		(width 0.254)
		(layer "F.Cu")
		(net "MB3_HS_SENSE_N")
	)
	(segment
		(start 245.8085 -387.4008)
		(end 245.5291 -387.6802)
		(width 0.254)
		(layer "F.Cu")
		(net "MB3_HS_SENSE_N")
	)
	(segment
		(start 245.5291 -387.6802)
		(end 244.3099 -387.6802)
		(width 0.254)
		(layer "F.Cu")
		(net "MB3_HS_SENSE_N")
	)
	(segment
		(start 364.272068 -139.6619)
		(end 364.056168 -139.8778)
		(width 0.254)
		(layer "F.Cu")
		(net "MB1_HS_SENSE_P")
	)
	(segment
		(start 362.930694 -139.8778)
		(end 363.329474 -139.47902)
		(width 0.254)
		(layer "F.Cu")
		(net "MB1_HS_SENSE_P")
	)
	(segment
		(start 363.728254 -139.8778)
		(end 363.329474 -139.47902)
		(width 0.254)
		(layer "F.Cu")
		(net "MB1_HS_SENSE_P")
	)
	(segment
		(start 366.805464 -139.848336)
		(end 367.6523 -139.848336)
		(width 0.254)
		(layer "F.Cu")
		(net "MB1_HS_SENSE_P")
	)
	(segment
		(start 362.3437 -139.8778)
		(end 362.930694 -139.8778)
		(width 0.254)
		(layer "F.Cu")
		(net "MB1_HS_SENSE_P")
	)
	(segment
		(start 366.8014 -139.8524)
		(end 366.805464 -139.848336)
		(width 0.254)
		(layer "F.Cu")
		(net "MB1_HS_SENSE_P")
	)
	(segment
		(start 364.7948 -139.6619)
		(end 364.272068 -139.6619)
		(width 0.254)
		(layer "F.Cu")
		(net "MB1_HS_SENSE_P")
	)
	(segment
		(start 364.056168 -139.8778)
		(end 363.728254 -139.8778)
		(width 0.254)
		(layer "F.Cu")
		(net "MB1_HS_SENSE_P")
	)
	(segment
		(start 364.9853 -139.8524)
		(end 366.8014 -139.8524)
		(width 0.254)
		(layer "F.Cu")
		(net "MB1_HS_SENSE_P")
	)
	(segment
		(start 364.7948 -139.6619)
		(end 364.9853 -139.8524)
		(width 0.254)
		(layer "F.Cu")
		(net "MB1_HS_SENSE_P")
	)
	(segment
		(start 362.0643 -139.5984)
		(end 362.3437 -139.8778)
		(width 0.254)
		(layer "F.Cu")
		(net "MB1_HS_SENSE_P")
	)
	(via
		(at 363.329474 -139.47902)
		(size 0.6604)
		(drill 0.3302)
		(layers "F.Cu" "B.Cu")
		(net "MB1_HS_SENSE_P")
	)
	(segment
		(start 366.776 -140.3096)
		(end 366.814862 -140.348462)
		(width 0.254)
		(layer "F.Cu")
		(net "MB1_HS_SENSE_N")
	)
	(segment
		(start 366.814862 -140.348462)
		(end 367.6523 -140.348462)
		(width 0.254)
		(layer "F.Cu")
		(net "MB1_HS_SENSE_N")
	)
	(segment
		(start 362.915454 -140.335)
		(end 363.329474 -140.74902)
		(width 0.254)
		(layer "F.Cu")
		(net "MB1_HS_SENSE_N")
	)
	(segment
		(start 364.272068 -140.5509)
		(end 364.056168 -140.335)
		(width 0.254)
		(layer "F.Cu")
		(net "MB1_HS_SENSE_N")
	)
	(segment
		(start 365.0361 -140.3096)
		(end 366.776 -140.3096)
		(width 0.254)
		(layer "F.Cu")
		(net "MB1_HS_SENSE_N")
	)
	(segment
		(start 362.0643 -140.6144)
		(end 362.3437 -140.335)
		(width 0.254)
		(layer "F.Cu")
		(net "MB1_HS_SENSE_N")
	)
	(segment
		(start 364.056168 -140.335)
		(end 363.743494 -140.335)
		(width 0.254)
		(layer "F.Cu")
		(net "MB1_HS_SENSE_N")
	)
	(segment
		(start 364.7948 -140.5509)
		(end 365.0361 -140.3096)
		(width 0.254)
		(layer "F.Cu")
		(net "MB1_HS_SENSE_N")
	)
	(segment
		(start 362.3437 -140.335)
		(end 362.915454 -140.335)
		(width 0.254)
		(layer "F.Cu")
		(net "MB1_HS_SENSE_N")
	)
	(segment
		(start 364.7948 -140.5509)
		(end 364.272068 -140.5509)
		(width 0.254)
		(layer "F.Cu")
		(net "MB1_HS_SENSE_N")
	)
	(segment
		(start 363.743494 -140.335)
		(end 363.329474 -140.74902)
		(width 0.254)
		(layer "F.Cu")
		(net "MB1_HS_SENSE_N")
	)
	(via
		(at 363.329474 -140.74902)
		(size 0.6604)
		(drill 0.3302)
		(layers "F.Cu" "B.Cu")
		(net "MB1_HS_SENSE_N")
	)
	(segment
		(start 152.788366 -137.879074)
		(end 152.432766 -137.523474)
		(width 0.254)
		(layer "F.Cu")
		(net "MB0_HS_SENSE_P")
	)
	(segment
		(start 151.007064 -137.523474)
		(end 151.489156 -138.005566)
		(width 0.254)
		(layer "F.Cu")
		(net "MB0_HS_SENSE_P")
	)
	(segment
		(start 150.603966 -137.523474)
		(end 151.007064 -137.523474)
		(width 0.254)
		(layer "F.Cu")
		(net "MB0_HS_SENSE_P")
	)
	(segment
		(start 150.111968 -137.615676)
		(end 148.480018 -137.615676)
		(width 0.254)
		(layer "F.Cu")
		(net "MB0_HS_SENSE_P")
	)
	(segment
		(start 152.432766 -137.523474)
		(end 151.971248 -137.523474)
		(width 0.254)
		(layer "F.Cu")
		(net "MB0_HS_SENSE_P")
	)
	(segment
		(start 150.311866 -137.815574)
		(end 150.603966 -137.523474)
		(width 0.254)
		(layer "F.Cu")
		(net "MB0_HS_SENSE_P")
	)
	(segment
		(start 150.311866 -137.815574)
		(end 150.111968 -137.615676)
		(width 0.254)
		(layer "F.Cu")
		(net "MB0_HS_SENSE_P")
	)
	(segment
		(start 148.480018 -137.615676)
		(end 148.466556 -137.629138)
		(width 0.254)
		(layer "F.Cu")
		(net "MB0_HS_SENSE_P")
	)
	(segment
		(start 151.971248 -137.523474)
		(end 151.489156 -138.005566)
		(width 0.254)
		(layer "F.Cu")
		(net "MB0_HS_SENSE_P")
	)
	(segment
		(start 148.466556 -137.629138)
		(end 147.454366 -137.629138)
		(width 0.254)
		(layer "F.Cu")
		(net "MB0_HS_SENSE_P")
	)
	(via
		(at 151.489156 -138.005566)
		(size 0.6604)
		(drill 0.3302)
		(layers "F.Cu" "B.Cu")
		(net "MB0_HS_SENSE_P")
	)
	(segment
		(start 152.585166 -137.066274)
		(end 151.819864 -137.066274)
		(width 0.254)
		(layer "F.Cu")
		(net "MB0_HS_SENSE_N")
	)
	(segment
		(start 150.451566 -137.066274)
		(end 151.158448 -137.066274)
		(width 0.254)
		(layer "F.Cu")
		(net "MB0_HS_SENSE_N")
	)
	(segment
		(start 151.819864 -137.066274)
		(end 151.489156 -136.735566)
		(width 0.254)
		(layer "F.Cu")
		(net "MB0_HS_SENSE_N")
	)
	(segment
		(start 150.079964 -137.158476)
		(end 148.323554 -137.158476)
		(width 0.254)
		(layer "F.Cu")
		(net "MB0_HS_SENSE_N")
	)
	(segment
		(start 150.311866 -136.926574)
		(end 150.079964 -137.158476)
		(width 0.254)
		(layer "F.Cu")
		(net "MB0_HS_SENSE_N")
	)
	(segment
		(start 148.29409 -137.129012)
		(end 147.454366 -137.129012)
		(width 0.254)
		(layer "F.Cu")
		(net "MB0_HS_SENSE_N")
	)
	(segment
		(start 150.311866 -136.926574)
		(end 150.451566 -137.066274)
		(width 0.254)
		(layer "F.Cu")
		(net "MB0_HS_SENSE_N")
	)
	(segment
		(start 151.158448 -137.066274)
		(end 151.489156 -136.735566)
		(width 0.254)
		(layer "F.Cu")
		(net "MB0_HS_SENSE_N")
	)
	(segment
		(start 152.788366 -136.863074)
		(end 152.585166 -137.066274)
		(width 0.254)
		(layer "F.Cu")
		(net "MB0_HS_SENSE_N")
	)
	(segment
		(start 148.323554 -137.158476)
		(end 148.29409 -137.129012)
		(width 0.254)
		(layer "F.Cu")
		(net "MB0_HS_SENSE_N")
	)
	(via
		(at 151.489156 -136.735566)
		(size 0.6604)
		(drill 0.3302)
		(layers "F.Cu" "B.Cu")
		(net "MB0_HS_SENSE_N")
	)
	(segment
		(start 282.16733 -272.7579)
		(end 283.34208 -273.93265)
		(width 0.17145)
		(layer "F.Cu")
		(net "IO_EXP2_HDD_FAULT_INT_N")
	)
	(segment
		(start 283.57068 -274.16125)
		(end 283.34208 -273.93265)
		(width 0.17145)
		(layer "F.Cu")
		(net "IO_EXP2_HDD_FAULT_INT_N")
	)
	(segment
		(start 283.57068 -275.5646)
		(end 283.57068 -274.16125)
		(width 0.17145)
		(layer "F.Cu")
		(net "IO_EXP2_HDD_FAULT_INT_N")
	)
	(segment
		(start 282.067 -272.7579)
		(end 282.16733 -272.7579)
		(width 0.17145)
		(layer "F.Cu")
		(net "IO_EXP2_HDD_FAULT_INT_N")
	)
	(via
		(at 283.34208 -273.93265)
		(size 0.6604)
		(drill 0.3302)
		(layers "F.Cu" "B.Cu")
		(net "IO_EXP2_HDD_FAULT_INT_N")
	)
	(segment
		(start 336.16011 -31.50489)
		(end 335.64957 -31.50489)
		(width 0.17145)
		(layer "F.Cu")
		(net "IO_EXP11_SDA")
	)
	(segment
		(start 335.228438 -33.105852)
		(end 335.228438 -31.926022)
		(width 0.17145)
		(layer "F.Cu")
		(net "IO_EXP11_SDA")
	)
	(segment
		(start 335.64957 -31.50489)
		(end 335.230978 -31.923482)
		(width 0.17145)
		(layer "F.Cu")
		(net "IO_EXP11_SDA")
	)
	(segment
		(start 336.702654 -30.05709)
		(end 336.702654 -30.962346)
		(width 0.17145)
		(layer "F.Cu")
		(net "IO_EXP11_SDA")
	)
	(segment
		(start 336.702654 -30.962346)
		(end 336.16011 -31.50489)
		(width 0.17145)
		(layer "F.Cu")
		(net "IO_EXP11_SDA")
	)
	(segment
		(start 335.228438 -31.926022)
		(end 335.230978 -31.923482)
		(width 0.17145)
		(layer "F.Cu")
		(net "IO_EXP11_SDA")
	)
	(via
		(at 335.230978 -31.923482)
		(size 0.6604)
		(drill 0.3302)
		(layers "F.Cu" "B.Cu")
		(net "IO_EXP11_SDA")
	)
	(segment
		(start 337.352894 -31.40329)
		(end 337.135978 -31.620206)
		(width 0.17145)
		(layer "F.Cu")
		(net "IO_EXP11_SCL")
	)
	(segment
		(start 337.447636 -32.533082)
		(end 337.135978 -32.221424)
		(width 0.17145)
		(layer "F.Cu")
		(net "IO_EXP11_SCL")
	)
	(segment
		(start 337.352894 -30.05709)
		(end 337.352894 -31.40329)
		(width 0.17145)
		(layer "F.Cu")
		(net "IO_EXP11_SCL")
	)
	(segment
		(start 337.135978 -32.221424)
		(end 337.135978 -31.620206)
		(width 0.17145)
		(layer "F.Cu")
		(net "IO_EXP11_SCL")
	)
	(segment
		(start 337.447636 -33.105852)
		(end 337.447636 -32.533082)
		(width 0.17145)
		(layer "F.Cu")
		(net "IO_EXP11_SCL")
	)
	(via
		(at 337.135978 -31.620206)
		(size 0.6604)
		(drill 0.3302)
		(layers "F.Cu" "B.Cu")
		(net "IO_EXP11_SCL")
	)
	(segment
		(start 224.475802 -216.07526)
		(end 225.011742 -216.6112)
		(width 0.17145)
		(layer "F.Cu")
		(net "I2C_SCC_BUFF_READY")
	)
	(segment
		(start 224.475802 -214.770462)
		(end 224.475802 -216.07526)
		(width 0.17145)
		(layer "F.Cu")
		(net "I2C_SCC_BUFF_READY")
	)
	(segment
		(start 225.006662 -216.61628)
		(end 225.011742 -216.6112)
		(width 0.17145)
		(layer "F.Cu")
		(net "I2C_SCC_BUFF_READY")
	)
	(segment
		(start 225.006662 -217.608658)
		(end 225.006662 -216.61628)
		(width 0.17145)
		(layer "F.Cu")
		(net "I2C_SCC_BUFF_READY")
	)
	(via
		(at 225.011742 -216.6112)
		(size 0.6604)
		(drill 0.3302)
		(layers "F.Cu" "B.Cu")
		(net "I2C_SCC_BUFF_READY")
	)
	(segment
		(start 222.141542 -207.967834)
		(end 222.126302 -207.983074)
		(width 0.17145)
		(layer "F.Cu")
		(net "I2C_SCC_BUFF_EN")
	)
	(segment
		(start 222.126302 -208.920334)
		(end 222.154242 -208.948274)
		(width 0.17145)
		(layer "F.Cu")
		(net "I2C_SCC_BUFF_EN")
	)
	(segment
		(start 222.126302 -207.983074)
		(end 222.126302 -208.920334)
		(width 0.17145)
		(layer "F.Cu")
		(net "I2C_SCC_BUFF_EN")
	)
	(segment
		(start 222.141542 -206.90332)
		(end 222.141542 -207.967834)
		(width 0.17145)
		(layer "F.Cu")
		(net "I2C_SCC_BUFF_EN")
	)
	(segment
		(start 222.525082 -209.319114)
		(end 222.154242 -208.948274)
		(width 0.17145)
		(layer "F.Cu")
		(net "I2C_SCC_BUFF_EN")
	)
	(segment
		(start 222.525082 -210.630262)
		(end 222.525082 -209.319114)
		(width 0.17145)
		(layer "F.Cu")
		(net "I2C_SCC_BUFF_EN")
	)
	(via
		(at 222.154242 -208.948274)
		(size 0.6604)
		(drill 0.3302)
		(layers "F.Cu" "B.Cu")
		(net "I2C_SCC_BUFF_EN")
	)
	(segment
		(start 221.906338 -218.859862)
		(end 222.928942 -218.859862)
		(width 0.17145)
		(layer "F.Cu")
		(net "I2C_SCC_A_SDA_BUF")
	)
	(segment
		(start 223.175322 -214.770462)
		(end 223.175322 -216.193878)
		(width 0.17145)
		(layer "F.Cu")
		(net "I2C_SCC_A_SDA_BUF")
	)
	(segment
		(start 222.916242 -217.653362)
		(end 222.7326 -217.46972)
		(width 0.17145)
		(layer "F.Cu")
		(net "I2C_SCC_A_SDA_BUF")
	)
	(segment
		(start 223.175322 -216.193878)
		(end 222.7326 -216.6366)
		(width 0.17145)
		(layer "F.Cu")
		(net "I2C_SCC_A_SDA_BUF")
	)
	(segment
		(start 222.916242 -218.847162)
		(end 222.916242 -217.653362)
		(width 0.17145)
		(layer "F.Cu")
		(net "I2C_SCC_A_SDA_BUF")
	)
	(segment
		(start 222.928942 -218.859862)
		(end 222.916242 -218.847162)
		(width 0.17145)
		(layer "F.Cu")
		(net "I2C_SCC_A_SDA_BUF")
	)
	(segment
		(start 222.7326 -217.46972)
		(end 222.7326 -216.6366)
		(width 0.17145)
		(layer "F.Cu")
		(net "I2C_SCC_A_SDA_BUF")
	)
	(via
		(at 221.906338 -218.859862)
		(size 0.5588)
		(drill 0.3048)
		(layers "F.Cu" "B.Cu")
		(net "I2C_SCC_A_SDA_BUF")
	)
	(via
		(at 276.6822 -212.3694)
		(size 0.5588)
		(drill 0.3048)
		(layers "F.Cu" "B.Cu")
		(net "I2C_SCC_A_SDA_BUF")
	)
	(via
		(at 222.7326 -216.6366)
		(size 0.6604)
		(drill 0.3302)
		(layers "F.Cu" "B.Cu")
		(net "I2C_SCC_A_SDA_BUF")
	)
	(segment
		(start 276.451314 -212.600286)
		(end 258.804664 -212.600286)
		(width 0.13335)
		(layer "In2.Cu")
		(net "I2C_SCC_A_SDA_BUF")
	)
	(segment
		(start 276.6822 -212.3694)
		(end 276.451314 -212.600286)
		(width 0.13335)
		(layer "In2.Cu")
		(net "I2C_SCC_A_SDA_BUF")
	)
	(segment
		(start 255.92659 -215.47836)
		(end 229.78364 -215.47836)
		(width 0.13335)
		(layer "In2.Cu")
		(net "I2C_SCC_A_SDA_BUF")
	)
	(segment
		(start 229.78364 -215.47836)
		(end 225.5774 -219.6846)
		(width 0.13335)
		(layer "In2.Cu")
		(net "I2C_SCC_A_SDA_BUF")
	)
	(segment
		(start 225.5774 -219.6846)
		(end 222.731076 -219.6846)
		(width 0.13335)
		(layer "In2.Cu")
		(net "I2C_SCC_A_SDA_BUF")
	)
	(segment
		(start 258.804664 -212.600286)
		(end 255.92659 -215.47836)
		(width 0.13335)
		(layer "In2.Cu")
		(net "I2C_SCC_A_SDA_BUF")
	)
	(segment
		(start 222.731076 -219.6846)
		(end 221.906338 -218.859862)
		(width 0.13335)
		(layer "In2.Cu")
		(net "I2C_SCC_A_SDA_BUF")
	)
	(segment
		(start 277.295102 -260.785356)
		(end 273.81835 -257.308604)
		(width 0.12065)
		(layer "In4.Cu")
		(net "I2C_SCC_A_SDA_BUF")
	)
	(segment
		(start 273.81835 -257.308604)
		(end 273.81835 -241.522504)
		(width 0.12065)
		(layer "In4.Cu")
		(net "I2C_SCC_A_SDA_BUF")
	)
	(segment
		(start 276.6822 -238.658654)
		(end 276.6822 -212.3694)
		(width 0.12065)
		(layer "In4.Cu")
		(net "I2C_SCC_A_SDA_BUF")
	)
	(segment
		(start 282.153614 -260.785356)
		(end 277.295102 -260.785356)
		(width 0.12065)
		(layer "In4.Cu")
		(net "I2C_SCC_A_SDA_BUF")
	)
	(segment
		(start 282.83662 -260.10235)
		(end 282.153614 -260.785356)
		(width 0.12065)
		(layer "In4.Cu")
		(net "I2C_SCC_A_SDA_BUF")
	)
	(segment
		(start 273.81835 -241.522504)
		(end 276.6822 -238.658654)
		(width 0.12065)
		(layer "In4.Cu")
		(net "I2C_SCC_A_SDA_BUF")
	)
	(segment
		(start 223.398842 -206.299562)
		(end 223.182942 -206.083662)
		(width 0.17145)
		(layer "F.Cu")
		(net "I2C_SCC_A_SCL_BUF")
	)
	(segment
		(start 223.398842 -207.290162)
		(end 223.398842 -206.299562)
		(width 0.17145)
		(layer "F.Cu")
		(net "I2C_SCC_A_SCL_BUF")
	)
	(segment
		(start 223.16948 -206.0702)
		(end 222.140526 -206.0702)
		(width 0.17145)
		(layer "F.Cu")
		(net "I2C_SCC_A_SCL_BUF")
	)
	(segment
		(start 223.397826 -208.70037)
		(end 223.397826 -208.351374)
		(width 0.17145)
		(layer "F.Cu")
		(net "I2C_SCC_A_SCL_BUF")
	)
	(segment
		(start 223.398842 -208.350358)
		(end 223.398842 -207.290162)
		(width 0.17145)
		(layer "F.Cu")
		(net "I2C_SCC_A_SCL_BUF")
	)
	(segment
		(start 223.397826 -208.351374)
		(end 223.398842 -208.350358)
		(width 0.17145)
		(layer "F.Cu")
		(net "I2C_SCC_A_SCL_BUF")
	)
	(segment
		(start 223.175322 -208.922874)
		(end 223.397826 -208.70037)
		(width 0.17145)
		(layer "F.Cu")
		(net "I2C_SCC_A_SCL_BUF")
	)
	(segment
		(start 223.175322 -210.630262)
		(end 223.175322 -208.922874)
		(width 0.17145)
		(layer "F.Cu")
		(net "I2C_SCC_A_SCL_BUF")
	)
	(segment
		(start 223.182942 -206.083662)
		(end 223.16948 -206.0702)
		(width 0.17145)
		(layer "F.Cu")
		(net "I2C_SCC_A_SCL_BUF")
	)
	(via
		(at 223.397826 -208.70037)
		(size 0.6604)
		(drill 0.3302)
		(layers "F.Cu" "B.Cu")
		(net "I2C_SCC_A_SCL_BUF")
	)
	(via
		(at 275.9964 -211.6328)
		(size 0.5588)
		(drill 0.3048)
		(layers "F.Cu" "B.Cu")
		(net "I2C_SCC_A_SCL_BUF")
	)
	(via
		(at 222.140526 -206.0702)
		(size 0.5588)
		(drill 0.3048)
		(layers "F.Cu" "B.Cu")
		(net "I2C_SCC_A_SCL_BUF")
	)
	(segment
		(start 222.123 -213.233)
		(end 223.7232 -214.8332)
		(width 0.13335)
		(layer "In2.Cu")
		(net "I2C_SCC_A_SCL_BUF")
	)
	(segment
		(start 255.664716 -214.8332)
		(end 259.068316 -211.4296)
		(width 0.13335)
		(layer "In2.Cu")
		(net "I2C_SCC_A_SCL_BUF")
	)
	(segment
		(start 223.7232 -214.8332)
		(end 255.664716 -214.8332)
		(width 0.13335)
		(layer "In2.Cu")
		(net "I2C_SCC_A_SCL_BUF")
	)
	(segment
		(start 259.068316 -211.4296)
		(end 275.7932 -211.4296)
		(width 0.13335)
		(layer "In2.Cu")
		(net "I2C_SCC_A_SCL_BUF")
	)
	(segment
		(start 222.140526 -206.0702)
		(end 222.140526 -206.057246)
		(width 0.13335)
		(layer "In2.Cu")
		(net "I2C_SCC_A_SCL_BUF")
	)
	(segment
		(start 222.140526 -206.057246)
		(end 222.123 -206.074772)
		(width 0.13335)
		(layer "In2.Cu")
		(net "I2C_SCC_A_SCL_BUF")
	)
	(segment
		(start 275.7932 -211.4296)
		(end 275.9964 -211.6328)
		(width 0.13335)
		(layer "In2.Cu")
		(net "I2C_SCC_A_SCL_BUF")
	)
	(segment
		(start 222.123 -206.074772)
		(end 222.123 -213.233)
		(width 0.13335)
		(layer "In2.Cu")
		(net "I2C_SCC_A_SCL_BUF")
	)
	(segment
		(start 283.077412 -261.261606)
		(end 276.882098 -261.261606)
		(width 0.12065)
		(layer "In4.Cu")
		(net "I2C_SCC_A_SCL_BUF")
	)
	(segment
		(start 273.1897 -257.569208)
		(end 273.1897 -241.2619)
		(width 0.12065)
		(layer "In4.Cu")
		(net "I2C_SCC_A_SCL_BUF")
	)
	(segment
		(start 276.882098 -261.261606)
		(end 273.1897 -257.569208)
		(width 0.12065)
		(layer "In4.Cu")
		(net "I2C_SCC_A_SCL_BUF")
	)
	(segment
		(start 275.9964 -238.4552)
		(end 275.9964 -211.6328)
		(width 0.12065)
		(layer "In4.Cu")
		(net "I2C_SCC_A_SCL_BUF")
	)
	(segment
		(start 284.236668 -260.10235)
		(end 283.077412 -261.261606)
		(width 0.12065)
		(layer "In4.Cu")
		(net "I2C_SCC_A_SCL_BUF")
	)
	(segment
		(start 273.1897 -241.2619)
		(end 275.9964 -238.4552)
		(width 0.12065)
		(layer "In4.Cu")
		(net "I2C_SCC_A_SCL_BUF")
	)
	(segment
		(start 222.528384 -382.396746)
		(end 222.350838 -382.2192)
		(width 0.17145)
		(layer "F.Cu")
		(net "I2C_DRIVE_B_FLT_LED_SDA")
	)
	(segment
		(start 222.350838 -379.3617)
		(end 223.347534 -378.365004)
		(width 0.17145)
		(layer "F.Cu")
		(net "I2C_DRIVE_B_FLT_LED_SDA")
	)
	(segment
		(start 223.347534 -378.365004)
		(end 223.347534 -378.373894)
		(width 0.17145)
		(layer "F.Cu")
		(net "I2C_DRIVE_B_FLT_LED_SDA")
	)
	(segment
		(start 223.347534 -377.446794)
		(end 223.347534 -378.365004)
		(width 0.17145)
		(layer "F.Cu")
		(net "I2C_DRIVE_B_FLT_LED_SDA")
	)
	(segment
		(start 222.350838 -382.2192)
		(end 222.350838 -379.3617)
		(width 0.17145)
		(layer "F.Cu")
		(net "I2C_DRIVE_B_FLT_LED_SDA")
	)
	(via
		(at 222.528384 -382.396746)
		(size 0.5588)
		(drill 0.3048)
		(layers "F.Cu" "B.Cu")
		(net "I2C_DRIVE_B_FLT_LED_SDA")
	)
	(via
		(at 223.347534 -378.373894)
		(size 0.6604)
		(drill 0.3302)
		(layers "F.Cu" "B.Cu")
		(net "I2C_DRIVE_B_FLT_LED_SDA")
	)
	(segment
		(start 220.132656 -402.559774)
		(end 220.132656 -413.166052)
		(width 0.13335)
		(layer "In2.Cu")
		(net "I2C_DRIVE_B_FLT_LED_SDA")
	)
	(segment
		(start 218.765374 -401.192492)
		(end 220.132656 -402.559774)
		(width 0.13335)
		(layer "In2.Cu")
		(net "I2C_DRIVE_B_FLT_LED_SDA")
	)
	(segment
		(start 222.528384 -382.396746)
		(end 218.765374 -386.159756)
		(width 0.13335)
		(layer "In2.Cu")
		(net "I2C_DRIVE_B_FLT_LED_SDA")
	)
	(segment
		(start 219.00007 -414.298638)
		(end 219.00007 -414.600136)
		(width 0.13335)
		(layer "In2.Cu")
		(net "I2C_DRIVE_B_FLT_LED_SDA")
	)
	(segment
		(start 218.765374 -386.159756)
		(end 218.765374 -401.192492)
		(width 0.13335)
		(layer "In2.Cu")
		(net "I2C_DRIVE_B_FLT_LED_SDA")
	)
	(segment
		(start 220.132656 -413.166052)
		(end 219.00007 -414.298638)
		(width 0.13335)
		(layer "In2.Cu")
		(net "I2C_DRIVE_B_FLT_LED_SDA")
	)
	(segment
		(start 224.522538 -378.707396)
		(end 224.173288 -379.056646)
		(width 0.17145)
		(layer "F.Cu")
		(net "I2C_DRIVE_B_FLT_LED_SCL")
	)
	(segment
		(start 223.112076 -380.117858)
		(end 224.173288 -379.056646)
		(width 0.17145)
		(layer "F.Cu")
		(net "I2C_DRIVE_B_FLT_LED_SCL")
	)
	(segment
		(start 224.522538 -377.44908)
		(end 224.522538 -378.707396)
		(width 0.17145)
		(layer "F.Cu")
		(net "I2C_DRIVE_B_FLT_LED_SCL")
	)
	(segment
		(start 222.998284 -380.117858)
		(end 223.112076 -380.117858)
		(width 0.17145)
		(layer "F.Cu")
		(net "I2C_DRIVE_B_FLT_LED_SCL")
	)
	(via
		(at 224.173288 -379.056646)
		(size 0.6604)
		(drill 0.3302)
		(layers "F.Cu" "B.Cu")
		(net "I2C_DRIVE_B_FLT_LED_SCL")
	)
	(via
		(at 222.998284 -380.117858)
		(size 0.5588)
		(drill 0.3048)
		(layers "F.Cu" "B.Cu")
		(net "I2C_DRIVE_B_FLT_LED_SCL")
	)
	(segment
		(start 222.262954 -381.755142)
		(end 218.124024 -385.894072)
		(width 0.13335)
		(layer "In2.Cu")
		(net "I2C_DRIVE_B_FLT_LED_SCL")
	)
	(segment
		(start 223.640904 -380.760478)
		(end 223.640904 -381.311404)
		(width 0.13335)
		(layer "In2.Cu")
		(net "I2C_DRIVE_B_FLT_LED_SCL")
	)
	(segment
		(start 218.124024 -385.894072)
		(end 218.124024 -401.610576)
		(width 0.13335)
		(layer "In2.Cu")
		(net "I2C_DRIVE_B_FLT_LED_SCL")
	)
	(segment
		(start 222.998284 -380.117858)
		(end 223.640904 -380.760478)
		(width 0.13335)
		(layer "In2.Cu")
		(net "I2C_DRIVE_B_FLT_LED_SCL")
	)
	(segment
		(start 218.124024 -401.610576)
		(end 219.643706 -403.130258)
		(width 0.13335)
		(layer "In2.Cu")
		(net "I2C_DRIVE_B_FLT_LED_SCL")
	)
	(segment
		(start 223.197166 -381.755142)
		(end 222.262954 -381.755142)
		(width 0.13335)
		(layer "In2.Cu")
		(net "I2C_DRIVE_B_FLT_LED_SCL")
	)
	(segment
		(start 223.640904 -381.311404)
		(end 223.197166 -381.755142)
		(width 0.13335)
		(layer "In2.Cu")
		(net "I2C_DRIVE_B_FLT_LED_SCL")
	)
	(segment
		(start 219.643706 -403.130258)
		(end 219.643706 -412.556452)
		(width 0.13335)
		(layer "In2.Cu")
		(net "I2C_DRIVE_B_FLT_LED_SCL")
	)
	(segment
		(start 219.643706 -412.556452)
		(end 219.00007 -413.200088)
		(width 0.13335)
		(layer "In2.Cu")
		(net "I2C_DRIVE_B_FLT_LED_SCL")
	)
	(segment
		(start 265.471402 -218.936062)
		(end 265.471402 -220.005402)
		(width 0.17145)
		(layer "F.Cu")
		(net "I2C_DPB_BUFF_READY")
	)
	(segment
		(start 265.887962 -221.659958)
		(end 265.887962 -220.7006)
		(width 0.17145)
		(layer "F.Cu")
		(net "I2C_DPB_BUFF_READY")
	)
	(segment
		(start 265.887962 -220.421962)
		(end 265.887962 -220.7006)
		(width 0.17145)
		(layer "F.Cu")
		(net "I2C_DPB_BUFF_READY")
	)
	(segment
		(start 265.471402 -220.005402)
		(end 265.887962 -220.421962)
		(width 0.17145)
		(layer "F.Cu")
		(net "I2C_DPB_BUFF_READY")
	)
	(via
		(at 265.887962 -220.7006)
		(size 0.6604)
		(drill 0.3302)
		(layers "F.Cu" "B.Cu")
		(net "I2C_DPB_BUFF_READY")
	)
	(segment
		(start 263.137142 -213.657942)
		(end 263.137142 -213.024466)
		(width 0.17145)
		(layer "F.Cu")
		(net "I2C_DPB_BUFF_EN")
	)
	(segment
		(start 263.137142 -213.016846)
		(end 263.137142 -212.048344)
		(width 0.17145)
		(layer "F.Cu")
		(net "I2C_DPB_BUFF_EN")
	)
	(segment
		(start 263.13892 -212.046566)
		(end 263.137142 -212.048344)
		(width 0.17145)
		(layer "F.Cu")
		(net "I2C_DPB_BUFF_EN")
	)
	(segment
		(start 263.137142 -213.024466)
		(end 263.133332 -213.020656)
		(width 0.17145)
		(layer "F.Cu")
		(net "I2C_DPB_BUFF_EN")
	)
	(segment
		(start 263.137142 -212.048344)
		(end 263.137142 -211.062062)
		(width 0.17145)
		(layer "F.Cu")
		(net "I2C_DPB_BUFF_EN")
	)
	(segment
		(start 263.520682 -214.041482)
		(end 263.137142 -213.657942)
		(width 0.17145)
		(layer "F.Cu")
		(net "I2C_DPB_BUFF_EN")
	)
	(segment
		(start 263.520682 -214.795862)
		(end 263.520682 -214.041482)
		(width 0.17145)
		(layer "F.Cu")
		(net "I2C_DPB_BUFF_EN")
	)
	(segment
		(start 263.133332 -213.020656)
		(end 263.137142 -213.016846)
		(width 0.17145)
		(layer "F.Cu")
		(net "I2C_DPB_BUFF_EN")
	)
	(via
		(at 263.133332 -213.020656)
		(size 0.6604)
		(drill 0.3302)
		(layers "F.Cu" "B.Cu")
		(net "I2C_DPB_BUFF_EN")
	)
	(segment
		(start 263.4996 -221.045024)
		(end 263.810242 -221.355666)
		(width 0.17145)
		(layer "F.Cu")
		(net "I2C_DPB_A_SDA_BUF")
	)
	(segment
		(start 212.67674 -408.723592)
		(end 212.67674 -393.01674)
		(width 0.17145)
		(layer "F.Cu")
		(net "I2C_DPB_A_SDA_BUF")
	)
	(segment
		(start 220.957648 -382.5113)
		(end 220.957394 -382.511554)
		(width 0.17145)
		(layer "F.Cu")
		(net "I2C_DPB_A_SDA_BUF")
	)
	(segment
		(start 263.80059 -221.676214)
		(end 262.703056 -221.676214)
		(width 0.17145)
		(layer "F.Cu")
		(net "I2C_DPB_A_SDA_BUF")
	)
	(segment
		(start 221.889574 -350.624648)
		(end 221.88678 -350.621854)
		(width 0.17145)
		(layer "F.Cu")
		(net "I2C_DPB_A_SDA_BUF")
	)
	(segment
		(start 252.429264 24.176736)
		(end 253.470156 25.217628)
		(width 0.17145)
		(layer "F.Cu")
		(net "I2C_DPB_A_SDA_BUF")
	)
	(segment
		(start 264.170922 -218.936062)
		(end 264.170922 -219.953078)
		(width 0.17145)
		(layer "F.Cu")
		(net "I2C_DPB_A_SDA_BUF")
	)
	(segment
		(start 222.976948 -350.624648)
		(end 221.889574 -350.624648)
		(width 0.17145)
		(layer "F.Cu")
		(net "I2C_DPB_A_SDA_BUF")
	)
	(segment
		(start 211.362798 -391.702798)
		(end 211.362798 -380.461012)
		(width 0.17145)
		(layer "F.Cu")
		(net "I2C_DPB_A_SDA_BUF")
	)
	(segment
		(start 211.362798 -380.461012)
		(end 214.42553 -377.39828)
		(width 0.17145)
		(layer "F.Cu")
		(net "I2C_DPB_A_SDA_BUF")
	)
	(segment
		(start 264.170922 -219.953078)
		(end 263.4996 -220.6244)
		(width 0.17145)
		(layer "F.Cu")
		(net "I2C_DPB_A_SDA_BUF")
	)
	(segment
		(start 220.957394 -382.511554)
		(end 220.957394 -383.074418)
		(width 0.17145)
		(layer "F.Cu")
		(net "I2C_DPB_A_SDA_BUF")
	)
	(segment
		(start 263.4996 -220.6244)
		(end 263.4996 -221.045024)
		(width 0.17145)
		(layer "F.Cu")
		(net "I2C_DPB_A_SDA_BUF")
	)
	(segment
		(start 214.42553 -377.39828)
		(end 218.42857 -377.39828)
		(width 0.17145)
		(layer "F.Cu")
		(net "I2C_DPB_A_SDA_BUF")
	)
	(segment
		(start 226.48164 -383.850896)
		(end 226.831144 -384.2004)
		(width 0.17145)
		(layer "F.Cu")
		(net "I2C_DPB_A_SDA_BUF")
	)
	(segment
		(start 257.683 -301.6885)
		(end 259.349494 -303.354994)
		(width 0.17145)
		(layer "F.Cu")
		(net "I2C_DPB_A_SDA_BUF")
	)
	(segment
		(start 263.810242 -221.666562)
		(end 263.80059 -221.676214)
		(width 0.17145)
		(layer "F.Cu")
		(net "I2C_DPB_A_SDA_BUF")
	)
	(segment
		(start 262.703056 -221.676214)
		(end 262.703056 -222.733616)
		(width 0.17145)
		(layer "F.Cu")
		(net "I2C_DPB_A_SDA_BUF")
	)
	(segment
		(start 263.810242 -221.355666)
		(end 263.810242 -221.666562)
		(width 0.17145)
		(layer "F.Cu")
		(net "I2C_DPB_A_SDA_BUF")
	)
	(segment
		(start 221.733872 -383.850896)
		(end 226.48164 -383.850896)
		(width 0.17145)
		(layer "F.Cu")
		(net "I2C_DPB_A_SDA_BUF")
	)
	(segment
		(start 218.42857 -377.39828)
		(end 220.957648 -379.927358)
		(width 0.17145)
		(layer "F.Cu")
		(net "I2C_DPB_A_SDA_BUF")
	)
	(segment
		(start 220.957648 -379.927358)
		(end 220.957648 -382.5113)
		(width 0.17145)
		(layer "F.Cu")
		(net "I2C_DPB_A_SDA_BUF")
	)
	(segment
		(start 262.703056 -222.733616)
		(end 262.704834 -222.735394)
		(width 0.17145)
		(layer "F.Cu")
		(net "I2C_DPB_A_SDA_BUF")
	)
	(segment
		(start 220.957394 -383.074418)
		(end 221.733872 -383.850896)
		(width 0.17145)
		(layer "F.Cu")
		(net "I2C_DPB_A_SDA_BUF")
	)
	(segment
		(start 259.349494 -303.354994)
		(end 259.349494 -304.429922)
		(width 0.17145)
		(layer "F.Cu")
		(net "I2C_DPB_A_SDA_BUF")
	)
	(segment
		(start 211.800186 -409.600146)
		(end 212.67674 -408.723592)
		(width 0.17145)
		(layer "F.Cu")
		(net "I2C_DPB_A_SDA_BUF")
	)
	(segment
		(start 212.67674 -393.01674)
		(end 211.362798 -391.702798)
		(width 0.17145)
		(layer "F.Cu")
		(net "I2C_DPB_A_SDA_BUF")
	)
	(segment
		(start 253.470156 25.217628)
		(end 253.470156 26.404824)
		(width 0.17145)
		(layer "F.Cu")
		(net "I2C_DPB_A_SDA_BUF")
	)
	(segment
		(start 230.3399 -384.2004)
		(end 226.831144 -384.2004)
		(width 0.17145)
		(layer "F.Cu")
		(net "I2C_DPB_A_SDA_BUF")
	)
	(via
		(at 262.704834 -222.735394)
		(size 0.5588)
		(drill 0.3048)
		(layers "F.Cu" "B.Cu")
		(net "I2C_DPB_A_SDA_BUF")
	)
	(via
		(at 259.349494 -304.429922)
		(size 0.5588)
		(drill 0.3048)
		(layers "F.Cu" "B.Cu")
		(net "I2C_DPB_A_SDA_BUF")
	)
	(via
		(at 234.565444 -351.604072)
		(size 0.5588)
		(drill 0.3048)
		(layers "F.Cu" "B.Cu")
		(net "I2C_DPB_A_SDA_BUF")
	)
	(via
		(at 226.831144 -384.2004)
		(size 0.5588)
		(drill 0.3048)
		(layers "F.Cu" "B.Cu")
		(net "I2C_DPB_A_SDA_BUF")
	)
	(via
		(at 263.4996 -220.6244)
		(size 0.6604)
		(drill 0.3302)
		(layers "F.Cu" "B.Cu")
		(net "I2C_DPB_A_SDA_BUF")
	)
	(via
		(at 221.88678 -350.621854)
		(size 0.5588)
		(drill 0.3048)
		(layers "F.Cu" "B.Cu")
		(net "I2C_DPB_A_SDA_BUF")
	)
	(via
		(at 252.429264 24.176736)
		(size 0.5588)
		(drill 0.3048)
		(layers "F.Cu" "B.Cu")
		(net "I2C_DPB_A_SDA_BUF")
	)
	(segment
		(start 232.054654 -350.367854)
		(end 222.14078 -350.367854)
		(width 0.13335)
		(layer "In2.Cu")
		(net "I2C_DPB_A_SDA_BUF")
	)
	(segment
		(start 233.290872 -351.604072)
		(end 232.054654 -350.367854)
		(width 0.13335)
		(layer "In2.Cu")
		(net "I2C_DPB_A_SDA_BUF")
	)
	(segment
		(start 234.565444 -351.604072)
		(end 233.290872 -351.604072)
		(width 0.13335)
		(layer "In2.Cu")
		(net "I2C_DPB_A_SDA_BUF")
	)
	(segment
		(start 222.14078 -350.367854)
		(end 221.88678 -350.621854)
		(width 0.13335)
		(layer "In2.Cu")
		(net "I2C_DPB_A_SDA_BUF")
	)
	(segment
		(start 262.316722 -132.705094)
		(end 260.4008 -130.789172)
		(width 0.12065)
		(layer "In4.Cu")
		(net "I2C_DPB_A_SDA_BUF")
	)
	(segment
		(start 259.44195 20.288504)
		(end 258.92125 20.288504)
		(width 0.12065)
		(layer "In4.Cu")
		(net "I2C_DPB_A_SDA_BUF")
	)
	(segment
		(start 262.316722 -203.079604)
		(end 262.316722 -132.705094)
		(width 0.12065)
		(layer "In4.Cu")
		(net "I2C_DPB_A_SDA_BUF")
	)
	(segment
		(start 256.31775 20.28825)
		(end 252.429264 24.176736)
		(width 0.12065)
		(layer "In4.Cu")
		(net "I2C_DPB_A_SDA_BUF")
	)
	(segment
		(start 260.4008 -130.789172)
		(end 260.4008 -20.98167)
		(width 0.12065)
		(layer "In4.Cu")
		(net "I2C_DPB_A_SDA_BUF")
	)
	(segment
		(start 262.704834 -222.735394)
		(end 268.4272 -217.013028)
		(width 0.12065)
		(layer "In4.Cu")
		(net "I2C_DPB_A_SDA_BUF")
	)
	(segment
		(start 263.968992 -224.878138)
		(end 263.968992 -250.239784)
		(width 0.12065)
		(layer "In4.Cu")
		(net "I2C_DPB_A_SDA_BUF")
	)
	(segment
		(start 261.324852 -302.454564)
		(end 259.349494 -304.429922)
		(width 0.12065)
		(layer "In4.Cu")
		(net "I2C_DPB_A_SDA_BUF")
	)
	(segment
		(start 260.4008 -20.98167)
		(end 263.030462 -18.352008)
		(width 0.12065)
		(layer "In4.Cu")
		(net "I2C_DPB_A_SDA_BUF")
	)
	(segment
		(start 258.920996 20.28825)
		(end 256.31775 20.28825)
		(width 0.12065)
		(layer "In4.Cu")
		(net "I2C_DPB_A_SDA_BUF")
	)
	(segment
		(start 263.968992 -250.239784)
		(end 261.255764 -252.953012)
		(width 0.12065)
		(layer "In4.Cu")
		(net "I2C_DPB_A_SDA_BUF")
	)
	(segment
		(start 261.10565 5.466588)
		(end 261.10565 18.624804)
		(width 0.12065)
		(layer "In4.Cu")
		(net "I2C_DPB_A_SDA_BUF")
	)
	(segment
		(start 260.461252 -273.93392)
		(end 261.324852 -274.79752)
		(width 0.12065)
		(layer "In4.Cu")
		(net "I2C_DPB_A_SDA_BUF")
	)
	(segment
		(start 258.92125 20.288504)
		(end 258.920996 20.28825)
		(width 0.12065)
		(layer "In4.Cu")
		(net "I2C_DPB_A_SDA_BUF")
	)
	(segment
		(start 261.255764 -254.647954)
		(end 260.461252 -255.442466)
		(width 0.12065)
		(layer "In4.Cu")
		(net "I2C_DPB_A_SDA_BUF")
	)
	(segment
		(start 262.704834 -222.735394)
		(end 262.704834 -223.61398)
		(width 0.12065)
		(layer "In4.Cu")
		(net "I2C_DPB_A_SDA_BUF")
	)
	(segment
		(start 263.030462 3.541776)
		(end 261.10565 5.466588)
		(width 0.12065)
		(layer "In4.Cu")
		(net "I2C_DPB_A_SDA_BUF")
	)
	(segment
		(start 260.461252 -255.442466)
		(end 260.461252 -273.93392)
		(width 0.12065)
		(layer "In4.Cu")
		(net "I2C_DPB_A_SDA_BUF")
	)
	(segment
		(start 261.10565 18.624804)
		(end 259.44195 20.288504)
		(width 0.12065)
		(layer "In4.Cu")
		(net "I2C_DPB_A_SDA_BUF")
	)
	(segment
		(start 268.4272 -217.013028)
		(end 268.4272 -209.190082)
		(width 0.12065)
		(layer "In4.Cu")
		(net "I2C_DPB_A_SDA_BUF")
	)
	(segment
		(start 263.030462 -18.352008)
		(end 263.030462 3.541776)
		(width 0.12065)
		(layer "In4.Cu")
		(net "I2C_DPB_A_SDA_BUF")
	)
	(segment
		(start 268.4272 -209.190082)
		(end 262.316722 -203.079604)
		(width 0.12065)
		(layer "In4.Cu")
		(net "I2C_DPB_A_SDA_BUF")
	)
	(segment
		(start 262.704834 -223.61398)
		(end 263.968992 -224.878138)
		(width 0.12065)
		(layer "In4.Cu")
		(net "I2C_DPB_A_SDA_BUF")
	)
	(segment
		(start 261.255764 -252.953012)
		(end 261.255764 -254.647954)
		(width 0.12065)
		(layer "In4.Cu")
		(net "I2C_DPB_A_SDA_BUF")
	)
	(segment
		(start 261.324852 -274.79752)
		(end 261.324852 -302.454564)
		(width 0.12065)
		(layer "In4.Cu")
		(net "I2C_DPB_A_SDA_BUF")
	)
	(segment
		(start 227.69195 -362.584492)
		(end 222.8596 -357.752142)
		(width 0.12065)
		(layer "In7.Cu")
		(net "I2C_DPB_A_SDA_BUF")
	)
	(segment
		(start 226.1108 -383.480056)
		(end 226.1108 -380.6698)
		(width 0.12065)
		(layer "In7.Cu")
		(net "I2C_DPB_A_SDA_BUF")
	)
	(segment
		(start 226.1108 -380.6698)
		(end 227.69195 -379.08865)
		(width 0.12065)
		(layer "In7.Cu")
		(net "I2C_DPB_A_SDA_BUF")
	)
	(segment
		(start 226.831144 -384.2004)
		(end 226.1108 -383.480056)
		(width 0.12065)
		(layer "In7.Cu")
		(net "I2C_DPB_A_SDA_BUF")
	)
	(segment
		(start 222.8596 -357.752142)
		(end 222.8596 -351.594674)
		(width 0.12065)
		(layer "In7.Cu")
		(net "I2C_DPB_A_SDA_BUF")
	)
	(segment
		(start 227.69195 -379.08865)
		(end 227.69195 -362.584492)
		(width 0.12065)
		(layer "In7.Cu")
		(net "I2C_DPB_A_SDA_BUF")
	)
	(segment
		(start 222.8596 -351.594674)
		(end 221.88678 -350.621854)
		(width 0.12065)
		(layer "In7.Cu")
		(net "I2C_DPB_A_SDA_BUF")
	)
	(segment
		(start 259.349494 -323.120004)
		(end 259.349494 -304.429922)
		(width 0.13335)
		(layer "In9.Cu")
		(net "I2C_DPB_A_SDA_BUF")
	)
	(segment
		(start 274.890738 -334.92059)
		(end 274.935696 -334.965548)
		(width 0.13335)
		(layer "In9.Cu")
		(net "I2C_DPB_A_SDA_BUF")
	)
	(segment
		(start 274.935696 -334.965548)
		(end 281.176222 -334.965548)
		(width 0.13335)
		(layer "In9.Cu")
		(net "I2C_DPB_A_SDA_BUF")
	)
	(segment
		(start 235.767626 -348.59976)
		(end 244.135402 -348.59976)
		(width 0.13335)
		(layer "In9.Cu")
		(net "I2C_DPB_A_SDA_BUF")
	)
	(segment
		(start 234.565444 -349.801942)
		(end 235.767626 -348.59976)
		(width 0.13335)
		(layer "In9.Cu")
		(net "I2C_DPB_A_SDA_BUF")
	)
	(segment
		(start 244.135402 -348.59976)
		(end 257.814572 -334.92059)
		(width 0.13335)
		(layer "In9.Cu")
		(net "I2C_DPB_A_SDA_BUF")
	)
	(segment
		(start 234.565444 -351.604072)
		(end 234.565444 -349.801942)
		(width 0.13335)
		(layer "In9.Cu")
		(net "I2C_DPB_A_SDA_BUF")
	)
	(segment
		(start 257.814572 -334.92059)
		(end 274.890738 -334.92059)
		(width 0.13335)
		(layer "In9.Cu")
		(net "I2C_DPB_A_SDA_BUF")
	)
	(segment
		(start 281.176222 -334.965548)
		(end 281.836622 -334.305148)
		(width 0.13335)
		(layer "In9.Cu")
		(net "I2C_DPB_A_SDA_BUF")
	)
	(segment
		(start 269.888716 -333.659226)
		(end 259.349494 -323.120004)
		(width 0.13335)
		(layer "In9.Cu")
		(net "I2C_DPB_A_SDA_BUF")
	)
	(segment
		(start 281.836622 -334.305148)
		(end 281.1907 -333.659226)
		(width 0.13335)
		(layer "In9.Cu")
		(net "I2C_DPB_A_SDA_BUF")
	)
	(segment
		(start 281.1907 -333.659226)
		(end 269.888716 -333.659226)
		(width 0.13335)
		(layer "In9.Cu")
		(net "I2C_DPB_A_SDA_BUF")
	)
	(segment
		(start 265.65606 -210.607402)
		(end 265.2014 -211.062062)
		(width 0.17145)
		(layer "F.Cu")
		(net "I2C_DPB_A_SCL_BUF")
	)
	(segment
		(start 210.683348 -392.39063)
		(end 210.683348 -380.179326)
		(width 0.17145)
		(layer "F.Cu")
		(net "I2C_DPB_A_SCL_BUF")
	)
	(segment
		(start 211.800186 -411.000194)
		(end 210.977226 -410.177234)
		(width 0.17145)
		(layer "F.Cu")
		(net "I2C_DPB_A_SCL_BUF")
	)
	(segment
		(start 266.893802 -210.607402)
		(end 265.921998 -210.607402)
		(width 0.17145)
		(layer "F.Cu")
		(net "I2C_DPB_A_SCL_BUF")
	)
	(segment
		(start 264.170922 -212.441282)
		(end 264.170922 -214.795862)
		(width 0.17145)
		(layer "F.Cu")
		(net "I2C_DPB_A_SCL_BUF")
	)
	(segment
		(start 222.015558 -383.171446)
		(end 226.813364 -383.171446)
		(width 0.17145)
		(layer "F.Cu")
		(net "I2C_DPB_A_SCL_BUF")
	)
	(segment
		(start 256.413 -301.82058)
		(end 258.407916 -303.815496)
		(width 0.17145)
		(layer "F.Cu")
		(net "I2C_DPB_A_SCL_BUF")
	)
	(segment
		(start 256.413 -301.6885)
		(end 256.413 -301.82058)
		(width 0.17145)
		(layer "F.Cu")
		(net "I2C_DPB_A_SCL_BUF")
	)
	(segment
		(start 221.637098 -382.792986)
		(end 222.015558 -383.171446)
		(width 0.17145)
		(layer "F.Cu")
		(net "I2C_DPB_A_SCL_BUF")
	)
	(segment
		(start 264.356342 -212.255862)
		(end 264.343642 -212.268562)
		(width 0.17145)
		(layer "F.Cu")
		(net "I2C_DPB_A_SCL_BUF")
	)
	(segment
		(start 230.3399 -383.0574)
		(end 226.92741 -383.0574)
		(width 0.17145)
		(layer "F.Cu")
		(net "I2C_DPB_A_SCL_BUF")
	)
	(segment
		(start 252.670056 25.509728)
		(end 252.670056 26.404824)
		(width 0.17145)
		(layer "F.Cu")
		(net "I2C_DPB_A_SCL_BUF")
	)
	(segment
		(start 265.921998 -210.607402)
		(end 265.65606 -210.607402)
		(width 0.17145)
		(layer "F.Cu")
		(net "I2C_DPB_A_SCL_BUF")
	)
	(segment
		(start 210.977226 -410.177234)
		(end 210.977226 -392.684508)
		(width 0.17145)
		(layer "F.Cu")
		(net "I2C_DPB_A_SCL_BUF")
	)
	(segment
		(start 210.977226 -392.684508)
		(end 210.683348 -392.39063)
		(width 0.17145)
		(layer "F.Cu")
		(net "I2C_DPB_A_SCL_BUF")
	)
	(segment
		(start 251.286264 24.125936)
		(end 252.670056 25.509728)
		(width 0.17145)
		(layer "F.Cu")
		(net "I2C_DPB_A_SCL_BUF")
	)
	(segment
		(start 226.92741 -383.0574)
		(end 226.813364 -383.171446)
		(width 0.17145)
		(layer "F.Cu")
		(net "I2C_DPB_A_SCL_BUF")
	)
	(segment
		(start 264.343642 -212.268562)
		(end 264.170922 -212.441282)
		(width 0.17145)
		(layer "F.Cu")
		(net "I2C_DPB_A_SCL_BUF")
	)
	(segment
		(start 214.143844 -376.71883)
		(end 218.710256 -376.71883)
		(width 0.17145)
		(layer "F.Cu")
		(net "I2C_DPB_A_SCL_BUF")
	)
	(segment
		(start 264.356342 -211.062062)
		(end 264.356342 -212.255862)
		(width 0.17145)
		(layer "F.Cu")
		(net "I2C_DPB_A_SCL_BUF")
	)
	(segment
		(start 265.2014 -211.062062)
		(end 264.356342 -211.062062)
		(width 0.17145)
		(layer "F.Cu")
		(net "I2C_DPB_A_SCL_BUF")
	)
	(segment
		(start 221.637098 -379.645672)
		(end 221.637098 -382.792986)
		(width 0.17145)
		(layer "F.Cu")
		(net "I2C_DPB_A_SCL_BUF")
	)
	(segment
		(start 210.683348 -380.179326)
		(end 214.143844 -376.71883)
		(width 0.17145)
		(layer "F.Cu")
		(net "I2C_DPB_A_SCL_BUF")
	)
	(segment
		(start 218.710256 -376.71883)
		(end 221.637098 -379.645672)
		(width 0.17145)
		(layer "F.Cu")
		(net "I2C_DPB_A_SCL_BUF")
	)
	(segment
		(start 222.976694 -349.439484)
		(end 221.9198 -349.439484)
		(width 0.17145)
		(layer "F.Cu")
		(net "I2C_DPB_A_SCL_BUF")
	)
	(via
		(at 258.407916 -303.815496)
		(size 0.5588)
		(drill 0.3048)
		(layers "F.Cu" "B.Cu")
		(net "I2C_DPB_A_SCL_BUF")
	)
	(via
		(at 265.921998 -210.607402)
		(size 0.6604)
		(drill 0.3302)
		(layers "F.Cu" "B.Cu")
		(net "I2C_DPB_A_SCL_BUF")
	)
	(via
		(at 221.9198 -349.439484)
		(size 0.5588)
		(drill 0.3048)
		(layers "F.Cu" "B.Cu")
		(net "I2C_DPB_A_SCL_BUF")
	)
	(via
		(at 251.286264 24.125936)
		(size 0.5588)
		(drill 0.3048)
		(layers "F.Cu" "B.Cu")
		(net "I2C_DPB_A_SCL_BUF")
	)
	(via
		(at 266.893802 -210.607402)
		(size 0.5588)
		(drill 0.3048)
		(layers "F.Cu" "B.Cu")
		(net "I2C_DPB_A_SCL_BUF")
	)
	(via
		(at 226.813364 -383.171446)
		(size 0.5588)
		(drill 0.3048)
		(layers "F.Cu" "B.Cu")
		(net "I2C_DPB_A_SCL_BUF")
	)
	(via
		(at 235.610654 -351.645982)
		(size 0.5588)
		(drill 0.3048)
		(layers "F.Cu" "B.Cu")
		(net "I2C_DPB_A_SCL_BUF")
	)
	(segment
		(start 232.527602 -349.621602)
		(end 233.54665 -350.64065)
		(width 0.13335)
		(layer "In2.Cu")
		(net "I2C_DPB_A_SCL_BUF")
	)
	(segment
		(start 233.54665 -350.64065)
		(end 234.605322 -350.64065)
		(width 0.13335)
		(layer "In2.Cu")
		(net "I2C_DPB_A_SCL_BUF")
	)
	(segment
		(start 234.605322 -350.64065)
		(end 235.610654 -351.645982)
		(width 0.13335)
		(layer "In2.Cu")
		(net "I2C_DPB_A_SCL_BUF")
	)
	(segment
		(start 222.101918 -349.621602)
		(end 232.527602 -349.621602)
		(width 0.13335)
		(layer "In2.Cu")
		(net "I2C_DPB_A_SCL_BUF")
	)
	(segment
		(start 221.9198 -349.439484)
		(end 222.101918 -349.621602)
		(width 0.13335)
		(layer "In2.Cu")
		(net "I2C_DPB_A_SCL_BUF")
	)
	(segment
		(start 262.54075 -250.778772)
		(end 259.404104 -253.915418)
		(width 0.12065)
		(layer "In4.Cu")
		(net "I2C_DPB_A_SCL_BUF")
	)
	(segment
		(start 258.407916 -302.374046)
		(end 258.407916 -303.815496)
		(width 0.12065)
		(layer "In4.Cu")
		(net "I2C_DPB_A_SCL_BUF")
	)
	(segment
		(start 260.477 18.3642)
		(end 259.1816 19.6596)
		(width 0.12065)
		(layer "In4.Cu")
		(net "I2C_DPB_A_SCL_BUF")
	)
	(segment
		(start 260.181852 -289.318446)
		(end 260.58876 -289.725354)
		(width 0.12065)
		(layer "In4.Cu")
		(net "I2C_DPB_A_SCL_BUF")
	)
	(segment
		(start 260.696202 -275.058124)
		(end 260.696202 -285.471362)
		(width 0.12065)
		(layer "In4.Cu")
		(net "I2C_DPB_A_SCL_BUF")
	)
	(segment
		(start 259.738368 -259.876798)
		(end 259.738368 -260.284722)
		(width 0.12065)
		(layer "In4.Cu")
		(net "I2C_DPB_A_SCL_BUF")
	)
	(segment
		(start 260.58876 -300.193202)
		(end 258.407916 -302.374046)
		(width 0.12065)
		(layer "In4.Cu")
		(net "I2C_DPB_A_SCL_BUF")
	)
	(segment
		(start 262.401812 -17.88033)
		(end 262.401812 3.281172)
		(width 0.12065)
		(layer "In4.Cu")
		(net "I2C_DPB_A_SCL_BUF")
	)
	(segment
		(start 259.476748 -271.247362)
		(end 259.832602 -271.603216)
		(width 0.12065)
		(layer "In4.Cu")
		(net "I2C_DPB_A_SCL_BUF")
	)
	(segment
		(start 259.1816 19.6596)
		(end 255.7526 19.6596)
		(width 0.12065)
		(layer "In4.Cu")
		(net "I2C_DPB_A_SCL_BUF")
	)
	(segment
		(start 263.229852 -225.028506)
		(end 263.229852 -234.558332)
		(width 0.12065)
		(layer "In4.Cu")
		(net "I2C_DPB_A_SCL_BUF")
	)
	(segment
		(start 262.04926 -222.05188)
		(end 262.04926 -223.847914)
		(width 0.12065)
		(layer "In4.Cu")
		(net "I2C_DPB_A_SCL_BUF")
	)
	(segment
		(start 259.77215 -20.509992)
		(end 262.401812 -17.88033)
		(width 0.12065)
		(layer "In4.Cu")
		(net "I2C_DPB_A_SCL_BUF")
	)
	(segment
		(start 259.6642 -270.651986)
		(end 259.476748 -270.839438)
		(width 0.12065)
		(layer "In4.Cu")
		(net "I2C_DPB_A_SCL_BUF")
	)
	(segment
		(start 266.893802 -210.607402)
		(end 266.893802 -217.207338)
		(width 0.12065)
		(layer "In4.Cu")
		(net "I2C_DPB_A_SCL_BUF")
	)
	(segment
		(start 261.688072 -203.420472)
		(end 261.688072 -132.965698)
		(width 0.12065)
		(layer "In4.Cu")
		(net "I2C_DPB_A_SCL_BUF")
	)
	(segment
		(start 255.7526 19.6596)
		(end 251.286264 24.125936)
		(width 0.12065)
		(layer "In4.Cu")
		(net "I2C_DPB_A_SCL_BUF")
	)
	(segment
		(start 259.404104 -259.542534)
		(end 259.738368 -259.876798)
		(width 0.12065)
		(layer "In4.Cu")
		(net "I2C_DPB_A_SCL_BUF")
	)
	(segment
		(start 259.738368 -260.284722)
		(end 259.6642 -260.35889)
		(width 0.12065)
		(layer "In4.Cu")
		(net "I2C_DPB_A_SCL_BUF")
	)
	(segment
		(start 261.688072 -132.965698)
		(end 259.77215 -131.049776)
		(width 0.12065)
		(layer "In4.Cu")
		(net "I2C_DPB_A_SCL_BUF")
	)
	(segment
		(start 259.476748 -270.839438)
		(end 259.476748 -271.247362)
		(width 0.12065)
		(layer "In4.Cu")
		(net "I2C_DPB_A_SCL_BUF")
	)
	(segment
		(start 259.832602 -271.603216)
		(end 259.832602 -274.194524)
		(width 0.12065)
		(layer "In4.Cu")
		(net "I2C_DPB_A_SCL_BUF")
	)
	(segment
		(start 263.229852 -234.558332)
		(end 262.54075 -235.247434)
		(width 0.12065)
		(layer "In4.Cu")
		(net "I2C_DPB_A_SCL_BUF")
	)
	(segment
		(start 260.477 5.205984)
		(end 260.477 18.3642)
		(width 0.12065)
		(layer "In4.Cu")
		(net "I2C_DPB_A_SCL_BUF")
	)
	(segment
		(start 266.893802 -217.207338)
		(end 262.04926 -222.05188)
		(width 0.12065)
		(layer "In4.Cu")
		(net "I2C_DPB_A_SCL_BUF")
	)
	(segment
		(start 259.77215 -131.049776)
		(end 259.77215 -20.509992)
		(width 0.12065)
		(layer "In4.Cu")
		(net "I2C_DPB_A_SCL_BUF")
	)
	(segment
		(start 260.58876 -289.725354)
		(end 260.58876 -300.193202)
		(width 0.12065)
		(layer "In4.Cu")
		(net "I2C_DPB_A_SCL_BUF")
	)
	(segment
		(start 266.893802 -208.626202)
		(end 261.688072 -203.420472)
		(width 0.12065)
		(layer "In4.Cu")
		(net "I2C_DPB_A_SCL_BUF")
	)
	(segment
		(start 260.696202 -285.471362)
		(end 260.181852 -285.985712)
		(width 0.12065)
		(layer "In4.Cu")
		(net "I2C_DPB_A_SCL_BUF")
	)
	(segment
		(start 259.6642 -260.35889)
		(end 259.6642 -270.651986)
		(width 0.12065)
		(layer "In4.Cu")
		(net "I2C_DPB_A_SCL_BUF")
	)
	(segment
		(start 259.832602 -274.194524)
		(end 260.696202 -275.058124)
		(width 0.12065)
		(layer "In4.Cu")
		(net "I2C_DPB_A_SCL_BUF")
	)
	(segment
		(start 262.04926 -223.847914)
		(end 263.229852 -225.028506)
		(width 0.12065)
		(layer "In4.Cu")
		(net "I2C_DPB_A_SCL_BUF")
	)
	(segment
		(start 260.181852 -285.985712)
		(end 260.181852 -289.318446)
		(width 0.12065)
		(layer "In4.Cu")
		(net "I2C_DPB_A_SCL_BUF")
	)
	(segment
		(start 266.893802 -210.607402)
		(end 266.893802 -208.626202)
		(width 0.12065)
		(layer "In4.Cu")
		(net "I2C_DPB_A_SCL_BUF")
	)
	(segment
		(start 259.404104 -253.915418)
		(end 259.404104 -259.542534)
		(width 0.12065)
		(layer "In4.Cu")
		(net "I2C_DPB_A_SCL_BUF")
	)
	(segment
		(start 262.401812 3.281172)
		(end 260.477 5.205984)
		(width 0.12065)
		(layer "In4.Cu")
		(net "I2C_DPB_A_SCL_BUF")
	)
	(segment
		(start 262.54075 -235.247434)
		(end 262.54075 -250.778772)
		(width 0.12065)
		(layer "In4.Cu")
		(net "I2C_DPB_A_SCL_BUF")
	)
	(segment
		(start 223.48825 -351.33407)
		(end 221.9198 -349.76562)
		(width 0.12065)
		(layer "In7.Cu")
		(net "I2C_DPB_A_SCL_BUF")
	)
	(segment
		(start 226.813364 -380.881636)
		(end 228.3206 -379.3744)
		(width 0.12065)
		(layer "In7.Cu")
		(net "I2C_DPB_A_SCL_BUF")
	)
	(segment
		(start 221.9198 -349.76562)
		(end 221.9198 -349.439484)
		(width 0.12065)
		(layer "In7.Cu")
		(net "I2C_DPB_A_SCL_BUF")
	)
	(segment
		(start 228.3206 -379.3744)
		(end 228.3206 -362.323888)
		(width 0.12065)
		(layer "In7.Cu")
		(net "I2C_DPB_A_SCL_BUF")
	)
	(segment
		(start 226.813364 -383.171446)
		(end 226.813364 -380.881636)
		(width 0.12065)
		(layer "In7.Cu")
		(net "I2C_DPB_A_SCL_BUF")
	)
	(segment
		(start 223.48825 -357.491538)
		(end 223.48825 -351.33407)
		(width 0.12065)
		(layer "In7.Cu")
		(net "I2C_DPB_A_SCL_BUF")
	)
	(segment
		(start 228.3206 -362.323888)
		(end 223.48825 -357.491538)
		(width 0.12065)
		(layer "In7.Cu")
		(net "I2C_DPB_A_SCL_BUF")
	)
	(segment
		(start 259.568696 -303.815496)
		(end 258.407916 -303.815496)
		(width 0.13335)
		(layer "In9.Cu")
		(net "I2C_DPB_A_SCL_BUF")
	)
	(segment
		(start 258.080256 -335.56194)
		(end 274.890738 -335.56194)
		(width 0.13335)
		(layer "In9.Cu")
		(net "I2C_DPB_A_SCL_BUF")
	)
	(segment
		(start 260.051042 -322.914518)
		(end 260.051042 -304.297842)
		(width 0.13335)
		(layer "In9.Cu")
		(net "I2C_DPB_A_SCL_BUF")
	)
	(segment
		(start 235.998512 -349.350838)
		(end 244.291358 -349.350838)
		(width 0.13335)
		(layer "In9.Cu")
		(net "I2C_DPB_A_SCL_BUF")
	)
	(segment
		(start 235.256324 -351.032318)
		(end 235.256324 -350.093026)
		(width 0.13335)
		(layer "In9.Cu")
		(net "I2C_DPB_A_SCL_BUF")
	)
	(segment
		(start 275.828252 -333.017876)
		(end 270.1544 -333.017876)
		(width 0.13335)
		(layer "In9.Cu")
		(net "I2C_DPB_A_SCL_BUF")
	)
	(segment
		(start 235.610654 -351.645982)
		(end 235.610654 -351.386648)
		(width 0.13335)
		(layer "In9.Cu")
		(net "I2C_DPB_A_SCL_BUF")
	)
	(segment
		(start 235.256324 -350.093026)
		(end 235.998512 -349.350838)
		(width 0.13335)
		(layer "In9.Cu")
		(net "I2C_DPB_A_SCL_BUF")
	)
	(segment
		(start 275.980652 -333.170276)
		(end 275.828252 -333.017876)
		(width 0.13335)
		(layer "In9.Cu")
		(net "I2C_DPB_A_SCL_BUF")
	)
	(segment
		(start 274.99818 -335.454498)
		(end 282.08732 -335.454498)
		(width 0.13335)
		(layer "In9.Cu")
		(net "I2C_DPB_A_SCL_BUF")
	)
	(segment
		(start 274.890738 -335.56194)
		(end 274.99818 -335.454498)
		(width 0.13335)
		(layer "In9.Cu")
		(net "I2C_DPB_A_SCL_BUF")
	)
	(segment
		(start 282.08732 -335.454498)
		(end 283.23667 -334.305148)
		(width 0.13335)
		(layer "In9.Cu")
		(net "I2C_DPB_A_SCL_BUF")
	)
	(segment
		(start 260.051042 -304.297842)
		(end 259.568696 -303.815496)
		(width 0.13335)
		(layer "In9.Cu")
		(net "I2C_DPB_A_SCL_BUF")
	)
	(segment
		(start 235.610654 -351.386648)
		(end 235.256324 -351.032318)
		(width 0.13335)
		(layer "In9.Cu")
		(net "I2C_DPB_A_SCL_BUF")
	)
	(segment
		(start 270.1544 -333.017876)
		(end 260.051042 -322.914518)
		(width 0.13335)
		(layer "In9.Cu")
		(net "I2C_DPB_A_SCL_BUF")
	)
	(segment
		(start 282.101798 -333.170276)
		(end 275.980652 -333.170276)
		(width 0.13335)
		(layer "In9.Cu")
		(net "I2C_DPB_A_SCL_BUF")
	)
	(segment
		(start 244.291358 -349.350838)
		(end 258.080256 -335.56194)
		(width 0.13335)
		(layer "In9.Cu")
		(net "I2C_DPB_A_SCL_BUF")
	)
	(segment
		(start 283.23667 -334.305148)
		(end 282.101798 -333.170276)
		(width 0.13335)
		(layer "In9.Cu")
		(net "I2C_DPB_A_SCL_BUF")
	)
	(segment
		(start 281.920188 15.612364)
		(end 282.21813 15.314422)
		(width 0.17145)
		(layer "F.Cu")
		(net "DPB_PWR_BTN_BUF_B")
	)
	(segment
		(start 281.920188 16.540734)
		(end 281.920188 15.612364)
		(width 0.17145)
		(layer "F.Cu")
		(net "DPB_PWR_BTN_BUF_B")
	)
	(segment
		(start 284.48 15.6718)
		(end 284.48 22.5298)
		(width 0.254)
		(layer "F.Cu")
		(net "DPB_PWR_BTN_BUF_B")
	)
	(segment
		(start 282.391612 15.314422)
		(end 283.363162 15.314422)
		(width 0.17145)
		(layer "F.Cu")
		(net "DPB_PWR_BTN_BUF_B")
	)
	(segment
		(start 282.21813 15.314422)
		(end 282.391612 15.314422)
		(width 0.17145)
		(layer "F.Cu")
		(net "DPB_PWR_BTN_BUF_B")
	)
	(segment
		(start 284.48 22.5298)
		(end 284.2514 22.7584)
		(width 0.254)
		(layer "F.Cu")
		(net "DPB_PWR_BTN_BUF_B")
	)
	(segment
		(start 284.2514 22.7584)
		(end 282.7909 22.7584)
		(width 0.254)
		(layer "F.Cu")
		(net "DPB_PWR_BTN_BUF_B")
	)
	(segment
		(start 284.122622 15.314422)
		(end 284.48 15.6718)
		(width 0.254)
		(layer "F.Cu")
		(net "DPB_PWR_BTN_BUF_B")
	)
	(segment
		(start 283.363162 15.314422)
		(end 284.122622 15.314422)
		(width 0.254)
		(layer "F.Cu")
		(net "DPB_PWR_BTN_BUF_B")
	)
	(via
		(at 283.363162 15.314422)
		(size 0.5588)
		(drill 0.3048)
		(layers "F.Cu" "B.Cu")
		(net "DPB_PWR_BTN_BUF_B")
	)
	(via
		(at 252.01499 13.820394)
		(size 0.5588)
		(drill 0.3048)
		(layers "F.Cu" "B.Cu")
		(net "DPB_PWR_BTN_BUF_B")
	)
	(via
		(at 282.391612 15.314422)
		(size 0.6604)
		(drill 0.3302)
		(layers "F.Cu" "B.Cu")
		(net "DPB_PWR_BTN_BUF_B")
	)
	(segment
		(start 281.741372 15.314422)
		(end 283.363162 15.314422)
		(width 0.254)
		(layer "In2.Cu")
		(net "DPB_PWR_BTN_BUF_B")
	)
	(segment
		(start 255.778 13.5382)
		(end 262.2804 13.5382)
		(width 0.254)
		(layer "In2.Cu")
		(net "DPB_PWR_BTN_BUF_B")
	)
	(segment
		(start 255.495806 13.820394)
		(end 255.778 13.5382)
		(width 0.254)
		(layer "In2.Cu")
		(net "DPB_PWR_BTN_BUF_B")
	)
	(segment
		(start 278.66975 12.2428)
		(end 281.741372 15.314422)
		(width 0.254)
		(layer "In2.Cu")
		(net "DPB_PWR_BTN_BUF_B")
	)
	(segment
		(start 263.5758 12.2428)
		(end 278.66975 12.2428)
		(width 0.254)
		(layer "In2.Cu")
		(net "DPB_PWR_BTN_BUF_B")
	)
	(segment
		(start 262.2804 13.5382)
		(end 263.5758 12.2428)
		(width 0.254)
		(layer "In2.Cu")
		(net "DPB_PWR_BTN_BUF_B")
	)
	(segment
		(start 252.01499 13.820394)
		(end 255.495806 13.820394)
		(width 0.254)
		(layer "In2.Cu")
		(net "DPB_PWR_BTN_BUF_B")
	)
	(segment
		(start 224.599754 -215.749378)
		(end 224.599754 -214.907622)
		(width 0.254)
		(layer "In4.Cu")
		(net "DPB_PWR_BTN_BUF_B")
	)
	(segment
		(start 214.996268 -384.941826)
		(end 214.996268 -325.137272)
		(width 0.254)
		(layer "In4.Cu")
		(net "DPB_PWR_BTN_BUF_B")
	)
	(segment
		(start 216.090754 -391.548112)
		(end 215.41486 -390.872218)
		(width 0.254)
		(layer "In4.Cu")
		(net "DPB_PWR_BTN_BUF_B")
	)
	(segment
		(start 221.386654 -221.164912)
		(end 223.5835 -218.968066)
		(width 0.254)
		(layer "In4.Cu")
		(net "DPB_PWR_BTN_BUF_B")
	)
	(segment
		(start 221.386654 -318.746886)
		(end 221.386654 -221.164912)
		(width 0.254)
		(layer "In4.Cu")
		(net "DPB_PWR_BTN_BUF_B")
	)
	(segment
		(start 224.584768 -402.99513)
		(end 216.090754 -394.501116)
		(width 0.254)
		(layer "In4.Cu")
		(net "DPB_PWR_BTN_BUF_B")
	)
	(segment
		(start 226.200208 -409.50007)
		(end 224.584768 -407.88463)
		(width 0.254)
		(layer "In4.Cu")
		(net "DPB_PWR_BTN_BUF_B")
	)
	(segment
		(start 252.01499 9.249156)
		(end 252.01499 13.820394)
		(width 0.254)
		(layer "In4.Cu")
		(net "DPB_PWR_BTN_BUF_B")
	)
	(segment
		(start 253.34087 -26.567892)
		(end 253.34087 -10.754868)
		(width 0.254)
		(layer "In4.Cu")
		(net "DPB_PWR_BTN_BUF_B")
	)
	(segment
		(start 215.41486 -385.360418)
		(end 214.996268 -384.941826)
		(width 0.254)
		(layer "In4.Cu")
		(net "DPB_PWR_BTN_BUF_B")
	)
	(segment
		(start 253.34087 -10.754868)
		(end 253.675896 -10.419842)
		(width 0.254)
		(layer "In4.Cu")
		(net "DPB_PWR_BTN_BUF_B")
	)
	(segment
		(start 223.5835 -218.968066)
		(end 223.5835 -216.765632)
		(width 0.254)
		(layer "In4.Cu")
		(net "DPB_PWR_BTN_BUF_B")
	)
	(segment
		(start 224.5995 -214.907368)
		(end 224.5995 -210.6295)
		(width 0.254)
		(layer "In4.Cu")
		(net "DPB_PWR_BTN_BUF_B")
	)
	(segment
		(start 246.507 -193.0908)
		(end 246.507 -163.278058)
		(width 0.254)
		(layer "In4.Cu")
		(net "DPB_PWR_BTN_BUF_B")
	)
	(segment
		(start 224.5995 -210.6295)
		(end 238.506 -196.723)
		(width 0.254)
		(layer "In4.Cu")
		(net "DPB_PWR_BTN_BUF_B")
	)
	(segment
		(start 215.41486 -390.872218)
		(end 215.41486 -385.360418)
		(width 0.254)
		(layer "In4.Cu")
		(net "DPB_PWR_BTN_BUF_B")
	)
	(segment
		(start 246.507 -163.278058)
		(end 251.888244 -157.896814)
		(width 0.254)
		(layer "In4.Cu")
		(net "DPB_PWR_BTN_BUF_B")
	)
	(segment
		(start 251.888244 -157.896814)
		(end 251.888244 -137.790936)
		(width 0.254)
		(layer "In4.Cu")
		(net "DPB_PWR_BTN_BUF_B")
	)
	(segment
		(start 253.675896 7.58825)
		(end 252.01499 9.249156)
		(width 0.254)
		(layer "In4.Cu")
		(net "DPB_PWR_BTN_BUF_B")
	)
	(segment
		(start 214.996268 -325.137272)
		(end 221.386654 -318.746886)
		(width 0.254)
		(layer "In4.Cu")
		(net "DPB_PWR_BTN_BUF_B")
	)
	(segment
		(start 249.06478 -94.21876)
		(end 253.675896 -89.607644)
		(width 0.254)
		(layer "In4.Cu")
		(net "DPB_PWR_BTN_BUF_B")
	)
	(segment
		(start 216.090754 -394.501116)
		(end 216.090754 -391.548112)
		(width 0.254)
		(layer "In4.Cu")
		(net "DPB_PWR_BTN_BUF_B")
	)
	(segment
		(start 224.599754 -214.907622)
		(end 224.5995 -214.907368)
		(width 0.254)
		(layer "In4.Cu")
		(net "DPB_PWR_BTN_BUF_B")
	)
	(segment
		(start 253.675896 -10.419842)
		(end 253.675896 7.58825)
		(width 0.254)
		(layer "In4.Cu")
		(net "DPB_PWR_BTN_BUF_B")
	)
	(segment
		(start 253.675896 -89.607644)
		(end 253.675896 -26.902918)
		(width 0.254)
		(layer "In4.Cu")
		(net "DPB_PWR_BTN_BUF_B")
	)
	(segment
		(start 253.675896 -26.902918)
		(end 253.34087 -26.567892)
		(width 0.254)
		(layer "In4.Cu")
		(net "DPB_PWR_BTN_BUF_B")
	)
	(segment
		(start 249.06478 -134.967472)
		(end 249.06478 -94.21876)
		(width 0.254)
		(layer "In4.Cu")
		(net "DPB_PWR_BTN_BUF_B")
	)
	(segment
		(start 223.5835 -216.765632)
		(end 224.599754 -215.749378)
		(width 0.254)
		(layer "In4.Cu")
		(net "DPB_PWR_BTN_BUF_B")
	)
	(segment
		(start 242.8748 -196.723)
		(end 246.507 -193.0908)
		(width 0.254)
		(layer "In4.Cu")
		(net "DPB_PWR_BTN_BUF_B")
	)
	(segment
		(start 251.888244 -137.790936)
		(end 249.06478 -134.967472)
		(width 0.254)
		(layer "In4.Cu")
		(net "DPB_PWR_BTN_BUF_B")
	)
	(segment
		(start 238.506 -196.723)
		(end 242.8748 -196.723)
		(width 0.254)
		(layer "In4.Cu")
		(net "DPB_PWR_BTN_BUF_B")
	)
	(segment
		(start 224.584768 -407.88463)
		(end 224.584768 -402.99513)
		(width 0.254)
		(layer "In4.Cu")
		(net "DPB_PWR_BTN_BUF_B")
	)
	(segment
		(start 228.407468 -386.090668)
		(end 227.67671 -386.090668)
		(width 0.17145)
		(layer "F.Cu")
		(net "DPB_PWR_BTN_BUF_A")
	)
	(segment
		(start 227.66909 -386.098288)
		(end 227.66909 -387.339332)
		(width 0.17145)
		(layer "F.Cu")
		(net "DPB_PWR_BTN_BUF_A")
	)
	(segment
		(start 280.619708 16.540734)
		(end 280.619708 15.621508)
		(width 0.17145)
		(layer "F.Cu")
		(net "DPB_PWR_BTN_BUF_A")
	)
	(segment
		(start 280.619708 15.621508)
		(end 280.2382 15.24)
		(width 0.17145)
		(layer "F.Cu")
		(net "DPB_PWR_BTN_BUF_A")
	)
	(segment
		(start 230.6193 -386.715)
		(end 229.0318 -386.715)
		(width 0.17145)
		(layer "F.Cu")
		(net "DPB_PWR_BTN_BUF_A")
	)
	(segment
		(start 227.66909 -387.339332)
		(end 226.811332 -387.339332)
		(width 0.17145)
		(layer "F.Cu")
		(net "DPB_PWR_BTN_BUF_A")
	)
	(segment
		(start 279.273 15.6464)
		(end 279.273 19.2024)
		(width 0.254)
		(layer "F.Cu")
		(net "DPB_PWR_BTN_BUF_A")
	)
	(segment
		(start 227.67671 -386.090668)
		(end 227.66909 -386.098288)
		(width 0.17145)
		(layer "F.Cu")
		(net "DPB_PWR_BTN_BUF_A")
	)
	(segment
		(start 279.273 19.2024)
		(end 279.6159 19.5453)
		(width 0.254)
		(layer "F.Cu")
		(net "DPB_PWR_BTN_BUF_A")
	)
	(segment
		(start 279.6794 15.24)
		(end 279.273 15.6464)
		(width 0.254)
		(layer "F.Cu")
		(net "DPB_PWR_BTN_BUF_A")
	)
	(segment
		(start 228.662992 -386.346192)
		(end 228.407468 -386.090668)
		(width 0.17145)
		(layer "F.Cu")
		(net "DPB_PWR_BTN_BUF_A")
	)
	(segment
		(start 226.811332 -387.339332)
		(end 226.7458 -387.2738)
		(width 0.17145)
		(layer "F.Cu")
		(net "DPB_PWR_BTN_BUF_A")
	)
	(segment
		(start 280.2382 15.24)
		(end 279.6794 15.24)
		(width 0.254)
		(layer "F.Cu")
		(net "DPB_PWR_BTN_BUF_A")
	)
	(segment
		(start 229.0318 -386.715)
		(end 228.662992 -386.346192)
		(width 0.17145)
		(layer "F.Cu")
		(net "DPB_PWR_BTN_BUF_A")
	)
	(segment
		(start 279.6159 19.5453)
		(end 279.6159 19.9136)
		(width 0.254)
		(layer "F.Cu")
		(net "DPB_PWR_BTN_BUF_A")
	)
	(via
		(at 228.662992 -386.346192)
		(size 0.6604)
		(drill 0.3302)
		(layers "F.Cu" "B.Cu")
		(net "DPB_PWR_BTN_BUF_A")
	)
	(via
		(at 252.222 15.3924)
		(size 0.5588)
		(drill 0.3048)
		(layers "F.Cu" "B.Cu")
		(net "DPB_PWR_BTN_BUF_A")
	)
	(via
		(at 226.7458 -387.2738)
		(size 0.5588)
		(drill 0.3048)
		(layers "F.Cu" "B.Cu")
		(net "DPB_PWR_BTN_BUF_A")
	)
	(via
		(at 280.2382 15.24)
		(size 0.5588)
		(drill 0.3048)
		(layers "F.Cu" "B.Cu")
		(net "DPB_PWR_BTN_BUF_A")
	)
	(segment
		(start 257.805428 15.02918)
		(end 258.016248 15.24)
		(width 0.254)
		(layer "In2.Cu")
		(net "DPB_PWR_BTN_BUF_A")
	)
	(segment
		(start 252.222 15.3924)
		(end 252.58522 15.02918)
		(width 0.254)
		(layer "In2.Cu")
		(net "DPB_PWR_BTN_BUF_A")
	)
	(segment
		(start 269.3416 13.4366)
		(end 278.4348 13.4366)
		(width 0.254)
		(layer "In2.Cu")
		(net "DPB_PWR_BTN_BUF_A")
	)
	(segment
		(start 267.5382 15.24)
		(end 269.3416 13.4366)
		(width 0.254)
		(layer "In2.Cu")
		(net "DPB_PWR_BTN_BUF_A")
	)
	(segment
		(start 258.016248 15.24)
		(end 267.5382 15.24)
		(width 0.254)
		(layer "In2.Cu")
		(net "DPB_PWR_BTN_BUF_A")
	)
	(segment
		(start 278.4348 13.4366)
		(end 280.2382 15.24)
		(width 0.254)
		(layer "In2.Cu")
		(net "DPB_PWR_BTN_BUF_A")
	)
	(segment
		(start 252.58522 15.02918)
		(end 257.805428 15.02918)
		(width 0.254)
		(layer "In2.Cu")
		(net "DPB_PWR_BTN_BUF_A")
	)
	(segment
		(start 226.4918 -357.325676)
		(end 226.4918 -344.240104)
		(width 0.254)
		(layer "In4.Cu")
		(net "DPB_PWR_BTN_BUF_A")
	)
	(segment
		(start 227.903278 -366.078008)
		(end 227.903278 -358.737154)
		(width 0.254)
		(layer "In4.Cu")
		(net "DPB_PWR_BTN_BUF_A")
	)
	(segment
		(start 226.927664 -250.19508)
		(end 226.939094 -250.18365)
		(width 0.254)
		(layer "In4.Cu")
		(net "DPB_PWR_BTN_BUF_A")
	)
	(segment
		(start 226.927664 -321.612514)
		(end 226.927664 -250.19508)
		(width 0.254)
		(layer "In4.Cu")
		(net "DPB_PWR_BTN_BUF_A")
	)
	(segment
		(start 253.816358 9.415272)
		(end 253.816358 13.812012)
		(width 0.254)
		(layer "In4.Cu")
		(net "DPB_PWR_BTN_BUF_A")
	)
	(segment
		(start 253.279148 -158.622238)
		(end 253.279148 -137.079228)
		(width 0.254)
		(layer "In4.Cu")
		(net "DPB_PWR_BTN_BUF_A")
	)
	(segment
		(start 225.68027 -368.301016)
		(end 227.903278 -366.078008)
		(width 0.254)
		(layer "In4.Cu")
		(net "DPB_PWR_BTN_BUF_A")
	)
	(segment
		(start 254.731774 -25.991312)
		(end 254.731774 -11.331448)
		(width 0.254)
		(layer "In4.Cu")
		(net "DPB_PWR_BTN_BUF_A")
	)
	(segment
		(start 228.860096 -323.544946)
		(end 226.927664 -321.612514)
		(width 0.254)
		(layer "In4.Cu")
		(net "DPB_PWR_BTN_BUF_A")
	)
	(segment
		(start 226.939094 -250.18365)
		(end 226.939094 -225.053906)
		(width 0.254)
		(layer "In4.Cu")
		(net "DPB_PWR_BTN_BUF_A")
	)
	(segment
		(start 255.286256 -89.964768)
		(end 255.286256 -26.545794)
		(width 0.254)
		(layer "In4.Cu")
		(net "DPB_PWR_BTN_BUF_A")
	)
	(segment
		(start 225.1964 -377.50623)
		(end 225.68027 -377.02236)
		(width 0.254)
		(layer "In4.Cu")
		(net "DPB_PWR_BTN_BUF_A")
	)
	(segment
		(start 254.731774 -11.331448)
		(end 255.68783 -10.375392)
		(width 0.254)
		(layer "In4.Cu")
		(net "DPB_PWR_BTN_BUF_A")
	)
	(segment
		(start 225.1964 -385.7244)
		(end 225.1964 -377.50623)
		(width 0.254)
		(layer "In4.Cu")
		(net "DPB_PWR_BTN_BUF_A")
	)
	(segment
		(start 255.286256 -26.545794)
		(end 254.731774 -25.991312)
		(width 0.254)
		(layer "In4.Cu")
		(net "DPB_PWR_BTN_BUF_A")
	)
	(segment
		(start 249.790966 -202.202034)
		(end 249.790966 -162.11042)
		(width 0.254)
		(layer "In4.Cu")
		(net "DPB_PWR_BTN_BUF_A")
	)
	(segment
		(start 228.860096 -341.871808)
		(end 228.860096 -323.544946)
		(width 0.254)
		(layer "In4.Cu")
		(net "DPB_PWR_BTN_BUF_A")
	)
	(segment
		(start 255.68783 -10.375392)
		(end 255.68783 7.5438)
		(width 0.254)
		(layer "In4.Cu")
		(net "DPB_PWR_BTN_BUF_A")
	)
	(segment
		(start 226.7458 -387.2738)
		(end 225.1964 -385.7244)
		(width 0.254)
		(layer "In4.Cu")
		(net "DPB_PWR_BTN_BUF_A")
	)
	(segment
		(start 227.903278 -358.737154)
		(end 226.4918 -357.325676)
		(width 0.254)
		(layer "In4.Cu")
		(net "DPB_PWR_BTN_BUF_A")
	)
	(segment
		(start 250.596654 -94.65437)
		(end 255.286256 -89.964768)
		(width 0.254)
		(layer "In4.Cu")
		(net "DPB_PWR_BTN_BUF_A")
	)
	(segment
		(start 250.596654 -134.396734)
		(end 250.596654 -94.65437)
		(width 0.254)
		(layer "In4.Cu")
		(net "DPB_PWR_BTN_BUF_A")
	)
	(segment
		(start 225.68027 -377.02236)
		(end 225.68027 -368.301016)
		(width 0.254)
		(layer "In4.Cu")
		(net "DPB_PWR_BTN_BUF_A")
	)
	(segment
		(start 252.222 15.40637)
		(end 252.222 15.3924)
		(width 0.254)
		(layer "In4.Cu")
		(net "DPB_PWR_BTN_BUF_A")
	)
	(segment
		(start 253.279148 -137.079228)
		(end 250.596654 -134.396734)
		(width 0.254)
		(layer "In4.Cu")
		(net "DPB_PWR_BTN_BUF_A")
	)
	(segment
		(start 253.816358 13.812012)
		(end 252.222 15.40637)
		(width 0.254)
		(layer "In4.Cu")
		(net "DPB_PWR_BTN_BUF_A")
	)
	(segment
		(start 249.790966 -162.11042)
		(end 253.279148 -158.622238)
		(width 0.254)
		(layer "In4.Cu")
		(net "DPB_PWR_BTN_BUF_A")
	)
	(segment
		(start 255.68783 7.5438)
		(end 253.816358 9.415272)
		(width 0.254)
		(layer "In4.Cu")
		(net "DPB_PWR_BTN_BUF_A")
	)
	(segment
		(start 226.4918 -344.240104)
		(end 228.860096 -341.871808)
		(width 0.254)
		(layer "In4.Cu")
		(net "DPB_PWR_BTN_BUF_A")
	)
	(segment
		(start 226.939094 -225.053906)
		(end 249.790966 -202.202034)
		(width 0.254)
		(layer "In4.Cu")
		(net "DPB_PWR_BTN_BUF_A")
	)
	(segment
		(start 227.501704 -345.933522)
		(end 221.604078 -345.933522)
		(width 0.17145)
		(layer "F.Cu")
		(net "VOL_SEN_INT_N")
	)
	(segment
		(start 221.205806 -346.331794)
		(end 220.861636 -346.331794)
		(width 0.17145)
		(layer "F.Cu")
		(net "VOL_SEN_INT_N")
	)
	(segment
		(start 220.629988 -345.066112)
		(end 220.629988 -346.100146)
		(width 0.17145)
		(layer "F.Cu")
		(net "VOL_SEN_INT_N")
	)
	(segment
		(start 220.629988 -346.100146)
		(end 220.861636 -346.331794)
		(width 0.17145)
		(layer "F.Cu")
		(net "VOL_SEN_INT_N")
	)
	(segment
		(start 221.604078 -345.933522)
		(end 221.205806 -346.331794)
		(width 0.17145)
		(layer "F.Cu")
		(net "VOL_SEN_INT_N")
	)
	(segment
		(start 226.3521 -344.3351)
		(end 226.3521 -343.475564)
		(width 0.17145)
		(layer "F.Cu")
		(net "VOL_SEN_ADDR1")
	)
	(segment
		(start 224.998788 -342.122252)
		(end 225.862642 -342.986106)
		(width 0.17145)
		(layer "F.Cu")
		(net "VOL_SEN_ADDR1")
	)
	(segment
		(start 222.69196 -342.128856)
		(end 223.874076 -342.128856)
		(width 0.17145)
		(layer "F.Cu")
		(net "VOL_SEN_ADDR1")
	)
	(segment
		(start 227.501704 -344.633042)
		(end 226.650042 -344.633042)
		(width 0.17145)
		(layer "F.Cu")
		(net "VOL_SEN_ADDR1")
	)
	(segment
		(start 226.3521 -343.475564)
		(end 225.862642 -342.986106)
		(width 0.17145)
		(layer "F.Cu")
		(net "VOL_SEN_ADDR1")
	)
	(segment
		(start 223.88068 -342.122252)
		(end 224.998788 -342.122252)
		(width 0.17145)
		(layer "F.Cu")
		(net "VOL_SEN_ADDR1")
	)
	(segment
		(start 223.874076 -342.128856)
		(end 223.88068 -342.122252)
		(width 0.17145)
		(layer "F.Cu")
		(net "VOL_SEN_ADDR1")
	)
	(segment
		(start 226.650042 -344.633042)
		(end 226.3521 -344.3351)
		(width 0.17145)
		(layer "F.Cu")
		(net "VOL_SEN_ADDR1")
	)
	(via
		(at 225.862642 -342.986106)
		(size 0.6604)
		(drill 0.3302)
		(layers "F.Cu" "B.Cu")
		(net "VOL_SEN_ADDR1")
	)
	(segment
		(start 223.887792 -344.184478)
		(end 222.693992 -344.184478)
		(width 0.17145)
		(layer "F.Cu")
		(net "VOL_SEN_ADDR0")
	)
	(segment
		(start 226.43084 -345.283282)
		(end 225.715322 -344.567764)
		(width 0.17145)
		(layer "F.Cu")
		(net "VOL_SEN_ADDR0")
	)
	(segment
		(start 225.332036 -344.184478)
		(end 223.887792 -344.184478)
		(width 0.17145)
		(layer "F.Cu")
		(net "VOL_SEN_ADDR0")
	)
	(segment
		(start 227.501704 -345.283282)
		(end 226.43084 -345.283282)
		(width 0.17145)
		(layer "F.Cu")
		(net "VOL_SEN_ADDR0")
	)
	(segment
		(start 225.715322 -344.567764)
		(end 225.332036 -344.184478)
		(width 0.17145)
		(layer "F.Cu")
		(net "VOL_SEN_ADDR0")
	)
	(via
		(at 225.715322 -344.567764)
		(size 0.6604)
		(drill 0.3302)
		(layers "F.Cu" "B.Cu")
		(net "VOL_SEN_ADDR0")
	)
	(segment
		(start 269.8496 18.991834)
		(end 269.766034 19.0754)
		(width 0.17145)
		(layer "F.Cu")
		(net "USB_OCS_N2")
	)
	(segment
		(start 269.766034 19.0754)
		(end 269.766034 19.450812)
		(width 0.17145)
		(layer "F.Cu")
		(net "USB_OCS_N2")
	)
	(segment
		(start 269.8496 18.091658)
		(end 269.8496 18.4912)
		(width 0.17145)
		(layer "F.Cu")
		(net "USB_OCS_N2")
	)
	(segment
		(start 269.766542 16.915638)
		(end 269.766542 18.0086)
		(width 0.17145)
		(layer "F.Cu")
		(net "USB_OCS_N2")
	)
	(segment
		(start 269.766034 20.555712)
		(end 269.778734 20.568412)
		(width 0.17145)
		(layer "F.Cu")
		(net "USB_OCS_N2")
	)
	(segment
		(start 269.766542 18.0086)
		(end 269.8496 18.091658)
		(width 0.17145)
		(layer "F.Cu")
		(net "USB_OCS_N2")
	)
	(segment
		(start 269.8496 18.4912)
		(end 269.8496 18.991834)
		(width 0.17145)
		(layer "F.Cu")
		(net "USB_OCS_N2")
	)
	(segment
		(start 269.766034 19.450812)
		(end 269.766034 20.555712)
		(width 0.17145)
		(layer "F.Cu")
		(net "USB_OCS_N2")
	)
	(via
		(at 269.8496 18.4912)
		(size 0.6604)
		(drill 0.3302)
		(layers "F.Cu" "B.Cu")
		(net "USB_OCS_N2")
	)
	(segment
		(start 264.04824 16.62176)
		(end 264.04824 15.58417)
		(width 0.17145)
		(layer "F.Cu")
		(net "USB_OCS_N1")
	)
	(segment
		(start 263.857232 17.1958)
		(end 263.857232 16.812768)
		(width 0.17145)
		(layer "F.Cu")
		(net "USB_OCS_N1")
	)
	(segment
		(start 263.857232 19.287744)
		(end 263.857232 18.170144)
		(width 0.17145)
		(layer "F.Cu")
		(net "USB_OCS_N1")
	)
	(segment
		(start 263.857232 16.812768)
		(end 264.04824 16.62176)
		(width 0.17145)
		(layer "F.Cu")
		(net "USB_OCS_N1")
	)
	(segment
		(start 263.857232 18.170144)
		(end 263.857232 17.1958)
		(width 0.17145)
		(layer "F.Cu")
		(net "USB_OCS_N1")
	)
	(via
		(at 263.857232 17.1958)
		(size 0.6604)
		(drill 0.3302)
		(layers "F.Cu" "B.Cu")
		(net "USB_OCS_N1")
	)
	(segment
		(start 270.82115 12.0523)
		(end 269.57655 12.0523)
		(width 0.17145)
		(layer "F.Cu")
		(net "USB_EN_2")
	)
	(segment
		(start 269.57655 12.789408)
		(end 269.766542 12.9794)
		(width 0.17145)
		(layer "F.Cu")
		(net "USB_EN_2")
	)
	(segment
		(start 269.57655 12.0523)
		(end 269.57655 12.789408)
		(width 0.17145)
		(layer "F.Cu")
		(net "USB_EN_2")
	)
	(segment
		(start 269.766542 12.9794)
		(end 269.766542 14.629638)
		(width 0.17145)
		(layer "F.Cu")
		(net "USB_EN_2")
	)
	(via
		(at 269.766542 12.9794)
		(size 0.6604)
		(drill 0.3302)
		(layers "F.Cu" "B.Cu")
		(net "USB_EN_2")
	)
	(segment
		(start 264.950448 10.682732)
		(end 264.937748 10.670032)
		(width 0.17145)
		(layer "F.Cu")
		(net "USB_EN_1")
	)
	(segment
		(start 263.832848 10.670032)
		(end 263.832848 11.052048)
		(width 0.17145)
		(layer "F.Cu")
		(net "USB_EN_1")
	)
	(segment
		(start 264.04824 11.6586)
		(end 264.04824 13.29817)
		(width 0.17145)
		(layer "F.Cu")
		(net "USB_EN_1")
	)
	(segment
		(start 264.937748 10.670032)
		(end 263.832848 10.670032)
		(width 0.17145)
		(layer "F.Cu")
		(net "USB_EN_1")
	)
	(segment
		(start 264.04824 11.26744)
		(end 264.04824 11.6586)
		(width 0.17145)
		(layer "F.Cu")
		(net "USB_EN_1")
	)
	(segment
		(start 263.832848 11.052048)
		(end 264.04824 11.26744)
		(width 0.17145)
		(layer "F.Cu")
		(net "USB_EN_1")
	)
	(via
		(at 264.04824 11.6586)
		(size 0.6604)
		(drill 0.3302)
		(layers "F.Cu" "B.Cu")
		(net "USB_EN_1")
	)
	(via
		(at 373.788432 -195.199)
		(size 0.5588)
		(drill 0.3048)
		(layers "F.Cu" "B.Cu")
		(net "UART_SDB_B_TX")
	)
	(via
		(at 243.237766 -194.622674)
		(size 0.5588)
		(drill 0.3048)
		(layers "F.Cu" "B.Cu")
		(net "UART_SDB_B_TX")
	)
	(segment
		(start 319.51041 -196.05879)
		(end 331.34681 -196.05879)
		(width 0.13335)
		(layer "In2.Cu")
		(net "UART_SDB_B_TX")
	)
	(segment
		(start 373.642382 -195.34505)
		(end 373.788432 -195.199)
		(width 0.13335)
		(layer "In2.Cu")
		(net "UART_SDB_B_TX")
	)
	(segment
		(start 249.858784 -200.514458)
		(end 315.054742 -200.514458)
		(width 0.13335)
		(layer "In2.Cu")
		(net "UART_SDB_B_TX")
	)
	(segment
		(start 331.34681 -196.05879)
		(end 332.06055 -195.34505)
		(width 0.13335)
		(layer "In2.Cu")
		(net "UART_SDB_B_TX")
	)
	(segment
		(start 243.968016 -194.62369)
		(end 249.858784 -200.514458)
		(width 0.13335)
		(layer "In2.Cu")
		(net "UART_SDB_B_TX")
	)
	(segment
		(start 243.237766 -194.622674)
		(end 243.23675 -194.62369)
		(width 0.13335)
		(layer "In2.Cu")
		(net "UART_SDB_B_TX")
	)
	(segment
		(start 243.23675 -194.62369)
		(end 243.968016 -194.62369)
		(width 0.13335)
		(layer "In2.Cu")
		(net "UART_SDB_B_TX")
	)
	(segment
		(start 332.06055 -195.34505)
		(end 373.642382 -195.34505)
		(width 0.13335)
		(layer "In2.Cu")
		(net "UART_SDB_B_TX")
	)
	(segment
		(start 315.054742 -200.514458)
		(end 319.51041 -196.05879)
		(width 0.13335)
		(layer "In2.Cu")
		(net "UART_SDB_B_TX")
	)
	(segment
		(start 221.498414 -403.520656)
		(end 213.284816 -395.307058)
		(width 0.12065)
		(layer "In4.Cu")
		(net "UART_SDB_B_TX")
	)
	(segment
		(start 373.788432 -155.60929)
		(end 373.788432 -195.199)
		(width 0.12065)
		(layer "In4.Cu")
		(net "UART_SDB_B_TX")
	)
	(segment
		(start 213.284816 -390.595866)
		(end 213.703408 -390.177274)
		(width 0.12065)
		(layer "In4.Cu")
		(net "UART_SDB_B_TX")
	)
	(segment
		(start 220.800168 -410.600144)
		(end 221.498414 -409.901898)
		(width 0.12065)
		(layer "In4.Cu")
		(net "UART_SDB_B_TX")
	)
	(segment
		(start 222.631 -208.28)
		(end 235.966 -194.945)
		(width 0.12065)
		(layer "In4.Cu")
		(net "UART_SDB_B_TX")
	)
	(segment
		(start 222.631 -215.265)
		(end 222.631 -208.28)
		(width 0.12065)
		(layer "In4.Cu")
		(net "UART_SDB_B_TX")
	)
	(segment
		(start 219.675202 -318.037464)
		(end 219.675202 -218.220798)
		(width 0.12065)
		(layer "In4.Cu")
		(net "UART_SDB_B_TX")
	)
	(segment
		(start 241.867436 -194.622674)
		(end 243.237766 -194.622674)
		(width 0.12065)
		(layer "In4.Cu")
		(net "UART_SDB_B_TX")
	)
	(segment
		(start 378.549916 -25.550114)
		(end 377.38685 -26.71318)
		(width 0.12065)
		(layer "In4.Cu")
		(net "UART_SDB_B_TX")
	)
	(segment
		(start 373.50065 -35.605212)
		(end 373.50065 -117.01145)
		(width 0.12065)
		(layer "In4.Cu")
		(net "UART_SDB_B_TX")
	)
	(segment
		(start 219.675202 -218.220798)
		(end 222.631 -215.265)
		(width 0.12065)
		(layer "In4.Cu")
		(net "UART_SDB_B_TX")
	)
	(segment
		(start 213.284816 -324.42785)
		(end 219.675202 -318.037464)
		(width 0.12065)
		(layer "In4.Cu")
		(net "UART_SDB_B_TX")
	)
	(segment
		(start 377.38685 -31.719012)
		(end 373.50065 -35.605212)
		(width 0.12065)
		(layer "In4.Cu")
		(net "UART_SDB_B_TX")
	)
	(segment
		(start 377.38685 -26.71318)
		(end 377.38685 -31.719012)
		(width 0.12065)
		(layer "In4.Cu")
		(net "UART_SDB_B_TX")
	)
	(segment
		(start 241.54511 -194.945)
		(end 241.867436 -194.622674)
		(width 0.12065)
		(layer "In4.Cu")
		(net "UART_SDB_B_TX")
	)
	(segment
		(start 235.966 -194.945)
		(end 241.54511 -194.945)
		(width 0.12065)
		(layer "In4.Cu")
		(net "UART_SDB_B_TX")
	)
	(segment
		(start 213.284816 -395.307058)
		(end 213.284816 -390.595866)
		(width 0.12065)
		(layer "In4.Cu")
		(net "UART_SDB_B_TX")
	)
	(segment
		(start 213.284816 -385.651248)
		(end 213.284816 -324.42785)
		(width 0.12065)
		(layer "In4.Cu")
		(net "UART_SDB_B_TX")
	)
	(segment
		(start 373.50065 -117.01145)
		(end 387.084316 -130.595116)
		(width 0.12065)
		(layer "In4.Cu")
		(net "UART_SDB_B_TX")
	)
	(segment
		(start 221.498414 -409.901898)
		(end 221.498414 -403.520656)
		(width 0.12065)
		(layer "In4.Cu")
		(net "UART_SDB_B_TX")
	)
	(segment
		(start 387.084316 -142.313406)
		(end 373.788432 -155.60929)
		(width 0.12065)
		(layer "In4.Cu")
		(net "UART_SDB_B_TX")
	)
	(segment
		(start 213.703408 -390.177274)
		(end 213.703408 -386.06984)
		(width 0.12065)
		(layer "In4.Cu")
		(net "UART_SDB_B_TX")
	)
	(segment
		(start 387.084316 -130.595116)
		(end 387.084316 -142.313406)
		(width 0.12065)
		(layer "In4.Cu")
		(net "UART_SDB_B_TX")
	)
	(segment
		(start 213.703408 -386.06984)
		(end 213.284816 -385.651248)
		(width 0.12065)
		(layer "In4.Cu")
		(net "UART_SDB_B_TX")
	)
	(via
		(at 374.417082 -194.2465)
		(size 0.5588)
		(drill 0.3048)
		(layers "F.Cu" "B.Cu")
		(net "UART_SDB_B_RX")
	)
	(via
		(at 240.757964 -193.939414)
		(size 0.5588)
		(drill 0.3048)
		(layers "F.Cu" "B.Cu")
		(net "UART_SDB_B_RX")
	)
	(segment
		(start 250.278646 -199.873108)
		(end 244.344952 -193.939414)
		(width 0.13335)
		(layer "In2.Cu")
		(net "UART_SDB_B_RX")
	)
	(segment
		(start 314.726828 -199.873108)
		(end 250.278646 -199.873108)
		(width 0.13335)
		(layer "In2.Cu")
		(net "UART_SDB_B_RX")
	)
	(segment
		(start 332.252066 -194.2465)
		(end 331.081126 -195.41744)
		(width 0.13335)
		(layer "In2.Cu")
		(net "UART_SDB_B_RX")
	)
	(segment
		(start 355.8921 -194.2465)
		(end 332.252066 -194.2465)
		(width 0.13335)
		(layer "In2.Cu")
		(net "UART_SDB_B_RX")
	)
	(segment
		(start 374.297194 -194.366388)
		(end 356.011988 -194.366388)
		(width 0.13335)
		(layer "In2.Cu")
		(net "UART_SDB_B_RX")
	)
	(segment
		(start 244.344952 -193.939414)
		(end 240.757964 -193.939414)
		(width 0.13335)
		(layer "In2.Cu")
		(net "UART_SDB_B_RX")
	)
	(segment
		(start 319.182496 -195.41744)
		(end 314.726828 -199.873108)
		(width 0.13335)
		(layer "In2.Cu")
		(net "UART_SDB_B_RX")
	)
	(segment
		(start 356.011988 -194.366388)
		(end 355.8921 -194.2465)
		(width 0.13335)
		(layer "In2.Cu")
		(net "UART_SDB_B_RX")
	)
	(segment
		(start 331.081126 -195.41744)
		(end 319.182496 -195.41744)
		(width 0.13335)
		(layer "In2.Cu")
		(net "UART_SDB_B_RX")
	)
	(segment
		(start 374.417082 -194.2465)
		(end 374.297194 -194.366388)
		(width 0.13335)
		(layer "In2.Cu")
		(net "UART_SDB_B_RX")
	)
	(segment
		(start 221.5134 -214.972646)
		(end 221.5134 -212.587078)
		(width 0.12065)
		(layer "In4.Cu")
		(net "UART_SDB_B_RX")
	)
	(segment
		(start 236.006386 -193.939414)
		(end 240.757964 -193.939414)
		(width 0.12065)
		(layer "In4.Cu")
		(net "UART_SDB_B_RX")
	)
	(segment
		(start 374.417082 -155.869894)
		(end 374.417082 -194.2465)
		(width 0.12065)
		(layer "In4.Cu")
		(net "UART_SDB_B_RX")
	)
	(segment
		(start 221.513654 -214.9729)
		(end 221.5134 -214.972646)
		(width 0.12065)
		(layer "In4.Cu")
		(net "UART_SDB_B_RX")
	)
	(segment
		(start 221.513654 -212.1789)
		(end 221.5134 -212.178646)
		(width 0.12065)
		(layer "In4.Cu")
		(net "UART_SDB_B_RX")
	)
	(segment
		(start 221.513654 -215.380824)
		(end 221.513654 -214.9729)
		(width 0.12065)
		(layer "In4.Cu")
		(net "UART_SDB_B_RX")
	)
	(segment
		(start 219.046552 -317.77686)
		(end 219.046552 -217.847926)
		(width 0.12065)
		(layer "In4.Cu")
		(net "UART_SDB_B_RX")
	)
	(segment
		(start 221.5134 -208.4324)
		(end 236.006386 -193.939414)
		(width 0.12065)
		(layer "In4.Cu")
		(net "UART_SDB_B_RX")
	)
	(segment
		(start 377.8631 -32.502602)
		(end 374.1293 -36.236402)
		(width 0.12065)
		(layer "In4.Cu")
		(net "UART_SDB_B_RX")
	)
	(segment
		(start 387.712966 -142.57401)
		(end 374.417082 -155.869894)
		(width 0.12065)
		(layer "In4.Cu")
		(net "UART_SDB_B_RX")
	)
	(segment
		(start 221.5134 -212.178646)
		(end 221.5134 -208.4324)
		(width 0.12065)
		(layer "In4.Cu")
		(net "UART_SDB_B_RX")
	)
	(segment
		(start 219.046552 -217.847926)
		(end 221.513654 -215.380824)
		(width 0.12065)
		(layer "In4.Cu")
		(net "UART_SDB_B_RX")
	)
	(segment
		(start 221.5134 -212.587078)
		(end 221.513654 -212.586824)
		(width 0.12065)
		(layer "In4.Cu")
		(net "UART_SDB_B_RX")
	)
	(segment
		(start 220.170502 -411.370526)
		(end 220.170502 -403.081998)
		(width 0.12065)
		(layer "In4.Cu")
		(net "UART_SDB_B_RX")
	)
	(segment
		(start 212.656166 -395.567662)
		(end 212.656166 -389.760206)
		(width 0.12065)
		(layer "In4.Cu")
		(net "UART_SDB_B_RX")
	)
	(segment
		(start 212.656166 -389.760206)
		(end 212.712046 -389.704326)
		(width 0.12065)
		(layer "In4.Cu")
		(net "UART_SDB_B_RX")
	)
	(segment
		(start 374.1293 -36.236402)
		(end 374.1293 -116.630196)
		(width 0.12065)
		(layer "In4.Cu")
		(net "UART_SDB_B_RX")
	)
	(segment
		(start 221.513654 -212.586824)
		(end 221.513654 -212.1789)
		(width 0.12065)
		(layer "In4.Cu")
		(net "UART_SDB_B_RX")
	)
	(segment
		(start 377.8631 -27.636978)
		(end 377.8631 -32.502602)
		(width 0.12065)
		(layer "In4.Cu")
		(net "UART_SDB_B_RX")
	)
	(segment
		(start 220.170502 -403.081998)
		(end 212.656166 -395.567662)
		(width 0.12065)
		(layer "In4.Cu")
		(net "UART_SDB_B_RX")
	)
	(segment
		(start 387.712966 -130.213862)
		(end 387.712966 -142.57401)
		(width 0.12065)
		(layer "In4.Cu")
		(net "UART_SDB_B_RX")
	)
	(segment
		(start 374.1293 -116.630196)
		(end 387.712966 -130.213862)
		(width 0.12065)
		(layer "In4.Cu")
		(net "UART_SDB_B_RX")
	)
	(segment
		(start 220.800168 -412.000192)
		(end 220.170502 -411.370526)
		(width 0.12065)
		(layer "In4.Cu")
		(net "UART_SDB_B_RX")
	)
	(segment
		(start 212.656166 -324.167246)
		(end 219.046552 -317.77686)
		(width 0.12065)
		(layer "In4.Cu")
		(net "UART_SDB_B_RX")
	)
	(segment
		(start 212.712046 -389.183118)
		(end 212.656166 -389.127238)
		(width 0.12065)
		(layer "In4.Cu")
		(net "UART_SDB_B_RX")
	)
	(segment
		(start 212.712046 -389.704326)
		(end 212.712046 -389.183118)
		(width 0.12065)
		(layer "In4.Cu")
		(net "UART_SDB_B_RX")
	)
	(segment
		(start 378.549916 -26.950162)
		(end 377.8631 -27.636978)
		(width 0.12065)
		(layer "In4.Cu")
		(net "UART_SDB_B_RX")
	)
	(segment
		(start 212.656166 -389.127238)
		(end 212.656166 -324.167246)
		(width 0.12065)
		(layer "In4.Cu")
		(net "UART_SDB_B_RX")
	)
	(via
		(at 132.461 -341.0712)
		(size 0.5588)
		(drill 0.3048)
		(layers "F.Cu" "B.Cu")
		(net "UART_SDB_A_TX")
	)
	(segment
		(start 210.015836 -338.8487)
		(end 214.683594 -343.516458)
		(width 0.13335)
		(layer "In2.Cu")
		(net "UART_SDB_A_TX")
	)
	(segment
		(start 261.715504 -348.21495)
		(end 262.06196 -348.561406)
		(width 0.13335)
		(layer "In2.Cu")
		(net "UART_SDB_A_TX")
	)
	(segment
		(start 168.346374 -338.8487)
		(end 210.015836 -338.8487)
		(width 0.13335)
		(layer "In2.Cu")
		(net "UART_SDB_A_TX")
	)
	(segment
		(start 245.015004 -346.17787)
		(end 246.156734 -347.3196)
		(width 0.13335)
		(layer "In2.Cu")
		(net "UART_SDB_A_TX")
	)
	(segment
		(start 225.19767 -343.516458)
		(end 227.153216 -345.472004)
		(width 0.13335)
		(layer "In2.Cu")
		(net "UART_SDB_A_TX")
	)
	(segment
		(start 165.377876 -341.817198)
		(end 168.346374 -338.8487)
		(width 0.13335)
		(layer "In2.Cu")
		(net "UART_SDB_A_TX")
	)
	(segment
		(start 260.813042 -347.3196)
		(end 261.708392 -348.21495)
		(width 0.13335)
		(layer "In2.Cu")
		(net "UART_SDB_A_TX")
	)
	(segment
		(start 246.156734 -347.3196)
		(end 260.813042 -347.3196)
		(width 0.13335)
		(layer "In2.Cu")
		(net "UART_SDB_A_TX")
	)
	(segment
		(start 235.56087 -346.17787)
		(end 245.015004 -346.17787)
		(width 0.13335)
		(layer "In2.Cu")
		(net "UART_SDB_A_TX")
	)
	(segment
		(start 283.101542 -348.040198)
		(end 284.236668 -346.905072)
		(width 0.13335)
		(layer "In2.Cu")
		(net "UART_SDB_A_TX")
	)
	(segment
		(start 275.301202 -348.040198)
		(end 283.101542 -348.040198)
		(width 0.13335)
		(layer "In2.Cu")
		(net "UART_SDB_A_TX")
	)
	(segment
		(start 274.779994 -348.561406)
		(end 275.301202 -348.040198)
		(width 0.13335)
		(layer "In2.Cu")
		(net "UART_SDB_A_TX")
	)
	(segment
		(start 141.351 -341.188802)
		(end 141.979396 -341.817198)
		(width 0.13335)
		(layer "In2.Cu")
		(net "UART_SDB_A_TX")
	)
	(segment
		(start 214.683594 -343.516458)
		(end 225.19767 -343.516458)
		(width 0.13335)
		(layer "In2.Cu")
		(net "UART_SDB_A_TX")
	)
	(segment
		(start 227.153216 -345.472004)
		(end 234.855004 -345.472004)
		(width 0.13335)
		(layer "In2.Cu")
		(net "UART_SDB_A_TX")
	)
	(segment
		(start 261.708392 -348.21495)
		(end 261.715504 -348.21495)
		(width 0.13335)
		(layer "In2.Cu")
		(net "UART_SDB_A_TX")
	)
	(segment
		(start 132.578602 -341.188802)
		(end 141.351 -341.188802)
		(width 0.13335)
		(layer "In2.Cu")
		(net "UART_SDB_A_TX")
	)
	(segment
		(start 141.979396 -341.817198)
		(end 165.377876 -341.817198)
		(width 0.13335)
		(layer "In2.Cu")
		(net "UART_SDB_A_TX")
	)
	(segment
		(start 234.855004 -345.472004)
		(end 235.56087 -346.17787)
		(width 0.13335)
		(layer "In2.Cu")
		(net "UART_SDB_A_TX")
	)
	(segment
		(start 132.461 -341.0712)
		(end 132.578602 -341.188802)
		(width 0.13335)
		(layer "In2.Cu")
		(net "UART_SDB_A_TX")
	)
	(segment
		(start 262.06196 -348.561406)
		(end 274.779994 -348.561406)
		(width 0.13335)
		(layer "In2.Cu")
		(net "UART_SDB_A_TX")
	)
	(segment
		(start 125.473206 -123.53798)
		(end 121.35104 -127.660146)
		(width 0.12065)
		(layer "In4.Cu")
		(net "UART_SDB_A_TX")
	)
	(segment
		(start 125.472952 -88.998298)
		(end 125.472952 -89.543636)
		(width 0.12065)
		(layer "In4.Cu")
		(net "UART_SDB_A_TX")
	)
	(segment
		(start 136.5758 -284.738064)
		(end 135.29818 -286.015684)
		(width 0.12065)
		(layer "In4.Cu")
		(net "UART_SDB_A_TX")
	)
	(segment
		(start 132.148072 -63.143892)
		(end 132.148072 -82.323178)
		(width 0.12065)
		(layer "In4.Cu")
		(net "UART_SDB_A_TX")
	)
	(segment
		(start 131.780788 -176.208436)
		(end 142.865602 -187.29325)
		(width 0.12065)
		(layer "In4.Cu")
		(net "UART_SDB_A_TX")
	)
	(segment
		(start 136.575546 -243.837206)
		(end 136.5758 -243.83746)
		(width 0.12065)
		(layer "In4.Cu")
		(net "UART_SDB_A_TX")
	)
	(segment
		(start 133.10489 -340.42731)
		(end 132.461 -341.0712)
		(width 0.12065)
		(layer "In4.Cu")
		(net "UART_SDB_A_TX")
	)
	(segment
		(start 131.780788 -171.654978)
		(end 131.780788 -176.208436)
		(width 0.12065)
		(layer "In4.Cu")
		(net "UART_SDB_A_TX")
	)
	(segment
		(start 136.5758 -242.795044)
		(end 136.575292 -242.795552)
		(width 0.12065)
		(layer "In4.Cu")
		(net "UART_SDB_A_TX")
	)
	(segment
		(start 132.5499 -25.550114)
		(end 131.426966 -26.673048)
		(width 0.12065)
		(layer "In4.Cu")
		(net "UART_SDB_A_TX")
	)
	(segment
		(start 132.148072 -82.323178)
		(end 125.472952 -88.998298)
		(width 0.12065)
		(layer "In4.Cu")
		(net "UART_SDB_A_TX")
	)
	(segment
		(start 145.551906 -196.125084)
		(end 145.551906 -227.94976)
		(width 0.12065)
		(layer "In4.Cu")
		(net "UART_SDB_A_TX")
	)
	(segment
		(start 124.839222 -164.713412)
		(end 131.780788 -171.654978)
		(width 0.12065)
		(layer "In4.Cu")
		(net "UART_SDB_A_TX")
	)
	(segment
		(start 125.473206 -122.961908)
		(end 125.473206 -123.53798)
		(width 0.12065)
		(layer "In4.Cu")
		(net "UART_SDB_A_TX")
	)
	(segment
		(start 135.9408 -293.469568)
		(end 135.9408 -313.746896)
		(width 0.12065)
		(layer "In4.Cu")
		(net "UART_SDB_A_TX")
	)
	(segment
		(start 133.10489 -316.582806)
		(end 133.10489 -340.42731)
		(width 0.12065)
		(layer "In4.Cu")
		(net "UART_SDB_A_TX")
	)
	(segment
		(start 135.29818 -286.015684)
		(end 135.29818 -292.826948)
		(width 0.12065)
		(layer "In4.Cu")
		(net "UART_SDB_A_TX")
	)
	(segment
		(start 136.5758 -236.925866)
		(end 136.5758 -242.795044)
		(width 0.12065)
		(layer "In4.Cu")
		(net "UART_SDB_A_TX")
	)
	(segment
		(start 136.575292 -243.316252)
		(end 136.575546 -243.316506)
		(width 0.12065)
		(layer "In4.Cu")
		(net "UART_SDB_A_TX")
	)
	(segment
		(start 121.35104 -127.660146)
		(end 121.35104 -149.42185)
		(width 0.12065)
		(layer "In4.Cu")
		(net "UART_SDB_A_TX")
	)
	(segment
		(start 125.472698 -122.9614)
		(end 125.473206 -122.961908)
		(width 0.12065)
		(layer "In4.Cu")
		(net "UART_SDB_A_TX")
	)
	(segment
		(start 121.35104 -149.42185)
		(end 121.284238 -149.488652)
		(width 0.12065)
		(layer "In4.Cu")
		(net "UART_SDB_A_TX")
	)
	(segment
		(start 145.551906 -227.94976)
		(end 136.5758 -236.925866)
		(width 0.12065)
		(layer "In4.Cu")
		(net "UART_SDB_A_TX")
	)
	(segment
		(start 125.472698 -89.54389)
		(end 125.472698 -122.9614)
		(width 0.12065)
		(layer "In4.Cu")
		(net "UART_SDB_A_TX")
	)
	(segment
		(start 142.865602 -193.43878)
		(end 145.551906 -196.125084)
		(width 0.12065)
		(layer "In4.Cu")
		(net "UART_SDB_A_TX")
	)
	(segment
		(start 121.284238 -149.488652)
		(end 121.284238 -158.077916)
		(width 0.12065)
		(layer "In4.Cu")
		(net "UART_SDB_A_TX")
	)
	(segment
		(start 135.29818 -292.826948)
		(end 135.9408 -293.469568)
		(width 0.12065)
		(layer "In4.Cu")
		(net "UART_SDB_A_TX")
	)
	(segment
		(start 121.284238 -158.077916)
		(end 124.839222 -161.6329)
		(width 0.12065)
		(layer "In4.Cu")
		(net "UART_SDB_A_TX")
	)
	(segment
		(start 135.9408 -313.746896)
		(end 133.10489 -316.582806)
		(width 0.12065)
		(layer "In4.Cu")
		(net "UART_SDB_A_TX")
	)
	(segment
		(start 125.472952 -89.543636)
		(end 125.472698 -89.54389)
		(width 0.12065)
		(layer "In4.Cu")
		(net "UART_SDB_A_TX")
	)
	(segment
		(start 136.575292 -242.795552)
		(end 136.575292 -243.316252)
		(width 0.12065)
		(layer "In4.Cu")
		(net "UART_SDB_A_TX")
	)
	(segment
		(start 136.575546 -243.316506)
		(end 136.575546 -243.837206)
		(width 0.12065)
		(layer "In4.Cu")
		(net "UART_SDB_A_TX")
	)
	(segment
		(start 124.839222 -161.6329)
		(end 124.839222 -164.713412)
		(width 0.12065)
		(layer "In4.Cu")
		(net "UART_SDB_A_TX")
	)
	(segment
		(start 136.5758 -243.83746)
		(end 136.5758 -284.738064)
		(width 0.12065)
		(layer "In4.Cu")
		(net "UART_SDB_A_TX")
	)
	(segment
		(start 131.426966 -26.673048)
		(end 131.426966 -62.422786)
		(width 0.12065)
		(layer "In4.Cu")
		(net "UART_SDB_A_TX")
	)
	(segment
		(start 142.865602 -187.29325)
		(end 142.865602 -193.43878)
		(width 0.12065)
		(layer "In4.Cu")
		(net "UART_SDB_A_TX")
	)
	(segment
		(start 131.426966 -62.422786)
		(end 132.148072 -63.143892)
		(width 0.12065)
		(layer "In4.Cu")
		(net "UART_SDB_A_TX")
	)
	(via
		(at 133.858 -340.5124)
		(size 0.5588)
		(drill 0.3048)
		(layers "F.Cu" "B.Cu")
		(net "UART_SDB_A_RX")
	)
	(segment
		(start 274.814538 -347.83522)
		(end 275.09851 -347.551248)
		(width 0.13335)
		(layer "In2.Cu")
		(net "UART_SDB_A_RX")
	)
	(segment
		(start 260.424676 -346.0242)
		(end 261.974076 -347.5736)
		(width 0.13335)
		(layer "In2.Cu")
		(net "UART_SDB_A_RX")
	)
	(segment
		(start 133.893052 -340.547452)
		(end 141.616684 -340.547452)
		(width 0.13335)
		(layer "In2.Cu")
		(net "UART_SDB_A_RX")
	)
	(segment
		(start 245.905528 -346.0242)
		(end 260.424676 -346.0242)
		(width 0.13335)
		(layer "In2.Cu")
		(net "UART_SDB_A_RX")
	)
	(segment
		(start 282.190444 -347.551248)
		(end 282.83662 -346.905072)
		(width 0.13335)
		(layer "In2.Cu")
		(net "UART_SDB_A_RX")
	)
	(segment
		(start 262.242808 -347.83522)
		(end 274.814538 -347.83522)
		(width 0.13335)
		(layer "In2.Cu")
		(net "UART_SDB_A_RX")
	)
	(segment
		(start 210.796886 -338.20735)
		(end 214.88654 -342.297004)
		(width 0.13335)
		(layer "In2.Cu")
		(net "UART_SDB_A_RX")
	)
	(segment
		(start 168.08069 -338.20735)
		(end 210.796886 -338.20735)
		(width 0.13335)
		(layer "In2.Cu")
		(net "UART_SDB_A_RX")
	)
	(segment
		(start 261.981188 -347.5736)
		(end 262.242808 -347.83522)
		(width 0.13335)
		(layer "In2.Cu")
		(net "UART_SDB_A_RX")
	)
	(segment
		(start 261.974076 -347.5736)
		(end 261.981188 -347.5736)
		(width 0.13335)
		(layer "In2.Cu")
		(net "UART_SDB_A_RX")
	)
	(segment
		(start 224.88525 -342.297004)
		(end 227.4189 -344.830654)
		(width 0.13335)
		(layer "In2.Cu")
		(net "UART_SDB_A_RX")
	)
	(segment
		(start 133.858 -340.5124)
		(end 133.893052 -340.547452)
		(width 0.13335)
		(layer "In2.Cu")
		(net "UART_SDB_A_RX")
	)
	(segment
		(start 275.09851 -347.551248)
		(end 282.190444 -347.551248)
		(width 0.13335)
		(layer "In2.Cu")
		(net "UART_SDB_A_RX")
	)
	(segment
		(start 165.112192 -341.175848)
		(end 168.08069 -338.20735)
		(width 0.13335)
		(layer "In2.Cu")
		(net "UART_SDB_A_RX")
	)
	(segment
		(start 141.616684 -340.547452)
		(end 142.24508 -341.175848)
		(width 0.13335)
		(layer "In2.Cu")
		(net "UART_SDB_A_RX")
	)
	(segment
		(start 227.4189 -344.830654)
		(end 244.711982 -344.830654)
		(width 0.13335)
		(layer "In2.Cu")
		(net "UART_SDB_A_RX")
	)
	(segment
		(start 214.88654 -342.297004)
		(end 224.88525 -342.297004)
		(width 0.13335)
		(layer "In2.Cu")
		(net "UART_SDB_A_RX")
	)
	(segment
		(start 244.711982 -344.830654)
		(end 245.905528 -346.0242)
		(width 0.13335)
		(layer "In2.Cu")
		(net "UART_SDB_A_RX")
	)
	(segment
		(start 142.24508 -341.175848)
		(end 165.112192 -341.175848)
		(width 0.13335)
		(layer "In2.Cu")
		(net "UART_SDB_A_RX")
	)
	(segment
		(start 124.17679 -153.462736)
		(end 124.17679 -160.081214)
		(width 0.12065)
		(layer "In4.Cu")
		(net "UART_SDB_A_RX")
	)
	(segment
		(start 132.776722 -83.12912)
		(end 126.101348 -89.804494)
		(width 0.12065)
		(layer "In4.Cu")
		(net "UART_SDB_A_RX")
	)
	(segment
		(start 143.494252 -193.178176)
		(end 146.180556 -195.86448)
		(width 0.12065)
		(layer "In4.Cu")
		(net "UART_SDB_A_RX")
	)
	(segment
		(start 121.912888 -149.749256)
		(end 121.912888 -151.198834)
		(width 0.12065)
		(layer "In4.Cu")
		(net "UART_SDB_A_RX")
	)
	(segment
		(start 137.20445 -284.998668)
		(end 137.007346 -285.195772)
		(width 0.12065)
		(layer "In4.Cu")
		(net "UART_SDB_A_RX")
	)
	(segment
		(start 137.20445 -243.055648)
		(end 137.204196 -243.055902)
		(width 0.12065)
		(layer "In4.Cu")
		(net "UART_SDB_A_RX")
	)
	(segment
		(start 121.97969 -149.682454)
		(end 121.912888 -149.749256)
		(width 0.12065)
		(layer "In4.Cu")
		(net "UART_SDB_A_RX")
	)
	(segment
		(start 126.101348 -122.700796)
		(end 126.101856 -122.701304)
		(width 0.12065)
		(layer "In4.Cu")
		(net "UART_SDB_A_RX")
	)
	(segment
		(start 133.73354 -316.84341)
		(end 133.73354 -340.38794)
		(width 0.12065)
		(layer "In4.Cu")
		(net "UART_SDB_A_RX")
	)
	(segment
		(start 121.912888 -151.198834)
		(end 124.17679 -153.462736)
		(width 0.12065)
		(layer "In4.Cu")
		(net "UART_SDB_A_RX")
	)
	(segment
		(start 126.101856 -123.798584)
		(end 121.97969 -127.92075)
		(width 0.12065)
		(layer "In4.Cu")
		(net "UART_SDB_A_RX")
	)
	(segment
		(start 137.204196 -243.576602)
		(end 137.20445 -243.576856)
		(width 0.12065)
		(layer "In4.Cu")
		(net "UART_SDB_A_RX")
	)
	(segment
		(start 124.17679 -160.081214)
		(end 125.467872 -161.372296)
		(width 0.12065)
		(layer "In4.Cu")
		(net "UART_SDB_A_RX")
	)
	(segment
		(start 146.180556 -195.86448)
		(end 146.180556 -228.494082)
		(width 0.12065)
		(layer "In4.Cu")
		(net "UART_SDB_A_RX")
	)
	(segment
		(start 137.20445 -243.576856)
		(end 137.20445 -284.998668)
		(width 0.12065)
		(layer "In4.Cu")
		(net "UART_SDB_A_RX")
	)
	(segment
		(start 125.467872 -161.372296)
		(end 125.467872 -164.452808)
		(width 0.12065)
		(layer "In4.Cu")
		(net "UART_SDB_A_RX")
	)
	(segment
		(start 137.204196 -243.055902)
		(end 137.204196 -243.576602)
		(width 0.12065)
		(layer "In4.Cu")
		(net "UART_SDB_A_RX")
	)
	(segment
		(start 133.73354 -340.38794)
		(end 133.858 -340.5124)
		(width 0.12065)
		(layer "In4.Cu")
		(net "UART_SDB_A_RX")
	)
	(segment
		(start 121.97969 -127.92075)
		(end 121.97969 -149.682454)
		(width 0.12065)
		(layer "In4.Cu")
		(net "UART_SDB_A_RX")
	)
	(segment
		(start 131.903216 -27.596846)
		(end 131.903216 -32.376364)
		(width 0.12065)
		(layer "In4.Cu")
		(net "UART_SDB_A_RX")
	)
	(segment
		(start 132.205476 -43.41749)
		(end 132.776722 -43.988736)
		(width 0.12065)
		(layer "In4.Cu")
		(net "UART_SDB_A_RX")
	)
	(segment
		(start 132.409438 -171.394374)
		(end 132.409438 -175.947832)
		(width 0.12065)
		(layer "In4.Cu")
		(net "UART_SDB_A_RX")
	)
	(segment
		(start 126.101856 -122.701304)
		(end 126.101856 -123.798584)
		(width 0.12065)
		(layer "In4.Cu")
		(net "UART_SDB_A_RX")
	)
	(segment
		(start 132.776722 -43.988736)
		(end 132.776722 -83.12912)
		(width 0.12065)
		(layer "In4.Cu")
		(net "UART_SDB_A_RX")
	)
	(segment
		(start 125.467872 -164.452808)
		(end 132.409438 -171.394374)
		(width 0.12065)
		(layer "In4.Cu")
		(net "UART_SDB_A_RX")
	)
	(segment
		(start 131.903216 -32.376364)
		(end 132.205476 -32.678624)
		(width 0.12065)
		(layer "In4.Cu")
		(net "UART_SDB_A_RX")
	)
	(segment
		(start 137.20445 -237.470188)
		(end 137.20445 -243.055648)
		(width 0.12065)
		(layer "In4.Cu")
		(net "UART_SDB_A_RX")
	)
	(segment
		(start 137.007346 -313.569604)
		(end 133.73354 -316.84341)
		(width 0.12065)
		(layer "In4.Cu")
		(net "UART_SDB_A_RX")
	)
	(segment
		(start 146.180556 -228.494082)
		(end 137.20445 -237.470188)
		(width 0.12065)
		(layer "In4.Cu")
		(net "UART_SDB_A_RX")
	)
	(segment
		(start 132.205476 -32.678624)
		(end 132.205476 -43.41749)
		(width 0.12065)
		(layer "In4.Cu")
		(net "UART_SDB_A_RX")
	)
	(segment
		(start 132.5499 -26.950162)
		(end 131.903216 -27.596846)
		(width 0.12065)
		(layer "In4.Cu")
		(net "UART_SDB_A_RX")
	)
	(segment
		(start 143.494252 -187.032646)
		(end 143.494252 -193.178176)
		(width 0.12065)
		(layer "In4.Cu")
		(net "UART_SDB_A_RX")
	)
	(segment
		(start 137.007346 -285.195772)
		(end 137.007346 -313.569604)
		(width 0.12065)
		(layer "In4.Cu")
		(net "UART_SDB_A_RX")
	)
	(segment
		(start 132.409438 -175.947832)
		(end 143.494252 -187.032646)
		(width 0.12065)
		(layer "In4.Cu")
		(net "UART_SDB_A_RX")
	)
	(segment
		(start 126.101348 -89.804494)
		(end 126.101348 -122.700796)
		(width 0.12065)
		(layer "In4.Cu")
		(net "UART_SDB_A_RX")
	)
	(segment
		(start 277.9522 21.5138)
		(end 277.33244 20.89404)
		(width 0.17145)
		(layer "F.Cu")
		(net "SYS_PWR_LED_B")
	)
	(segment
		(start 277.33244 19.667728)
		(end 277.33244 18.88744)
		(width 0.17145)
		(layer "F.Cu")
		(net "SYS_PWR_LED_B")
	)
	(segment
		(start 272.246344 23.866856)
		(end 276.985984 23.866856)
		(width 0.17145)
		(layer "F.Cu")
		(net "SYS_PWR_LED_B")
	)
	(segment
		(start 262.055102 31.074868)
		(end 262.055102 29.333698)
		(width 0.17145)
		(layer "F.Cu")
		(net "SYS_PWR_LED_B")
	)
	(segment
		(start 268.76375 27.34945)
		(end 272.246344 23.866856)
		(width 0.17145)
		(layer "F.Cu")
		(net "SYS_PWR_LED_B")
	)
	(segment
		(start 276.03196 18.54835)
		(end 276.03196 17.788128)
		(width 0.17145)
		(layer "F.Cu")
		(net "SYS_PWR_LED_B")
	)
	(segment
		(start 277.1648 18.7198)
		(end 276.20341 18.7198)
		(width 0.17145)
		(layer "F.Cu")
		(net "SYS_PWR_LED_B")
	)
	(segment
		(start 276.20341 18.7198)
		(end 276.03196 18.54835)
		(width 0.17145)
		(layer "F.Cu")
		(net "SYS_PWR_LED_B")
	)
	(segment
		(start 277.33244 20.89404)
		(end 277.33244 19.667728)
		(width 0.17145)
		(layer "F.Cu")
		(net "SYS_PWR_LED_B")
	)
	(segment
		(start 276.985984 23.866856)
		(end 277.9522 22.90064)
		(width 0.17145)
		(layer "F.Cu")
		(net "SYS_PWR_LED_B")
	)
	(segment
		(start 277.9522 22.90064)
		(end 277.9522 21.5138)
		(width 0.17145)
		(layer "F.Cu")
		(net "SYS_PWR_LED_B")
	)
	(segment
		(start 277.33244 18.88744)
		(end 277.1648 18.7198)
		(width 0.17145)
		(layer "F.Cu")
		(net "SYS_PWR_LED_B")
	)
	(segment
		(start 264.03935 27.34945)
		(end 268.76375 27.34945)
		(width 0.17145)
		(layer "F.Cu")
		(net "SYS_PWR_LED_B")
	)
	(segment
		(start 262.055102 29.333698)
		(end 264.03935 27.34945)
		(width 0.17145)
		(layer "F.Cu")
		(net "SYS_PWR_LED_B")
	)
	(via
		(at 277.9522 21.5138)
		(size 0.6604)
		(drill 0.3302)
		(layers "F.Cu" "B.Cu")
		(net "SYS_PWR_LED_B")
	)
	(segment
		(start 255.69164 23.89124)
		(end 255.870202 24.069802)
		(width 0.17145)
		(layer "F.Cu")
		(net "SYS_PWR_LED_A")
	)
	(segment
		(start 255.40335 14.351)
		(end 254.7112 14.351)
		(width 0.17145)
		(layer "F.Cu")
		(net "SYS_PWR_LED_A")
	)
	(segment
		(start 254.39116 14.03096)
		(end 254.39116 13.352272)
		(width 0.17145)
		(layer "F.Cu")
		(net "SYS_PWR_LED_A")
	)
	(segment
		(start 255.69164 15.231872)
		(end 255.69164 14.63929)
		(width 0.17145)
		(layer "F.Cu")
		(net "SYS_PWR_LED_A")
	)
	(segment
		(start 255.69164 20.6248)
		(end 255.69164 23.89124)
		(width 0.17145)
		(layer "F.Cu")
		(net "SYS_PWR_LED_A")
	)
	(segment
		(start 255.69164 15.231872)
		(end 255.69164 20.6248)
		(width 0.17145)
		(layer "F.Cu")
		(net "SYS_PWR_LED_A")
	)
	(segment
		(start 255.870202 24.069802)
		(end 255.870202 26.404824)
		(width 0.17145)
		(layer "F.Cu")
		(net "SYS_PWR_LED_A")
	)
	(segment
		(start 254.7112 14.351)
		(end 254.39116 14.03096)
		(width 0.17145)
		(layer "F.Cu")
		(net "SYS_PWR_LED_A")
	)
	(segment
		(start 255.69164 14.63929)
		(end 255.40335 14.351)
		(width 0.17145)
		(layer "F.Cu")
		(net "SYS_PWR_LED_A")
	)
	(via
		(at 255.69164 20.6248)
		(size 0.6604)
		(drill 0.3302)
		(layers "F.Cu" "B.Cu")
		(net "SYS_PWR_LED_A")
	)
	(segment
		(start 342.056212 -31.643828)
		(end 343.156032 -31.643828)
		(width 0.17145)
		(layer "F.Cu")
		(net "SCC_B_TYPE_3")
	)
	(segment
		(start 341.254334 -30.84195)
		(end 342.056212 -31.643828)
		(width 0.17145)
		(layer "F.Cu")
		(net "SCC_B_TYPE_3")
	)
	(segment
		(start 343.156032 -32.427672)
		(end 343.156032 -31.643828)
		(width 0.17145)
		(layer "F.Cu")
		(net "SCC_B_TYPE_3")
	)
	(segment
		(start 343.32291 -32.59455)
		(end 343.156032 -32.427672)
		(width 0.17145)
		(layer "F.Cu")
		(net "SCC_B_TYPE_3")
	)
	(segment
		(start 341.254334 -30.05709)
		(end 341.254334 -30.84195)
		(width 0.17145)
		(layer "F.Cu")
		(net "SCC_B_TYPE_3")
	)
	(via
		(at 225.796348 -214.188548)
		(size 0.5588)
		(drill 0.3048)
		(layers "F.Cu" "B.Cu")
		(net "SCC_B_TYPE_3")
	)
	(via
		(at 343.32291 -32.59455)
		(size 0.5588)
		(drill 0.3048)
		(layers "F.Cu" "B.Cu")
		(net "SCC_B_TYPE_3")
	)
	(via
		(at 343.156032 -31.643828)
		(size 0.6604)
		(drill 0.3302)
		(layers "F.Cu" "B.Cu")
		(net "SCC_B_TYPE_3")
	)
	(via
		(at 338.919566 -197.061074)
		(size 0.5588)
		(drill 0.3048)
		(layers "F.Cu" "B.Cu")
		(net "SCC_B_TYPE_3")
	)
	(segment
		(start 237.133384 -202.851512)
		(end 316.215268 -202.851512)
		(width 0.13335)
		(layer "In2.Cu")
		(net "SCC_B_TYPE_3")
	)
	(segment
		(start 337.584796 -198.395844)
		(end 338.919566 -197.061074)
		(width 0.13335)
		(layer "In2.Cu")
		(net "SCC_B_TYPE_3")
	)
	(segment
		(start 320.670936 -198.395844)
		(end 337.584796 -198.395844)
		(width 0.13335)
		(layer "In2.Cu")
		(net "SCC_B_TYPE_3")
	)
	(segment
		(start 316.215268 -202.851512)
		(end 320.670936 -198.395844)
		(width 0.13335)
		(layer "In2.Cu")
		(net "SCC_B_TYPE_3")
	)
	(segment
		(start 225.796348 -214.188548)
		(end 237.133384 -202.851512)
		(width 0.13335)
		(layer "In2.Cu")
		(net "SCC_B_TYPE_3")
	)
	(segment
		(start 222.494856 -319.206372)
		(end 222.494856 -222.833946)
		(width 0.12065)
		(layer "In4.Cu")
		(net "SCC_B_TYPE_3")
	)
	(segment
		(start 341.319612 -74.70267)
		(end 342.772746 -76.155804)
		(width 0.12065)
		(layer "In4.Cu")
		(net "SCC_B_TYPE_3")
	)
	(segment
		(start 222.494856 -222.833946)
		(end 225.796348 -219.532454)
		(width 0.12065)
		(layer "In4.Cu")
		(net "SCC_B_TYPE_3")
	)
	(segment
		(start 225.606102 -406.406096)
		(end 225.606102 -402.140674)
		(width 0.12065)
		(layer "In4.Cu")
		(net "SCC_B_TYPE_3")
	)
	(segment
		(start 222.438722 -319.262506)
		(end 222.494856 -319.206372)
		(width 0.12065)
		(layer "In4.Cu")
		(net "SCC_B_TYPE_3")
	)
	(segment
		(start 339.404452 -182.610506)
		(end 339.404452 -196.306948)
		(width 0.12065)
		(layer "In4.Cu")
		(net "SCC_B_TYPE_3")
	)
	(segment
		(start 328.041 -171.247054)
		(end 339.404452 -182.610506)
		(width 0.12065)
		(layer "In4.Cu")
		(net "SCC_B_TYPE_3")
	)
	(segment
		(start 338.919566 -196.791834)
		(end 338.919566 -197.061074)
		(width 0.12065)
		(layer "In4.Cu")
		(net "SCC_B_TYPE_3")
	)
	(segment
		(start 216.10447 -384.48234)
		(end 216.10447 -325.597012)
		(width 0.12065)
		(layer "In4.Cu")
		(net "SCC_B_TYPE_3")
	)
	(segment
		(start 217.693748 -394.22832)
		(end 217.693748 -386.071618)
		(width 0.12065)
		(layer "In4.Cu")
		(net "SCC_B_TYPE_3")
	)
	(segment
		(start 328.041 -121.375424)
		(end 328.041 -171.247054)
		(width 0.12065)
		(layer "In4.Cu")
		(net "SCC_B_TYPE_3")
	)
	(segment
		(start 344.048588 -34.120328)
		(end 344.048588 -36.722812)
		(width 0.12065)
		(layer "In4.Cu")
		(net "SCC_B_TYPE_3")
	)
	(segment
		(start 226.200208 -407.000202)
		(end 225.606102 -406.406096)
		(width 0.12065)
		(layer "In4.Cu")
		(net "SCC_B_TYPE_3")
	)
	(segment
		(start 225.796348 -219.532454)
		(end 225.796348 -214.188548)
		(width 0.12065)
		(layer "In4.Cu")
		(net "SCC_B_TYPE_3")
	)
	(segment
		(start 344.048588 -36.722812)
		(end 341.319612 -39.451788)
		(width 0.12065)
		(layer "In4.Cu")
		(net "SCC_B_TYPE_3")
	)
	(segment
		(start 342.772746 -106.643678)
		(end 328.041 -121.375424)
		(width 0.12065)
		(layer "In4.Cu")
		(net "SCC_B_TYPE_3")
	)
	(segment
		(start 343.32291 -32.59455)
		(end 343.32291 -33.39465)
		(width 0.12065)
		(layer "In4.Cu")
		(net "SCC_B_TYPE_3")
	)
	(segment
		(start 225.606102 -402.140674)
		(end 217.693748 -394.22832)
		(width 0.12065)
		(layer "In4.Cu")
		(net "SCC_B_TYPE_3")
	)
	(segment
		(start 341.319612 -39.451788)
		(end 341.319612 -74.70267)
		(width 0.12065)
		(layer "In4.Cu")
		(net "SCC_B_TYPE_3")
	)
	(segment
		(start 339.404452 -196.306948)
		(end 338.919566 -196.791834)
		(width 0.12065)
		(layer "In4.Cu")
		(net "SCC_B_TYPE_3")
	)
	(segment
		(start 217.693748 -386.071618)
		(end 216.10447 -384.48234)
		(width 0.12065)
		(layer "In4.Cu")
		(net "SCC_B_TYPE_3")
	)
	(segment
		(start 342.772746 -76.155804)
		(end 342.772746 -106.643678)
		(width 0.12065)
		(layer "In4.Cu")
		(net "SCC_B_TYPE_3")
	)
	(segment
		(start 216.10447 -325.597012)
		(end 222.438722 -319.26276)
		(width 0.12065)
		(layer "In4.Cu")
		(net "SCC_B_TYPE_3")
	)
	(segment
		(start 343.32291 -33.39465)
		(end 344.048588 -34.120328)
		(width 0.12065)
		(layer "In4.Cu")
		(net "SCC_B_TYPE_3")
	)
	(segment
		(start 222.438722 -319.26276)
		(end 222.438722 -319.262506)
		(width 0.12065)
		(layer "In4.Cu")
		(net "SCC_B_TYPE_3")
	)
	(segment
		(start 276.6822 21.072348)
		(end 276.6822 19.667728)
		(width 0.17145)
		(layer "F.Cu")
		(net "SCC_B_PWR_LED")
	)
	(segment
		(start 276.6822 22.220428)
		(end 276.6822 21.072348)
		(width 0.17145)
		(layer "F.Cu")
		(net "SCC_B_PWR_LED")
	)
	(segment
		(start 276.686772 22.225)
		(end 276.6822 22.220428)
		(width 0.17145)
		(layer "F.Cu")
		(net "SCC_B_PWR_LED")
	)
	(segment
		(start 276.686772 22.225)
		(end 276.686772 23.287228)
		(width 0.17145)
		(layer "F.Cu")
		(net "SCC_B_PWR_LED")
	)
	(via
		(at 276.686772 23.287228)
		(size 0.5588)
		(drill 0.3048)
		(layers "F.Cu" "B.Cu")
		(net "SCC_B_PWR_LED")
	)
	(via
		(at 276.6822 21.072348)
		(size 0.6604)
		(drill 0.3302)
		(layers "F.Cu" "B.Cu")
		(net "SCC_B_PWR_LED")
	)
	(via
		(at 292.055042 -313.276742)
		(size 0.5588)
		(drill 0.3048)
		(layers "F.Cu" "B.Cu")
		(net "SCC_B_PWR_LED")
	)
	(segment
		(start 288.8234 -45.633132)
		(end 288.8234 -44.6786)
		(width 0.12065)
		(layer "In4.Cu")
		(net "SCC_B_PWR_LED")
	)
	(segment
		(start 294.039798 -311.291986)
		(end 294.039798 -291.753798)
		(width 0.12065)
		(layer "In4.Cu")
		(net "SCC_B_PWR_LED")
	)
	(segment
		(start 290.104068 -254.10541)
		(end 290.104068 -46.9138)
		(width 0.12065)
		(layer "In4.Cu")
		(net "SCC_B_PWR_LED")
	)
	(segment
		(start 284.226 -281.94)
		(end 284.226 -276.3266)
		(width 0.12065)
		(layer "In4.Cu")
		(net "SCC_B_PWR_LED")
	)
	(segment
		(start 292.055042 -313.276742)
		(end 294.039798 -311.291986)
		(width 0.12065)
		(layer "In4.Cu")
		(net "SCC_B_PWR_LED")
	)
	(segment
		(start 290.104068 -46.9138)
		(end 288.8234 -45.633132)
		(width 0.12065)
		(layer "In4.Cu")
		(net "SCC_B_PWR_LED")
	)
	(segment
		(start 294.039798 -291.753798)
		(end 284.226 -281.94)
		(width 0.12065)
		(layer "In4.Cu")
		(net "SCC_B_PWR_LED")
	)
	(segment
		(start 288.8234 -44.6786)
		(end 288.0487 -43.9039)
		(width 0.12065)
		(layer "In4.Cu")
		(net "SCC_B_PWR_LED")
	)
	(segment
		(start 290.560252 -254.561594)
		(end 290.104068 -254.10541)
		(width 0.12065)
		(layer "In4.Cu")
		(net "SCC_B_PWR_LED")
	)
	(segment
		(start 288.0487 -43.9039)
		(end 288.0487 -2.399792)
		(width 0.12065)
		(layer "In4.Cu")
		(net "SCC_B_PWR_LED")
	)
	(segment
		(start 284.226 -276.3266)
		(end 290.560252 -269.992348)
		(width 0.12065)
		(layer "In4.Cu")
		(net "SCC_B_PWR_LED")
	)
	(segment
		(start 290.560252 -269.992348)
		(end 290.560252 -254.561594)
		(width 0.12065)
		(layer "In4.Cu")
		(net "SCC_B_PWR_LED")
	)
	(segment
		(start 288.0487 -2.399792)
		(end 277.32355 8.325358)
		(width 0.12065)
		(layer "In4.Cu")
		(net "SCC_B_PWR_LED")
	)
	(segment
		(start 277.32355 22.65045)
		(end 276.686772 23.287228)
		(width 0.12065)
		(layer "In4.Cu")
		(net "SCC_B_PWR_LED")
	)
	(segment
		(start 277.32355 8.325358)
		(end 277.32355 22.65045)
		(width 0.12065)
		(layer "In4.Cu")
		(net "SCC_B_PWR_LED")
	)
	(segment
		(start 226.16668 -398.17294)
		(end 226.16668 -396.91564)
		(width 0.12065)
		(layer "In7.Cu")
		(net "SCC_B_PWR_LED")
	)
	(segment
		(start 291.17925 -356.734618)
		(end 291.17925 -332.061058)
		(width 0.12065)
		(layer "In7.Cu")
		(net "SCC_B_PWR_LED")
	)
	(segment
		(start 266.4714 -360.045)
		(end 287.868868 -360.045)
		(width 0.12065)
		(layer "In7.Cu")
		(net "SCC_B_PWR_LED")
	)
	(segment
		(start 229.1334 -393.94892)
		(end 229.1334 -379.374654)
		(width 0.12065)
		(layer "In7.Cu")
		(net "SCC_B_PWR_LED")
	)
	(segment
		(start 256.38506 -355.90734)
		(end 262.33374 -355.90734)
		(width 0.12065)
		(layer "In7.Cu")
		(net "SCC_B_PWR_LED")
	)
	(segment
		(start 262.33374 -355.90734)
		(end 266.4714 -360.045)
		(width 0.12065)
		(layer "In7.Cu")
		(net "SCC_B_PWR_LED")
	)
	(segment
		(start 232.120948 -351.139252)
		(end 233.905552 -349.354648)
		(width 0.12065)
		(layer "In7.Cu")
		(net "SCC_B_PWR_LED")
	)
	(segment
		(start 291.17925 -332.061058)
		(end 291.888164 -331.352144)
		(width 0.12065)
		(layer "In7.Cu")
		(net "SCC_B_PWR_LED")
	)
	(segment
		(start 291.888164 -313.44362)
		(end 292.055042 -313.276742)
		(width 0.12065)
		(layer "In7.Cu")
		(net "SCC_B_PWR_LED")
	)
	(segment
		(start 232.120948 -376.387106)
		(end 232.120948 -351.139252)
		(width 0.12065)
		(layer "In7.Cu")
		(net "SCC_B_PWR_LED")
	)
	(segment
		(start 226.81692 -418.27704)
		(end 226.81692 -398.82318)
		(width 0.12065)
		(layer "In7.Cu")
		(net "SCC_B_PWR_LED")
	)
	(segment
		(start 226.81692 -398.82318)
		(end 226.16668 -398.17294)
		(width 0.12065)
		(layer "In7.Cu")
		(net "SCC_B_PWR_LED")
	)
	(segment
		(start 291.888164 -331.352144)
		(end 291.888164 -313.44362)
		(width 0.12065)
		(layer "In7.Cu")
		(net "SCC_B_PWR_LED")
	)
	(segment
		(start 287.868868 -360.045)
		(end 291.17925 -356.734618)
		(width 0.12065)
		(layer "In7.Cu")
		(net "SCC_B_PWR_LED")
	)
	(segment
		(start 228.000052 -419.300152)
		(end 227.840032 -419.300152)
		(width 0.12065)
		(layer "In7.Cu")
		(net "SCC_B_PWR_LED")
	)
	(segment
		(start 227.840032 -419.300152)
		(end 226.81692 -418.27704)
		(width 0.12065)
		(layer "In7.Cu")
		(net "SCC_B_PWR_LED")
	)
	(segment
		(start 233.905552 -349.354648)
		(end 249.832368 -349.354648)
		(width 0.12065)
		(layer "In7.Cu")
		(net "SCC_B_PWR_LED")
	)
	(segment
		(start 229.1334 -379.374654)
		(end 232.120948 -376.387106)
		(width 0.12065)
		(layer "In7.Cu")
		(net "SCC_B_PWR_LED")
	)
	(segment
		(start 249.832368 -349.354648)
		(end 256.38506 -355.90734)
		(width 0.12065)
		(layer "In7.Cu")
		(net "SCC_B_PWR_LED")
	)
	(segment
		(start 226.16668 -396.91564)
		(end 229.1334 -393.94892)
		(width 0.12065)
		(layer "In7.Cu")
		(net "SCC_B_PWR_LED")
	)
	(segment
		(start 261.522718 -338.906612)
		(end 258.795012 -338.906612)
		(width 0.17145)
		(layer "F.Cu")
		(net "SCC_A_TYPE_3")
	)
	(segment
		(start 263.7028 -338.052664)
		(end 262.376666 -338.052664)
		(width 0.17145)
		(layer "F.Cu")
		(net "SCC_A_TYPE_3")
	)
	(segment
		(start 262.376666 -338.052664)
		(end 261.522718 -338.906612)
		(width 0.17145)
		(layer "F.Cu")
		(net "SCC_A_TYPE_3")
	)
	(segment
		(start 263.7028 -338.052664)
		(end 264.755122 -338.052664)
		(width 0.17145)
		(layer "F.Cu")
		(net "SCC_A_TYPE_3")
	)
	(segment
		(start 258.795012 -338.906612)
		(end 258.2164 -338.328)
		(width 0.17145)
		(layer "F.Cu")
		(net "SCC_A_TYPE_3")
	)
	(segment
		(start 87.711534 -27.86761)
		(end 87.711534 -30.205934)
		(width 0.17145)
		(layer "F.Cu")
		(net "SCC_A_TYPE_3")
	)
	(via
		(at 258.2164 -338.328)
		(size 0.5588)
		(drill 0.3048)
		(layers "F.Cu" "B.Cu")
		(net "SCC_A_TYPE_3")
	)
	(via
		(at 263.7028 -338.052664)
		(size 0.6604)
		(drill 0.3302)
		(layers "F.Cu" "B.Cu")
		(net "SCC_A_TYPE_3")
	)
	(via
		(at 74.3204 -339.691218)
		(size 0.5588)
		(drill 0.3048)
		(layers "F.Cu" "B.Cu")
		(net "SCC_A_TYPE_3")
	)
	(via
		(at 264.755122 -338.052664)
		(size 0.5588)
		(drill 0.3048)
		(layers "F.Cu" "B.Cu")
		(net "SCC_A_TYPE_3")
	)
	(via
		(at 87.711534 -30.205934)
		(size 0.5588)
		(drill 0.3048)
		(layers "F.Cu" "B.Cu")
		(net "SCC_A_TYPE_3")
	)
	(segment
		(start 142.058644 -339.480652)
		(end 75.987148 -339.480652)
		(width 0.13335)
		(layer "In2.Cu")
		(net "SCC_A_TYPE_3")
	)
	(segment
		(start 213.996524 -329.05065)
		(end 175.72863 -329.05065)
		(width 0.13335)
		(layer "In2.Cu")
		(net "SCC_A_TYPE_3")
	)
	(segment
		(start 164.670232 -340.109048)
		(end 142.68704 -340.109048)
		(width 0.13335)
		(layer "In2.Cu")
		(net "SCC_A_TYPE_3")
	)
	(segment
		(start 75.987148 -339.480652)
		(end 75.776582 -339.691218)
		(width 0.13335)
		(layer "In2.Cu")
		(net "SCC_A_TYPE_3")
	)
	(segment
		(start 258.2164 -338.328)
		(end 223.273874 -338.328)
		(width 0.13335)
		(layer "In2.Cu")
		(net "SCC_A_TYPE_3")
	)
	(segment
		(start 75.776582 -339.691218)
		(end 74.3204 -339.691218)
		(width 0.13335)
		(layer "In2.Cu")
		(net "SCC_A_TYPE_3")
	)
	(segment
		(start 142.68704 -340.109048)
		(end 142.058644 -339.480652)
		(width 0.13335)
		(layer "In2.Cu")
		(net "SCC_A_TYPE_3")
	)
	(segment
		(start 223.273874 -338.328)
		(end 213.996524 -329.05065)
		(width 0.13335)
		(layer "In2.Cu")
		(net "SCC_A_TYPE_3")
	)
	(segment
		(start 175.72863 -329.05065)
		(end 164.670232 -340.109048)
		(width 0.13335)
		(layer "In2.Cu")
		(net "SCC_A_TYPE_3")
	)
	(segment
		(start 76.397612 -181.598062)
		(end 76.397612 -162.218116)
		(width 0.12065)
		(layer "In4.Cu")
		(net "SCC_A_TYPE_3")
	)
	(segment
		(start 71.220838 -54.865524)
		(end 87.940642 -38.14572)
		(width 0.12065)
		(layer "In4.Cu")
		(net "SCC_A_TYPE_3")
	)
	(segment
		(start 274.578064 -345.48699)
		(end 272.977102 -345.48699)
		(width 0.12065)
		(layer "In4.Cu")
		(net "SCC_A_TYPE_3")
	)
	(segment
		(start 87.940642 -30.435042)
		(end 87.711534 -30.205934)
		(width 0.12065)
		(layer "In4.Cu")
		(net "SCC_A_TYPE_3")
	)
	(segment
		(start 80.31861 -141.1605)
		(end 71.220838 -132.062728)
		(width 0.12065)
		(layer "In4.Cu")
		(net "SCC_A_TYPE_3")
	)
	(segment
		(start 277.147274 -348.0562)
		(end 274.578064 -345.48699)
		(width 0.12065)
		(layer "In4.Cu")
		(net "SCC_A_TYPE_3")
	)
	(segment
		(start 87.940642 -38.14572)
		(end 87.940642 -30.435042)
		(width 0.12065)
		(layer "In4.Cu")
		(net "SCC_A_TYPE_3")
	)
	(segment
		(start 281.836622 -348.70517)
		(end 281.836622 -348.683072)
		(width 0.12065)
		(layer "In4.Cu")
		(net "SCC_A_TYPE_3")
	)
	(segment
		(start 74.3331 -305.8287)
		(end 74.3331 -191.767968)
		(width 0.12065)
		(layer "In4.Cu")
		(net "SCC_A_TYPE_3")
	)
	(segment
		(start 71.220838 -132.062728)
		(end 71.220838 -54.865524)
		(width 0.12065)
		(layer "In4.Cu")
		(net "SCC_A_TYPE_3")
	)
	(segment
		(start 80.31861 -158.297118)
		(end 80.31861 -141.1605)
		(width 0.12065)
		(layer "In4.Cu")
		(net "SCC_A_TYPE_3")
	)
	(segment
		(start 74.3331 -191.767968)
		(end 75.779122 -190.321946)
		(width 0.12065)
		(layer "In4.Cu")
		(net "SCC_A_TYPE_3")
	)
	(segment
		(start 74.076052 -306.085748)
		(end 74.3331 -305.8287)
		(width 0.12065)
		(layer "In4.Cu")
		(net "SCC_A_TYPE_3")
	)
	(segment
		(start 281.836622 -348.683072)
		(end 281.20975 -348.0562)
		(width 0.12065)
		(layer "In4.Cu")
		(net "SCC_A_TYPE_3")
	)
	(segment
		(start 281.20975 -348.0562)
		(end 277.147274 -348.0562)
		(width 0.12065)
		(layer "In4.Cu")
		(net "SCC_A_TYPE_3")
	)
	(segment
		(start 76.397612 -162.218116)
		(end 80.31861 -158.297118)
		(width 0.12065)
		(layer "In4.Cu")
		(net "SCC_A_TYPE_3")
	)
	(segment
		(start 75.779122 -182.216552)
		(end 76.397612 -181.598062)
		(width 0.12065)
		(layer "In4.Cu")
		(net "SCC_A_TYPE_3")
	)
	(segment
		(start 75.779122 -190.321946)
		(end 75.779122 -182.216552)
		(width 0.12065)
		(layer "In4.Cu")
		(net "SCC_A_TYPE_3")
	)
	(segment
		(start 272.977102 -345.48699)
		(end 265.542776 -338.052664)
		(width 0.12065)
		(layer "In4.Cu")
		(net "SCC_A_TYPE_3")
	)
	(segment
		(start 74.3204 -339.691218)
		(end 74.076052 -339.44687)
		(width 0.12065)
		(layer "In4.Cu")
		(net "SCC_A_TYPE_3")
	)
	(segment
		(start 265.542776 -338.052664)
		(end 264.755122 -338.052664)
		(width 0.12065)
		(layer "In4.Cu")
		(net "SCC_A_TYPE_3")
	)
	(segment
		(start 74.076052 -339.44687)
		(end 74.076052 -306.085748)
		(width 0.12065)
		(layer "In4.Cu")
		(net "SCC_A_TYPE_3")
	)
	(segment
		(start 254.106172 17.775428)
		(end 255.0414 17.775428)
		(width 0.17145)
		(layer "F.Cu")
		(net "SCC_A_PWR_LED")
	)
	(segment
		(start 255.0414 17.775428)
		(end 255.0414 16.6878)
		(width 0.17145)
		(layer "F.Cu")
		(net "SCC_A_PWR_LED")
	)
	(segment
		(start 255.0414 16.6878)
		(end 255.0414 15.231872)
		(width 0.17145)
		(layer "F.Cu")
		(net "SCC_A_PWR_LED")
	)
	(via
		(at 255.0414 16.6878)
		(size 0.6604)
		(drill 0.3302)
		(layers "F.Cu" "B.Cu")
		(net "SCC_A_PWR_LED")
	)
	(via
		(at 254.106172 17.775428)
		(size 0.5588)
		(drill 0.3048)
		(layers "F.Cu" "B.Cu")
		(net "SCC_A_PWR_LED")
	)
	(segment
		(start 248.897648 -319.103502)
		(end 248.897648 -300.373288)
		(width 0.12065)
		(layer "In4.Cu")
		(net "SCC_A_PWR_LED")
	)
	(segment
		(start 257.835146 -204.542898)
		(end 257.835146 -133.110986)
		(width 0.12065)
		(layer "In4.Cu")
		(net "SCC_A_PWR_LED")
	)
	(segment
		(start 244.745764 -256.900934)
		(end 244.745764 -252.048264)
		(width 0.12065)
		(layer "In4.Cu")
		(net "SCC_A_PWR_LED")
	)
	(segment
		(start 257.432302 14.449298)
		(end 254.106172 17.775428)
		(width 0.12065)
		(layer "In4.Cu")
		(net "SCC_A_PWR_LED")
	)
	(segment
		(start 250.918726 -211.459318)
		(end 257.835146 -204.542898)
		(width 0.12065)
		(layer "In4.Cu")
		(net "SCC_A_PWR_LED")
	)
	(segment
		(start 249.034046 -300.23689)
		(end 249.034046 -286.27578)
		(width 0.12065)
		(layer "In4.Cu")
		(net "SCC_A_PWR_LED")
	)
	(segment
		(start 245.35384 -262.649462)
		(end 245.35384 -257.50901)
		(width 0.12065)
		(layer "In4.Cu")
		(net "SCC_A_PWR_LED")
	)
	(segment
		(start 256.055876 -25.442418)
		(end 256.055876 -11.880342)
		(width 0.12065)
		(layer "In4.Cu")
		(net "SCC_A_PWR_LED")
	)
	(segment
		(start 248.897648 -300.373288)
		(end 249.034046 -300.23689)
		(width 0.12065)
		(layer "In4.Cu")
		(net "SCC_A_PWR_LED")
	)
	(segment
		(start 283.602176 -342.670638)
		(end 272.464784 -342.670638)
		(width 0.12065)
		(layer "In4.Cu")
		(net "SCC_A_PWR_LED")
	)
	(segment
		(start 256.748534 -132.024374)
		(end 256.748534 -26.135076)
		(width 0.12065)
		(layer "In4.Cu")
		(net "SCC_A_PWR_LED")
	)
	(segment
		(start 256.055876 -11.880342)
		(end 257.432302 -10.503916)
		(width 0.12065)
		(layer "In4.Cu")
		(net "SCC_A_PWR_LED")
	)
	(segment
		(start 250.918726 -245.875302)
		(end 250.918726 -211.459318)
		(width 0.12065)
		(layer "In4.Cu")
		(net "SCC_A_PWR_LED")
	)
	(segment
		(start 249.034046 -286.27578)
		(end 252.397006 -282.91282)
		(width 0.12065)
		(layer "In4.Cu")
		(net "SCC_A_PWR_LED")
	)
	(segment
		(start 245.35384 -257.50901)
		(end 244.745764 -256.900934)
		(width 0.12065)
		(layer "In4.Cu")
		(net "SCC_A_PWR_LED")
	)
	(segment
		(start 244.745764 -252.048264)
		(end 250.918726 -245.875302)
		(width 0.12065)
		(layer "In4.Cu")
		(net "SCC_A_PWR_LED")
	)
	(segment
		(start 257.432302 -10.503916)
		(end 257.432302 14.449298)
		(width 0.12065)
		(layer "In4.Cu")
		(net "SCC_A_PWR_LED")
	)
	(segment
		(start 272.464784 -342.670638)
		(end 248.897648 -319.103502)
		(width 0.12065)
		(layer "In4.Cu")
		(net "SCC_A_PWR_LED")
	)
	(segment
		(start 256.748534 -26.135076)
		(end 256.055876 -25.442418)
		(width 0.12065)
		(layer "In4.Cu")
		(net "SCC_A_PWR_LED")
	)
	(segment
		(start 252.397006 -269.692628)
		(end 245.35384 -262.649462)
		(width 0.12065)
		(layer "In4.Cu")
		(net "SCC_A_PWR_LED")
	)
	(segment
		(start 284.236668 -343.30513)
		(end 283.602176 -342.670638)
		(width 0.12065)
		(layer "In4.Cu")
		(net "SCC_A_PWR_LED")
	)
	(segment
		(start 252.397006 -282.91282)
		(end 252.397006 -269.692628)
		(width 0.12065)
		(layer "In4.Cu")
		(net "SCC_A_PWR_LED")
	)
	(segment
		(start 257.835146 -133.110986)
		(end 256.748534 -132.024374)
		(width 0.12065)
		(layer "In4.Cu")
		(net "SCC_A_PWR_LED")
	)
	(segment
		(start 212.50021 -388.795514)
		(end 213.743032 -388.795514)
		(width 0.17145)
		(layer "F.Cu")
		(net "RST_BTN_B_N")
	)
	(segment
		(start 264.595102 29.32811)
		(end 264.595102 31.074868)
		(width 0.17145)
		(layer "F.Cu")
		(net "RST_BTN_B_N")
	)
	(segment
		(start 212.042502 -388.337806)
		(end 212.50021 -388.795514)
		(width 0.17145)
		(layer "F.Cu")
		(net "RST_BTN_B_N")
	)
	(via
		(at 264.595102 29.32811)
		(size 0.5588)
		(drill 0.3048)
		(layers "F.Cu" "B.Cu")
		(net "RST_BTN_B_N")
	)
	(via
		(at 265.093196 -114.787934)
		(size 0.5588)
		(drill 0.3048)
		(layers "F.Cu" "B.Cu")
		(net "RST_BTN_B_N")
	)
	(via
		(at 197.360286 -335.96326)
		(size 0.5588)
		(drill 0.3048)
		(layers "F.Cu" "B.Cu")
		(net "RST_BTN_B_N")
	)
	(via
		(at 212.042502 -388.337806)
		(size 0.5588)
		(drill 0.3048)
		(layers "F.Cu" "B.Cu")
		(net "RST_BTN_B_N")
	)
	(segment
		(start 267.809472 -20.656042)
		(end 265.026394 -17.872964)
		(width 0.12065)
		(layer "In4.Cu")
		(net "RST_BTN_B_N")
	)
	(segment
		(start 262.388096 -41.493694)
		(end 267.809472 -36.072318)
		(width 0.12065)
		(layer "In4.Cu")
		(net "RST_BTN_B_N")
	)
	(segment
		(start 262.388096 -112.082834)
		(end 262.388096 -41.493694)
		(width 0.12065)
		(layer "In4.Cu")
		(net "RST_BTN_B_N")
	)
	(segment
		(start 265.026394 4.213606)
		(end 264.429748 4.810252)
		(width 0.12065)
		(layer "In4.Cu")
		(net "RST_BTN_B_N")
	)
	(segment
		(start 264.429748 4.810252)
		(end 264.429748 28.460446)
		(width 0.12065)
		(layer "In4.Cu")
		(net "RST_BTN_B_N")
	)
	(segment
		(start 265.026394 -17.872964)
		(end 265.026394 4.213606)
		(width 0.12065)
		(layer "In4.Cu")
		(net "RST_BTN_B_N")
	)
	(segment
		(start 264.595102 28.6258)
		(end 264.595102 29.32811)
		(width 0.12065)
		(layer "In4.Cu")
		(net "RST_BTN_B_N")
	)
	(segment
		(start 265.093196 -114.787934)
		(end 262.388096 -112.082834)
		(width 0.12065)
		(layer "In4.Cu")
		(net "RST_BTN_B_N")
	)
	(segment
		(start 267.809472 -36.072318)
		(end 267.809472 -20.656042)
		(width 0.12065)
		(layer "In4.Cu")
		(net "RST_BTN_B_N")
	)
	(segment
		(start 264.429748 28.460446)
		(end 264.595102 28.6258)
		(width 0.12065)
		(layer "In4.Cu")
		(net "RST_BTN_B_N")
	)
	(segment
		(start 197.139052 -338.195412)
		(end 197.139052 -336.184494)
		(width 0.12065)
		(layer "In7.Cu")
		(net "RST_BTN_B_N")
	)
	(segment
		(start 212.042502 -388.337806)
		(end 211.97189 -388.337806)
		(width 0.12065)
		(layer "In7.Cu")
		(net "RST_BTN_B_N")
	)
	(segment
		(start 210.0326 -386.398516)
		(end 210.0326 -351.08896)
		(width 0.12065)
		(layer "In7.Cu")
		(net "RST_BTN_B_N")
	)
	(segment
		(start 197.139052 -336.184494)
		(end 197.360286 -335.96326)
		(width 0.12065)
		(layer "In7.Cu")
		(net "RST_BTN_B_N")
	)
	(segment
		(start 210.0326 -351.08896)
		(end 197.139052 -338.195412)
		(width 0.12065)
		(layer "In7.Cu")
		(net "RST_BTN_B_N")
	)
	(segment
		(start 211.97189 -388.337806)
		(end 210.0326 -386.398516)
		(width 0.12065)
		(layer "In7.Cu")
		(net "RST_BTN_B_N")
	)
	(segment
		(start 239.334802 -191.880998)
		(end 239.90935 -191.30645)
		(width 0.13335)
		(layer "In9.Cu")
		(net "RST_BTN_B_N")
	)
	(segment
		(start 197.360286 -313.261756)
		(end 193.072512 -308.973982)
		(width 0.13335)
		(layer "In9.Cu")
		(net "RST_BTN_B_N")
	)
	(segment
		(start 230.80345 -200.41235)
		(end 230.831898 -200.383902)
		(width 0.13335)
		(layer "In9.Cu")
		(net "RST_BTN_B_N")
	)
	(segment
		(start 230.831898 -200.383902)
		(end 230.831898 -199.082152)
		(width 0.13335)
		(layer "In9.Cu")
		(net "RST_BTN_B_N")
	)
	(segment
		(start 239.90935 -191.30645)
		(end 239.90935 -187.703714)
		(width 0.13335)
		(layer "In9.Cu")
		(net "RST_BTN_B_N")
	)
	(segment
		(start 244.32514 -183.287924)
		(end 244.32514 -155.20924)
		(width 0.13335)
		(layer "In9.Cu")
		(net "RST_BTN_B_N")
	)
	(segment
		(start 195.482718 -296.026078)
		(end 195.482718 -278.93518)
		(width 0.13335)
		(layer "In9.Cu")
		(net "RST_BTN_B_N")
	)
	(segment
		(start 230.831898 -199.082152)
		(end 238.033052 -191.880998)
		(width 0.13335)
		(layer "In9.Cu")
		(net "RST_BTN_B_N")
	)
	(segment
		(start 244.32514 -155.20924)
		(end 254.19685 -145.33753)
		(width 0.13335)
		(layer "In9.Cu")
		(net "RST_BTN_B_N")
	)
	(segment
		(start 239.90935 -187.703714)
		(end 244.32514 -183.287924)
		(width 0.13335)
		(layer "In9.Cu")
		(net "RST_BTN_B_N")
	)
	(segment
		(start 195.482718 -278.93518)
		(end 202.9714 -271.446498)
		(width 0.13335)
		(layer "In9.Cu")
		(net "RST_BTN_B_N")
	)
	(segment
		(start 202.9714 -271.446498)
		(end 202.9714 -243.009166)
		(width 0.13335)
		(layer "In9.Cu")
		(net "RST_BTN_B_N")
	)
	(segment
		(start 197.360286 -335.96326)
		(end 197.360286 -313.261756)
		(width 0.13335)
		(layer "In9.Cu")
		(net "RST_BTN_B_N")
	)
	(segment
		(start 193.072512 -308.973982)
		(end 193.072512 -298.436284)
		(width 0.13335)
		(layer "In9.Cu")
		(net "RST_BTN_B_N")
	)
	(segment
		(start 193.072512 -298.436284)
		(end 195.482718 -296.026078)
		(width 0.13335)
		(layer "In9.Cu")
		(net "RST_BTN_B_N")
	)
	(segment
		(start 202.9714 -243.009166)
		(end 230.80345 -215.177116)
		(width 0.13335)
		(layer "In9.Cu")
		(net "RST_BTN_B_N")
	)
	(segment
		(start 238.033052 -191.880998)
		(end 239.334802 -191.880998)
		(width 0.13335)
		(layer "In9.Cu")
		(net "RST_BTN_B_N")
	)
	(segment
		(start 230.80345 -215.177116)
		(end 230.80345 -200.41235)
		(width 0.13335)
		(layer "In9.Cu")
		(net "RST_BTN_B_N")
	)
	(segment
		(start 254.19685 -125.68428)
		(end 265.093196 -114.787934)
		(width 0.13335)
		(layer "In9.Cu")
		(net "RST_BTN_B_N")
	)
	(segment
		(start 254.19685 -145.33753)
		(end 254.19685 -125.68428)
		(width 0.13335)
		(layer "In9.Cu")
		(net "RST_BTN_B_N")
	)
	(segment
		(start 247.79097 -294.808656)
		(end 247.79097 -296.075862)
		(width 0.17145)
		(layer "F.Cu")
		(net "RST_BTN_A_N")
	)
	(segment
		(start 253.50343 20.1422)
		(end 253.50343 22.86)
		(width 0.17145)
		(layer "F.Cu")
		(net "RST_BTN_A_N")
	)
	(segment
		(start 254.270002 24.908002)
		(end 254.270002 26.404824)
		(width 0.17145)
		(layer "F.Cu")
		(net "RST_BTN_A_N")
	)
	(segment
		(start 253.50343 24.14143)
		(end 254.270002 24.908002)
		(width 0.17145)
		(layer "F.Cu")
		(net "RST_BTN_A_N")
	)
	(segment
		(start 253.50343 22.86)
		(end 253.50343 24.14143)
		(width 0.17145)
		(layer "F.Cu")
		(net "RST_BTN_A_N")
	)
	(segment
		(start 247.122696 -294.140382)
		(end 247.79097 -294.808656)
		(width 0.17145)
		(layer "F.Cu")
		(net "RST_BTN_A_N")
	)
	(via
		(at 253.50343 22.86)
		(size 0.6604)
		(drill 0.3302)
		(layers "F.Cu" "B.Cu")
		(net "RST_BTN_A_N")
	)
	(via
		(at 253.50343 20.1422)
		(size 0.5588)
		(drill 0.3048)
		(layers "F.Cu" "B.Cu")
		(net "RST_BTN_A_N")
	)
	(via
		(at 247.122696 -294.140382)
		(size 0.5588)
		(drill 0.3048)
		(layers "F.Cu" "B.Cu")
		(net "RST_BTN_A_N")
	)
	(segment
		(start 244.307868 -260.995668)
		(end 244.307868 -258.07543)
		(width 0.12065)
		(layer "In4.Cu")
		(net "RST_BTN_A_N")
	)
	(segment
		(start 251.768356 -269.953232)
		(end 244.677692 -262.862568)
		(width 0.12065)
		(layer "In4.Cu")
		(net "RST_BTN_A_N")
	)
	(segment
		(start 257.152902 -204.335888)
		(end 257.152902 -133.398514)
		(width 0.12065)
		(layer "In4.Cu")
		(net "RST_BTN_A_N")
	)
	(segment
		(start 255.427226 -25.703022)
		(end 255.427226 -11.619738)
		(width 0.12065)
		(layer "In4.Cu")
		(net "RST_BTN_A_N")
	)
	(segment
		(start 249.9487 -245.956074)
		(end 249.9487 -218.9607)
		(width 0.12065)
		(layer "In4.Cu")
		(net "RST_BTN_A_N")
	)
	(segment
		(start 251.768356 -282.652216)
		(end 251.768356 -269.953232)
		(width 0.12065)
		(layer "In4.Cu")
		(net "RST_BTN_A_N")
	)
	(segment
		(start 250.290076 -218.619324)
		(end 250.290076 -211.198714)
		(width 0.12065)
		(layer "In4.Cu")
		(net "RST_BTN_A_N")
	)
	(segment
		(start 257.152902 -133.398514)
		(end 256.199894 -132.445506)
		(width 0.12065)
		(layer "In4.Cu")
		(net "RST_BTN_A_N")
	)
	(segment
		(start 247.122696 -294.140382)
		(end 247.122696 -287.297876)
		(width 0.12065)
		(layer "In4.Cu")
		(net "RST_BTN_A_N")
	)
	(segment
		(start 256.199894 -132.364988)
		(end 255.981708 -132.146802)
		(width 0.12065)
		(layer "In4.Cu")
		(net "RST_BTN_A_N")
	)
	(segment
		(start 250.290076 -211.198714)
		(end 257.152902 -204.335888)
		(width 0.12065)
		(layer "In4.Cu")
		(net "RST_BTN_A_N")
	)
	(segment
		(start 255.981708 -26.257504)
		(end 255.427226 -25.703022)
		(width 0.12065)
		(layer "In4.Cu")
		(net "RST_BTN_A_N")
	)
	(segment
		(start 244.307868 -258.07543)
		(end 243.543328 -257.31089)
		(width 0.12065)
		(layer "In4.Cu")
		(net "RST_BTN_A_N")
	)
	(segment
		(start 255.981708 -132.146802)
		(end 255.981708 -26.257504)
		(width 0.12065)
		(layer "In4.Cu")
		(net "RST_BTN_A_N")
	)
	(segment
		(start 247.122696 -287.297876)
		(end 251.768356 -282.652216)
		(width 0.12065)
		(layer "In4.Cu")
		(net "RST_BTN_A_N")
	)
	(segment
		(start 243.543328 -252.361446)
		(end 249.9487 -245.956074)
		(width 0.12065)
		(layer "In4.Cu")
		(net "RST_BTN_A_N")
	)
	(segment
		(start 243.543328 -257.31089)
		(end 243.543328 -252.361446)
		(width 0.12065)
		(layer "In4.Cu")
		(net "RST_BTN_A_N")
	)
	(segment
		(start 244.677692 -262.862568)
		(end 244.677692 -261.365492)
		(width 0.12065)
		(layer "In4.Cu")
		(net "RST_BTN_A_N")
	)
	(segment
		(start 253.50343 17.46377)
		(end 253.50343 20.1422)
		(width 0.12065)
		(layer "In4.Cu")
		(net "RST_BTN_A_N")
	)
	(segment
		(start 255.427226 -11.619738)
		(end 256.803652 -10.243312)
		(width 0.12065)
		(layer "In4.Cu")
		(net "RST_BTN_A_N")
	)
	(segment
		(start 256.199894 -132.445506)
		(end 256.199894 -132.364988)
		(width 0.12065)
		(layer "In4.Cu")
		(net "RST_BTN_A_N")
	)
	(segment
		(start 256.803652 14.163548)
		(end 253.50343 17.46377)
		(width 0.12065)
		(layer "In4.Cu")
		(net "RST_BTN_A_N")
	)
	(segment
		(start 244.677692 -261.365492)
		(end 244.307868 -260.995668)
		(width 0.12065)
		(layer "In4.Cu")
		(net "RST_BTN_A_N")
	)
	(segment
		(start 256.803652 -10.243312)
		(end 256.803652 14.163548)
		(width 0.12065)
		(layer "In4.Cu")
		(net "RST_BTN_A_N")
	)
	(segment
		(start 249.9487 -218.9607)
		(end 250.290076 -218.619324)
		(width 0.12065)
		(layer "In4.Cu")
		(net "RST_BTN_A_N")
	)
	(segment
		(start 185.212228 -218.157552)
		(end 184.469532 -217.414856)
		(width 0.254)
		(layer "B.Cu")
		(net "PWRGD_P3V3_STBY")
	)
	(segment
		(start 182.246016 -222.747332)
		(end 182.246016 -223.698816)
		(width 0.254)
		(layer "B.Cu")
		(net "PWRGD_P3V3_STBY")
	)
	(segment
		(start 184.469532 -217.414856)
		(end 183.415432 -217.414856)
		(width 0.254)
		(layer "B.Cu")
		(net "PWRGD_P3V3_STBY")
	)
	(segment
		(start 185.212228 -219.062808)
		(end 185.212228 -218.157552)
		(width 0.254)
		(layer "B.Cu")
		(net "PWRGD_P3V3_STBY")
	)
	(segment
		(start 182.656226 -218.174062)
		(end 181.192678 -219.63761)
		(width 0.254)
		(layer "B.Cu")
		(net "PWRGD_P3V3_STBY")
	)
	(segment
		(start 183.415432 -217.414856)
		(end 182.656226 -218.174062)
		(width 0.254)
		(layer "B.Cu")
		(net "PWRGD_P3V3_STBY")
	)
	(segment
		(start 181.192678 -219.63761)
		(end 181.192678 -221.32544)
		(width 0.254)
		(layer "B.Cu")
		(net "PWRGD_P3V3_STBY")
	)
	(segment
		(start 182.246016 -222.378778)
		(end 182.246016 -222.747332)
		(width 0.254)
		(layer "B.Cu")
		(net "PWRGD_P3V3_STBY")
	)
	(segment
		(start 181.192678 -221.32544)
		(end 182.246016 -222.378778)
		(width 0.254)
		(layer "B.Cu")
		(net "PWRGD_P3V3_STBY")
	)
	(segment
		(start 183.476646 -224.929446)
		(end 184.093104 -224.929446)
		(width 0.254)
		(layer "B.Cu")
		(net "PWRGD_P3V3_STBY")
	)
	(segment
		(start 182.246016 -223.698816)
		(end 183.476646 -224.929446)
		(width 0.254)
		(layer "B.Cu")
		(net "PWRGD_P3V3_STBY")
	)
	(via
		(at 199.55256 -337.40598)
		(size 0.5588)
		(drill 0.3048)
		(layers "F.Cu" "B.Cu")
		(net "PWM_SCC_A_ZONE_D")
	)
	(segment
		(start 225.491802 -340.833202)
		(end 215.493092 -340.833202)
		(width 0.13335)
		(layer "In2.Cu")
		(net "PWM_SCC_A_ZONE_D")
	)
	(segment
		(start 199.55256 -337.322922)
		(end 199.55256 -337.40598)
		(width 0.13335)
		(layer "In2.Cu")
		(net "PWM_SCC_A_ZONE_D")
	)
	(segment
		(start 200.343262 -336.53222)
		(end 199.55256 -337.322922)
		(width 0.13335)
		(layer "In2.Cu")
		(net "PWM_SCC_A_ZONE_D")
	)
	(segment
		(start 215.493092 -340.833202)
		(end 211.19211 -336.53222)
		(width 0.13335)
		(layer "In2.Cu")
		(net "PWM_SCC_A_ZONE_D")
	)
	(segment
		(start 261.730236 -345.245436)
		(end 261.045198 -344.560398)
		(width 0.13335)
		(layer "In2.Cu")
		(net "PWM_SCC_A_ZONE_D")
	)
	(segment
		(start 281.836622 -345.105228)
		(end 280.906474 -344.17508)
		(width 0.13335)
		(layer "In2.Cu")
		(net "PWM_SCC_A_ZONE_D")
	)
	(segment
		(start 280.906474 -344.17508)
		(end 272.15592 -344.17508)
		(width 0.13335)
		(layer "In2.Cu")
		(net "PWM_SCC_A_ZONE_D")
	)
	(segment
		(start 272.15592 -344.17508)
		(end 271.085564 -345.245436)
		(width 0.13335)
		(layer "In2.Cu")
		(net "PWM_SCC_A_ZONE_D")
	)
	(segment
		(start 211.19211 -336.53222)
		(end 200.343262 -336.53222)
		(width 0.13335)
		(layer "In2.Cu")
		(net "PWM_SCC_A_ZONE_D")
	)
	(segment
		(start 228.025452 -343.366852)
		(end 225.491802 -340.833202)
		(width 0.13335)
		(layer "In2.Cu")
		(net "PWM_SCC_A_ZONE_D")
	)
	(segment
		(start 261.045198 -344.560398)
		(end 246.609108 -344.560398)
		(width 0.13335)
		(layer "In2.Cu")
		(net "PWM_SCC_A_ZONE_D")
	)
	(segment
		(start 245.415562 -343.366852)
		(end 228.025452 -343.366852)
		(width 0.13335)
		(layer "In2.Cu")
		(net "PWM_SCC_A_ZONE_D")
	)
	(segment
		(start 246.609108 -344.560398)
		(end 245.415562 -343.366852)
		(width 0.13335)
		(layer "In2.Cu")
		(net "PWM_SCC_A_ZONE_D")
	)
	(segment
		(start 271.085564 -345.245436)
		(end 261.730236 -345.245436)
		(width 0.13335)
		(layer "In2.Cu")
		(net "PWM_SCC_A_ZONE_D")
	)
	(segment
		(start 221.64167 -401.626324)
		(end 214.042752 -394.027406)
		(width 0.12065)
		(layer "In7.Cu")
		(net "PWM_SCC_A_ZONE_D")
	)
	(segment
		(start 212.8012 -384.089402)
		(end 212.8012 -350.801686)
		(width 0.12065)
		(layer "In7.Cu")
		(net "PWM_SCC_A_ZONE_D")
	)
	(segment
		(start 222.600012 -409.600146)
		(end 221.64167 -408.641804)
		(width 0.12065)
		(layer "In7.Cu")
		(net "PWM_SCC_A_ZONE_D")
	)
	(segment
		(start 199.55256 -337.553046)
		(end 199.55256 -337.40598)
		(width 0.12065)
		(layer "In7.Cu")
		(net "PWM_SCC_A_ZONE_D")
	)
	(segment
		(start 212.8012 -350.801686)
		(end 199.55256 -337.553046)
		(width 0.12065)
		(layer "In7.Cu")
		(net "PWM_SCC_A_ZONE_D")
	)
	(segment
		(start 221.64167 -408.641804)
		(end 221.64167 -401.626324)
		(width 0.12065)
		(layer "In7.Cu")
		(net "PWM_SCC_A_ZONE_D")
	)
	(segment
		(start 214.042752 -385.330954)
		(end 212.8012 -384.089402)
		(width 0.12065)
		(layer "In7.Cu")
		(net "PWM_SCC_A_ZONE_D")
	)
	(segment
		(start 214.042752 -394.027406)
		(end 214.042752 -385.330954)
		(width 0.12065)
		(layer "In7.Cu")
		(net "PWM_SCC_A_ZONE_D")
	)
	(via
		(at 200.73366 -337.41614)
		(size 0.5588)
		(drill 0.3048)
		(layers "F.Cu" "B.Cu")
		(net "PWM_SCC_A_ZONE_C")
	)
	(segment
		(start 227.70973 -344.128852)
		(end 225.17608 -341.595202)
		(width 0.13335)
		(layer "In2.Cu")
		(net "PWM_SCC_A_ZONE_C")
	)
	(segment
		(start 210.843368 -337.2612)
		(end 200.8886 -337.2612)
		(width 0.13335)
		(layer "In2.Cu")
		(net "PWM_SCC_A_ZONE_C")
	)
	(segment
		(start 246.196358 -345.322398)
		(end 245.002812 -344.128852)
		(width 0.13335)
		(layer "In2.Cu")
		(net "PWM_SCC_A_ZONE_C")
	)
	(segment
		(start 261.414514 -346.007436)
		(end 260.729476 -345.322398)
		(width 0.13335)
		(layer "In2.Cu")
		(net "PWM_SCC_A_ZONE_C")
	)
	(segment
		(start 283.23667 -345.105228)
		(end 282.334462 -346.007436)
		(width 0.13335)
		(layer "In2.Cu")
		(net "PWM_SCC_A_ZONE_C")
	)
	(segment
		(start 245.002812 -344.128852)
		(end 227.70973 -344.128852)
		(width 0.13335)
		(layer "In2.Cu")
		(net "PWM_SCC_A_ZONE_C")
	)
	(segment
		(start 215.17737 -341.595202)
		(end 210.843368 -337.2612)
		(width 0.13335)
		(layer "In2.Cu")
		(net "PWM_SCC_A_ZONE_C")
	)
	(segment
		(start 282.334462 -346.007436)
		(end 261.414514 -346.007436)
		(width 0.13335)
		(layer "In2.Cu")
		(net "PWM_SCC_A_ZONE_C")
	)
	(segment
		(start 225.17608 -341.595202)
		(end 215.17737 -341.595202)
		(width 0.13335)
		(layer "In2.Cu")
		(net "PWM_SCC_A_ZONE_C")
	)
	(segment
		(start 200.8886 -337.2612)
		(end 200.73366 -337.41614)
		(width 0.13335)
		(layer "In2.Cu")
		(net "PWM_SCC_A_ZONE_C")
	)
	(segment
		(start 260.729476 -345.322398)
		(end 246.196358 -345.322398)
		(width 0.13335)
		(layer "In2.Cu")
		(net "PWM_SCC_A_ZONE_C")
	)
	(segment
		(start 213.5632 -383.77368)
		(end 213.5632 -350.355916)
		(width 0.12065)
		(layer "In7.Cu")
		(net "PWM_SCC_A_ZONE_C")
	)
	(segment
		(start 214.804752 -393.71143)
		(end 214.804752 -385.015232)
		(width 0.12065)
		(layer "In7.Cu")
		(net "PWM_SCC_A_ZONE_C")
	)
	(segment
		(start 222.882206 -411.000194)
		(end 223.3676 -410.5148)
		(width 0.12065)
		(layer "In7.Cu")
		(net "PWM_SCC_A_ZONE_C")
	)
	(segment
		(start 213.5632 -350.355916)
		(end 200.73366 -337.526376)
		(width 0.12065)
		(layer "In7.Cu")
		(net "PWM_SCC_A_ZONE_C")
	)
	(segment
		(start 214.804752 -385.015232)
		(end 213.5632 -383.77368)
		(width 0.12065)
		(layer "In7.Cu")
		(net "PWM_SCC_A_ZONE_C")
	)
	(segment
		(start 223.120458 -402.027136)
		(end 214.804752 -393.71143)
		(width 0.12065)
		(layer "In7.Cu")
		(net "PWM_SCC_A_ZONE_C")
	)
	(segment
		(start 223.3676 -403.344888)
		(end 223.120458 -403.097746)
		(width 0.12065)
		(layer "In7.Cu")
		(net "PWM_SCC_A_ZONE_C")
	)
	(segment
		(start 223.120458 -403.097746)
		(end 223.120458 -402.027136)
		(width 0.12065)
		(layer "In7.Cu")
		(net "PWM_SCC_A_ZONE_C")
	)
	(segment
		(start 222.600012 -411.000194)
		(end 222.882206 -411.000194)
		(width 0.12065)
		(layer "In7.Cu")
		(net "PWM_SCC_A_ZONE_C")
	)
	(segment
		(start 200.73366 -337.526376)
		(end 200.73366 -337.41614)
		(width 0.12065)
		(layer "In7.Cu")
		(net "PWM_SCC_A_ZONE_C")
	)
	(segment
		(start 223.3676 -410.5148)
		(end 223.3676 -403.344888)
		(width 0.12065)
		(layer "In7.Cu")
		(net "PWM_SCC_A_ZONE_C")
	)
	(via
		(at 341.391748 -187.4012)
		(size 0.5588)
		(drill 0.3048)
		(layers "F.Cu" "B.Cu")
		(net "PWM_BMC_B_ZONE_D")
	)
	(via
		(at 243.0526 -187.3504)
		(size 0.5588)
		(drill 0.3048)
		(layers "F.Cu" "B.Cu")
		(net "PWM_BMC_B_ZONE_D")
	)
	(segment
		(start 253.959106 -194.681856)
		(end 312.57621 -194.681856)
		(width 0.13335)
		(layer "In2.Cu")
		(net "PWM_BMC_B_ZONE_D")
	)
	(segment
		(start 246.62765 -187.3504)
		(end 253.959106 -194.681856)
		(width 0.13335)
		(layer "In2.Cu")
		(net "PWM_BMC_B_ZONE_D")
	)
	(segment
		(start 340.86292 -186.872372)
		(end 341.391748 -187.4012)
		(width 0.13335)
		(layer "In2.Cu")
		(net "PWM_BMC_B_ZONE_D")
	)
	(segment
		(start 243.0526 -187.3504)
		(end 246.62765 -187.3504)
		(width 0.13335)
		(layer "In2.Cu")
		(net "PWM_BMC_B_ZONE_D")
	)
	(segment
		(start 320.385694 -186.872372)
		(end 340.86292 -186.872372)
		(width 0.13335)
		(layer "In2.Cu")
		(net "PWM_BMC_B_ZONE_D")
	)
	(segment
		(start 312.57621 -194.681856)
		(end 320.385694 -186.872372)
		(width 0.13335)
		(layer "In2.Cu")
		(net "PWM_BMC_B_ZONE_D")
	)
	(segment
		(start 206.490062 -414.290002)
		(end 210.000088 -417.800028)
		(width 0.12065)
		(layer "In4.Cu")
		(net "PWM_BMC_B_ZONE_D")
	)
	(segment
		(start 231.414574 -187.924948)
		(end 213.388702 -205.95082)
		(width 0.12065)
		(layer "In4.Cu")
		(net "PWM_BMC_B_ZONE_D")
	)
	(segment
		(start 213.388702 -205.95082)
		(end 213.388702 -315.431424)
		(width 0.12065)
		(layer "In4.Cu")
		(net "PWM_BMC_B_ZONE_D")
	)
	(segment
		(start 329.561952 -122.17781)
		(end 329.561952 -170.616372)
		(width 0.12065)
		(layer "In4.Cu")
		(net "PWM_BMC_B_ZONE_D")
	)
	(segment
		(start 341.391748 -182.446168)
		(end 341.391748 -187.4012)
		(width 0.12065)
		(layer "In4.Cu")
		(net "PWM_BMC_B_ZONE_D")
	)
	(segment
		(start 329.561952 -170.616372)
		(end 341.391748 -182.446168)
		(width 0.12065)
		(layer "In4.Cu")
		(net "PWM_BMC_B_ZONE_D")
	)
	(segment
		(start 342.957912 -74.189336)
		(end 344.293698 -75.525122)
		(width 0.12065)
		(layer "In4.Cu")
		(net "PWM_BMC_B_ZONE_D")
	)
	(segment
		(start 344.293698 -75.525122)
		(end 344.293698 -107.446064)
		(width 0.12065)
		(layer "In4.Cu")
		(net "PWM_BMC_B_ZONE_D")
	)
	(segment
		(start 355.149912 -24.550116)
		(end 355.149912 -24.732488)
		(width 0.12065)
		(layer "In4.Cu")
		(net "PWM_BMC_B_ZONE_D")
	)
	(segment
		(start 355.149912 -24.732488)
		(end 350.34474 -29.53766)
		(width 0.12065)
		(layer "In4.Cu")
		(net "PWM_BMC_B_ZONE_D")
	)
	(segment
		(start 213.388702 -315.431424)
		(end 206.490062 -322.330064)
		(width 0.12065)
		(layer "In4.Cu")
		(net "PWM_BMC_B_ZONE_D")
	)
	(segment
		(start 342.957912 -41.594278)
		(end 342.957912 -74.189336)
		(width 0.12065)
		(layer "In4.Cu")
		(net "PWM_BMC_B_ZONE_D")
	)
	(segment
		(start 242.478052 -187.924948)
		(end 231.414574 -187.924948)
		(width 0.12065)
		(layer "In4.Cu")
		(net "PWM_BMC_B_ZONE_D")
	)
	(segment
		(start 344.293698 -107.446064)
		(end 329.561952 -122.17781)
		(width 0.12065)
		(layer "In4.Cu")
		(net "PWM_BMC_B_ZONE_D")
	)
	(segment
		(start 243.0526 -187.3504)
		(end 242.478052 -187.924948)
		(width 0.12065)
		(layer "In4.Cu")
		(net "PWM_BMC_B_ZONE_D")
	)
	(segment
		(start 206.490062 -322.330064)
		(end 206.490062 -414.290002)
		(width 0.12065)
		(layer "In4.Cu")
		(net "PWM_BMC_B_ZONE_D")
	)
	(segment
		(start 350.34474 -29.53766)
		(end 350.34474 -34.20745)
		(width 0.12065)
		(layer "In4.Cu")
		(net "PWM_BMC_B_ZONE_D")
	)
	(segment
		(start 350.34474 -34.20745)
		(end 342.957912 -41.594278)
		(width 0.12065)
		(layer "In4.Cu")
		(net "PWM_BMC_B_ZONE_D")
	)
	(via
		(at 342.2904 -186.455812)
		(size 0.5588)
		(drill 0.3048)
		(layers "F.Cu" "B.Cu")
		(net "PWM_BMC_B_ZONE_C")
	)
	(via
		(at 242.1128 -187.1218)
		(size 0.5588)
		(drill 0.3048)
		(layers "F.Cu" "B.Cu")
		(net "PWM_BMC_B_ZONE_C")
	)
	(segment
		(start 312.108088 -193.919856)
		(end 319.917572 -186.110372)
		(width 0.13335)
		(layer "In2.Cu")
		(net "PWM_BMC_B_ZONE_C")
	)
	(segment
		(start 246.917972 -186.563)
		(end 254.274828 -193.919856)
		(width 0.13335)
		(layer "In2.Cu")
		(net "PWM_BMC_B_ZONE_C")
	)
	(segment
		(start 254.274828 -193.919856)
		(end 312.108088 -193.919856)
		(width 0.13335)
		(layer "In2.Cu")
		(net "PWM_BMC_B_ZONE_C")
	)
	(segment
		(start 242.1128 -187.1218)
		(end 242.6716 -186.563)
		(width 0.13335)
		(layer "In2.Cu")
		(net "PWM_BMC_B_ZONE_C")
	)
	(segment
		(start 242.6716 -186.563)
		(end 246.917972 -186.563)
		(width 0.13335)
		(layer "In2.Cu")
		(net "PWM_BMC_B_ZONE_C")
	)
	(segment
		(start 319.917572 -186.110372)
		(end 341.94496 -186.110372)
		(width 0.13335)
		(layer "In2.Cu")
		(net "PWM_BMC_B_ZONE_C")
	)
	(segment
		(start 341.94496 -186.110372)
		(end 342.2904 -186.455812)
		(width 0.13335)
		(layer "In2.Cu")
		(net "PWM_BMC_B_ZONE_C")
	)
	(segment
		(start 342.2904 -182.267098)
		(end 342.2904 -186.455812)
		(width 0.12065)
		(layer "In4.Cu")
		(net "PWM_BMC_B_ZONE_C")
	)
	(segment
		(start 345.055698 -107.761786)
		(end 330.323952 -122.493532)
		(width 0.12065)
		(layer "In4.Cu")
		(net "PWM_BMC_B_ZONE_C")
	)
	(segment
		(start 205.728062 -322.508118)
		(end 212.975952 -315.260228)
		(width 0.12065)
		(layer "In4.Cu")
		(net "PWM_BMC_B_ZONE_C")
	)
	(segment
		(start 355.149912 -25.950164)
		(end 351.10674 -29.993336)
		(width 0.12065)
		(layer "In4.Cu")
		(net "PWM_BMC_B_ZONE_C")
	)
	(segment
		(start 345.055698 -75.2094)
		(end 345.055698 -107.761786)
		(width 0.12065)
		(layer "In4.Cu")
		(net "PWM_BMC_B_ZONE_C")
	)
	(segment
		(start 212.975952 -205.235048)
		(end 231.0892 -187.1218)
		(width 0.12065)
		(layer "In4.Cu")
		(net "PWM_BMC_B_ZONE_C")
	)
	(segment
		(start 343.719912 -41.91)
		(end 343.719912 -73.873614)
		(width 0.12065)
		(layer "In4.Cu")
		(net "PWM_BMC_B_ZONE_C")
	)
	(segment
		(start 330.323952 -170.30065)
		(end 342.2904 -182.267098)
		(width 0.12065)
		(layer "In4.Cu")
		(net "PWM_BMC_B_ZONE_C")
	)
	(segment
		(start 330.323952 -122.493532)
		(end 330.323952 -170.30065)
		(width 0.12065)
		(layer "In4.Cu")
		(net "PWM_BMC_B_ZONE_C")
	)
	(segment
		(start 205.728062 -414.92805)
		(end 205.728062 -322.508118)
		(width 0.12065)
		(layer "In4.Cu")
		(net "PWM_BMC_B_ZONE_C")
	)
	(segment
		(start 351.10674 -34.523172)
		(end 343.719912 -41.91)
		(width 0.12065)
		(layer "In4.Cu")
		(net "PWM_BMC_B_ZONE_C")
	)
	(segment
		(start 210.000088 -419.200076)
		(end 205.728062 -414.92805)
		(width 0.12065)
		(layer "In4.Cu")
		(net "PWM_BMC_B_ZONE_C")
	)
	(segment
		(start 343.719912 -73.873614)
		(end 345.055698 -75.2094)
		(width 0.12065)
		(layer "In4.Cu")
		(net "PWM_BMC_B_ZONE_C")
	)
	(segment
		(start 231.0892 -187.1218)
		(end 242.1128 -187.1218)
		(width 0.12065)
		(layer "In4.Cu")
		(net "PWM_BMC_B_ZONE_C")
	)
	(segment
		(start 351.10674 -29.993336)
		(end 351.10674 -34.523172)
		(width 0.12065)
		(layer "In4.Cu")
		(net "PWM_BMC_B_ZONE_C")
	)
	(segment
		(start 212.975952 -315.260228)
		(end 212.975952 -205.235048)
		(width 0.12065)
		(layer "In4.Cu")
		(net "PWM_BMC_B_ZONE_C")
	)
	(via
		(at 106.406188 -344.556588)
		(size 0.5588)
		(drill 0.3048)
		(layers "F.Cu" "B.Cu")
		(net "PWM_BMC_A_ZONE_D")
	)
	(segment
		(start 101.469952 -171.156884)
		(end 105.275634 -174.962566)
		(width 0.12065)
		(layer "In4.Cu")
		(net "PWM_BMC_A_ZONE_D")
	)
	(segment
		(start 109.149896 -24.550116)
		(end 106.138726 -27.561286)
		(width 0.12065)
		(layer "In4.Cu")
		(net "PWM_BMC_A_ZONE_D")
	)
	(segment
		(start 105.275634 -174.962566)
		(end 105.275634 -265.675618)
		(width 0.12065)
		(layer "In4.Cu")
		(net "PWM_BMC_A_ZONE_D")
	)
	(segment
		(start 104.024176 -87.63762)
		(end 104.024176 -125.089412)
		(width 0.12065)
		(layer "In4.Cu")
		(net "PWM_BMC_A_ZONE_D")
	)
	(segment
		(start 100.768658 -84.382102)
		(end 104.024176 -87.63762)
		(width 0.12065)
		(layer "In4.Cu")
		(net "PWM_BMC_A_ZONE_D")
	)
	(segment
		(start 100.950014 -273.947636)
		(end 100.950268 -273.94789)
		(width 0.12065)
		(layer "In4.Cu")
		(net "PWM_BMC_A_ZONE_D")
	)
	(segment
		(start 106.138726 -27.561286)
		(end 106.138726 -37.547804)
		(width 0.12065)
		(layer "In4.Cu")
		(net "PWM_BMC_A_ZONE_D")
	)
	(segment
		(start 100.950014 -273.3167)
		(end 100.950014 -273.947636)
		(width 0.12065)
		(layer "In4.Cu")
		(net "PWM_BMC_A_ZONE_D")
	)
	(segment
		(start 100.950268 -292.771068)
		(end 104.36098 -296.18178)
		(width 0.12065)
		(layer "In4.Cu")
		(net "PWM_BMC_A_ZONE_D")
	)
	(segment
		(start 104.024176 -125.089412)
		(end 101.469952 -127.643636)
		(width 0.12065)
		(layer "In4.Cu")
		(net "PWM_BMC_A_ZONE_D")
	)
	(segment
		(start 101.469952 -127.643636)
		(end 101.469952 -171.156884)
		(width 0.12065)
		(layer "In4.Cu")
		(net "PWM_BMC_A_ZONE_D")
	)
	(segment
		(start 100.950268 -273.94789)
		(end 100.950268 -292.771068)
		(width 0.12065)
		(layer "In4.Cu")
		(net "PWM_BMC_A_ZONE_D")
	)
	(segment
		(start 104.36098 -296.18178)
		(end 104.36098 -316.111636)
		(width 0.12065)
		(layer "In4.Cu")
		(net "PWM_BMC_A_ZONE_D")
	)
	(segment
		(start 106.406188 -318.156844)
		(end 106.406188 -344.556588)
		(width 0.12065)
		(layer "In4.Cu")
		(net "PWM_BMC_A_ZONE_D")
	)
	(segment
		(start 105.500424 -265.900408)
		(end 105.500424 -268.76629)
		(width 0.12065)
		(layer "In4.Cu")
		(net "PWM_BMC_A_ZONE_D")
	)
	(segment
		(start 105.500424 -268.76629)
		(end 100.950014 -273.3167)
		(width 0.12065)
		(layer "In4.Cu")
		(net "PWM_BMC_A_ZONE_D")
	)
	(segment
		(start 104.36098 -316.111636)
		(end 106.406188 -318.156844)
		(width 0.12065)
		(layer "In4.Cu")
		(net "PWM_BMC_A_ZONE_D")
	)
	(segment
		(start 100.768658 -42.917872)
		(end 100.768658 -84.382102)
		(width 0.12065)
		(layer "In4.Cu")
		(net "PWM_BMC_A_ZONE_D")
	)
	(segment
		(start 106.138726 -37.547804)
		(end 100.768658 -42.917872)
		(width 0.12065)
		(layer "In4.Cu")
		(net "PWM_BMC_A_ZONE_D")
	)
	(segment
		(start 105.275634 -265.675618)
		(end 105.500424 -265.900408)
		(width 0.12065)
		(layer "In4.Cu")
		(net "PWM_BMC_A_ZONE_D")
	)
	(segment
		(start 215.932512 -413.200088)
		(end 216.281 -412.8516)
		(width 0.12065)
		(layer "In7.Cu")
		(net "PWM_BMC_A_ZONE_D")
	)
	(segment
		(start 215.400128 -413.200088)
		(end 215.932512 -413.200088)
		(width 0.12065)
		(layer "In7.Cu")
		(net "PWM_BMC_A_ZONE_D")
	)
	(segment
		(start 216.281 -403.2758)
		(end 206.563722 -393.558522)
		(width 0.12065)
		(layer "In7.Cu")
		(net "PWM_BMC_A_ZONE_D")
	)
	(segment
		(start 206.563722 -351.69221)
		(end 200.971912 -346.1004)
		(width 0.12065)
		(layer "In7.Cu")
		(net "PWM_BMC_A_ZONE_D")
	)
	(segment
		(start 131.4704 -346.1004)
		(end 129.926588 -344.556588)
		(width 0.12065)
		(layer "In7.Cu")
		(net "PWM_BMC_A_ZONE_D")
	)
	(segment
		(start 216.281 -412.8516)
		(end 216.281 -403.2758)
		(width 0.12065)
		(layer "In7.Cu")
		(net "PWM_BMC_A_ZONE_D")
	)
	(segment
		(start 129.926588 -344.556588)
		(end 106.406188 -344.556588)
		(width 0.12065)
		(layer "In7.Cu")
		(net "PWM_BMC_A_ZONE_D")
	)
	(segment
		(start 206.563722 -393.558522)
		(end 206.563722 -351.69221)
		(width 0.12065)
		(layer "In7.Cu")
		(net "PWM_BMC_A_ZONE_D")
	)
	(segment
		(start 200.971912 -346.1004)
		(end 131.4704 -346.1004)
		(width 0.12065)
		(layer "In7.Cu")
		(net "PWM_BMC_A_ZONE_D")
	)
	(via
		(at 107.282742 -345.375738)
		(size 0.5588)
		(drill 0.3048)
		(layers "F.Cu" "B.Cu")
		(net "PWM_BMC_A_ZONE_C")
	)
	(segment
		(start 102.560882 -127.630428)
		(end 102.560882 -171.170092)
		(width 0.12065)
		(layer "In4.Cu")
		(net "PWM_BMC_A_ZONE_C")
	)
	(segment
		(start 105.913174 -265.729212)
		(end 105.913174 -269.431262)
		(width 0.12065)
		(layer "In4.Cu")
		(net "PWM_BMC_A_ZONE_C")
	)
	(segment
		(start 106.961178 -37.815266)
		(end 101.530658 -43.245786)
		(width 0.12065)
		(layer "In4.Cu")
		(net "PWM_BMC_A_ZONE_C")
	)
	(segment
		(start 101.530658 -84.06638)
		(end 104.836976 -87.372698)
		(width 0.12065)
		(layer "In4.Cu")
		(net "PWM_BMC_A_ZONE_C")
	)
	(segment
		(start 101.530658 -43.245786)
		(end 101.530658 -84.06638)
		(width 0.12065)
		(layer "In4.Cu")
		(net "PWM_BMC_A_ZONE_C")
	)
	(segment
		(start 109.149896 -25.950164)
		(end 106.961178 -28.138882)
		(width 0.12065)
		(layer "In4.Cu")
		(net "PWM_BMC_A_ZONE_C")
	)
	(segment
		(start 105.12298 -295.866058)
		(end 105.12298 -315.795914)
		(width 0.12065)
		(layer "In4.Cu")
		(net "PWM_BMC_A_ZONE_C")
	)
	(segment
		(start 101.712268 -292.455346)
		(end 105.12298 -295.866058)
		(width 0.12065)
		(layer "In4.Cu")
		(net "PWM_BMC_A_ZONE_C")
	)
	(segment
		(start 105.688384 -174.297594)
		(end 105.688384 -265.504422)
		(width 0.12065)
		(layer "In4.Cu")
		(net "PWM_BMC_A_ZONE_C")
	)
	(segment
		(start 107.282742 -317.955676)
		(end 107.282742 -345.375738)
		(width 0.12065)
		(layer "In4.Cu")
		(net "PWM_BMC_A_ZONE_C")
	)
	(segment
		(start 101.712268 -273.632168)
		(end 101.712268 -292.455346)
		(width 0.12065)
		(layer "In4.Cu")
		(net "PWM_BMC_A_ZONE_C")
	)
	(segment
		(start 102.560882 -171.170092)
		(end 105.688384 -174.297594)
		(width 0.12065)
		(layer "In4.Cu")
		(net "PWM_BMC_A_ZONE_C")
	)
	(segment
		(start 105.688384 -265.504422)
		(end 105.913174 -265.729212)
		(width 0.12065)
		(layer "In4.Cu")
		(net "PWM_BMC_A_ZONE_C")
	)
	(segment
		(start 105.12298 -315.795914)
		(end 107.282742 -317.955676)
		(width 0.12065)
		(layer "In4.Cu")
		(net "PWM_BMC_A_ZONE_C")
	)
	(segment
		(start 106.961178 -28.138882)
		(end 106.961178 -37.815266)
		(width 0.12065)
		(layer "In4.Cu")
		(net "PWM_BMC_A_ZONE_C")
	)
	(segment
		(start 105.913174 -269.431262)
		(end 101.712268 -273.632168)
		(width 0.12065)
		(layer "In4.Cu")
		(net "PWM_BMC_A_ZONE_C")
	)
	(segment
		(start 104.836976 -125.354334)
		(end 102.560882 -127.630428)
		(width 0.12065)
		(layer "In4.Cu")
		(net "PWM_BMC_A_ZONE_C")
	)
	(segment
		(start 104.836976 -87.372698)
		(end 104.836976 -125.354334)
		(width 0.12065)
		(layer "In4.Cu")
		(net "PWM_BMC_A_ZONE_C")
	)
	(segment
		(start 214.5284 -402.6916)
		(end 205.737714 -393.900914)
		(width 0.12065)
		(layer "In7.Cu")
		(net "PWM_BMC_A_ZONE_C")
	)
	(segment
		(start 130.926078 -346.6338)
		(end 129.668016 -345.375738)
		(width 0.12065)
		(layer "In7.Cu")
		(net "PWM_BMC_A_ZONE_C")
	)
	(segment
		(start 129.668016 -345.375738)
		(end 107.282742 -345.375738)
		(width 0.12065)
		(layer "In7.Cu")
		(net "PWM_BMC_A_ZONE_C")
	)
	(segment
		(start 205.737714 -352.034602)
		(end 200.336912 -346.6338)
		(width 0.12065)
		(layer "In7.Cu")
		(net "PWM_BMC_A_ZONE_C")
	)
	(segment
		(start 200.336912 -346.6338)
		(end 130.926078 -346.6338)
		(width 0.12065)
		(layer "In7.Cu")
		(net "PWM_BMC_A_ZONE_C")
	)
	(segment
		(start 215.400128 -414.600136)
		(end 215.108536 -414.600136)
		(width 0.12065)
		(layer "In7.Cu")
		(net "PWM_BMC_A_ZONE_C")
	)
	(segment
		(start 215.108536 -414.600136)
		(end 214.5284 -414.02)
		(width 0.12065)
		(layer "In7.Cu")
		(net "PWM_BMC_A_ZONE_C")
	)
	(segment
		(start 214.5284 -414.02)
		(end 214.5284 -402.6916)
		(width 0.12065)
		(layer "In7.Cu")
		(net "PWM_BMC_A_ZONE_C")
	)
	(segment
		(start 205.737714 -393.900914)
		(end 205.737714 -352.034602)
		(width 0.12065)
		(layer "In7.Cu")
		(net "PWM_BMC_A_ZONE_C")
	)
	(segment
		(start 267.866622 18.13814)
		(end 267.866622 16.915638)
		(width 0.381)
		(layer "F.Cu")
		(net "P5V_USB_B")
	)
	(segment
		(start 267.484098 18.520664)
		(end 267.866622 18.13814)
		(width 0.381)
		(layer "F.Cu")
		(net "P5V_USB_B")
	)
	(via
		(at 266.573 18.5928)
		(size 0.6604)
		(drill 0.3302)
		(layers "F.Cu" "B.Cu")
		(net "P5V_USB_B")
	)
	(segment
		(start 261.664196 17.087596)
		(end 262.14832 16.603472)
		(width 0.381)
		(layer "F.Cu")
		(net "P5V_USB_A")
	)
	(segment
		(start 262.14832 16.603472)
		(end 262.14832 15.58417)
		(width 0.381)
		(layer "F.Cu")
		(net "P5V_USB_A")
	)
	(via
		(at 261.5946 19.1516)
		(size 0.6604)
		(drill 0.3302)
		(layers "F.Cu" "B.Cu")
		(net "P5V_USB_A")
	)
	(segment
		(start 233.868468 -346.583762)
		(end 234.188 -346.26423)
		(width 0.17145)
		(layer "F.Cu")
		(net "P5V_A_4_SENSE")
	)
	(segment
		(start 235.817156 -343.753948)
		(end 235.809536 -343.746328)
		(width 0.17145)
		(layer "F.Cu")
		(net "P5V_A_4_SENSE")
	)
	(segment
		(start 234.188 -346.26423)
		(end 234.188 -345.367864)
		(width 0.17145)
		(layer "F.Cu")
		(net "P5V_A_4_SENSE")
	)
	(segment
		(start 233.140504 -346.583762)
		(end 233.868468 -346.583762)
		(width 0.17145)
		(layer "F.Cu")
		(net "P5V_A_4_SENSE")
	)
	(segment
		(start 236.871256 -343.753948)
		(end 235.817156 -343.753948)
		(width 0.17145)
		(layer "F.Cu")
		(net "P5V_A_4_SENSE")
	)
	(segment
		(start 235.809536 -343.746328)
		(end 235.029502 -344.526362)
		(width 0.17145)
		(layer "F.Cu")
		(net "P5V_A_4_SENSE")
	)
	(segment
		(start 234.188 -345.367864)
		(end 235.029502 -344.526362)
		(width 0.17145)
		(layer "F.Cu")
		(net "P5V_A_4_SENSE")
	)
	(segment
		(start 237.988856 -343.753948)
		(end 236.871256 -343.753948)
		(width 0.17145)
		(layer "F.Cu")
		(net "P5V_A_4_SENSE")
	)
	(via
		(at 235.029502 -344.526362)
		(size 0.6604)
		(drill 0.3302)
		(layers "F.Cu" "B.Cu")
		(net "P5V_A_4_SENSE")
	)
	(segment
		(start 241.775488 -345.910408)
		(end 241.17681 -345.910408)
		(width 0.17145)
		(layer "F.Cu")
		(net "P5V_A_3_SENSE")
	)
	(segment
		(start 234.7976 -346.4306)
		(end 234.7976 -345.948)
		(width 0.17145)
		(layer "F.Cu")
		(net "P5V_A_3_SENSE")
	)
	(segment
		(start 238.398558 -344.80627)
		(end 235.58373 -344.80627)
		(width 0.17145)
		(layer "F.Cu")
		(net "P5V_A_3_SENSE")
	)
	(segment
		(start 233.140504 -347.234002)
		(end 233.994198 -347.234002)
		(width 0.17145)
		(layer "F.Cu")
		(net "P5V_A_3_SENSE")
	)
	(segment
		(start 234.7976 -345.5924)
		(end 234.7976 -345.948)
		(width 0.17145)
		(layer "F.Cu")
		(net "P5V_A_3_SENSE")
	)
	(segment
		(start 240.578386 -345.906598)
		(end 240.324386 -345.906598)
		(width 0.17145)
		(layer "F.Cu")
		(net "P5V_A_3_SENSE")
	)
	(segment
		(start 240.316766 -345.898978)
		(end 239.491266 -345.898978)
		(width 0.17145)
		(layer "F.Cu")
		(net "P5V_A_3_SENSE")
	)
	(segment
		(start 241.173 -345.906598)
		(end 240.578386 -345.906598)
		(width 0.17145)
		(layer "F.Cu")
		(net "P5V_A_3_SENSE")
	)
	(segment
		(start 239.491266 -345.898978)
		(end 238.398558 -344.80627)
		(width 0.17145)
		(layer "F.Cu")
		(net "P5V_A_3_SENSE")
	)
	(segment
		(start 233.994198 -347.234002)
		(end 234.7976 -346.4306)
		(width 0.17145)
		(layer "F.Cu")
		(net "P5V_A_3_SENSE")
	)
	(segment
		(start 240.324386 -345.906598)
		(end 240.316766 -345.898978)
		(width 0.17145)
		(layer "F.Cu")
		(net "P5V_A_3_SENSE")
	)
	(segment
		(start 235.58373 -344.80627)
		(end 234.7976 -345.5924)
		(width 0.17145)
		(layer "F.Cu")
		(net "P5V_A_3_SENSE")
	)
	(segment
		(start 241.17681 -345.910408)
		(end 241.173 -345.906598)
		(width 0.17145)
		(layer "F.Cu")
		(net "P5V_A_3_SENSE")
	)
	(via
		(at 234.7976 -345.948)
		(size 0.6604)
		(drill 0.3302)
		(layers "F.Cu" "B.Cu")
		(net "P5V_A_3_SENSE")
	)
	(segment
		(start 236.87151 -347.22816)
		(end 237.987586 -347.22816)
		(width 0.17145)
		(layer "F.Cu")
		(net "P5V_A_2_SENSE")
	)
	(segment
		(start 234.806744 -347.234256)
		(end 235.823506 -347.234256)
		(width 0.17145)
		(layer "F.Cu")
		(net "P5V_A_2_SENSE")
	)
	(segment
		(start 233.140504 -347.884242)
		(end 234.156758 -347.884242)
		(width 0.17145)
		(layer "F.Cu")
		(net "P5V_A_2_SENSE")
	)
	(segment
		(start 235.823506 -347.234256)
		(end 235.831126 -347.226636)
		(width 0.17145)
		(layer "F.Cu")
		(net "P5V_A_2_SENSE")
	)
	(segment
		(start 235.831126 -347.226636)
		(end 236.869986 -347.226636)
		(width 0.17145)
		(layer "F.Cu")
		(net "P5V_A_2_SENSE")
	)
	(segment
		(start 234.156758 -347.884242)
		(end 234.806744 -347.234256)
		(width 0.17145)
		(layer "F.Cu")
		(net "P5V_A_2_SENSE")
	)
	(segment
		(start 236.869986 -347.226636)
		(end 236.87151 -347.22816)
		(width 0.17145)
		(layer "F.Cu")
		(net "P5V_A_2_SENSE")
	)
	(via
		(at 234.806744 -347.234256)
		(size 0.6604)
		(drill 0.3302)
		(layers "F.Cu" "B.Cu")
		(net "P5V_A_2_SENSE")
	)
	(segment
		(start 235.25353 -347.93047)
		(end 234.7468 -348.4372)
		(width 0.17145)
		(layer "F.Cu")
		(net "P5V_A_1_SENSE")
	)
	(segment
		(start 241.68735 -349.607378)
		(end 240.56975 -349.607378)
		(width 0.17145)
		(layer "F.Cu")
		(net "P5V_A_1_SENSE")
	)
	(segment
		(start 239.24895 -349.607378)
		(end 238.633 -348.991428)
		(width 0.17145)
		(layer "F.Cu")
		(net "P5V_A_1_SENSE")
	)
	(segment
		(start 234.649518 -348.534482)
		(end 234.7468 -348.4372)
		(width 0.17145)
		(layer "F.Cu")
		(net "P5V_A_1_SENSE")
	)
	(segment
		(start 239.50295 -349.607378)
		(end 239.24895 -349.607378)
		(width 0.17145)
		(layer "F.Cu")
		(net "P5V_A_1_SENSE")
	)
	(segment
		(start 240.56975 -349.607378)
		(end 239.50295 -349.607378)
		(width 0.17145)
		(layer "F.Cu")
		(net "P5V_A_1_SENSE")
	)
	(segment
		(start 238.12627 -347.93047)
		(end 235.25353 -347.93047)
		(width 0.17145)
		(layer "F.Cu")
		(net "P5V_A_1_SENSE")
	)
	(segment
		(start 233.140504 -348.534482)
		(end 234.649518 -348.534482)
		(width 0.17145)
		(layer "F.Cu")
		(net "P5V_A_1_SENSE")
	)
	(segment
		(start 238.633 -348.4372)
		(end 238.12627 -347.93047)
		(width 0.17145)
		(layer "F.Cu")
		(net "P5V_A_1_SENSE")
	)
	(segment
		(start 238.633 -348.991428)
		(end 238.633 -348.4372)
		(width 0.17145)
		(layer "F.Cu")
		(net "P5V_A_1_SENSE")
	)
	(via
		(at 234.7468 -348.4372)
		(size 0.6604)
		(drill 0.3302)
		(layers "F.Cu" "B.Cu")
		(net "P5V_A_1_SENSE")
	)
	(via
		(at 185.893964 -221.942406)
		(size 0.6096)
		(drill 0.3048)
		(layers "F.Cu" "B.Cu")
		(net "P3V3_STBY_VRG5")
	)
	(segment
		(start 186.329828 -220.631004)
		(end 186.329828 -221.254828)
		(width 0.254)
		(layer "B.Cu")
		(net "P3V3_STBY_VRG5")
	)
	(segment
		(start 186.329828 -221.254828)
		(end 185.893964 -221.690692)
		(width 0.254)
		(layer "B.Cu")
		(net "P3V3_STBY_VRG5")
	)
	(segment
		(start 185.893964 -224.141284)
		(end 185.893964 -221.942406)
		(width 0.254)
		(layer "B.Cu")
		(net "P3V3_STBY_VRG5")
	)
	(segment
		(start 185.212228 -219.951808)
		(end 185.891424 -220.631004)
		(width 0.254)
		(layer "B.Cu")
		(net "P3V3_STBY_VRG5")
	)
	(segment
		(start 185.893964 -221.690692)
		(end 185.893964 -221.942406)
		(width 0.254)
		(layer "B.Cu")
		(net "P3V3_STBY_VRG5")
	)
	(segment
		(start 185.891424 -220.631004)
		(end 186.329828 -220.631004)
		(width 0.254)
		(layer "B.Cu")
		(net "P3V3_STBY_VRG5")
	)
	(via
		(at 188.7728 -223.941132)
		(size 0.6096)
		(drill 0.3048)
		(layers "F.Cu" "B.Cu")
		(net "P3V3_STBY_VO")
	)
	(segment
		(start 187.194952 -224.929446)
		(end 187.784486 -224.929446)
		(width 0.254)
		(layer "B.Cu")
		(net "P3V3_STBY_VO")
	)
	(segment
		(start 187.784486 -224.929446)
		(end 188.7728 -223.941132)
		(width 0.254)
		(layer "B.Cu")
		(net "P3V3_STBY_VO")
	)
	(segment
		(start 188.7728 -223.0247)
		(end 188.7728 -223.941132)
		(width 0.254)
		(layer "B.Cu")
		(net "P3V3_STBY_VO")
	)
	(via
		(at 188.946282 -226.895406)
		(size 0.6096)
		(drill 0.3048)
		(layers "F.Cu" "B.Cu")
		(net "P3V3_STBY_VIN")
	)
	(via
		(at 191.488822 -231.80802)
		(size 0.6604)
		(drill 0.3048)
		(layers "F.Cu" "B.Cu")
		(net "P3V3_STBY_VFB_R")
	)
	(via
		(at 188.438282 -218.792806)
		(size 0.5588)
		(drill 0.3048)
		(layers "F.Cu" "B.Cu")
		(net "P3V3_STBY_VFB_R")
	)
	(segment
		(start 190.355982 -232.306876)
		(end 190.854838 -231.80802)
		(width 0.254)
		(layer "B.Cu")
		(net "P3V3_STBY_VFB_R")
	)
	(segment
		(start 190.355982 -232.661206)
		(end 190.355982 -232.306876)
		(width 0.254)
		(layer "B.Cu")
		(net "P3V3_STBY_VFB_R")
	)
	(segment
		(start 191.054482 -233.359706)
		(end 190.355982 -232.661206)
		(width 0.254)
		(layer "B.Cu")
		(net "P3V3_STBY_VFB_R")
	)
	(segment
		(start 191.054482 -233.753406)
		(end 191.054482 -233.359706)
		(width 0.254)
		(layer "B.Cu")
		(net "P3V3_STBY_VFB_R")
	)
	(segment
		(start 190.854838 -231.80802)
		(end 191.488822 -231.80802)
		(width 0.254)
		(layer "B.Cu")
		(net "P3V3_STBY_VFB_R")
	)
	(segment
		(start 188.438282 -219.796106)
		(end 188.438282 -218.792806)
		(width 0.254)
		(layer "B.Cu")
		(net "P3V3_STBY_VFB_R")
	)
	(segment
		(start 191.488822 -231.80802)
		(end 188.438282 -228.75748)
		(width 0.254)
		(layer "In9.Cu")
		(net "P3V3_STBY_VFB_R")
	)
	(segment
		(start 188.438282 -228.75748)
		(end 188.438282 -218.792806)
		(width 0.254)
		(layer "In9.Cu")
		(net "P3V3_STBY_VFB_R")
	)
	(via
		(at 187.372498 -221.612206)
		(size 0.6096)
		(drill 0.3048)
		(layers "F.Cu" "B.Cu")
		(net "P3V3_STBY_VFB")
	)
	(segment
		(start 186.39409 -224.128584)
		(end 186.39409 -223.732598)
		(width 0.254)
		(layer "B.Cu")
		(net "P3V3_STBY_VFB")
	)
	(segment
		(start 186.39409 -223.732598)
		(end 187.372498 -222.75419)
		(width 0.254)
		(layer "B.Cu")
		(net "P3V3_STBY_VFB")
	)
	(segment
		(start 188.436504 -220.686884)
		(end 187.447936 -220.686884)
		(width 0.254)
		(layer "B.Cu")
		(net "P3V3_STBY_VFB")
	)
	(segment
		(start 189.457584 -220.685106)
		(end 188.438282 -220.685106)
		(width 0.254)
		(layer "B.Cu")
		(net "P3V3_STBY_VFB")
	)
	(segment
		(start 187.372498 -220.762322)
		(end 187.372498 -221.612206)
		(width 0.254)
		(layer "B.Cu")
		(net "P3V3_STBY_VFB")
	)
	(segment
		(start 187.447936 -220.686884)
		(end 187.372498 -220.762322)
		(width 0.254)
		(layer "B.Cu")
		(net "P3V3_STBY_VFB")
	)
	(segment
		(start 189.461394 -220.688916)
		(end 189.457584 -220.685106)
		(width 0.254)
		(layer "B.Cu")
		(net "P3V3_STBY_VFB")
	)
	(segment
		(start 188.438282 -220.685106)
		(end 188.436504 -220.686884)
		(width 0.254)
		(layer "B.Cu")
		(net "P3V3_STBY_VFB")
	)
	(segment
		(start 189.466982 -219.707206)
		(end 189.466982 -220.683328)
		(width 0.254)
		(layer "B.Cu")
		(net "P3V3_STBY_VFB")
	)
	(segment
		(start 187.372498 -222.75419)
		(end 187.372498 -221.612206)
		(width 0.254)
		(layer "B.Cu")
		(net "P3V3_STBY_VFB")
	)
	(segment
		(start 189.466982 -220.683328)
		(end 189.461394 -220.688916)
		(width 0.254)
		(layer "B.Cu")
		(net "P3V3_STBY_VFB")
	)
	(via
		(at 188.722 -225.0948)
		(size 0.6096)
		(drill 0.3048)
		(layers "F.Cu" "B.Cu")
		(net "P3V3_STBY_VCC")
	)
	(segment
		(start 190.934594 -224.210118)
		(end 189.606682 -224.210118)
		(width 0.254)
		(layer "B.Cu")
		(net "P3V3_STBY_VCC")
	)
	(segment
		(start 188.387228 -225.429572)
		(end 188.722 -225.0948)
		(width 0.254)
		(layer "B.Cu")
		(net "P3V3_STBY_VCC")
	)
	(segment
		(start 187.182252 -225.429572)
		(end 188.387228 -225.429572)
		(width 0.254)
		(layer "B.Cu")
		(net "P3V3_STBY_VCC")
	)
	(segment
		(start 192.199006 -224.210118)
		(end 190.934594 -224.210118)
		(width 0.254)
		(layer "B.Cu")
		(net "P3V3_STBY_VCC")
	)
	(segment
		(start 192.206118 -224.203006)
		(end 192.199006 -224.210118)
		(width 0.254)
		(layer "B.Cu")
		(net "P3V3_STBY_VCC")
	)
	(segment
		(start 189.606682 -224.210118)
		(end 188.722 -225.0948)
		(width 0.254)
		(layer "B.Cu")
		(net "P3V3_STBY_VCC")
	)
	(via
		(at 189.530482 -228.952806)
		(size 0.6096)
		(drill 0.3048)
		(layers "F.Cu" "B.Cu")
		(net "P3V3_STBY_VBST_RR")
	)
	(via
		(at 187.371482 -228.597206)
		(size 0.6096)
		(drill 0.3048)
		(layers "F.Cu" "B.Cu")
		(net "P3V3_STBY_VBST")
	)
	(via
		(at 188.057282 -231.569006)
		(size 0.6096)
		(drill 0.3048)
		(layers "F.Cu" "B.Cu")
		(net "P3V3_STBY_SW")
	)
	(segment
		(start 189.530482 -231.569006)
		(end 188.057282 -231.569006)
		(width 0.508)
		(layer "B.Cu")
		(net "P3V3_STBY_SW")
	)
	(segment
		(start 185.771282 -231.188006)
		(end 186.152282 -231.569006)
		(width 0.508)
		(layer "B.Cu")
		(net "P3V3_STBY_SW")
	)
	(segment
		(start 180.691282 -231.061006)
		(end 180.119782 -231.632506)
		(width 0.508)
		(layer "B.Cu")
		(net "P3V3_STBY_SW")
	)
	(segment
		(start 186.152282 -231.569006)
		(end 188.057282 -231.569006)
		(width 0.508)
		(layer "B.Cu")
		(net "P3V3_STBY_SW")
	)
	(segment
		(start 189.466982 -231.632506)
		(end 189.530482 -231.569006)
		(width 0.508)
		(layer "B.Cu")
		(net "P3V3_STBY_SW")
	)
	(segment
		(start 180.119782 -231.632506)
		(end 178.786282 -231.632506)
		(width 0.508)
		(layer "B.Cu")
		(net "P3V3_STBY_SW")
	)
	(segment
		(start 189.466982 -232.661206)
		(end 189.466982 -231.632506)
		(width 0.508)
		(layer "B.Cu")
		(net "P3V3_STBY_SW")
	)
	(via
		(at 184.882282 -222.806006)
		(size 0.6096)
		(drill 0.3048)
		(layers "F.Cu" "B.Cu")
		(net "P3V3_STBY_SS")
	)
	(segment
		(start 184.44845 -221.880176)
		(end 184.44845 -222.372174)
		(width 0.254)
		(layer "B.Cu")
		(net "P3V3_STBY_SS")
	)
	(segment
		(start 185.394092 -224.141284)
		(end 185.394092 -223.317816)
		(width 0.254)
		(layer "B.Cu")
		(net "P3V3_STBY_SS")
	)
	(segment
		(start 185.394092 -223.317816)
		(end 184.882282 -222.806006)
		(width 0.254)
		(layer "B.Cu")
		(net "P3V3_STBY_SS")
	)
	(segment
		(start 184.44845 -222.372174)
		(end 184.882282 -222.806006)
		(width 0.254)
		(layer "B.Cu")
		(net "P3V3_STBY_SS")
	)
	(via
		(at 177.770282 -232.839006)
		(size 0.6096)
		(drill 0.3048)
		(layers "F.Cu" "B.Cu")
		(net "P3V3_STBY_SNB")
	)
	(via
		(at 181.326282 -226.108006)
		(size 0.6096)
		(drill 0.3048)
		(layers "F.Cu" "B.Cu")
		(net "P3V3_STBY_EN_R")
	)
	(segment
		(start 184.105804 -225.429572)
		(end 184.105296 -225.43008)
		(width 0.254)
		(layer "B.Cu")
		(net "P3V3_STBY_EN_R")
	)
	(segment
		(start 180.972206 -226.108006)
		(end 181.326282 -226.108006)
		(width 0.254)
		(layer "B.Cu")
		(net "P3V3_STBY_EN_R")
	)
	(segment
		(start 180.774594 -225.910394)
		(end 180.972206 -226.108006)
		(width 0.254)
		(layer "B.Cu")
		(net "P3V3_STBY_EN_R")
	)
	(segment
		(start 184.105296 -225.43008)
		(end 182.512208 -225.43008)
		(width 0.254)
		(layer "B.Cu")
		(net "P3V3_STBY_EN_R")
	)
	(segment
		(start 181.834282 -226.108006)
		(end 181.326282 -226.108006)
		(width 0.254)
		(layer "B.Cu")
		(net "P3V3_STBY_EN_R")
	)
	(segment
		(start 182.512208 -225.43008)
		(end 181.834282 -226.108006)
		(width 0.254)
		(layer "B.Cu")
		(net "P3V3_STBY_EN_R")
	)
	(segment
		(start 180.774594 -224.7773)
		(end 180.774594 -225.910394)
		(width 0.254)
		(layer "B.Cu")
		(net "P3V3_STBY_EN_R")
	)
	(via
		(at 189.6872 -221.6658)
		(size 0.6096)
		(drill 0.3048)
		(layers "F.Cu" "B.Cu")
		(net "P3V3_STBY_CC_R")
	)
	(segment
		(start 189.2173 -222.1357)
		(end 189.6872 -221.6658)
		(width 0.254)
		(layer "B.Cu")
		(net "P3V3_STBY_CC_R")
	)
	(segment
		(start 190.360046 -219.703142)
		(end 190.355982 -219.707206)
		(width 0.254)
		(layer "B.Cu")
		(net "P3V3_STBY_CC_R")
	)
	(segment
		(start 191.542416 -219.703142)
		(end 190.360046 -219.703142)
		(width 0.254)
		(layer "B.Cu")
		(net "P3V3_STBY_CC_R")
	)
	(segment
		(start 190.350394 -220.688916)
		(end 190.350394 -221.002606)
		(width 0.254)
		(layer "B.Cu")
		(net "P3V3_STBY_CC_R")
	)
	(segment
		(start 188.7728 -222.1357)
		(end 189.2173 -222.1357)
		(width 0.254)
		(layer "B.Cu")
		(net "P3V3_STBY_CC_R")
	)
	(segment
		(start 190.350394 -221.002606)
		(end 189.6872 -221.6658)
		(width 0.254)
		(layer "B.Cu")
		(net "P3V3_STBY_CC_R")
	)
	(segment
		(start 190.350394 -219.712794)
		(end 190.350394 -220.688916)
		(width 0.254)
		(layer "B.Cu")
		(net "P3V3_STBY_CC_R")
	)
	(segment
		(start 190.355982 -219.707206)
		(end 190.350394 -219.712794)
		(width 0.254)
		(layer "B.Cu")
		(net "P3V3_STBY_CC_R")
	)
	(via
		(at 192.446656 -220.719396)
		(size 0.5588)
		(drill 0.3048)
		(layers "F.Cu" "B.Cu")
		(net "P3V3_STBY_CC")
	)
	(via
		(at 189.835282 -234.871006)
		(size 0.6604)
		(drill 0.3048)
		(layers "F.Cu" "B.Cu")
		(net "P3V3_STBY_CC")
	)
	(segment
		(start 193.066416 -220.465396)
		(end 192.812416 -220.719396)
		(width 0.254)
		(layer "B.Cu")
		(net "P3V3_STBY_CC")
	)
	(segment
		(start 193.066416 -219.703142)
		(end 193.066416 -220.465396)
		(width 0.254)
		(layer "B.Cu")
		(net "P3V3_STBY_CC")
	)
	(segment
		(start 189.136782 -234.871006)
		(end 189.835282 -234.871006)
		(width 0.254)
		(layer "B.Cu")
		(net "P3V3_STBY_CC")
	)
	(segment
		(start 192.812416 -220.719396)
		(end 192.446656 -220.719396)
		(width 0.254)
		(layer "B.Cu")
		(net "P3V3_STBY_CC")
	)
	(segment
		(start 189.835282 -234.871006)
		(end 193.066416 -231.639872)
		(width 0.254)
		(layer "In9.Cu")
		(net "P3V3_STBY_CC")
	)
	(segment
		(start 193.066416 -231.639872)
		(end 193.066416 -221.339156)
		(width 0.254)
		(layer "In9.Cu")
		(net "P3V3_STBY_CC")
	)
	(segment
		(start 193.066416 -221.339156)
		(end 192.446656 -220.719396)
		(width 0.254)
		(layer "In9.Cu")
		(net "P3V3_STBY_CC")
	)
	(segment
		(start 276.6822 15.3162)
		(end 276.6822 16.39697)
		(width 0.17145)
		(layer "F.Cu")
		(net "IOM_B_PWR_LED")
	)
	(segment
		(start 276.6822 16.39697)
		(end 276.6822 17.788128)
		(width 0.17145)
		(layer "F.Cu")
		(net "IOM_B_PWR_LED")
	)
	(segment
		(start 277.9522 15.3162)
		(end 276.6822 15.3162)
		(width 0.17145)
		(layer "F.Cu")
		(net "IOM_B_PWR_LED")
	)
	(via
		(at 277.9522 15.3162)
		(size 0.5588)
		(drill 0.3048)
		(layers "F.Cu" "B.Cu")
		(net "IOM_B_PWR_LED")
	)
	(via
		(at 276.6822 16.39697)
		(size 0.6604)
		(drill 0.3302)
		(layers "F.Cu" "B.Cu")
		(net "IOM_B_PWR_LED")
	)
	(via
		(at 288.595562 -42.5704)
		(size 0.5588)
		(drill 0.3048)
		(layers "F.Cu" "B.Cu")
		(net "IOM_B_PWR_LED")
	)
	(segment
		(start 311.323736 -42.5704)
		(end 288.595562 -42.5704)
		(width 0.13335)
		(layer "In2.Cu")
		(net "IOM_B_PWR_LED")
	)
	(segment
		(start 365.21009 -50.28311)
		(end 319.036446 -50.28311)
		(width 0.13335)
		(layer "In2.Cu")
		(net "IOM_B_PWR_LED")
	)
	(segment
		(start 383.0828 -32.4104)
		(end 365.21009 -50.28311)
		(width 0.13335)
		(layer "In2.Cu")
		(net "IOM_B_PWR_LED")
	)
	(segment
		(start 319.036446 -50.28311)
		(end 311.323736 -42.5704)
		(width 0.13335)
		(layer "In2.Cu")
		(net "IOM_B_PWR_LED")
	)
	(segment
		(start 383.949956 -25.950164)
		(end 383.0828 -26.81732)
		(width 0.13335)
		(layer "In2.Cu")
		(net "IOM_B_PWR_LED")
	)
	(segment
		(start 383.0828 -26.81732)
		(end 383.0828 -32.4104)
		(width 0.13335)
		(layer "In2.Cu")
		(net "IOM_B_PWR_LED")
	)
	(segment
		(start 288.595562 -2.362708)
		(end 288.595562 -42.5704)
		(width 0.12065)
		(layer "In4.Cu")
		(net "IOM_B_PWR_LED")
	)
	(segment
		(start 277.9522 13.1826)
		(end 278.646382 12.488418)
		(width 0.12065)
		(layer "In4.Cu")
		(net "IOM_B_PWR_LED")
	)
	(segment
		(start 278.646382 12.488418)
		(end 278.646382 7.586472)
		(width 0.12065)
		(layer "In4.Cu")
		(net "IOM_B_PWR_LED")
	)
	(segment
		(start 278.646382 7.586472)
		(end 288.595562 -2.362708)
		(width 0.12065)
		(layer "In4.Cu")
		(net "IOM_B_PWR_LED")
	)
	(segment
		(start 277.9522 15.3162)
		(end 277.9522 13.1826)
		(width 0.12065)
		(layer "In4.Cu")
		(net "IOM_B_PWR_LED")
	)
	(segment
		(start 255.036828 11.049)
		(end 255.0414 11.053572)
		(width 0.17145)
		(layer "F.Cu")
		(net "IOM_A_PWR_LED")
	)
	(segment
		(start 255.036828 11.049)
		(end 255.036828 9.7028)
		(width 0.17145)
		(layer "F.Cu")
		(net "IOM_A_PWR_LED")
	)
	(segment
		(start 255.0414 12.031726)
		(end 255.0414 13.352272)
		(width 0.17145)
		(layer "F.Cu")
		(net "IOM_A_PWR_LED")
	)
	(segment
		(start 255.0414 11.053572)
		(end 255.0414 12.031726)
		(width 0.17145)
		(layer "F.Cu")
		(net "IOM_A_PWR_LED")
	)
	(via
		(at 255.0414 12.031726)
		(size 0.6604)
		(drill 0.3302)
		(layers "F.Cu" "B.Cu")
		(net "IOM_A_PWR_LED")
	)
	(via
		(at 235.747052 2.147062)
		(size 0.5588)
		(drill 0.3048)
		(layers "F.Cu" "B.Cu")
		(net "IOM_A_PWR_LED")
	)
	(via
		(at 255.036828 9.7028)
		(size 0.5588)
		(drill 0.3048)
		(layers "F.Cu" "B.Cu")
		(net "IOM_A_PWR_LED")
	)
	(segment
		(start 252.643386 2.170938)
		(end 235.770928 2.170938)
		(width 0.13335)
		(layer "In2.Cu")
		(net "IOM_A_PWR_LED")
	)
	(segment
		(start 255.036828 9.7028)
		(end 255.036828 4.56438)
		(width 0.13335)
		(layer "In2.Cu")
		(net "IOM_A_PWR_LED")
	)
	(segment
		(start 255.036828 4.56438)
		(end 252.643386 2.170938)
		(width 0.13335)
		(layer "In2.Cu")
		(net "IOM_A_PWR_LED")
	)
	(segment
		(start 235.770928 2.170938)
		(end 235.747052 2.147062)
		(width 0.13335)
		(layer "In2.Cu")
		(net "IOM_A_PWR_LED")
	)
	(segment
		(start 160.414208 -18.3261)
		(end 167.277288 -18.3261)
		(width 0.12065)
		(layer "In7.Cu")
		(net "IOM_A_PWR_LED")
	)
	(segment
		(start 179.84089 -5.762498)
		(end 227.57765 -5.762498)
		(width 0.12065)
		(layer "In7.Cu")
		(net "IOM_A_PWR_LED")
	)
	(segment
		(start 167.277288 -18.3261)
		(end 179.84089 -5.762498)
		(width 0.12065)
		(layer "In7.Cu")
		(net "IOM_A_PWR_LED")
	)
	(segment
		(start 235.48721 2.147062)
		(end 235.747052 2.147062)
		(width 0.12065)
		(layer "In7.Cu")
		(net "IOM_A_PWR_LED")
	)
	(segment
		(start 140.073126 -34.206942)
		(end 144.533366 -34.206942)
		(width 0.12065)
		(layer "In7.Cu")
		(net "IOM_A_PWR_LED")
	)
	(segment
		(start 137.94994 -25.950164)
		(end 137.20953 -26.690574)
		(width 0.12065)
		(layer "In7.Cu")
		(net "IOM_A_PWR_LED")
	)
	(segment
		(start 144.533366 -34.206942)
		(end 160.414208 -18.3261)
		(width 0.12065)
		(layer "In7.Cu")
		(net "IOM_A_PWR_LED")
	)
	(segment
		(start 137.20953 -31.343346)
		(end 140.073126 -34.206942)
		(width 0.12065)
		(layer "In7.Cu")
		(net "IOM_A_PWR_LED")
	)
	(segment
		(start 227.57765 -5.762498)
		(end 235.48721 2.147062)
		(width 0.12065)
		(layer "In7.Cu")
		(net "IOM_A_PWR_LED")
	)
	(segment
		(start 137.20953 -26.690574)
		(end 137.20953 -31.343346)
		(width 0.12065)
		(layer "In7.Cu")
		(net "IOM_A_PWR_LED")
	)
	(segment
		(start 222.87103 -357.516938)
		(end 222.673164 -357.516938)
		(width 0.17145)
		(layer "F.Cu")
		(net "I2C_CLIP_A_SDA")
	)
	(segment
		(start 222.673164 -357.516938)
		(end 221.918276 -356.76205)
		(width 0.17145)
		(layer "F.Cu")
		(net "I2C_CLIP_A_SDA")
	)
	(via
		(at 260.0198 -345.31935)
		(size 0.6096)
		(drill 0.3048)
		(layers "F.Cu" "B.Cu")
		(net "I2C_CLIP_A_SDA")
	)
	(via
		(at 221.918276 -356.76205)
		(size 0.5588)
		(drill 0.3048)
		(layers "F.Cu" "B.Cu")
		(net "I2C_CLIP_A_SDA")
	)
	(segment
		(start 223.189546 -341.706454)
		(end 226.1108 -338.7852)
		(width 0.17145)
		(layer "B.Cu")
		(net "I2C_CLIP_A_SDA")
	)
	(segment
		(start 226.1108 -338.7852)
		(end 250.141486 -338.7852)
		(width 0.17145)
		(layer "B.Cu")
		(net "I2C_CLIP_A_SDA")
	)
	(segment
		(start 223.1898 -355.490526)
		(end 223.1898 -342.320372)
		(width 0.17145)
		(layer "B.Cu")
		(net "I2C_CLIP_A_SDA")
	)
	(segment
		(start 274.6248 -338.539836)
		(end 267.845286 -345.31935)
		(width 0.17145)
		(layer "B.Cu")
		(net "I2C_CLIP_A_SDA")
	)
	(segment
		(start 223.189546 -342.320118)
		(end 223.189546 -341.706454)
		(width 0.17145)
		(layer "B.Cu")
		(net "I2C_CLIP_A_SDA")
	)
	(segment
		(start 256.675636 -345.31935)
		(end 260.0198 -345.31935)
		(width 0.17145)
		(layer "B.Cu")
		(net "I2C_CLIP_A_SDA")
	)
	(segment
		(start 221.918276 -356.76205)
		(end 223.1898 -355.490526)
		(width 0.17145)
		(layer "B.Cu")
		(net "I2C_CLIP_A_SDA")
	)
	(segment
		(start 250.141486 -338.7852)
		(end 256.675636 -345.31935)
		(width 0.17145)
		(layer "B.Cu")
		(net "I2C_CLIP_A_SDA")
	)
	(segment
		(start 267.845286 -345.31935)
		(end 260.0198 -345.31935)
		(width 0.17145)
		(layer "B.Cu")
		(net "I2C_CLIP_A_SDA")
	)
	(segment
		(start 281.201876 -338.539836)
		(end 274.6248 -338.539836)
		(width 0.17145)
		(layer "B.Cu")
		(net "I2C_CLIP_A_SDA")
	)
	(segment
		(start 223.1898 -342.320372)
		(end 223.189546 -342.320118)
		(width 0.17145)
		(layer "B.Cu")
		(net "I2C_CLIP_A_SDA")
	)
	(segment
		(start 281.836622 -337.90509)
		(end 281.201876 -338.539836)
		(width 0.17145)
		(layer "B.Cu")
		(net "I2C_CLIP_A_SDA")
	)
	(segment
		(start 220.745812 -356.76205)
		(end 221.918276 -356.76205)
		(width 0.13335)
		(layer "In2.Cu")
		(net "I2C_CLIP_A_SDA")
	)
	(segment
		(start 214.240872 -409.959302)
		(end 214.240872 -404.31847)
		(width 0.13335)
		(layer "In2.Cu")
		(net "I2C_CLIP_A_SDA")
	)
	(segment
		(start 214.061548 -363.446314)
		(end 220.745812 -356.76205)
		(width 0.13335)
		(layer "In2.Cu")
		(net "I2C_CLIP_A_SDA")
	)
	(segment
		(start 213.60003 -410.600144)
		(end 214.240872 -409.959302)
		(width 0.13335)
		(layer "In2.Cu")
		(net "I2C_CLIP_A_SDA")
	)
	(segment
		(start 214.061548 -404.139146)
		(end 214.061548 -363.446314)
		(width 0.13335)
		(layer "In2.Cu")
		(net "I2C_CLIP_A_SDA")
	)
	(segment
		(start 214.240872 -404.31847)
		(end 214.061548 -404.139146)
		(width 0.13335)
		(layer "In2.Cu")
		(net "I2C_CLIP_A_SDA")
	)
	(segment
		(start 224.14103 -356.721664)
		(end 224.085404 -356.666038)
		(width 0.17145)
		(layer "F.Cu")
		(net "I2C_CLIP_A_SCL")
	)
	(segment
		(start 224.14103 -357.516938)
		(end 224.14103 -356.721664)
		(width 0.17145)
		(layer "F.Cu")
		(net "I2C_CLIP_A_SCL")
	)
	(via
		(at 260.6294 -346.2782)
		(size 0.6096)
		(drill 0.3048)
		(layers "F.Cu" "B.Cu")
		(net "I2C_CLIP_A_SCL")
	)
	(via
		(at 224.085404 -356.666038)
		(size 0.5588)
		(drill 0.3048)
		(layers "F.Cu" "B.Cu")
		(net "I2C_CLIP_A_SCL")
	)
	(segment
		(start 223.86925 -356.449884)
		(end 223.86925 -341.987886)
		(width 0.17145)
		(layer "B.Cu")
		(net "I2C_CLIP_A_SCL")
	)
	(segment
		(start 224.085404 -356.666038)
		(end 223.86925 -356.449884)
		(width 0.17145)
		(layer "B.Cu")
		(net "I2C_CLIP_A_SCL")
	)
	(segment
		(start 275.058886 -339.066886)
		(end 267.847572 -346.2782)
		(width 0.17145)
		(layer "B.Cu")
		(net "I2C_CLIP_A_SCL")
	)
	(segment
		(start 249.8598 -339.46465)
		(end 256.67335 -346.2782)
		(width 0.17145)
		(layer "B.Cu")
		(net "I2C_CLIP_A_SCL")
	)
	(segment
		(start 223.86925 -341.987886)
		(end 226.392486 -339.46465)
		(width 0.17145)
		(layer "B.Cu")
		(net "I2C_CLIP_A_SCL")
	)
	(segment
		(start 256.67335 -346.2782)
		(end 260.6294 -346.2782)
		(width 0.17145)
		(layer "B.Cu")
		(net "I2C_CLIP_A_SCL")
	)
	(segment
		(start 226.392486 -339.46465)
		(end 249.8598 -339.46465)
		(width 0.17145)
		(layer "B.Cu")
		(net "I2C_CLIP_A_SCL")
	)
	(segment
		(start 283.23667 -337.90509)
		(end 282.074874 -339.066886)
		(width 0.17145)
		(layer "B.Cu")
		(net "I2C_CLIP_A_SCL")
	)
	(segment
		(start 282.074874 -339.066886)
		(end 275.058886 -339.066886)
		(width 0.17145)
		(layer "B.Cu")
		(net "I2C_CLIP_A_SCL")
	)
	(segment
		(start 267.847572 -346.2782)
		(end 260.6294 -346.2782)
		(width 0.17145)
		(layer "B.Cu")
		(net "I2C_CLIP_A_SCL")
	)
	(segment
		(start 214.729822 -404.115778)
		(end 214.702898 -404.088854)
		(width 0.13335)
		(layer "In2.Cu")
		(net "I2C_CLIP_A_SCL")
	)
	(segment
		(start 214.702898 -410.188918)
		(end 214.729822 -410.161994)
		(width 0.13335)
		(layer "In2.Cu")
		(net "I2C_CLIP_A_SCL")
	)
	(segment
		(start 222.13824 -357.44912)
		(end 222.921322 -356.666038)
		(width 0.13335)
		(layer "In2.Cu")
		(net "I2C_CLIP_A_SCL")
	)
	(segment
		(start 214.702898 -410.897324)
		(end 214.702898 -410.188918)
		(width 0.13335)
		(layer "In2.Cu")
		(net "I2C_CLIP_A_SCL")
	)
	(segment
		(start 220.965776 -357.44912)
		(end 222.13824 -357.44912)
		(width 0.13335)
		(layer "In2.Cu")
		(net "I2C_CLIP_A_SCL")
	)
	(segment
		(start 214.729822 -410.161994)
		(end 214.729822 -404.115778)
		(width 0.13335)
		(layer "In2.Cu")
		(net "I2C_CLIP_A_SCL")
	)
	(segment
		(start 214.702898 -404.088854)
		(end 214.702898 -363.711998)
		(width 0.13335)
		(layer "In2.Cu")
		(net "I2C_CLIP_A_SCL")
	)
	(segment
		(start 222.921322 -356.666038)
		(end 224.085404 -356.666038)
		(width 0.13335)
		(layer "In2.Cu")
		(net "I2C_CLIP_A_SCL")
	)
	(segment
		(start 214.702898 -363.711998)
		(end 220.965776 -357.44912)
		(width 0.13335)
		(layer "In2.Cu")
		(net "I2C_CLIP_A_SCL")
	)
	(segment
		(start 213.60003 -412.000192)
		(end 214.702898 -410.897324)
		(width 0.13335)
		(layer "In2.Cu")
		(net "I2C_CLIP_A_SCL")
	)
	(segment
		(start 281.907234 22.753066)
		(end 281.9019 22.7584)
		(width 0.254)
		(layer "F.Cu")
		(net "DPB_PWR_BTN_B")
	)
	(segment
		(start 281.907234 21.726652)
		(end 281.907234 20.532852)
		(width 0.254)
		(layer "F.Cu")
		(net "DPB_PWR_BTN_B")
	)
	(segment
		(start 272.935954 25.412446)
		(end 282.308554 25.412446)
		(width 0.254)
		(layer "F.Cu")
		(net "DPB_PWR_BTN_B")
	)
	(segment
		(start 282.6004 23.876)
		(end 282.6004 23.4569)
		(width 0.254)
		(layer "F.Cu")
		(net "DPB_PWR_BTN_B")
	)
	(segment
		(start 281.907234 20.532852)
		(end 281.907234 19.812)
		(width 0.254)
		(layer "F.Cu")
		(net "DPB_PWR_BTN_B")
	)
	(segment
		(start 269.675102 28.673298)
		(end 272.935954 25.412446)
		(width 0.254)
		(layer "F.Cu")
		(net "DPB_PWR_BTN_B")
	)
	(segment
		(start 281.907234 21.726652)
		(end 281.907234 22.753066)
		(width 0.254)
		(layer "F.Cu")
		(net "DPB_PWR_BTN_B")
	)
	(segment
		(start 282.6004 23.4569)
		(end 281.9019 22.7584)
		(width 0.254)
		(layer "F.Cu")
		(net "DPB_PWR_BTN_B")
	)
	(segment
		(start 269.675102 31.074868)
		(end 269.675102 28.673298)
		(width 0.254)
		(layer "F.Cu")
		(net "DPB_PWR_BTN_B")
	)
	(segment
		(start 281.907234 19.812)
		(end 281.920188 19.799046)
		(width 0.254)
		(layer "F.Cu")
		(net "DPB_PWR_BTN_B")
	)
	(segment
		(start 282.6004 25.1206)
		(end 282.6004 23.876)
		(width 0.254)
		(layer "F.Cu")
		(net "DPB_PWR_BTN_B")
	)
	(segment
		(start 282.308554 25.412446)
		(end 282.6004 25.1206)
		(width 0.254)
		(layer "F.Cu")
		(net "DPB_PWR_BTN_B")
	)
	(segment
		(start 281.920188 19.799046)
		(end 281.920188 18.420334)
		(width 0.254)
		(layer "F.Cu")
		(net "DPB_PWR_BTN_B")
	)
	(via
		(at 282.6004 23.876)
		(size 0.6604)
		(drill 0.3302)
		(layers "F.Cu" "B.Cu")
		(net "DPB_PWR_BTN_B")
	)
	(segment
		(start 281.0002 24.0792)
		(end 281.0002 23.368)
		(width 0.254)
		(layer "F.Cu")
		(net "DPB_PWR_BTN_A")
	)
	(segment
		(start 280.619708 18.420334)
		(end 280.619708 19.316192)
		(width 0.254)
		(layer "F.Cu")
		(net "DPB_PWR_BTN_A")
	)
	(segment
		(start 280.524966 22.892766)
		(end 280.524966 22.062948)
		(width 0.254)
		(layer "F.Cu")
		(net "DPB_PWR_BTN_A")
	)
	(segment
		(start 251.895102 31.074868)
		(end 251.895102 29.314902)
		(width 0.17145)
		(layer "F.Cu")
		(net "DPB_PWR_BTN_A")
	)
	(segment
		(start 280.524966 20.970748)
		(end 280.524966 22.062948)
		(width 0.254)
		(layer "F.Cu")
		(net "DPB_PWR_BTN_A")
	)
	(segment
		(start 280.7716 23.1394)
		(end 280.524966 22.892766)
		(width 0.254)
		(layer "F.Cu")
		(net "DPB_PWR_BTN_A")
	)
	(segment
		(start 280.499566 20.945348)
		(end 280.524966 20.970748)
		(width 0.254)
		(layer "F.Cu")
		(net "DPB_PWR_BTN_A")
	)
	(segment
		(start 280.5049 19.431)
		(end 280.5049 19.9136)
		(width 0.254)
		(layer "F.Cu")
		(net "DPB_PWR_BTN_A")
	)
	(segment
		(start 280.619708 19.316192)
		(end 280.5049 19.431)
		(width 0.254)
		(layer "F.Cu")
		(net "DPB_PWR_BTN_A")
	)
	(segment
		(start 281.0002 23.368)
		(end 280.7716 23.1394)
		(width 0.254)
		(layer "F.Cu")
		(net "DPB_PWR_BTN_A")
	)
	(segment
		(start 280.5049 20.940014)
		(end 280.499566 20.945348)
		(width 0.254)
		(layer "F.Cu")
		(net "DPB_PWR_BTN_A")
	)
	(segment
		(start 280.5049 19.9136)
		(end 280.5049 20.940014)
		(width 0.254)
		(layer "F.Cu")
		(net "DPB_PWR_BTN_A")
	)
	(via
		(at 281.0002 24.0792)
		(size 0.5588)
		(drill 0.3048)
		(layers "F.Cu" "B.Cu")
		(net "DPB_PWR_BTN_A")
	)
	(via
		(at 280.7716 23.1394)
		(size 0.6604)
		(drill 0.3302)
		(layers "F.Cu" "B.Cu")
		(net "DPB_PWR_BTN_A")
	)
	(via
		(at 251.895102 29.314902)
		(size 0.5588)
		(drill 0.3048)
		(layers "F.Cu" "B.Cu")
		(net "DPB_PWR_BTN_A")
	)
	(segment
		(start 281.0002 24.0792)
		(end 280.797 23.876)
		(width 0.254)
		(layer "In7.Cu")
		(net "DPB_PWR_BTN_A")
	)
	(segment
		(start 280.797 23.876)
		(end 260.846316 23.876)
		(width 0.254)
		(layer "In7.Cu")
		(net "DPB_PWR_BTN_A")
	)
	(segment
		(start 255.407414 29.314902)
		(end 251.895102 29.314902)
		(width 0.254)
		(layer "In7.Cu")
		(net "DPB_PWR_BTN_A")
	)
	(segment
		(start 260.846316 23.876)
		(end 255.407414 29.314902)
		(width 0.254)
		(layer "In7.Cu")
		(net "DPB_PWR_BTN_A")
	)
	(via
		(at 183.967882 -218.615006)
		(size 0.5588)
		(drill 0.3048)
		(layers "F.Cu" "B.Cu")
		(net "AGND_P3V3_STBY")
	)
	(via
		(at 187.447936 -218.869006)
		(size 0.6604)
		(drill 0.3048)
		(layers "F.Cu" "B.Cu")
		(net "AGND_P3V3_STBY")
	)
	(segment
		(start 187.447936 -218.869006)
		(end 187.447936 -219.797884)
		(width 0.254)
		(layer "B.Cu")
		(net "AGND_P3V3_STBY")
	)
	(segment
		(start 184.221882 -218.869006)
		(end 187.447936 -218.869006)
		(width 0.2032)
		(layer "In9.Cu")
		(net "AGND_P3V3_STBY")
	)
	(segment
		(start 183.967882 -218.615006)
		(end 184.221882 -218.869006)
		(width 0.2032)
		(layer "In9.Cu")
		(net "AGND_P3V3_STBY")
	)
	(segment
		(start 270.945102 31.074868)
		(end 270.945102 29.35478)
		(width 0.17145)
		(layer "F.Cu")
		(net "UART_IOC_B_TX")
	)
	(via
		(at 270.945102 29.35478)
		(size 0.5588)
		(drill 0.3048)
		(layers "F.Cu" "B.Cu")
		(net "UART_IOC_B_TX")
	)
	(via
		(at 270.76019 -116.967)
		(size 0.5588)
		(drill 0.3048)
		(layers "F.Cu" "B.Cu")
		(net "UART_IOC_B_TX")
	)
	(via
		(at 200.545446 -335.86674)
		(size 0.5588)
		(drill 0.3048)
		(layers "F.Cu" "B.Cu")
		(net "UART_IOC_B_TX")
	)
	(segment
		(start 269.511018 16.508222)
		(end 269.511018 26.636218)
		(width 0.12065)
		(layer "In4.Cu")
		(net "UART_IOC_B_TX")
	)
	(segment
		(start 268.483842 -18.646902)
		(end 268.483842 15.481046)
		(width 0.12065)
		(layer "In4.Cu")
		(net "UART_IOC_B_TX")
	)
	(segment
		(start 274.649946 -107.136438)
		(end 274.649946 -93.725746)
		(width 0.12065)
		(layer "In4.Cu")
		(net "UART_IOC_B_TX")
	)
	(segment
		(start 269.511018 26.636218)
		(end 270.945102 28.070302)
		(width 0.12065)
		(layer "In4.Cu")
		(net "UART_IOC_B_TX")
	)
	(segment
		(start 271.018 -116.70919)
		(end 271.018 -110.768384)
		(width 0.12065)
		(layer "In4.Cu")
		(net "UART_IOC_B_TX")
	)
	(segment
		(start 271.018 -21.18106)
		(end 268.483842 -18.646902)
		(width 0.12065)
		(layer "In4.Cu")
		(net "UART_IOC_B_TX")
	)
	(segment
		(start 271.018 -90.0938)
		(end 271.018 -21.18106)
		(width 0.12065)
		(layer "In4.Cu")
		(net "UART_IOC_B_TX")
	)
	(segment
		(start 274.649946 -93.725746)
		(end 271.018 -90.0938)
		(width 0.12065)
		(layer "In4.Cu")
		(net "UART_IOC_B_TX")
	)
	(segment
		(start 268.483842 15.481046)
		(end 269.511018 16.508222)
		(width 0.12065)
		(layer "In4.Cu")
		(net "UART_IOC_B_TX")
	)
	(segment
		(start 271.018 -110.768384)
		(end 274.649946 -107.136438)
		(width 0.12065)
		(layer "In4.Cu")
		(net "UART_IOC_B_TX")
	)
	(segment
		(start 270.945102 28.070302)
		(end 270.945102 29.35478)
		(width 0.12065)
		(layer "In4.Cu")
		(net "UART_IOC_B_TX")
	)
	(segment
		(start 270.76019 -116.967)
		(end 271.018 -116.70919)
		(width 0.12065)
		(layer "In4.Cu")
		(net "UART_IOC_B_TX")
	)
	(segment
		(start 218.377008 -395.272768)
		(end 224.44456 -401.34032)
		(width 0.12065)
		(layer "In7.Cu")
		(net "UART_IOC_B_TX")
	)
	(segment
		(start 224.44456 -401.34032)
		(end 224.44456 -412.755588)
		(width 0.12065)
		(layer "In7.Cu")
		(net "UART_IOC_B_TX")
	)
	(segment
		(start 224.44456 -412.755588)
		(end 222.600012 -414.600136)
		(width 0.12065)
		(layer "In7.Cu")
		(net "UART_IOC_B_TX")
	)
	(segment
		(start 214.887302 -348.825058)
		(end 214.887302 -383.224786)
		(width 0.12065)
		(layer "In7.Cu")
		(net "UART_IOC_B_TX")
	)
	(segment
		(start 214.887302 -383.224786)
		(end 218.377008 -386.714492)
		(width 0.12065)
		(layer "In7.Cu")
		(net "UART_IOC_B_TX")
	)
	(segment
		(start 200.545446 -335.86674)
		(end 200.547732 -335.869026)
		(width 0.12065)
		(layer "In7.Cu")
		(net "UART_IOC_B_TX")
	)
	(segment
		(start 200.547732 -335.869026)
		(end 201.93127 -335.869026)
		(width 0.12065)
		(layer "In7.Cu")
		(net "UART_IOC_B_TX")
	)
	(segment
		(start 201.93127 -335.869026)
		(end 214.887302 -348.825058)
		(width 0.12065)
		(layer "In7.Cu")
		(net "UART_IOC_B_TX")
	)
	(segment
		(start 218.377008 -386.714492)
		(end 218.377008 -395.272768)
		(width 0.12065)
		(layer "In7.Cu")
		(net "UART_IOC_B_TX")
	)
	(segment
		(start 244.923056 -186.318144)
		(end 244.923056 -191.049148)
		(width 0.13335)
		(layer "In9.Cu")
		(net "UART_IOC_B_TX")
	)
	(segment
		(start 244.923056 -191.049148)
		(end 242.424966 -193.547238)
		(width 0.13335)
		(layer "In9.Cu")
		(net "UART_IOC_B_TX")
	)
	(segment
		(start 256.76225 -130.96494)
		(end 256.76225 -146.40052)
		(width 0.13335)
		(layer "In9.Cu")
		(net "UART_IOC_B_TX")
	)
	(segment
		(start 205.5368 -272.6436)
		(end 200.545446 -277.634954)
		(width 0.13335)
		(layer "In9.Cu")
		(net "UART_IOC_B_TX")
	)
	(segment
		(start 205.5368 -244.971824)
		(end 205.5368 -272.6436)
		(width 0.13335)
		(layer "In9.Cu")
		(net "UART_IOC_B_TX")
	)
	(segment
		(start 242.424966 -193.90995)
		(end 233.49331 -202.841606)
		(width 0.13335)
		(layer "In9.Cu")
		(net "UART_IOC_B_TX")
	)
	(segment
		(start 270.76019 -116.967)
		(end 256.76225 -130.96494)
		(width 0.13335)
		(layer "In9.Cu")
		(net "UART_IOC_B_TX")
	)
	(segment
		(start 256.76225 -146.40052)
		(end 246.890794 -156.271976)
		(width 0.13335)
		(layer "In9.Cu")
		(net "UART_IOC_B_TX")
	)
	(segment
		(start 246.890794 -184.350406)
		(end 244.923056 -186.318144)
		(width 0.13335)
		(layer "In9.Cu")
		(net "UART_IOC_B_TX")
	)
	(segment
		(start 233.49331 -202.841606)
		(end 233.49331 -217.015314)
		(width 0.13335)
		(layer "In9.Cu")
		(net "UART_IOC_B_TX")
	)
	(segment
		(start 200.545446 -277.634954)
		(end 200.545446 -335.86674)
		(width 0.13335)
		(layer "In9.Cu")
		(net "UART_IOC_B_TX")
	)
	(segment
		(start 246.890794 -156.271976)
		(end 246.890794 -184.350406)
		(width 0.13335)
		(layer "In9.Cu")
		(net "UART_IOC_B_TX")
	)
	(segment
		(start 242.424966 -193.547238)
		(end 242.424966 -193.90995)
		(width 0.13335)
		(layer "In9.Cu")
		(net "UART_IOC_B_TX")
	)
	(segment
		(start 233.49331 -217.015314)
		(end 205.5368 -244.971824)
		(width 0.13335)
		(layer "In9.Cu")
		(net "UART_IOC_B_TX")
	)
	(segment
		(start 272.215102 31.074868)
		(end 272.215102 29.35478)
		(width 0.17145)
		(layer "F.Cu")
		(net "UART_IOC_B_RX")
	)
	(via
		(at 271.530572 -116.0526)
		(size 0.5588)
		(drill 0.3048)
		(layers "F.Cu" "B.Cu")
		(net "UART_IOC_B_RX")
	)
	(via
		(at 272.215102 29.35478)
		(size 0.5588)
		(drill 0.3048)
		(layers "F.Cu" "B.Cu")
		(net "UART_IOC_B_RX")
	)
	(via
		(at 199.47636 -335.38414)
		(size 0.5588)
		(drill 0.3048)
		(layers "F.Cu" "B.Cu")
		(net "UART_IOC_B_RX")
	)
	(segment
		(start 275.278596 -107.397042)
		(end 275.278596 -93.192346)
		(width 0.12065)
		(layer "In4.Cu")
		(net "UART_IOC_B_RX")
	)
	(segment
		(start 271.64665 -89.5604)
		(end 271.64665 -20.920456)
		(width 0.12065)
		(layer "In4.Cu")
		(net "UART_IOC_B_RX")
	)
	(segment
		(start 271.530572 -116.0526)
		(end 271.64665 -115.936522)
		(width 0.12065)
		(layer "In4.Cu")
		(net "UART_IOC_B_RX")
	)
	(segment
		(start 271.64665 -111.028988)
		(end 275.278596 -107.397042)
		(width 0.12065)
		(layer "In4.Cu")
		(net "UART_IOC_B_RX")
	)
	(segment
		(start 269.112492 8.889492)
		(end 270.175482 9.952482)
		(width 0.12065)
		(layer "In4.Cu")
		(net "UART_IOC_B_RX")
	)
	(segment
		(start 275.278596 -93.192346)
		(end 271.64665 -89.5604)
		(width 0.12065)
		(layer "In4.Cu")
		(net "UART_IOC_B_RX")
	)
	(segment
		(start 269.112492 -18.386298)
		(end 269.112492 8.889492)
		(width 0.12065)
		(layer "In4.Cu")
		(net "UART_IOC_B_RX")
	)
	(segment
		(start 271.64665 -20.920456)
		(end 269.112492 -18.386298)
		(width 0.12065)
		(layer "In4.Cu")
		(net "UART_IOC_B_RX")
	)
	(segment
		(start 271.64665 -115.936522)
		(end 271.64665 -111.028988)
		(width 0.12065)
		(layer "In4.Cu")
		(net "UART_IOC_B_RX")
	)
	(segment
		(start 270.175482 9.952482)
		(end 270.175482 26.35758)
		(width 0.12065)
		(layer "In4.Cu")
		(net "UART_IOC_B_RX")
	)
	(segment
		(start 272.215102 28.3972)
		(end 272.215102 29.35478)
		(width 0.12065)
		(layer "In4.Cu")
		(net "UART_IOC_B_RX")
	)
	(segment
		(start 270.175482 26.35758)
		(end 272.215102 28.3972)
		(width 0.12065)
		(layer "In4.Cu")
		(net "UART_IOC_B_RX")
	)
	(segment
		(start 214.258652 -349.146368)
		(end 214.258652 -383.48539)
		(width 0.12065)
		(layer "In7.Cu")
		(net "UART_IOC_B_RX")
	)
	(segment
		(start 199.47636 -335.81086)
		(end 200.406762 -336.741262)
		(width 0.12065)
		(layer "In7.Cu")
		(net "UART_IOC_B_RX")
	)
	(segment
		(start 200.406762 -336.741262)
		(end 201.853546 -336.741262)
		(width 0.12065)
		(layer "In7.Cu")
		(net "UART_IOC_B_RX")
	)
	(segment
		(start 217.748358 -386.975096)
		(end 217.748358 -395.012164)
		(width 0.12065)
		(layer "In7.Cu")
		(net "UART_IOC_B_RX")
	)
	(segment
		(start 223.81591 -403.025102)
		(end 223.96831 -403.177502)
		(width 0.12065)
		(layer "In7.Cu")
		(net "UART_IOC_B_RX")
	)
	(segment
		(start 223.96831 -411.83179)
		(end 222.600012 -413.200088)
		(width 0.12065)
		(layer "In7.Cu")
		(net "UART_IOC_B_RX")
	)
	(segment
		(start 223.96831 -403.177502)
		(end 223.96831 -411.83179)
		(width 0.12065)
		(layer "In7.Cu")
		(net "UART_IOC_B_RX")
	)
	(segment
		(start 223.81591 -401.69211)
		(end 223.81591 -403.025102)
		(width 0.12065)
		(layer "In7.Cu")
		(net "UART_IOC_B_RX")
	)
	(segment
		(start 214.258652 -383.48539)
		(end 217.748358 -386.975096)
		(width 0.12065)
		(layer "In7.Cu")
		(net "UART_IOC_B_RX")
	)
	(segment
		(start 199.47636 -335.38414)
		(end 199.47636 -335.81086)
		(width 0.12065)
		(layer "In7.Cu")
		(net "UART_IOC_B_RX")
	)
	(segment
		(start 217.748358 -395.624558)
		(end 223.81591 -401.69211)
		(width 0.12065)
		(layer "In7.Cu")
		(net "UART_IOC_B_RX")
	)
	(segment
		(start 217.748104 -395.012418)
		(end 217.748104 -395.533118)
		(width 0.12065)
		(layer "In7.Cu")
		(net "UART_IOC_B_RX")
	)
	(segment
		(start 217.748104 -395.533118)
		(end 217.748358 -395.533372)
		(width 0.12065)
		(layer "In7.Cu")
		(net "UART_IOC_B_RX")
	)
	(segment
		(start 201.853546 -336.741262)
		(end 214.258652 -349.146368)
		(width 0.12065)
		(layer "In7.Cu")
		(net "UART_IOC_B_RX")
	)
	(segment
		(start 217.748358 -395.533372)
		(end 217.748358 -395.624558)
		(width 0.12065)
		(layer "In7.Cu")
		(net "UART_IOC_B_RX")
	)
	(segment
		(start 217.748358 -395.012164)
		(end 217.748104 -395.012418)
		(width 0.12065)
		(layer "In7.Cu")
		(net "UART_IOC_B_RX")
	)
	(segment
		(start 256.1209 -130.699256)
		(end 256.1209 -146.134582)
		(width 0.13335)
		(layer "In9.Cu")
		(net "UART_IOC_B_RX")
	)
	(segment
		(start 271.530572 -116.0526)
		(end 270.767556 -116.0526)
		(width 0.13335)
		(layer "In9.Cu")
		(net "UART_IOC_B_RX")
	)
	(segment
		(start 204.89545 -244.362224)
		(end 204.89545 -272.24355)
		(width 0.13335)
		(layer "In9.Cu")
		(net "UART_IOC_B_RX")
	)
	(segment
		(start 256.1209 -146.134582)
		(end 246.249444 -156.006038)
		(width 0.13335)
		(layer "In9.Cu")
		(net "UART_IOC_B_RX")
	)
	(segment
		(start 204.89545 -272.24355)
		(end 199.904096 -277.234904)
		(width 0.13335)
		(layer "In9.Cu")
		(net "UART_IOC_B_RX")
	)
	(segment
		(start 246.249444 -184.084722)
		(end 244.281706 -186.05246)
		(width 0.13335)
		(layer "In9.Cu")
		(net "UART_IOC_B_RX")
	)
	(segment
		(start 246.249444 -156.006038)
		(end 246.249444 -184.084722)
		(width 0.13335)
		(layer "In9.Cu")
		(net "UART_IOC_B_RX")
	)
	(segment
		(start 199.904096 -334.956404)
		(end 199.47636 -335.38414)
		(width 0.13335)
		(layer "In9.Cu")
		(net "UART_IOC_B_RX")
	)
	(segment
		(start 244.281706 -190.783464)
		(end 241.783616 -193.281554)
		(width 0.13335)
		(layer "In9.Cu")
		(net "UART_IOC_B_RX")
	)
	(segment
		(start 244.281706 -186.05246)
		(end 244.281706 -190.783464)
		(width 0.13335)
		(layer "In9.Cu")
		(net "UART_IOC_B_RX")
	)
	(segment
		(start 232.85196 -216.405714)
		(end 204.89545 -244.362224)
		(width 0.13335)
		(layer "In9.Cu")
		(net "UART_IOC_B_RX")
	)
	(segment
		(start 241.783616 -193.644266)
		(end 232.85196 -202.575922)
		(width 0.13335)
		(layer "In9.Cu")
		(net "UART_IOC_B_RX")
	)
	(segment
		(start 232.85196 -202.575922)
		(end 232.85196 -216.405714)
		(width 0.13335)
		(layer "In9.Cu")
		(net "UART_IOC_B_RX")
	)
	(segment
		(start 199.904096 -277.234904)
		(end 199.904096 -334.956404)
		(width 0.13335)
		(layer "In9.Cu")
		(net "UART_IOC_B_RX")
	)
	(segment
		(start 241.783616 -193.281554)
		(end 241.783616 -193.644266)
		(width 0.13335)
		(layer "In9.Cu")
		(net "UART_IOC_B_RX")
	)
	(segment
		(start 270.767556 -116.0526)
		(end 256.1209 -130.699256)
		(width 0.13335)
		(layer "In9.Cu")
		(net "UART_IOC_B_RX")
	)
	(segment
		(start 279.105106 -129.35712)
		(end 276.765004 -129.35712)
		(width 0.17145)
		(layer "F.Cu")
		(net "TP_COMP_B_SATA_P0_TX_DP")
	)
	(segment
		(start 282.392628 -130.642614)
		(end 282.392628 -129.606294)
		(width 0.17145)
		(layer "F.Cu")
		(net "TP_COMP_B_SATA_P0_TX_DP")
	)
	(segment
		(start 275.997416 -130.124708)
		(end 267.197078 -130.124708)
		(width 0.17145)
		(layer "F.Cu")
		(net "TP_COMP_B_SATA_P0_TX_DP")
	)
	(segment
		(start 281.191208 -128.404874)
		(end 280.057352 -128.404874)
		(width 0.17145)
		(layer "F.Cu")
		(net "TP_COMP_B_SATA_P0_TX_DP")
	)
	(segment
		(start 283.249878 -131.499864)
		(end 282.392628 -130.642614)
		(width 0.17145)
		(layer "F.Cu")
		(net "TP_COMP_B_SATA_P0_TX_DP")
	)
	(segment
		(start 282.392628 -129.606294)
		(end 281.191208 -128.404874)
		(width 0.17145)
		(layer "F.Cu")
		(net "TP_COMP_B_SATA_P0_TX_DP")
	)
	(segment
		(start 276.765004 -129.35712)
		(end 275.997416 -130.124708)
		(width 0.17145)
		(layer "F.Cu")
		(net "TP_COMP_B_SATA_P0_TX_DP")
	)
	(segment
		(start 280.057352 -128.404874)
		(end 279.105106 -129.35712)
		(width 0.17145)
		(layer "F.Cu")
		(net "TP_COMP_B_SATA_P0_TX_DP")
	)
	(segment
		(start 280.394918 -126.642622)
		(end 279.39492 -127.64262)
		(width 0.17145)
		(layer "F.Cu")
		(net "TP_COMP_B_SATA_P0_TX_DN")
	)
	(segment
		(start 284.324044 -131.574032)
		(end 284.324044 -129.361692)
		(width 0.17145)
		(layer "F.Cu")
		(net "TP_COMP_B_SATA_P0_TX_DN")
	)
	(segment
		(start 285.249874 -132.499862)
		(end 284.324044 -131.574032)
		(width 0.17145)
		(layer "F.Cu")
		(net "TP_COMP_B_SATA_P0_TX_DN")
	)
	(segment
		(start 279.39492 -127.64262)
		(end 277.776432 -127.64262)
		(width 0.17145)
		(layer "F.Cu")
		(net "TP_COMP_B_SATA_P0_TX_DN")
	)
	(segment
		(start 283.60243 -128.640078)
		(end 282.582874 -128.640078)
		(width 0.17145)
		(layer "F.Cu")
		(net "TP_COMP_B_SATA_P0_TX_DN")
	)
	(segment
		(start 282.582874 -128.640078)
		(end 281.96413 -128.021334)
		(width 0.17145)
		(layer "F.Cu")
		(net "TP_COMP_B_SATA_P0_TX_DN")
	)
	(segment
		(start 277.776432 -127.64262)
		(end 276.970744 -128.448308)
		(width 0.17145)
		(layer "F.Cu")
		(net "TP_COMP_B_SATA_P0_TX_DN")
	)
	(segment
		(start 276.970744 -128.448308)
		(end 267.197078 -128.448308)
		(width 0.17145)
		(layer "F.Cu")
		(net "TP_COMP_B_SATA_P0_TX_DN")
	)
	(segment
		(start 281.96413 -128.021334)
		(end 281.96413 -127.086106)
		(width 0.17145)
		(layer "F.Cu")
		(net "TP_COMP_B_SATA_P0_TX_DN")
	)
	(segment
		(start 281.96413 -127.086106)
		(end 281.520646 -126.642622)
		(width 0.17145)
		(layer "F.Cu")
		(net "TP_COMP_B_SATA_P0_TX_DN")
	)
	(segment
		(start 284.324044 -129.361692)
		(end 283.60243 -128.640078)
		(width 0.17145)
		(layer "F.Cu")
		(net "TP_COMP_B_SATA_P0_TX_DN")
	)
	(segment
		(start 281.520646 -126.642622)
		(end 280.394918 -126.642622)
		(width 0.17145)
		(layer "F.Cu")
		(net "TP_COMP_B_SATA_P0_TX_DN")
	)
	(segment
		(start 279.515062 -131.636262)
		(end 267.18641 -131.636262)
		(width 0.17145)
		(layer "F.Cu")
		(net "TP_COMP_B_SATA_P0_RX_DP")
	)
	(segment
		(start 280.75001 -133.49986)
		(end 280.75001 -132.87121)
		(width 0.17145)
		(layer "F.Cu")
		(net "TP_COMP_B_SATA_P0_RX_DP")
	)
	(segment
		(start 280.75001 -132.87121)
		(end 279.515062 -131.636262)
		(width 0.17145)
		(layer "F.Cu")
		(net "TP_COMP_B_SATA_P0_RX_DP")
	)
	(segment
		(start 277.562818 -133.312662)
		(end 267.18641 -133.312662)
		(width 0.17145)
		(layer "F.Cu")
		(net "TP_COMP_B_SATA_P0_RX_DN")
	)
	(segment
		(start 278.750014 -134.499858)
		(end 277.562818 -133.312662)
		(width 0.17145)
		(layer "F.Cu")
		(net "TP_COMP_B_SATA_P0_RX_DN")
	)
	(segment
		(start 271.22247 -6.929628)
		(end 273.379946 -6.929628)
		(width 0.17145)
		(layer "F.Cu")
		(net "TP_COMP_B_NCSI_TXEN")
	)
	(via
		(at 273.379946 -6.929628)
		(size 0.5588)
		(drill 0.3048)
		(layers "F.Cu" "B.Cu")
		(net "TP_COMP_B_NCSI_TXEN")
	)
	(segment
		(start 279.9842 -6.3754)
		(end 279.429972 -6.929628)
		(width 0.13335)
		(layer "In2.Cu")
		(net "TP_COMP_B_NCSI_TXEN")
	)
	(segment
		(start 283.171138 -7.200138)
		(end 282.3464 -6.3754)
		(width 0.13335)
		(layer "In2.Cu")
		(net "TP_COMP_B_NCSI_TXEN")
	)
	(segment
		(start 279.429972 -6.929628)
		(end 273.379946 -6.929628)
		(width 0.13335)
		(layer "In2.Cu")
		(net "TP_COMP_B_NCSI_TXEN")
	)
	(segment
		(start 283.249878 -7.200138)
		(end 283.171138 -7.200138)
		(width 0.13335)
		(layer "In2.Cu")
		(net "TP_COMP_B_NCSI_TXEN")
	)
	(segment
		(start 282.3464 -6.3754)
		(end 279.9842 -6.3754)
		(width 0.13335)
		(layer "In2.Cu")
		(net "TP_COMP_B_NCSI_TXEN")
	)
	(segment
		(start 272.385028 -11.73353)
		(end 273.53387 -11.73353)
		(width 0.17145)
		(layer "F.Cu")
		(net "TP_COMP_B_NCSI_TXD1")
	)
	(via
		(at 273.53387 -11.73353)
		(size 0.5588)
		(drill 0.3048)
		(layers "F.Cu" "B.Cu")
		(net "TP_COMP_B_NCSI_TXD1")
	)
	(segment
		(start 282.398978 -10.051034)
		(end 280.10231 -10.051034)
		(width 0.13335)
		(layer "In2.Cu")
		(net "TP_COMP_B_NCSI_TXD1")
	)
	(segment
		(start 280.10231 -10.051034)
		(end 279.102312 -11.051032)
		(width 0.13335)
		(layer "In2.Cu")
		(net "TP_COMP_B_NCSI_TXD1")
	)
	(segment
		(start 279.102312 -11.051032)
		(end 275.791168 -11.051032)
		(width 0.13335)
		(layer "In2.Cu")
		(net "TP_COMP_B_NCSI_TXD1")
	)
	(segment
		(start 283.249878 -9.200134)
		(end 282.398978 -10.051034)
		(width 0.13335)
		(layer "In2.Cu")
		(net "TP_COMP_B_NCSI_TXD1")
	)
	(segment
		(start 275.10867 -11.73353)
		(end 273.53387 -11.73353)
		(width 0.13335)
		(layer "In2.Cu")
		(net "TP_COMP_B_NCSI_TXD1")
	)
	(segment
		(start 275.791168 -11.051032)
		(end 275.10867 -11.73353)
		(width 0.13335)
		(layer "In2.Cu")
		(net "TP_COMP_B_NCSI_TXD1")
	)
	(segment
		(start 272.34007 -9.901428)
		(end 273.578828 -9.901428)
		(width 0.17145)
		(layer "F.Cu")
		(net "TP_COMP_B_NCSI_TXD0")
	)
	(via
		(at 273.578828 -9.901428)
		(size 0.5588)
		(drill 0.3048)
		(layers "F.Cu" "B.Cu")
		(net "TP_COMP_B_NCSI_TXD0")
	)
	(segment
		(start 279.415494 -9.035034)
		(end 276.29104 -9.035034)
		(width 0.13335)
		(layer "In2.Cu")
		(net "TP_COMP_B_NCSI_TXD0")
	)
	(segment
		(start 285.249874 -8.200136)
		(end 280.250392 -8.200136)
		(width 0.13335)
		(layer "In2.Cu")
		(net "TP_COMP_B_NCSI_TXD0")
	)
	(segment
		(start 280.250392 -8.200136)
		(end 279.415494 -9.035034)
		(width 0.13335)
		(layer "In2.Cu")
		(net "TP_COMP_B_NCSI_TXD0")
	)
	(segment
		(start 275.424646 -9.901428)
		(end 273.578828 -9.901428)
		(width 0.13335)
		(layer "In2.Cu")
		(net "TP_COMP_B_NCSI_TXD0")
	)
	(segment
		(start 276.29104 -9.035034)
		(end 275.424646 -9.901428)
		(width 0.13335)
		(layer "In2.Cu")
		(net "TP_COMP_B_NCSI_TXD0")
	)
	(segment
		(start 272.3388 -13.208)
		(end 273.6596 -13.208)
		(width 0.17145)
		(layer "F.Cu")
		(net "TP_COMP_B_NCSI_RXER")
	)
	(via
		(at 273.6596 -13.208)
		(size 0.5588)
		(drill 0.3048)
		(layers "F.Cu" "B.Cu")
		(net "TP_COMP_B_NCSI_RXER")
	)
	(segment
		(start 280.427684 -12.319)
		(end 279.538684 -13.208)
		(width 0.13335)
		(layer "In2.Cu")
		(net "TP_COMP_B_NCSI_RXER")
	)
	(segment
		(start 282.131008 -12.319)
		(end 280.427684 -12.319)
		(width 0.13335)
		(layer "In2.Cu")
		(net "TP_COMP_B_NCSI_RXER")
	)
	(segment
		(start 283.249878 -11.20013)
		(end 282.131008 -12.319)
		(width 0.13335)
		(layer "In2.Cu")
		(net "TP_COMP_B_NCSI_RXER")
	)
	(segment
		(start 279.538684 -13.208)
		(end 273.6596 -13.208)
		(width 0.13335)
		(layer "In2.Cu")
		(net "TP_COMP_B_NCSI_RXER")
	)
	(segment
		(start 273.622262 -10.823448)
		(end 273.622262 -10.841228)
		(width 0.17145)
		(layer "F.Cu")
		(net "TP_COMP_B_NCSI_RXD1")
	)
	(segment
		(start 273.622262 -10.841228)
		(end 271.19707 -10.841228)
		(width 0.17145)
		(layer "F.Cu")
		(net "TP_COMP_B_NCSI_RXD1")
	)
	(segment
		(start 273.62404 -10.823448)
		(end 273.622262 -10.823448)
		(width 0.17145)
		(layer "F.Cu")
		(net "TP_COMP_B_NCSI_RXD1")
	)
	(via
		(at 273.62404 -10.823448)
		(size 0.5588)
		(drill 0.3048)
		(layers "F.Cu" "B.Cu")
		(net "TP_COMP_B_NCSI_RXD1")
	)
	(segment
		(start 276.467316 -9.460484)
		(end 275.104352 -10.823448)
		(width 0.13335)
		(layer "In2.Cu")
		(net "TP_COMP_B_NCSI_RXD1")
	)
	(segment
		(start 275.104352 -10.823448)
		(end 273.62404 -10.823448)
		(width 0.13335)
		(layer "In2.Cu")
		(net "TP_COMP_B_NCSI_RXD1")
	)
	(segment
		(start 280.75001 -9.200134)
		(end 280.48966 -9.460484)
		(width 0.13335)
		(layer "In2.Cu")
		(net "TP_COMP_B_NCSI_RXD1")
	)
	(segment
		(start 280.48966 -9.460484)
		(end 276.467316 -9.460484)
		(width 0.13335)
		(layer "In2.Cu")
		(net "TP_COMP_B_NCSI_RXD1")
	)
	(segment
		(start 271.19707 -8.936228)
		(end 273.543776 -8.936228)
		(width 0.17145)
		(layer "F.Cu")
		(net "TP_COMP_B_NCSI_RXD0")
	)
	(via
		(at 273.543776 -8.936228)
		(size 0.5588)
		(drill 0.3048)
		(layers "F.Cu" "B.Cu")
		(net "TP_COMP_B_NCSI_RXD0")
	)
	(segment
		(start 274.72259 -8.200136)
		(end 274.602448 -8.320278)
		(width 0.13335)
		(layer "In2.Cu")
		(net "TP_COMP_B_NCSI_RXD0")
	)
	(segment
		(start 274.159726 -8.320278)
		(end 273.543776 -8.936228)
		(width 0.13335)
		(layer "In2.Cu")
		(net "TP_COMP_B_NCSI_RXD0")
	)
	(segment
		(start 278.750014 -8.200136)
		(end 274.72259 -8.200136)
		(width 0.13335)
		(layer "In2.Cu")
		(net "TP_COMP_B_NCSI_RXD0")
	)
	(segment
		(start 274.602448 -8.320278)
		(end 274.159726 -8.320278)
		(width 0.13335)
		(layer "In2.Cu")
		(net "TP_COMP_B_NCSI_RXD0")
	)
	(segment
		(start 272.34007 -7.894828)
		(end 273.410172 -7.894828)
		(width 0.17145)
		(layer "F.Cu")
		(net "TP_COMP_B_NCSI_RCLK")
	)
	(via
		(at 273.410172 -7.894828)
		(size 0.5588)
		(drill 0.3048)
		(layers "F.Cu" "B.Cu")
		(net "TP_COMP_B_NCSI_RCLK")
	)
	(segment
		(start 274.426172 -7.894828)
		(end 273.410172 -7.894828)
		(width 0.13335)
		(layer "In2.Cu")
		(net "TP_COMP_B_NCSI_RCLK")
	)
	(segment
		(start 280.56332 -7.386828)
		(end 274.934172 -7.386828)
		(width 0.13335)
		(layer "In2.Cu")
		(net "TP_COMP_B_NCSI_RCLK")
	)
	(segment
		(start 274.934172 -7.386828)
		(end 274.426172 -7.894828)
		(width 0.13335)
		(layer "In2.Cu")
		(net "TP_COMP_B_NCSI_RCLK")
	)
	(segment
		(start 280.75001 -7.200138)
		(end 280.56332 -7.386828)
		(width 0.13335)
		(layer "In2.Cu")
		(net "TP_COMP_B_NCSI_RCLK")
	)
	(segment
		(start 278.551894 -11.109706)
		(end 277.241 -12.4206)
		(width 0.17145)
		(layer "F.Cu")
		(net "TP_COMP_B_NCSI_CRSDV")
	)
	(segment
		(start 277.241 -12.4206)
		(end 271.0688 -12.4206)
		(width 0.17145)
		(layer "F.Cu")
		(net "TP_COMP_B_NCSI_CRSDV")
	)
	(segment
		(start 279.994868 -10.200132)
		(end 279.085294 -11.109706)
		(width 0.17145)
		(layer "F.Cu")
		(net "TP_COMP_B_NCSI_CRSDV")
	)
	(segment
		(start 285.249874 -10.200132)
		(end 279.994868 -10.200132)
		(width 0.17145)
		(layer "F.Cu")
		(net "TP_COMP_B_NCSI_CRSDV")
	)
	(segment
		(start 279.085294 -11.109706)
		(end 278.551894 -11.109706)
		(width 0.17145)
		(layer "F.Cu")
		(net "TP_COMP_B_NCSI_CRSDV")
	)
	(segment
		(start 280.041604 -148.4884)
		(end 279.172924 -149.35708)
		(width 0.17145)
		(layer "F.Cu")
		(net "TP_COMP_B_KR_P0_TX_DP")
	)
	(segment
		(start 283.249878 -147.499832)
		(end 282.26131 -148.4884)
		(width 0.17145)
		(layer "F.Cu")
		(net "TP_COMP_B_KR_P0_TX_DP")
	)
	(segment
		(start 276.11959 -150.47341)
		(end 266.991338 -150.47341)
		(width 0.17145)
		(layer "F.Cu")
		(net "TP_COMP_B_KR_P0_TX_DP")
	)
	(segment
		(start 279.172924 -149.35708)
		(end 277.23592 -149.35708)
		(width 0.17145)
		(layer "F.Cu")
		(net "TP_COMP_B_KR_P0_TX_DP")
	)
	(segment
		(start 282.26131 -148.4884)
		(end 280.041604 -148.4884)
		(width 0.17145)
		(layer "F.Cu")
		(net "TP_COMP_B_KR_P0_TX_DP")
	)
	(segment
		(start 277.23592 -149.35708)
		(end 276.11959 -150.47341)
		(width 0.17145)
		(layer "F.Cu")
		(net "TP_COMP_B_KR_P0_TX_DP")
	)
	(segment
		(start 279.628092 -151.4094)
		(end 277.5712 -151.4094)
		(width 0.17145)
		(layer "F.Cu")
		(net "TP_COMP_B_KR_P0_TX_DN")
	)
	(segment
		(start 277.5712 -151.4094)
		(end 276.93239 -152.04821)
		(width 0.17145)
		(layer "F.Cu")
		(net "TP_COMP_B_KR_P0_TX_DN")
	)
	(segment
		(start 285.249874 -148.49983)
		(end 285.249874 -148.712174)
		(width 0.17145)
		(layer "F.Cu")
		(net "TP_COMP_B_KR_P0_TX_DN")
	)
	(segment
		(start 276.93239 -152.04821)
		(end 266.991338 -152.04821)
		(width 0.17145)
		(layer "F.Cu")
		(net "TP_COMP_B_KR_P0_TX_DN")
	)
	(segment
		(start 285.249874 -148.712174)
		(end 283.319474 -150.642574)
		(width 0.17145)
		(layer "F.Cu")
		(net "TP_COMP_B_KR_P0_TX_DN")
	)
	(segment
		(start 280.394918 -150.642574)
		(end 279.628092 -151.4094)
		(width 0.17145)
		(layer "F.Cu")
		(net "TP_COMP_B_KR_P0_TX_DN")
	)
	(segment
		(start 283.319474 -150.642574)
		(end 280.394918 -150.642574)
		(width 0.17145)
		(layer "F.Cu")
		(net "TP_COMP_B_KR_P0_TX_DN")
	)
	(segment
		(start 279.607264 -146.854926)
		(end 278.91359 -147.5486)
		(width 0.17145)
		(layer "F.Cu")
		(net "TP_COMP_B_KR_P0_RX_DP")
	)
	(segment
		(start 278.91359 -147.5486)
		(end 277.6728 -147.5486)
		(width 0.17145)
		(layer "F.Cu")
		(net "TP_COMP_B_KR_P0_RX_DP")
	)
	(segment
		(start 276.295866 -148.925534)
		(end 266.987274 -148.925534)
		(width 0.17145)
		(layer "F.Cu")
		(net "TP_COMP_B_KR_P0_RX_DP")
	)
	(segment
		(start 279.607264 -146.642582)
		(end 279.607264 -146.854926)
		(width 0.17145)
		(layer "F.Cu")
		(net "TP_COMP_B_KR_P0_RX_DP")
	)
	(segment
		(start 277.6728 -147.5486)
		(end 276.295866 -148.925534)
		(width 0.17145)
		(layer "F.Cu")
		(net "TP_COMP_B_KR_P0_RX_DP")
	)
	(segment
		(start 280.75001 -145.499836)
		(end 279.607264 -146.642582)
		(width 0.17145)
		(layer "F.Cu")
		(net "TP_COMP_B_KR_P0_RX_DP")
	)
	(segment
		(start 276.594062 -147.408138)
		(end 267.00099 -147.408138)
		(width 0.17145)
		(layer "F.Cu")
		(net "TP_COMP_B_KR_P0_RX_DN")
	)
	(segment
		(start 278.750014 -146.499834)
		(end 277.502366 -146.499834)
		(width 0.17145)
		(layer "F.Cu")
		(net "TP_COMP_B_KR_P0_RX_DN")
	)
	(segment
		(start 277.502366 -146.499834)
		(end 276.594062 -147.408138)
		(width 0.17145)
		(layer "F.Cu")
		(net "TP_COMP_B_KR_P0_RX_DN")
	)
	(segment
		(start 240.549938 -130.847338)
		(end 239.4458 -129.7432)
		(width 0.17145)
		(layer "F.Cu")
		(net "TP_COMP_A_SATA_P0_TX_DP")
	)
	(segment
		(start 239.4458 -129.7432)
		(end 239.4458 -128.8288)
		(width 0.17145)
		(layer "F.Cu")
		(net "TP_COMP_A_SATA_P0_TX_DP")
	)
	(segment
		(start 240.549938 -131.499864)
		(end 240.549938 -130.847338)
		(width 0.17145)
		(layer "F.Cu")
		(net "TP_COMP_A_SATA_P0_TX_DP")
	)
	(segment
		(start 224.8662 -127.508)
		(end 224.536 -127.8382)
		(width 0.17145)
		(layer "F.Cu")
		(net "TP_COMP_A_SATA_P0_TX_DP")
	)
	(segment
		(start 237.7186 -128.4224)
		(end 236.8042 -127.508)
		(width 0.17145)
		(layer "F.Cu")
		(net "TP_COMP_A_SATA_P0_TX_DP")
	)
	(segment
		(start 236.8042 -127.508)
		(end 224.8662 -127.508)
		(width 0.17145)
		(layer "F.Cu")
		(net "TP_COMP_A_SATA_P0_TX_DP")
	)
	(segment
		(start 239.4458 -128.8288)
		(end 239.0394 -128.4224)
		(width 0.17145)
		(layer "F.Cu")
		(net "TP_COMP_A_SATA_P0_TX_DP")
	)
	(segment
		(start 239.0394 -128.4224)
		(end 237.7186 -128.4224)
		(width 0.17145)
		(layer "F.Cu")
		(net "TP_COMP_A_SATA_P0_TX_DP")
	)
	(segment
		(start 234.708446 -131.357116)
		(end 232.8672 -129.51587)
		(width 0.17145)
		(layer "F.Cu")
		(net "TP_COMP_A_SATA_P0_TX_DN")
	)
	(segment
		(start 237.694978 -130.642614)
		(end 236.980476 -131.357116)
		(width 0.17145)
		(layer "F.Cu")
		(net "TP_COMP_A_SATA_P0_TX_DN")
	)
	(segment
		(start 240.26241 -132.499862)
		(end 238.405162 -130.642614)
		(width 0.17145)
		(layer "F.Cu")
		(net "TP_COMP_A_SATA_P0_TX_DN")
	)
	(segment
		(start 232.8672 -129.51587)
		(end 224.572322 -129.51587)
		(width 0.17145)
		(layer "F.Cu")
		(net "TP_COMP_A_SATA_P0_TX_DN")
	)
	(segment
		(start 238.405162 -130.642614)
		(end 237.694978 -130.642614)
		(width 0.17145)
		(layer "F.Cu")
		(net "TP_COMP_A_SATA_P0_TX_DN")
	)
	(segment
		(start 242.549934 -132.499862)
		(end 240.26241 -132.499862)
		(width 0.17145)
		(layer "F.Cu")
		(net "TP_COMP_A_SATA_P0_TX_DN")
	)
	(segment
		(start 236.980476 -131.357116)
		(end 234.708446 -131.357116)
		(width 0.17145)
		(layer "F.Cu")
		(net "TP_COMP_A_SATA_P0_TX_DN")
	)
	(segment
		(start 237.907322 -133.357112)
		(end 235.694982 -133.357112)
		(width 0.17145)
		(layer "F.Cu")
		(net "TP_COMP_A_SATA_P0_RX_DP")
	)
	(segment
		(start 238.05007 -133.49986)
		(end 237.907322 -133.357112)
		(width 0.17145)
		(layer "F.Cu")
		(net "TP_COMP_A_SATA_P0_RX_DP")
	)
	(segment
		(start 233.45394 -131.11607)
		(end 224.572322 -131.11607)
		(width 0.17145)
		(layer "F.Cu")
		(net "TP_COMP_A_SATA_P0_RX_DP")
	)
	(segment
		(start 235.694982 -133.357112)
		(end 233.45394 -131.11607)
		(width 0.17145)
		(layer "F.Cu")
		(net "TP_COMP_A_SATA_P0_RX_DP")
	)
	(segment
		(start 235.433616 -133.8834)
		(end 233.0958 -133.8834)
		(width 0.17145)
		(layer "F.Cu")
		(net "TP_COMP_A_SATA_P0_RX_DN")
	)
	(segment
		(start 233.0958 -133.8834)
		(end 232.00487 -132.79247)
		(width 0.17145)
		(layer "F.Cu")
		(net "TP_COMP_A_SATA_P0_RX_DN")
	)
	(segment
		(start 236.050074 -134.499858)
		(end 235.433616 -133.8834)
		(width 0.17145)
		(layer "F.Cu")
		(net "TP_COMP_A_SATA_P0_RX_DN")
	)
	(segment
		(start 232.00487 -132.79247)
		(end 224.572322 -132.79247)
		(width 0.17145)
		(layer "F.Cu")
		(net "TP_COMP_A_SATA_P0_RX_DN")
	)
	(segment
		(start 244.005862 -7.200138)
		(end 246.013478 -5.192522)
		(width 0.17145)
		(layer "F.Cu")
		(net "TP_COMP_A_NCSI_TXEN")
	)
	(segment
		(start 246.013478 -5.192522)
		(end 255.415034 -5.192522)
		(width 0.17145)
		(layer "F.Cu")
		(net "TP_COMP_A_NCSI_TXEN")
	)
	(segment
		(start 240.549938 -7.200138)
		(end 244.005862 -7.200138)
		(width 0.17145)
		(layer "F.Cu")
		(net "TP_COMP_A_NCSI_TXEN")
	)
	(segment
		(start 246.654066 -9.200134)
		(end 247.639078 -8.215122)
		(width 0.17145)
		(layer "F.Cu")
		(net "TP_COMP_A_NCSI_TXD1")
	)
	(segment
		(start 240.549938 -9.200134)
		(end 246.654066 -9.200134)
		(width 0.17145)
		(layer "F.Cu")
		(net "TP_COMP_A_NCSI_TXD1")
	)
	(segment
		(start 247.639078 -8.215122)
		(end 255.389634 -8.215122)
		(width 0.17145)
		(layer "F.Cu")
		(net "TP_COMP_A_NCSI_TXD1")
	)
	(segment
		(start 246.927878 -6.741922)
		(end 255.389634 -6.741922)
		(width 0.17145)
		(layer "F.Cu")
		(net "TP_COMP_A_NCSI_TXD0")
	)
	(segment
		(start 245.469664 -8.200136)
		(end 246.927878 -6.741922)
		(width 0.17145)
		(layer "F.Cu")
		(net "TP_COMP_A_NCSI_TXD0")
	)
	(segment
		(start 242.549934 -8.200136)
		(end 245.469664 -8.200136)
		(width 0.17145)
		(layer "F.Cu")
		(net "TP_COMP_A_NCSI_TXD0")
	)
	(segment
		(start 243.5225 -13.12291)
		(end 243.978176 -12.667234)
		(width 0.17145)
		(layer "F.Cu")
		(net "TP_COMP_A_NCSI_RXER")
	)
	(segment
		(start 240.549938 -11.746738)
		(end 241.92611 -13.12291)
		(width 0.17145)
		(layer "F.Cu")
		(net "TP_COMP_A_NCSI_RXER")
	)
	(segment
		(start 240.549938 -11.20013)
		(end 240.549938 -11.746738)
		(width 0.17145)
		(layer "F.Cu")
		(net "TP_COMP_A_NCSI_RXER")
	)
	(segment
		(start 241.92611 -13.12291)
		(end 243.5225 -13.12291)
		(width 0.17145)
		(layer "F.Cu")
		(net "TP_COMP_A_NCSI_RXER")
	)
	(segment
		(start 243.978176 -12.667234)
		(end 255.411478 -12.667234)
		(width 0.17145)
		(layer "F.Cu")
		(net "TP_COMP_A_NCSI_RXER")
	)
	(segment
		(start 242.149122 -11.186922)
		(end 255.364234 -11.186922)
		(width 0.17145)
		(layer "F.Cu")
		(net "TP_COMP_A_NCSI_RXD1")
	)
	(segment
		(start 239.060736 -10.2108)
		(end 241.173 -10.2108)
		(width 0.17145)
		(layer "F.Cu")
		(net "TP_COMP_A_NCSI_RXD1")
	)
	(segment
		(start 238.05007 -9.200134)
		(end 239.060736 -10.2108)
		(width 0.17145)
		(layer "F.Cu")
		(net "TP_COMP_A_NCSI_RXD1")
	)
	(segment
		(start 241.173 -10.2108)
		(end 242.149122 -11.186922)
		(width 0.17145)
		(layer "F.Cu")
		(net "TP_COMP_A_NCSI_RXD1")
	)
	(segment
		(start 255.415034 -2.017522)
		(end 253.44247 -3.990086)
		(width 0.17145)
		(layer "F.Cu")
		(net "TP_COMP_A_NCSI_RXD0")
	)
	(segment
		(start 238.7854 -6.1214)
		(end 237.4392 -6.1214)
		(width 0.17145)
		(layer "F.Cu")
		(net "TP_COMP_A_NCSI_RXD0")
	)
	(segment
		(start 243.512848 -3.342894)
		(end 242.194842 -3.342894)
		(width 0.17145)
		(layer "F.Cu")
		(net "TP_COMP_A_NCSI_RXD0")
	)
	(segment
		(start 243.877084 -3.83286)
		(end 243.877084 -3.70713)
		(width 0.17145)
		(layer "F.Cu")
		(net "TP_COMP_A_NCSI_RXD0")
	)
	(segment
		(start 253.44247 -3.990086)
		(end 244.03431 -3.990086)
		(width 0.17145)
		(layer "F.Cu")
		(net "TP_COMP_A_NCSI_RXD0")
	)
	(segment
		(start 244.03431 -3.990086)
		(end 243.877084 -3.83286)
		(width 0.17145)
		(layer "F.Cu")
		(net "TP_COMP_A_NCSI_RXD0")
	)
	(segment
		(start 241.1222 -4.318)
		(end 239.776 -4.318)
		(width 0.17145)
		(layer "F.Cu")
		(net "TP_COMP_A_NCSI_RXD0")
	)
	(segment
		(start 239.2426 -5.6642)
		(end 238.7854 -6.1214)
		(width 0.17145)
		(layer "F.Cu")
		(net "TP_COMP_A_NCSI_RXD0")
	)
	(segment
		(start 239.2426 -4.8514)
		(end 239.2426 -5.6642)
		(width 0.17145)
		(layer "F.Cu")
		(net "TP_COMP_A_NCSI_RXD0")
	)
	(segment
		(start 242.194842 -3.342894)
		(end 241.704876 -3.83286)
		(width 0.17145)
		(layer "F.Cu")
		(net "TP_COMP_A_NCSI_RXD0")
	)
	(segment
		(start 243.877084 -3.70713)
		(end 243.512848 -3.342894)
		(width 0.17145)
		(layer "F.Cu")
		(net "TP_COMP_A_NCSI_RXD0")
	)
	(segment
		(start 237.4392 -6.1214)
		(end 236.050074 -7.510526)
		(width 0.17145)
		(layer "F.Cu")
		(net "TP_COMP_A_NCSI_RXD0")
	)
	(segment
		(start 236.050074 -7.510526)
		(end 236.050074 -8.200136)
		(width 0.17145)
		(layer "F.Cu")
		(net "TP_COMP_A_NCSI_RXD0")
	)
	(segment
		(start 241.704876 -3.83286)
		(end 241.60734 -3.83286)
		(width 0.17145)
		(layer "F.Cu")
		(net "TP_COMP_A_NCSI_RXD0")
	)
	(segment
		(start 241.60734 -3.83286)
		(end 241.1222 -4.318)
		(width 0.17145)
		(layer "F.Cu")
		(net "TP_COMP_A_NCSI_RXD0")
	)
	(segment
		(start 239.776 -4.318)
		(end 239.2426 -4.8514)
		(width 0.17145)
		(layer "F.Cu")
		(net "TP_COMP_A_NCSI_RXD0")
	)
	(segment
		(start 241.173 -6.1214)
		(end 239.7252 -6.1214)
		(width 0.17145)
		(layer "F.Cu")
		(net "TP_COMP_A_NCSI_RCLK")
	)
	(segment
		(start 242.0874 -5.207)
		(end 241.173 -6.1214)
		(width 0.17145)
		(layer "F.Cu")
		(net "TP_COMP_A_NCSI_RCLK")
	)
	(segment
		(start 243.2304 -5.207)
		(end 242.0874 -5.207)
		(width 0.17145)
		(layer "F.Cu")
		(net "TP_COMP_A_NCSI_RCLK")
	)
	(segment
		(start 239.7252 -6.1214)
		(end 238.646462 -7.200138)
		(width 0.17145)
		(layer "F.Cu")
		(net "TP_COMP_A_NCSI_RCLK")
	)
	(segment
		(start 238.646462 -7.200138)
		(end 238.05007 -7.200138)
		(width 0.17145)
		(layer "F.Cu")
		(net "TP_COMP_A_NCSI_RCLK")
	)
	(segment
		(start 255.389634 -3.617722)
		(end 254.434594 -4.572762)
		(width 0.17145)
		(layer "F.Cu")
		(net "TP_COMP_A_NCSI_RCLK")
	)
	(segment
		(start 243.864638 -4.572762)
		(end 243.2304 -5.207)
		(width 0.17145)
		(layer "F.Cu")
		(net "TP_COMP_A_NCSI_RCLK")
	)
	(segment
		(start 254.434594 -4.572762)
		(end 243.864638 -4.572762)
		(width 0.17145)
		(layer "F.Cu")
		(net "TP_COMP_A_NCSI_RCLK")
	)
	(segment
		(start 246.942102 -10.200132)
		(end 247.4214 -9.720834)
		(width 0.17145)
		(layer "F.Cu")
		(net "TP_COMP_A_NCSI_CRSDV")
	)
	(segment
		(start 242.549934 -10.200132)
		(end 246.942102 -10.200132)
		(width 0.17145)
		(layer "F.Cu")
		(net "TP_COMP_A_NCSI_CRSDV")
	)
	(segment
		(start 247.4214 -9.720834)
		(end 255.386078 -9.720834)
		(width 0.17145)
		(layer "F.Cu")
		(net "TP_COMP_A_NCSI_CRSDV")
	)
	(segment
		(start 239.61217 -148.4376)
		(end 237.363 -148.4376)
		(width 0.17145)
		(layer "F.Cu")
		(net "TP_COMP_A_KR_P0_TX_DP")
	)
	(segment
		(start 236.44352 -149.35708)
		(end 235.22432 -149.35708)
		(width 0.17145)
		(layer "F.Cu")
		(net "TP_COMP_A_KR_P0_TX_DP")
	)
	(segment
		(start 230.78313 -153.79827)
		(end 224.546922 -153.79827)
		(width 0.17145)
		(layer "F.Cu")
		(net "TP_COMP_A_KR_P0_TX_DP")
	)
	(segment
		(start 240.549938 -147.499832)
		(end 239.61217 -148.4376)
		(width 0.17145)
		(layer "F.Cu")
		(net "TP_COMP_A_KR_P0_TX_DP")
	)
	(segment
		(start 237.363 -148.4376)
		(end 236.44352 -149.35708)
		(width 0.17145)
		(layer "F.Cu")
		(net "TP_COMP_A_KR_P0_TX_DP")
	)
	(segment
		(start 235.22432 -149.35708)
		(end 230.78313 -153.79827)
		(width 0.17145)
		(layer "F.Cu")
		(net "TP_COMP_A_KR_P0_TX_DP")
	)
	(segment
		(start 234.7468 -151.6126)
		(end 230.93553 -155.42387)
		(width 0.17145)
		(layer "F.Cu")
		(net "TP_COMP_A_KR_P0_TX_DN")
	)
	(segment
		(start 237.405164 -152.357074)
		(end 236.66069 -151.6126)
		(width 0.17145)
		(layer "F.Cu")
		(net "TP_COMP_A_KR_P0_TX_DN")
	)
	(segment
		(start 238.405162 -152.357074)
		(end 237.405164 -152.357074)
		(width 0.17145)
		(layer "F.Cu")
		(net "TP_COMP_A_KR_P0_TX_DN")
	)
	(segment
		(start 240.343436 -150.4188)
		(end 238.405162 -152.357074)
		(width 0.17145)
		(layer "F.Cu")
		(net "TP_COMP_A_KR_P0_TX_DN")
	)
	(segment
		(start 241.7318 -149.530308)
		(end 240.843308 -150.4188)
		(width 0.17145)
		(layer "F.Cu")
		(net "TP_COMP_A_KR_P0_TX_DN")
	)
	(segment
		(start 240.843308 -150.4188)
		(end 240.343436 -150.4188)
		(width 0.17145)
		(layer "F.Cu")
		(net "TP_COMP_A_KR_P0_TX_DN")
	)
	(segment
		(start 230.93553 -155.42387)
		(end 224.546922 -155.42387)
		(width 0.17145)
		(layer "F.Cu")
		(net "TP_COMP_A_KR_P0_TX_DN")
	)
	(segment
		(start 241.7318 -149.317964)
		(end 241.7318 -149.530308)
		(width 0.17145)
		(layer "F.Cu")
		(net "TP_COMP_A_KR_P0_TX_DN")
	)
	(segment
		(start 236.66069 -151.6126)
		(end 234.7468 -151.6126)
		(width 0.17145)
		(layer "F.Cu")
		(net "TP_COMP_A_KR_P0_TX_DN")
	)
	(segment
		(start 242.549934 -148.49983)
		(end 241.7318 -149.317964)
		(width 0.17145)
		(layer "F.Cu")
		(net "TP_COMP_A_KR_P0_TX_DN")
	)
	(segment
		(start 236.3978 -147.4978)
		(end 235.3564 -147.4978)
		(width 0.17145)
		(layer "F.Cu")
		(net "TP_COMP_A_KR_P0_RX_DP")
	)
	(segment
		(start 238.05007 -145.499836)
		(end 237.109 -146.440906)
		(width 0.17145)
		(layer "F.Cu")
		(net "TP_COMP_A_KR_P0_RX_DP")
	)
	(segment
		(start 237.109 -146.440906)
		(end 237.109 -146.7866)
		(width 0.17145)
		(layer "F.Cu")
		(net "TP_COMP_A_KR_P0_RX_DP")
	)
	(segment
		(start 237.109 -146.7866)
		(end 236.3978 -147.4978)
		(width 0.17145)
		(layer "F.Cu")
		(net "TP_COMP_A_KR_P0_RX_DP")
	)
	(segment
		(start 235.3564 -147.4978)
		(end 230.65613 -152.19807)
		(width 0.17145)
		(layer "F.Cu")
		(net "TP_COMP_A_KR_P0_RX_DP")
	)
	(segment
		(start 230.65613 -152.19807)
		(end 224.572322 -152.19807)
		(width 0.17145)
		(layer "F.Cu")
		(net "TP_COMP_A_KR_P0_RX_DP")
	)
	(segment
		(start 236.050074 -146.499834)
		(end 235.262166 -146.499834)
		(width 0.17145)
		(layer "F.Cu")
		(net "TP_COMP_A_KR_P0_RX_DN")
	)
	(segment
		(start 231.11333 -150.64867)
		(end 224.572322 -150.64867)
		(width 0.17145)
		(layer "F.Cu")
		(net "TP_COMP_A_KR_P0_RX_DN")
	)
	(segment
		(start 235.262166 -146.499834)
		(end 231.11333 -150.64867)
		(width 0.17145)
		(layer "F.Cu")
		(net "TP_COMP_A_KR_P0_RX_DN")
	)
	(segment
		(start 317.60414 -59.171586)
		(end 316.011814 -59.171586)
		(width 0.17145)
		(layer "F.Cu")
		(net "SYS_B_RESET_N")
	)
	(segment
		(start 315.9252 -59.2582)
		(end 315.0616 -59.2582)
		(width 0.17145)
		(layer "F.Cu")
		(net "SYS_B_RESET_N")
	)
	(segment
		(start 317.246 -57.8358)
		(end 317.60414 -58.19394)
		(width 0.17145)
		(layer "F.Cu")
		(net "SYS_B_RESET_N")
	)
	(segment
		(start 317.60414 -58.19394)
		(end 317.60414 -59.171586)
		(width 0.17145)
		(layer "F.Cu")
		(net "SYS_B_RESET_N")
	)
	(segment
		(start 318.3382 -57.8358)
		(end 317.246 -57.8358)
		(width 0.17145)
		(layer "F.Cu")
		(net "SYS_B_RESET_N")
	)
	(segment
		(start 316.011814 -59.171586)
		(end 315.9252 -59.2582)
		(width 0.17145)
		(layer "F.Cu")
		(net "SYS_B_RESET_N")
	)
	(via
		(at 317.246 -57.8358)
		(size 0.6604)
		(drill 0.3302)
		(layers "F.Cu" "B.Cu")
		(net "SYS_B_RESET_N")
	)
	(via
		(at 318.3382 -57.8358)
		(size 0.5588)
		(drill 0.3048)
		(layers "F.Cu" "B.Cu")
		(net "SYS_B_RESET_N")
	)
	(via
		(at 333.314802 -24.247602)
		(size 0.5588)
		(drill 0.3048)
		(layers "F.Cu" "B.Cu")
		(net "SYS_B_RESET_N")
	)
	(segment
		(start 359.84053 -31.270702)
		(end 357.621078 -33.490154)
		(width 0.13335)
		(layer "In2.Cu")
		(net "SYS_B_RESET_N")
	)
	(segment
		(start 357.621078 -33.490154)
		(end 353.33686 -33.490154)
		(width 0.13335)
		(layer "In2.Cu")
		(net "SYS_B_RESET_N")
	)
	(segment
		(start 340.784434 -25.158954)
		(end 338.647532 -25.158954)
		(width 0.13335)
		(layer "In2.Cu")
		(net "SYS_B_RESET_N")
	)
	(segment
		(start 338.647532 -25.158954)
		(end 338.647278 -25.159208)
		(width 0.13335)
		(layer "In2.Cu")
		(net "SYS_B_RESET_N")
	)
	(segment
		(start 360.549952 -29.150056)
		(end 359.84053 -29.859478)
		(width 0.13335)
		(layer "In2.Cu")
		(net "SYS_B_RESET_N")
	)
	(segment
		(start 346.307918 -26.461212)
		(end 342.086692 -26.461212)
		(width 0.13335)
		(layer "In2.Cu")
		(net "SYS_B_RESET_N")
	)
	(segment
		(start 336.740246 -23.780496)
		(end 333.781908 -23.780496)
		(width 0.13335)
		(layer "In2.Cu")
		(net "SYS_B_RESET_N")
	)
	(segment
		(start 338.118958 -25.159208)
		(end 336.740246 -23.780496)
		(width 0.13335)
		(layer "In2.Cu")
		(net "SYS_B_RESET_N")
	)
	(segment
		(start 359.84053 -29.859478)
		(end 359.84053 -31.270702)
		(width 0.13335)
		(layer "In2.Cu")
		(net "SYS_B_RESET_N")
	)
	(segment
		(start 333.781908 -23.780496)
		(end 333.314802 -24.247602)
		(width 0.13335)
		(layer "In2.Cu")
		(net "SYS_B_RESET_N")
	)
	(segment
		(start 353.33686 -33.490154)
		(end 346.307918 -26.461212)
		(width 0.13335)
		(layer "In2.Cu")
		(net "SYS_B_RESET_N")
	)
	(segment
		(start 342.086692 -26.461212)
		(end 340.784434 -25.158954)
		(width 0.13335)
		(layer "In2.Cu")
		(net "SYS_B_RESET_N")
	)
	(segment
		(start 338.647278 -25.159208)
		(end 338.118958 -25.159208)
		(width 0.13335)
		(layer "In2.Cu")
		(net "SYS_B_RESET_N")
	)
	(segment
		(start 333.51724 -31.84398)
		(end 333.51724 -38.220396)
		(width 0.12065)
		(layer "In4.Cu")
		(net "SYS_B_RESET_N")
	)
	(segment
		(start 335.1911 -26.820368)
		(end 335.1911 -30.17012)
		(width 0.12065)
		(layer "In4.Cu")
		(net "SYS_B_RESET_N")
	)
	(segment
		(start 324.226682 -52.175918)
		(end 318.5668 -57.8358)
		(width 0.12065)
		(layer "In4.Cu")
		(net "SYS_B_RESET_N")
	)
	(segment
		(start 333.314802 -24.247602)
		(end 333.314802 -24.94407)
		(width 0.12065)
		(layer "In4.Cu")
		(net "SYS_B_RESET_N")
	)
	(segment
		(start 318.5668 -57.8358)
		(end 318.3382 -57.8358)
		(width 0.12065)
		(layer "In4.Cu")
		(net "SYS_B_RESET_N")
	)
	(segment
		(start 327.705466 -44.03217)
		(end 327.705466 -48.63465)
		(width 0.12065)
		(layer "In4.Cu")
		(net "SYS_B_RESET_N")
	)
	(segment
		(start 335.1911 -30.17012)
		(end 333.51724 -31.84398)
		(width 0.12065)
		(layer "In4.Cu")
		(net "SYS_B_RESET_N")
	)
	(segment
		(start 324.226682 -52.113434)
		(end 324.226682 -52.175918)
		(width 0.12065)
		(layer "In4.Cu")
		(net "SYS_B_RESET_N")
	)
	(segment
		(start 333.51724 -38.220396)
		(end 327.705466 -44.03217)
		(width 0.12065)
		(layer "In4.Cu")
		(net "SYS_B_RESET_N")
	)
	(segment
		(start 327.705466 -48.63465)
		(end 324.226682 -52.113434)
		(width 0.12065)
		(layer "In4.Cu")
		(net "SYS_B_RESET_N")
	)
	(segment
		(start 333.314802 -24.94407)
		(end 335.1911 -26.820368)
		(width 0.12065)
		(layer "In4.Cu")
		(net "SYS_B_RESET_N")
	)
	(segment
		(start 169.261282 -27.99334)
		(end 171.691808 -27.99334)
		(width 0.17145)
		(layer "F.Cu")
		(net "SYS_A_RESET_N")
	)
	(segment
		(start 169.200068 -27.932126)
		(end 168.056052 -27.932126)
		(width 0.17145)
		(layer "F.Cu")
		(net "SYS_A_RESET_N")
	)
	(segment
		(start 168.056052 -28.90393)
		(end 168.516046 -29.363924)
		(width 0.17145)
		(layer "F.Cu")
		(net "SYS_A_RESET_N")
	)
	(segment
		(start 169.200068 -27.932126)
		(end 169.261282 -27.99334)
		(width 0.17145)
		(layer "F.Cu")
		(net "SYS_A_RESET_N")
	)
	(segment
		(start 168.056052 -27.932126)
		(end 168.056052 -28.90393)
		(width 0.17145)
		(layer "F.Cu")
		(net "SYS_A_RESET_N")
	)
	(via
		(at 168.056052 -27.932126)
		(size 0.6604)
		(drill 0.3302)
		(layers "F.Cu" "B.Cu")
		(net "SYS_A_RESET_N")
	)
	(via
		(at 168.516046 -29.363924)
		(size 0.5588)
		(drill 0.3048)
		(layers "F.Cu" "B.Cu")
		(net "SYS_A_RESET_N")
	)
	(segment
		(start 120.736106 -41.230296)
		(end 126.917196 -41.230296)
		(width 0.12065)
		(layer "In7.Cu")
		(net "SYS_A_RESET_N")
	)
	(segment
		(start 113.981484 -30.314646)
		(end 113.981484 -34.475674)
		(width 0.12065)
		(layer "In7.Cu")
		(net "SYS_A_RESET_N")
	)
	(segment
		(start 126.917196 -41.230296)
		(end 127.302768 -40.844724)
		(width 0.12065)
		(layer "In7.Cu")
		(net "SYS_A_RESET_N")
	)
	(segment
		(start 139.511278 -43.238928)
		(end 151.317452 -43.238928)
		(width 0.12065)
		(layer "In7.Cu")
		(net "SYS_A_RESET_N")
	)
	(segment
		(start 168.516046 -35.676332)
		(end 168.516046 -29.363924)
		(width 0.12065)
		(layer "In7.Cu")
		(net "SYS_A_RESET_N")
	)
	(segment
		(start 127.302768 -40.844724)
		(end 137.117074 -40.844724)
		(width 0.12065)
		(layer "In7.Cu")
		(net "SYS_A_RESET_N")
	)
	(segment
		(start 137.117074 -40.844724)
		(end 139.511278 -43.238928)
		(width 0.12065)
		(layer "In7.Cu")
		(net "SYS_A_RESET_N")
	)
	(segment
		(start 114.549936 -29.150056)
		(end 114.549936 -29.746194)
		(width 0.12065)
		(layer "In7.Cu")
		(net "SYS_A_RESET_N")
	)
	(segment
		(start 113.981484 -34.475674)
		(end 120.736106 -41.230296)
		(width 0.12065)
		(layer "In7.Cu")
		(net "SYS_A_RESET_N")
	)
	(segment
		(start 114.549936 -29.746194)
		(end 113.981484 -30.314646)
		(width 0.12065)
		(layer "In7.Cu")
		(net "SYS_A_RESET_N")
	)
	(segment
		(start 151.317452 -43.238928)
		(end 152.921462 -41.634918)
		(width 0.12065)
		(layer "In7.Cu")
		(net "SYS_A_RESET_N")
	)
	(segment
		(start 152.921462 -41.634918)
		(end 162.55746 -41.634918)
		(width 0.12065)
		(layer "In7.Cu")
		(net "SYS_A_RESET_N")
	)
	(segment
		(start 162.55746 -41.634918)
		(end 168.516046 -35.676332)
		(width 0.12065)
		(layer "In7.Cu")
		(net "SYS_A_RESET_N")
	)
	(segment
		(start 22.551898 -274.871942)
		(end 22.551898 -276.014942)
		(width 0.17145)
		(layer "F.Cu")
		(net "SW_PWR_R_HDD0")
	)
	(segment
		(start 20.811998 -278.554942)
		(end 20.430998 -278.935942)
		(width 0.17145)
		(layer "F.Cu")
		(net "SW_PWR_R_HDD0")
	)
	(segment
		(start 22.551898 -278.554942)
		(end 20.811998 -278.554942)
		(width 0.17145)
		(layer "F.Cu")
		(net "SW_PWR_R_HDD0")
	)
	(segment
		(start 22.551898 -277.284942)
		(end 22.551898 -278.554942)
		(width 0.17145)
		(layer "F.Cu")
		(net "SW_PWR_R_HDD0")
	)
	(segment
		(start 22.551898 -276.014942)
		(end 22.551898 -277.284942)
		(width 0.17145)
		(layer "F.Cu")
		(net "SW_PWR_R_HDD0")
	)
	(segment
		(start 20.430998 -278.935942)
		(end 20.430998 -279.494742)
		(width 0.17145)
		(layer "F.Cu")
		(net "SW_PWR_R_HDD0")
	)
	(via
		(at 22.551898 -277.284942)
		(size 0.6604)
		(drill 0.3302)
		(layers "F.Cu" "B.Cu")
		(net "SW_PWR_R_HDD0")
	)
	(segment
		(start 16.874998 -275.506942)
		(end 15.338298 -275.506942)
		(width 0.17145)
		(layer "F.Cu")
		(net "SW_HDD_R0")
	)
	(segment
		(start 15.338298 -275.506942)
		(end 15.236698 -275.608542)
		(width 0.17145)
		(layer "F.Cu")
		(net "SW_HDD_R0")
	)
	(segment
		(start 15.236698 -275.608542)
		(end 15.223998 -275.621242)
		(width 0.17145)
		(layer "F.Cu")
		(net "SW_HDD_R0")
	)
	(segment
		(start 17.509998 -275.506942)
		(end 16.874998 -275.506942)
		(width 0.17145)
		(layer "F.Cu")
		(net "SW_HDD_R0")
	)
	(segment
		(start 21.081238 -275.585682)
		(end 20.684998 -275.189442)
		(width 0.17145)
		(layer "F.Cu")
		(net "SW_HDD_R0")
	)
	(segment
		(start 18.500598 -275.189442)
		(end 17.827498 -275.189442)
		(width 0.17145)
		(layer "F.Cu")
		(net "SW_HDD_R0")
	)
	(segment
		(start 20.684998 -275.189442)
		(end 18.500598 -275.189442)
		(width 0.17145)
		(layer "F.Cu")
		(net "SW_HDD_R0")
	)
	(segment
		(start 15.223998 -275.621242)
		(end 15.223998 -276.713442)
		(width 0.17145)
		(layer "F.Cu")
		(net "SW_HDD_R0")
	)
	(segment
		(start 21.081238 -277.615142)
		(end 21.081238 -275.585682)
		(width 0.17145)
		(layer "F.Cu")
		(net "SW_HDD_R0")
	)
	(segment
		(start 17.827498 -275.189442)
		(end 17.509998 -275.506942)
		(width 0.17145)
		(layer "F.Cu")
		(net "SW_HDD_R0")
	)
	(via
		(at 20.684998 -275.189442)
		(size 0.6604)
		(drill 0.3302)
		(layers "F.Cu" "B.Cu")
		(net "SW_HDD_R0")
	)
	(segment
		(start 17.268698 -282.110942)
		(end 17.268698 -283.152342)
		(width 0.17145)
		(layer "F.Cu")
		(net "SW_HDD_P0")
	)
	(segment
		(start 18.779998 -286.301942)
		(end 18.779998 -287.825942)
		(width 0.17145)
		(layer "F.Cu")
		(net "SW_HDD_P0")
	)
	(segment
		(start 17.268698 -284.790642)
		(end 18.779998 -286.301942)
		(width 0.17145)
		(layer "F.Cu")
		(net "SW_HDD_P0")
	)
	(segment
		(start 17.2974 -280.663142)
		(end 17.268698 -280.663142)
		(width 0.17145)
		(layer "F.Cu")
		(net "SW_HDD_P0")
	)
	(segment
		(start 17.268698 -280.663142)
		(end 17.268698 -282.110942)
		(width 0.17145)
		(layer "F.Cu")
		(net "SW_HDD_P0")
	)
	(segment
		(start 19.780758 -279.494742)
		(end 18.284698 -279.494742)
		(width 0.17145)
		(layer "F.Cu")
		(net "SW_HDD_P0")
	)
	(segment
		(start 17.268698 -283.152342)
		(end 17.268698 -284.790642)
		(width 0.17145)
		(layer "F.Cu")
		(net "SW_HDD_P0")
	)
	(segment
		(start 17.2974 -280.48204)
		(end 17.2974 -280.663142)
		(width 0.17145)
		(layer "F.Cu")
		(net "SW_HDD_P0")
	)
	(segment
		(start 18.284698 -279.494742)
		(end 17.2974 -280.48204)
		(width 0.17145)
		(layer "F.Cu")
		(net "SW_HDD_P0")
	)
	(via
		(at 17.2974 -280.663142)
		(size 0.6604)
		(drill 0.3302)
		(layers "F.Cu" "B.Cu")
		(net "SW_HDD_P0")
	)
	(segment
		(start 15.287498 -279.316942)
		(end 15.287498 -278.3713)
		(width 0.17145)
		(layer "F.Cu")
		(net "SW_HDD_N0")
	)
	(segment
		(start 15.93596 -277.602442)
		(end 16.12646 -277.792942)
		(width 0.17145)
		(layer "F.Cu")
		(net "SW_HDD_N0")
	)
	(segment
		(start 15.223998 -278.3078)
		(end 15.223998 -277.602442)
		(width 0.17145)
		(layer "F.Cu")
		(net "SW_HDD_N0")
	)
	(segment
		(start 15.287498 -278.3713)
		(end 15.223998 -278.3078)
		(width 0.17145)
		(layer "F.Cu")
		(net "SW_HDD_N0")
	)
	(segment
		(start 15.287498 -284.523942)
		(end 16.747998 -285.984442)
		(width 0.17145)
		(layer "F.Cu")
		(net "SW_HDD_N0")
	)
	(segment
		(start 16.747998 -285.984442)
		(end 16.747998 -287.317942)
		(width 0.17145)
		(layer "F.Cu")
		(net "SW_HDD_N0")
	)
	(segment
		(start 15.223998 -277.602442)
		(end 15.93596 -277.602442)
		(width 0.17145)
		(layer "F.Cu")
		(net "SW_HDD_N0")
	)
	(segment
		(start 15.287498 -279.316942)
		(end 15.287498 -283.482542)
		(width 0.17145)
		(layer "F.Cu")
		(net "SW_HDD_N0")
	)
	(segment
		(start 15.287498 -283.482542)
		(end 15.287498 -284.523942)
		(width 0.17145)
		(layer "F.Cu")
		(net "SW_HDD_N0")
	)
	(segment
		(start 16.12646 -277.792942)
		(end 16.874998 -277.792942)
		(width 0.17145)
		(layer "F.Cu")
		(net "SW_HDD_N0")
	)
	(via
		(at 15.287498 -279.316942)
		(size 0.6604)
		(drill 0.3302)
		(layers "F.Cu" "B.Cu")
		(net "SW_HDD_N0")
	)
	(segment
		(start 19.618198 -276.078442)
		(end 18.500598 -276.078442)
		(width 0.17145)
		(layer "F.Cu")
		(net "SW_HDD_G0")
	)
	(segment
		(start 20.430998 -277.615142)
		(end 20.430998 -276.891242)
		(width 0.17145)
		(layer "F.Cu")
		(net "SW_HDD_G0")
	)
	(segment
		(start 20.430998 -276.891242)
		(end 19.618198 -276.078442)
		(width 0.17145)
		(layer "F.Cu")
		(net "SW_HDD_G0")
	)
	(via
		(at 19.618198 -276.078442)
		(size 0.6604)
		(drill 0.3302)
		(layers "F.Cu" "B.Cu")
		(net "SW_HDD_G0")
	)
	(via
		(at 222.5548 -395.8336)
		(size 0.5588)
		(drill 0.3048)
		(layers "F.Cu" "B.Cu")
		(net "SCC_B_STBY_PWR_EN")
	)
	(via
		(at 377.5964 -199.785986)
		(size 0.5588)
		(drill 0.3048)
		(layers "F.Cu" "B.Cu")
		(net "SCC_B_STBY_PWR_EN")
	)
	(via
		(at 229.362 -213.995)
		(size 0.5588)
		(drill 0.3048)
		(layers "F.Cu" "B.Cu")
		(net "SCC_B_STBY_PWR_EN")
	)
	(segment
		(start 316.970664 -204.58557)
		(end 321.607434 -199.9488)
		(width 0.254)
		(layer "In2.Cu")
		(net "SCC_B_STBY_PWR_EN")
	)
	(segment
		(start 226.200208 -410.600144)
		(end 225.464116 -409.864052)
		(width 0.254)
		(layer "In2.Cu")
		(net "SCC_B_STBY_PWR_EN")
	)
	(segment
		(start 225.464116 -409.864052)
		(end 225.464116 -400.319748)
		(width 0.254)
		(layer "In2.Cu")
		(net "SCC_B_STBY_PWR_EN")
	)
	(segment
		(start 229.362 -213.995)
		(end 238.77143 -204.58557)
		(width 0.254)
		(layer "In2.Cu")
		(net "SCC_B_STBY_PWR_EN")
	)
	(segment
		(start 238.77143 -204.58557)
		(end 316.970664 -204.58557)
		(width 0.254)
		(layer "In2.Cu")
		(net "SCC_B_STBY_PWR_EN")
	)
	(segment
		(start 377.433586 -199.9488)
		(end 377.5964 -199.785986)
		(width 0.254)
		(layer "In2.Cu")
		(net "SCC_B_STBY_PWR_EN")
	)
	(segment
		(start 222.5548 -397.410432)
		(end 222.5548 -395.8336)
		(width 0.254)
		(layer "In2.Cu")
		(net "SCC_B_STBY_PWR_EN")
	)
	(segment
		(start 321.607434 -199.9488)
		(end 377.433586 -199.9488)
		(width 0.254)
		(layer "In2.Cu")
		(net "SCC_B_STBY_PWR_EN")
	)
	(segment
		(start 225.464116 -400.319748)
		(end 222.5548 -397.410432)
		(width 0.254)
		(layer "In2.Cu")
		(net "SCC_B_STBY_PWR_EN")
	)
	(segment
		(start 222.5548 -395.8336)
		(end 220.9546 -394.2334)
		(width 0.254)
		(layer "In4.Cu")
		(net "SCC_B_STBY_PWR_EN")
	)
	(segment
		(start 225.364294 -321.043046)
		(end 225.364294 -223.402906)
		(width 0.254)
		(layer "In4.Cu")
		(net "SCC_B_STBY_PWR_EN")
	)
	(segment
		(start 223.64827 -376.180096)
		(end 223.64827 -367.349278)
		(width 0.254)
		(layer "In4.Cu")
		(net "SCC_B_STBY_PWR_EN")
	)
	(segment
		(start 228.517704 -214.839296)
		(end 229.362 -213.995)
		(width 0.254)
		(layer "In4.Cu")
		(net "SCC_B_STBY_PWR_EN")
	)
	(segment
		(start 225.871278 -365.12627)
		(end 225.871278 -360.177334)
		(width 0.254)
		(layer "In4.Cu")
		(net "SCC_B_STBY_PWR_EN")
	)
	(segment
		(start 220.9546 -394.2334)
		(end 220.9546 -380.456694)
		(width 0.254)
		(layer "In4.Cu")
		(net "SCC_B_STBY_PWR_EN")
	)
	(segment
		(start 391.159238 -143.668496)
		(end 377.627134 -157.2006)
		(width 0.254)
		(layer "In4.Cu")
		(net "SCC_B_STBY_PWR_EN")
	)
	(segment
		(start 222.60179 -377.226576)
		(end 223.64827 -376.180096)
		(width 0.254)
		(layer "In4.Cu")
		(net "SCC_B_STBY_PWR_EN")
	)
	(segment
		(start 228.517704 -220.249496)
		(end 228.517704 -214.839296)
		(width 0.254)
		(layer "In4.Cu")
		(net "SCC_B_STBY_PWR_EN")
	)
	(segment
		(start 222.60179 -378.809504)
		(end 222.60179 -377.226576)
		(width 0.254)
		(layer "In4.Cu")
		(net "SCC_B_STBY_PWR_EN")
	)
	(segment
		(start 225.871278 -360.177334)
		(end 222.582994 -356.88905)
		(width 0.254)
		(layer "In4.Cu")
		(net "SCC_B_STBY_PWR_EN")
	)
	(segment
		(start 383.949956 -24.558244)
		(end 382.9558 -25.5524)
		(width 0.254)
		(layer "In4.Cu")
		(net "SCC_B_STBY_PWR_EN")
	)
	(segment
		(start 225.262694 -321.1449)
		(end 225.262694 -321.144646)
		(width 0.254)
		(layer "In4.Cu")
		(net "SCC_B_STBY_PWR_EN")
	)
	(segment
		(start 383.949956 -24.550116)
		(end 383.949956 -24.558244)
		(width 0.254)
		(layer "In4.Cu")
		(net "SCC_B_STBY_PWR_EN")
	)
	(segment
		(start 377.627134 -199.755252)
		(end 377.5964 -199.785986)
		(width 0.254)
		(layer "In4.Cu")
		(net "SCC_B_STBY_PWR_EN")
	)
	(segment
		(start 225.364294 -223.402906)
		(end 228.517704 -220.249496)
		(width 0.254)
		(layer "In4.Cu")
		(net "SCC_B_STBY_PWR_EN")
	)
	(segment
		(start 377.926346 -115.886484)
		(end 391.159238 -129.119376)
		(width 0.254)
		(layer "In4.Cu")
		(net "SCC_B_STBY_PWR_EN")
	)
	(segment
		(start 382.9558 -25.5524)
		(end 382.9558 -33.0454)
		(width 0.254)
		(layer "In4.Cu")
		(net "SCC_B_STBY_PWR_EN")
	)
	(segment
		(start 225.262694 -321.144646)
		(end 225.364294 -321.043046)
		(width 0.254)
		(layer "In4.Cu")
		(net "SCC_B_STBY_PWR_EN")
	)
	(segment
		(start 220.9546 -380.456694)
		(end 222.60179 -378.809504)
		(width 0.254)
		(layer "In4.Cu")
		(net "SCC_B_STBY_PWR_EN")
	)
	(segment
		(start 382.9558 -33.0454)
		(end 377.926346 -38.074854)
		(width 0.254)
		(layer "In4.Cu")
		(net "SCC_B_STBY_PWR_EN")
	)
	(segment
		(start 223.64827 -367.349278)
		(end 225.871278 -365.12627)
		(width 0.254)
		(layer "In4.Cu")
		(net "SCC_B_STBY_PWR_EN")
	)
	(segment
		(start 377.627134 -157.2006)
		(end 377.627134 -199.755252)
		(width 0.254)
		(layer "In4.Cu")
		(net "SCC_B_STBY_PWR_EN")
	)
	(segment
		(start 377.926346 -38.074854)
		(end 377.926346 -115.886484)
		(width 0.254)
		(layer "In4.Cu")
		(net "SCC_B_STBY_PWR_EN")
	)
	(segment
		(start 391.159238 -129.119376)
		(end 391.159238 -143.668496)
		(width 0.254)
		(layer "In4.Cu")
		(net "SCC_B_STBY_PWR_EN")
	)
	(segment
		(start 222.582994 -323.8246)
		(end 225.262694 -321.1449)
		(width 0.254)
		(layer "In4.Cu")
		(net "SCC_B_STBY_PWR_EN")
	)
	(segment
		(start 222.582994 -356.88905)
		(end 222.582994 -323.8246)
		(width 0.254)
		(layer "In4.Cu")
		(net "SCC_B_STBY_PWR_EN")
	)
	(via
		(at 262.001 -357.632)
		(size 0.5588)
		(drill 0.3048)
		(layers "F.Cu" "B.Cu")
		(net "SCC_B_HEARTBEAT")
	)
	(via
		(at 280.753312 7.87527)
		(size 0.5588)
		(drill 0.3048)
		(layers "F.Cu" "B.Cu")
		(net "SCC_B_HEARTBEAT")
	)
	(via
		(at 289.687 -43.5356)
		(size 0.5588)
		(drill 0.3048)
		(layers "F.Cu" "B.Cu")
		(net "SCC_B_HEARTBEAT")
	)
	(via
		(at 381.4064 -340.9442)
		(size 0.5588)
		(drill 0.3048)
		(layers "F.Cu" "B.Cu")
		(net "SCC_B_HEARTBEAT")
	)
	(segment
		(start 289.56 -351.917)
		(end 288.544 -352.933)
		(width 0.13335)
		(layer "In2.Cu")
		(net "SCC_B_HEARTBEAT")
	)
	(segment
		(start 384.613658 -31.855918)
		(end 365.761016 -50.70856)
		(width 0.13335)
		(layer "In2.Cu")
		(net "SCC_B_HEARTBEAT")
	)
	(segment
		(start 311.68721 -43.5356)
		(end 289.687 -43.5356)
		(width 0.13335)
		(layer "In2.Cu")
		(net "SCC_B_HEARTBEAT")
	)
	(segment
		(start 289.56 -346.3798)
		(end 289.56 -351.917)
		(width 0.13335)
		(layer "In2.Cu")
		(net "SCC_B_HEARTBEAT")
	)
	(segment
		(start 381.4064 -340.8172)
		(end 381.0508 -340.4616)
		(width 0.13335)
		(layer "In2.Cu")
		(net "SCC_B_HEARTBEAT")
	)
	(segment
		(start 378.055886 -340.4616)
		(end 377.989084 -340.528402)
		(width 0.13335)
		(layer "In2.Cu")
		(net "SCC_B_HEARTBEAT")
	)
	(segment
		(start 381.4064 -340.9442)
		(end 381.4064 -340.8172)
		(width 0.13335)
		(layer "In2.Cu")
		(net "SCC_B_HEARTBEAT")
	)
	(segment
		(start 283.05379 -354.10521)
		(end 282.83662 -354.10521)
		(width 0.13335)
		(layer "In2.Cu")
		(net "SCC_B_HEARTBEAT")
	)
	(segment
		(start 288.544 -352.933)
		(end 284.226 -352.933)
		(width 0.13335)
		(layer "In2.Cu")
		(net "SCC_B_HEARTBEAT")
	)
	(segment
		(start 381.0508 -340.4616)
		(end 378.055886 -340.4616)
		(width 0.13335)
		(layer "In2.Cu")
		(net "SCC_B_HEARTBEAT")
	)
	(segment
		(start 377.989084 -340.528402)
		(end 295.411398 -340.528402)
		(width 0.13335)
		(layer "In2.Cu")
		(net "SCC_B_HEARTBEAT")
	)
	(segment
		(start 385.750054 -25.550114)
		(end 384.613658 -26.68651)
		(width 0.13335)
		(layer "In2.Cu")
		(net "SCC_B_HEARTBEAT")
	)
	(segment
		(start 284.226 -352.933)
		(end 283.05379 -354.10521)
		(width 0.13335)
		(layer "In2.Cu")
		(net "SCC_B_HEARTBEAT")
	)
	(segment
		(start 365.761016 -50.70856)
		(end 318.86017 -50.70856)
		(width 0.13335)
		(layer "In2.Cu")
		(net "SCC_B_HEARTBEAT")
	)
	(segment
		(start 318.86017 -50.70856)
		(end 311.68721 -43.5356)
		(width 0.13335)
		(layer "In2.Cu")
		(net "SCC_B_HEARTBEAT")
	)
	(segment
		(start 295.411398 -340.528402)
		(end 289.56 -346.3798)
		(width 0.13335)
		(layer "In2.Cu")
		(net "SCC_B_HEARTBEAT")
	)
	(segment
		(start 384.613658 -26.68651)
		(end 384.613658 -31.855918)
		(width 0.13335)
		(layer "In2.Cu")
		(net "SCC_B_HEARTBEAT")
	)
	(segment
		(start 275.7678 -359.090468)
		(end 274.589494 -360.268774)
		(width 0.12065)
		(layer "In4.Cu")
		(net "SCC_B_HEARTBEAT")
	)
	(segment
		(start 381.4064 -340.7664)
		(end 381.4064 -340.9442)
		(width 0.12065)
		(layer "In4.Cu")
		(net "SCC_B_HEARTBEAT")
	)
	(segment
		(start 386.8674 -26.66746)
		(end 386.8674 -33.3756)
		(width 0.12065)
		(layer "In4.Cu")
		(net "SCC_B_HEARTBEAT")
	)
	(segment
		(start 382.1176 -280.5176)
		(end 382.1176 -295.8084)
		(width 0.12065)
		(layer "In4.Cu")
		(net "SCC_B_HEARTBEAT")
	)
	(segment
		(start 381.508 -296.418)
		(end 381.508 -340.6648)
		(width 0.12065)
		(layer "In4.Cu")
		(net "SCC_B_HEARTBEAT")
	)
	(segment
		(start 382.1176 -295.8084)
		(end 381.508 -296.418)
		(width 0.12065)
		(layer "In4.Cu")
		(net "SCC_B_HEARTBEAT")
	)
	(segment
		(start 280.753312 7.87527)
		(end 280.753312 7.028942)
		(width 0.12065)
		(layer "In4.Cu")
		(net "SCC_B_HEARTBEAT")
	)
	(segment
		(start 274.589494 -360.268774)
		(end 266.415774 -360.268774)
		(width 0.12065)
		(layer "In4.Cu")
		(net "SCC_B_HEARTBEAT")
	)
	(segment
		(start 380.050548 -40.192452)
		(end 380.050548 -115.005866)
		(width 0.12065)
		(layer "In4.Cu")
		(net "SCC_B_HEARTBEAT")
	)
	(segment
		(start 266.415774 -360.268774)
		(end 263.779 -357.632)
		(width 0.12065)
		(layer "In4.Cu")
		(net "SCC_B_HEARTBEAT")
	)
	(segment
		(start 263.779 -357.632)
		(end 262.001 -357.632)
		(width 0.12065)
		(layer "In4.Cu")
		(net "SCC_B_HEARTBEAT")
	)
	(segment
		(start 379.9205 -235.978954)
		(end 380.873 -236.931454)
		(width 0.12065)
		(layer "In4.Cu")
		(net "SCC_B_HEARTBEAT")
	)
	(segment
		(start 380.050548 -115.005866)
		(end 393.28344 -128.238758)
		(width 0.12065)
		(layer "In4.Cu")
		(net "SCC_B_HEARTBEAT")
	)
	(segment
		(start 385.750054 -25.550114)
		(end 386.8674 -26.66746)
		(width 0.12065)
		(layer "In4.Cu")
		(net "SCC_B_HEARTBEAT")
	)
	(segment
		(start 386.8674 -33.3756)
		(end 380.050548 -40.192452)
		(width 0.12065)
		(layer "In4.Cu")
		(net "SCC_B_HEARTBEAT")
	)
	(segment
		(start 380.977648 -156.854906)
		(end 380.977648 -179.454302)
		(width 0.12065)
		(layer "In4.Cu")
		(net "SCC_B_HEARTBEAT")
	)
	(segment
		(start 275.7678 -355.4476)
		(end 275.7678 -359.090468)
		(width 0.12065)
		(layer "In4.Cu")
		(net "SCC_B_HEARTBEAT")
	)
	(segment
		(start 379.9205 -180.51145)
		(end 379.9205 -235.978954)
		(width 0.12065)
		(layer "In4.Cu")
		(net "SCC_B_HEARTBEAT")
	)
	(segment
		(start 280.753312 7.028942)
		(end 289.687 -1.904746)
		(width 0.12065)
		(layer "In4.Cu")
		(net "SCC_B_HEARTBEAT")
	)
	(segment
		(start 381.508 -340.6648)
		(end 381.4064 -340.7664)
		(width 0.12065)
		(layer "In4.Cu")
		(net "SCC_B_HEARTBEAT")
	)
	(segment
		(start 380.873 -279.273)
		(end 382.1176 -280.5176)
		(width 0.12065)
		(layer "In4.Cu")
		(net "SCC_B_HEARTBEAT")
	)
	(segment
		(start 282.83662 -354.10521)
		(end 282.180284 -354.761546)
		(width 0.12065)
		(layer "In4.Cu")
		(net "SCC_B_HEARTBEAT")
	)
	(segment
		(start 380.873 -236.931454)
		(end 380.873 -279.273)
		(width 0.12065)
		(layer "In4.Cu")
		(net "SCC_B_HEARTBEAT")
	)
	(segment
		(start 282.180284 -354.761546)
		(end 276.453854 -354.761546)
		(width 0.12065)
		(layer "In4.Cu")
		(net "SCC_B_HEARTBEAT")
	)
	(segment
		(start 393.28344 -144.549114)
		(end 380.977648 -156.854906)
		(width 0.12065)
		(layer "In4.Cu")
		(net "SCC_B_HEARTBEAT")
	)
	(segment
		(start 380.977648 -179.454302)
		(end 379.9205 -180.51145)
		(width 0.12065)
		(layer "In4.Cu")
		(net "SCC_B_HEARTBEAT")
	)
	(segment
		(start 276.453854 -354.761546)
		(end 275.7678 -355.4476)
		(width 0.12065)
		(layer "In4.Cu")
		(net "SCC_B_HEARTBEAT")
	)
	(segment
		(start 393.28344 -128.238758)
		(end 393.28344 -144.549114)
		(width 0.12065)
		(layer "In4.Cu")
		(net "SCC_B_HEARTBEAT")
	)
	(segment
		(start 289.687 -1.904746)
		(end 289.687 -43.5356)
		(width 0.12065)
		(layer "In4.Cu")
		(net "SCC_B_HEARTBEAT")
	)
	(segment
		(start 234.68965 3.516376)
		(end 240.751614 3.516376)
		(width 0.12065)
		(layer "In7.Cu")
		(net "SCC_B_HEARTBEAT")
	)
	(segment
		(start 240.751614 3.516376)
		(end 243.243354 1.024636)
		(width 0.12065)
		(layer "In7.Cu")
		(net "SCC_B_HEARTBEAT")
	)
	(segment
		(start 227.616512 -3.556762)
		(end 234.68965 3.516376)
		(width 0.12065)
		(layer "In7.Cu")
		(net "SCC_B_HEARTBEAT")
	)
	(segment
		(start 232.533698 -376.558302)
		(end 232.533698 -351.310448)
		(width 0.12065)
		(layer "In7.Cu")
		(net "SCC_B_HEARTBEAT")
	)
	(segment
		(start 274.813268 8.499094)
		(end 280.129488 8.499094)
		(width 0.12065)
		(layer "In7.Cu")
		(net "SCC_B_HEARTBEAT")
	)
	(segment
		(start 166.74592 -17.08785)
		(end 179.891182 -3.942588)
		(width 0.12065)
		(layer "In7.Cu")
		(net "SCC_B_HEARTBEAT")
	)
	(segment
		(start 233.340148 -411.459934)
		(end 233.340148 -399.28927)
		(width 0.12065)
		(layer "In7.Cu")
		(net "SCC_B_HEARTBEAT")
	)
	(segment
		(start 141.678152 -32.946086)
		(end 143.797782 -32.946086)
		(width 0.12065)
		(layer "In7.Cu")
		(net "SCC_B_HEARTBEAT")
	)
	(segment
		(start 234.076748 -349.767398)
		(end 249.661172 -349.767398)
		(width 0.12065)
		(layer "In7.Cu")
		(net "SCC_B_HEARTBEAT")
	)
	(segment
		(start 222.214186 -3.942588)
		(end 222.600012 -3.556762)
		(width 0.12065)
		(layer "In7.Cu")
		(net "SCC_B_HEARTBEAT")
	)
	(segment
		(start 249.661172 -349.767398)
		(end 257.525774 -357.632)
		(width 0.12065)
		(layer "In7.Cu")
		(net "SCC_B_HEARTBEAT")
	)
	(segment
		(start 271.25549 8.728202)
		(end 274.58416 8.728202)
		(width 0.12065)
		(layer "In7.Cu")
		(net "SCC_B_HEARTBEAT")
	)
	(segment
		(start 274.58416 8.728202)
		(end 274.813268 8.499094)
		(width 0.12065)
		(layer "In7.Cu")
		(net "SCC_B_HEARTBEAT")
	)
	(segment
		(start 222.600012 -3.556762)
		(end 227.616512 -3.556762)
		(width 0.12065)
		(layer "In7.Cu")
		(net "SCC_B_HEARTBEAT")
	)
	(segment
		(start 140.3858 -27.585924)
		(end 140.3858 -31.653734)
		(width 0.12065)
		(layer "In7.Cu")
		(net "SCC_B_HEARTBEAT")
	)
	(segment
		(start 179.891182 -3.942588)
		(end 222.214186 -3.942588)
		(width 0.12065)
		(layer "In7.Cu")
		(net "SCC_B_HEARTBEAT")
	)
	(segment
		(start 280.129488 8.499094)
		(end 280.753312 7.87527)
		(width 0.12065)
		(layer "In7.Cu")
		(net "SCC_B_HEARTBEAT")
	)
	(segment
		(start 257.525774 -357.632)
		(end 262.001 -357.632)
		(width 0.12065)
		(layer "In7.Cu")
		(net "SCC_B_HEARTBEAT")
	)
	(segment
		(start 232.533698 -351.310448)
		(end 234.076748 -349.767398)
		(width 0.12065)
		(layer "In7.Cu")
		(net "SCC_B_HEARTBEAT")
	)
	(segment
		(start 143.797782 -32.946086)
		(end 159.656018 -17.08785)
		(width 0.12065)
		(layer "In7.Cu")
		(net "SCC_B_HEARTBEAT")
	)
	(segment
		(start 140.3858 -31.653734)
		(end 141.678152 -32.946086)
		(width 0.12065)
		(layer "In7.Cu")
		(net "SCC_B_HEARTBEAT")
	)
	(segment
		(start 139.750038 -26.950162)
		(end 140.3858 -27.585924)
		(width 0.12065)
		(layer "In7.Cu")
		(net "SCC_B_HEARTBEAT")
	)
	(segment
		(start 159.656018 -17.08785)
		(end 166.74592 -17.08785)
		(width 0.12065)
		(layer "In7.Cu")
		(net "SCC_B_HEARTBEAT")
	)
	(segment
		(start 243.243354 1.024636)
		(end 263.551924 1.024636)
		(width 0.12065)
		(layer "In7.Cu")
		(net "SCC_B_HEARTBEAT")
	)
	(segment
		(start 229.631748 -395.58087)
		(end 229.631748 -379.460252)
		(width 0.12065)
		(layer "In7.Cu")
		(net "SCC_B_HEARTBEAT")
	)
	(segment
		(start 229.631748 -379.460252)
		(end 232.533698 -376.558302)
		(width 0.12065)
		(layer "In7.Cu")
		(net "SCC_B_HEARTBEAT")
	)
	(segment
		(start 263.551924 1.024636)
		(end 271.25549 8.728202)
		(width 0.12065)
		(layer "In7.Cu")
		(net "SCC_B_HEARTBEAT")
	)
	(segment
		(start 231.599994 -413.200088)
		(end 233.340148 -411.459934)
		(width 0.12065)
		(layer "In7.Cu")
		(net "SCC_B_HEARTBEAT")
	)
	(segment
		(start 233.340148 -399.28927)
		(end 229.631748 -395.58087)
		(width 0.12065)
		(layer "In7.Cu")
		(net "SCC_B_HEARTBEAT")
	)
	(segment
		(start 383.0066 -29.093414)
		(end 383.0066 -31.02229)
		(width 0.254)
		(layer "F.Cu")
		(net "SCC_B_FULL_PWR_EN")
	)
	(segment
		(start 383.0066 -31.02229)
		(end 383.838958 -31.854648)
		(width 0.254)
		(layer "F.Cu")
		(net "SCC_B_FULL_PWR_EN")
	)
	(segment
		(start 383.949956 -28.150058)
		(end 383.0066 -29.093414)
		(width 0.254)
		(layer "F.Cu")
		(net "SCC_B_FULL_PWR_EN")
	)
	(via
		(at 222.5294 -393.446)
		(size 0.5588)
		(drill 0.3048)
		(layers "F.Cu" "B.Cu")
		(net "SCC_B_FULL_PWR_EN")
	)
	(via
		(at 248.359676 -176.556162)
		(size 0.5588)
		(drill 0.3048)
		(layers "F.Cu" "B.Cu")
		(net "SCC_B_FULL_PWR_EN")
	)
	(via
		(at 378.206 -183.642)
		(size 0.5588)
		(drill 0.3048)
		(layers "F.Cu" "B.Cu")
		(net "SCC_B_FULL_PWR_EN")
	)
	(via
		(at 346.12199 -33.047686)
		(size 0.5588)
		(drill 0.3048)
		(layers "F.Cu" "B.Cu")
		(net "SCC_B_FULL_PWR_EN")
	)
	(via
		(at 383.838958 -31.854648)
		(size 0.5588)
		(drill 0.3048)
		(layers "F.Cu" "B.Cu")
		(net "SCC_B_FULL_PWR_EN")
	)
	(via
		(at 344.043 -19.1516)
		(size 0.5588)
		(drill 0.3048)
		(layers "F.Cu" "B.Cu")
		(net "SCC_B_FULL_PWR_EN")
	)
	(segment
		(start 226.200208 -416.699954)
		(end 225.437954 -416.699954)
		(width 0.254)
		(layer "In2.Cu")
		(net "SCC_B_FULL_PWR_EN")
	)
	(segment
		(start 137.31494 -30.185106)
		(end 137.31494 -30.950154)
		(width 0.254)
		(layer "In2.Cu")
		(net "SCC_B_FULL_PWR_EN")
	)
	(segment
		(start 224.056702 -415.318702)
		(end 224.056702 -400.637502)
		(width 0.254)
		(layer "In2.Cu")
		(net "SCC_B_FULL_PWR_EN")
	)
	(segment
		(start 221.107 -394.8684)
		(end 222.5294 -393.446)
		(width 0.254)
		(layer "In2.Cu")
		(net "SCC_B_FULL_PWR_EN")
	)
	(segment
		(start 342.8238 -17.9324)
		(end 344.043 -19.1516)
		(width 0.254)
		(layer "In2.Cu")
		(net "SCC_B_FULL_PWR_EN")
	)
	(segment
		(start 310.930544 -192.649856)
		(end 319.9384 -183.642)
		(width 0.254)
		(layer "In2.Cu")
		(net "SCC_B_FULL_PWR_EN")
	)
	(segment
		(start 218.764612 -11.730736)
		(end 221.978982 -8.516366)
		(width 0.254)
		(layer "In2.Cu")
		(net "SCC_B_FULL_PWR_EN")
	)
	(segment
		(start 209.632804 -16.387318)
		(end 214.289386 -11.730736)
		(width 0.254)
		(layer "In2.Cu")
		(net "SCC_B_FULL_PWR_EN")
	)
	(segment
		(start 205.994762 -24.356568)
		(end 209.632804 -20.718526)
		(width 0.254)
		(layer "In2.Cu")
		(net "SCC_B_FULL_PWR_EN")
	)
	(segment
		(start 209.632804 -20.718526)
		(end 209.632804 -16.387318)
		(width 0.254)
		(layer "In2.Cu")
		(net "SCC_B_FULL_PWR_EN")
	)
	(segment
		(start 137.94994 -29.550106)
		(end 137.31494 -30.185106)
		(width 0.254)
		(layer "In2.Cu")
		(net "SCC_B_FULL_PWR_EN")
	)
	(segment
		(start 307.935376 -6.353302)
		(end 312.505852 -10.923778)
		(width 0.254)
		(layer "In2.Cu")
		(net "SCC_B_FULL_PWR_EN")
	)
	(segment
		(start 139.234164 -32.869378)
		(end 145.083022 -32.869378)
		(width 0.254)
		(layer "In2.Cu")
		(net "SCC_B_FULL_PWR_EN")
	)
	(segment
		(start 205.573884 -24.356314)
		(end 205.574138 -24.356568)
		(width 0.254)
		(layer "In2.Cu")
		(net "SCC_B_FULL_PWR_EN")
	)
	(segment
		(start 224.056702 -400.637502)
		(end 221.107 -397.6878)
		(width 0.254)
		(layer "In2.Cu")
		(net "SCC_B_FULL_PWR_EN")
	)
	(segment
		(start 145.083022 -32.869378)
		(end 153.596086 -24.356314)
		(width 0.254)
		(layer "In2.Cu")
		(net "SCC_B_FULL_PWR_EN")
	)
	(segment
		(start 264.45337 -192.649856)
		(end 310.930544 -192.649856)
		(width 0.254)
		(layer "In2.Cu")
		(net "SCC_B_FULL_PWR_EN")
	)
	(segment
		(start 337.988148 -17.9324)
		(end 342.8238 -17.9324)
		(width 0.254)
		(layer "In2.Cu")
		(net "SCC_B_FULL_PWR_EN")
	)
	(segment
		(start 295.92397 -6.353302)
		(end 307.935376 -6.353302)
		(width 0.254)
		(layer "In2.Cu")
		(net "SCC_B_FULL_PWR_EN")
	)
	(segment
		(start 314.90158 -18.354548)
		(end 337.566 -18.354548)
		(width 0.254)
		(layer "In2.Cu")
		(net "SCC_B_FULL_PWR_EN")
	)
	(segment
		(start 221.978982 -8.516366)
		(end 229.940612 -8.516366)
		(width 0.254)
		(layer "In2.Cu")
		(net "SCC_B_FULL_PWR_EN")
	)
	(segment
		(start 225.437954 -416.699954)
		(end 224.056702 -415.318702)
		(width 0.254)
		(layer "In2.Cu")
		(net "SCC_B_FULL_PWR_EN")
	)
	(segment
		(start 137.31494 -30.950154)
		(end 139.234164 -32.869378)
		(width 0.254)
		(layer "In2.Cu")
		(net "SCC_B_FULL_PWR_EN")
	)
	(segment
		(start 312.505852 -15.95882)
		(end 314.90158 -18.354548)
		(width 0.254)
		(layer "In2.Cu")
		(net "SCC_B_FULL_PWR_EN")
	)
	(segment
		(start 236.602524 -1.854454)
		(end 253.449582 -1.854454)
		(width 0.254)
		(layer "In2.Cu")
		(net "SCC_B_FULL_PWR_EN")
	)
	(segment
		(start 337.566 -18.354548)
		(end 337.988148 -17.9324)
		(width 0.254)
		(layer "In2.Cu")
		(net "SCC_B_FULL_PWR_EN")
	)
	(segment
		(start 205.574138 -24.356568)
		(end 205.994762 -24.356568)
		(width 0.254)
		(layer "In2.Cu")
		(net "SCC_B_FULL_PWR_EN")
	)
	(segment
		(start 312.505852 -10.923778)
		(end 312.505852 -15.95882)
		(width 0.254)
		(layer "In2.Cu")
		(net "SCC_B_FULL_PWR_EN")
	)
	(segment
		(start 258.936236 3.6322)
		(end 285.938468 3.6322)
		(width 0.254)
		(layer "In2.Cu")
		(net "SCC_B_FULL_PWR_EN")
	)
	(segment
		(start 153.596086 -24.356314)
		(end 205.573884 -24.356314)
		(width 0.254)
		(layer "In2.Cu")
		(net "SCC_B_FULL_PWR_EN")
	)
	(segment
		(start 285.938468 3.6322)
		(end 295.92397 -6.353302)
		(width 0.254)
		(layer "In2.Cu")
		(net "SCC_B_FULL_PWR_EN")
	)
	(segment
		(start 229.940612 -8.516366)
		(end 236.602524 -1.854454)
		(width 0.254)
		(layer "In2.Cu")
		(net "SCC_B_FULL_PWR_EN")
	)
	(segment
		(start 253.449582 -1.854454)
		(end 258.936236 3.6322)
		(width 0.254)
		(layer "In2.Cu")
		(net "SCC_B_FULL_PWR_EN")
	)
	(segment
		(start 319.9384 -183.642)
		(end 378.206 -183.642)
		(width 0.254)
		(layer "In2.Cu")
		(net "SCC_B_FULL_PWR_EN")
	)
	(segment
		(start 248.359676 -176.556162)
		(end 264.45337 -192.649856)
		(width 0.254)
		(layer "In2.Cu")
		(net "SCC_B_FULL_PWR_EN")
	)
	(segment
		(start 221.107 -397.6878)
		(end 221.107 -394.8684)
		(width 0.254)
		(layer "In2.Cu")
		(net "SCC_B_FULL_PWR_EN")
	)
	(segment
		(start 214.289386 -11.730736)
		(end 218.764612 -11.730736)
		(width 0.254)
		(layer "In2.Cu")
		(net "SCC_B_FULL_PWR_EN")
	)
	(segment
		(start 224.644204 -349.485204)
		(end 224.644204 -357.513128)
		(width 0.254)
		(layer "In4.Cu")
		(net "SCC_B_FULL_PWR_EN")
	)
	(segment
		(start 226.887278 -359.756202)
		(end 226.887278 -365.656876)
		(width 0.254)
		(layer "In4.Cu")
		(net "SCC_B_FULL_PWR_EN")
	)
	(segment
		(start 224.66427 -367.879884)
		(end 224.66427 -376.601228)
		(width 0.254)
		(layer "In4.Cu")
		(net "SCC_B_FULL_PWR_EN")
	)
	(segment
		(start 344.043 -21.539708)
		(end 345.69908 -23.195788)
		(width 0.254)
		(layer "In4.Cu")
		(net "SCC_B_FULL_PWR_EN")
	)
	(segment
		(start 226.419664 -321.425316)
		(end 224.119694 -323.725286)
		(width 0.254)
		(layer "In4.Cu")
		(net "SCC_B_FULL_PWR_EN")
	)
	(segment
		(start 391.667238 -143.879062)
		(end 391.667238 -128.90881)
		(width 0.254)
		(layer "In4.Cu")
		(net "SCC_B_FULL_PWR_EN")
	)
	(segment
		(start 224.119694 -323.725286)
		(end 224.119694 -348.960694)
		(width 0.254)
		(layer "In4.Cu")
		(net "SCC_B_FULL_PWR_EN")
	)
	(segment
		(start 221.9706 -392.8872)
		(end 222.5294 -393.446)
		(width 0.254)
		(layer "In4.Cu")
		(net "SCC_B_FULL_PWR_EN")
	)
	(segment
		(start 248.824242 -201.705718)
		(end 226.380294 -224.149666)
		(width 0.254)
		(layer "In4.Cu")
		(net "SCC_B_FULL_PWR_EN")
	)
	(segment
		(start 224.644204 -357.513128)
		(end 226.887278 -359.756202)
		(width 0.254)
		(layer "In4.Cu")
		(net "SCC_B_FULL_PWR_EN")
	)
	(segment
		(start 378.434346 -38.671246)
		(end 383.838958 -33.266634)
		(width 0.254)
		(layer "In4.Cu")
		(net "SCC_B_FULL_PWR_EN")
	)
	(segment
		(start 248.824242 -201.644758)
		(end 248.824242 -201.705718)
		(width 0.254)
		(layer "In4.Cu")
		(net "SCC_B_FULL_PWR_EN")
	)
	(segment
		(start 226.419664 -249.984514)
		(end 226.419664 -321.425316)
		(width 0.254)
		(layer "In4.Cu")
		(net "SCC_B_FULL_PWR_EN")
	)
	(segment
		(start 226.380294 -249.945144)
		(end 226.419664 -249.984514)
		(width 0.254)
		(layer "In4.Cu")
		(net "SCC_B_FULL_PWR_EN")
	)
	(segment
		(start 224.1804 -377.085098)
		(end 224.1804 -386.09778)
		(width 0.254)
		(layer "In4.Cu")
		(net "SCC_B_FULL_PWR_EN")
	)
	(segment
		(start 344.043 -19.1516)
		(end 344.043 -21.539708)
		(width 0.254)
		(layer "In4.Cu")
		(net "SCC_B_FULL_PWR_EN")
	)
	(segment
		(start 378.206 -183.642)
		(end 378.206 -157.3403)
		(width 0.254)
		(layer "In4.Cu")
		(net "SCC_B_FULL_PWR_EN")
	)
	(segment
		(start 224.66427 -376.601228)
		(end 224.1804 -377.085098)
		(width 0.254)
		(layer "In4.Cu")
		(net "SCC_B_FULL_PWR_EN")
	)
	(segment
		(start 345.69908 -31.534862)
		(end 346.12199 -31.957772)
		(width 0.254)
		(layer "In4.Cu")
		(net "SCC_B_FULL_PWR_EN")
	)
	(segment
		(start 221.9706 -388.30758)
		(end 221.9706 -392.8872)
		(width 0.254)
		(layer "In4.Cu")
		(net "SCC_B_FULL_PWR_EN")
	)
	(segment
		(start 248.359676 -176.556162)
		(end 248.874788 -177.071274)
		(width 0.254)
		(layer "In4.Cu")
		(net "SCC_B_FULL_PWR_EN")
	)
	(segment
		(start 383.838958 -33.266634)
		(end 383.838958 -31.854648)
		(width 0.254)
		(layer "In4.Cu")
		(net "SCC_B_FULL_PWR_EN")
	)
	(segment
		(start 346.12199 -31.957772)
		(end 346.12199 -33.047686)
		(width 0.254)
		(layer "In4.Cu")
		(net "SCC_B_FULL_PWR_EN")
	)
	(segment
		(start 226.887278 -365.656876)
		(end 224.66427 -367.879884)
		(width 0.254)
		(layer "In4.Cu")
		(net "SCC_B_FULL_PWR_EN")
	)
	(segment
		(start 224.119694 -348.960694)
		(end 224.644204 -349.485204)
		(width 0.254)
		(layer "In4.Cu")
		(net "SCC_B_FULL_PWR_EN")
	)
	(segment
		(start 378.434346 -115.675918)
		(end 378.434346 -38.671246)
		(width 0.254)
		(layer "In4.Cu")
		(net "SCC_B_FULL_PWR_EN")
	)
	(segment
		(start 248.874788 -201.594212)
		(end 248.824242 -201.644758)
		(width 0.254)
		(layer "In4.Cu")
		(net "SCC_B_FULL_PWR_EN")
	)
	(segment
		(start 226.380294 -224.149666)
		(end 226.380294 -249.945144)
		(width 0.254)
		(layer "In4.Cu")
		(net "SCC_B_FULL_PWR_EN")
	)
	(segment
		(start 248.874788 -177.071274)
		(end 248.874788 -201.594212)
		(width 0.254)
		(layer "In4.Cu")
		(net "SCC_B_FULL_PWR_EN")
	)
	(segment
		(start 378.206 -157.3403)
		(end 391.667238 -143.879062)
		(width 0.254)
		(layer "In4.Cu")
		(net "SCC_B_FULL_PWR_EN")
	)
	(segment
		(start 391.667238 -128.90881)
		(end 378.434346 -115.675918)
		(width 0.254)
		(layer "In4.Cu")
		(net "SCC_B_FULL_PWR_EN")
	)
	(segment
		(start 345.69908 -23.195788)
		(end 345.69908 -31.534862)
		(width 0.254)
		(layer "In4.Cu")
		(net "SCC_B_FULL_PWR_EN")
	)
	(segment
		(start 224.1804 -386.09778)
		(end 221.9706 -388.30758)
		(width 0.254)
		(layer "In4.Cu")
		(net "SCC_B_FULL_PWR_EN")
	)
	(segment
		(start 383.949956 -28.150058)
		(end 383.0828 -29.017214)
		(width 0.254)
		(layer "In7.Cu")
		(net "SCC_B_FULL_PWR_EN")
	)
	(segment
		(start 357.835708 -37.314378)
		(end 350.388682 -37.314378)
		(width 0.254)
		(layer "In7.Cu")
		(net "SCC_B_FULL_PWR_EN")
	)
	(segment
		(start 383.0828 -29.017214)
		(end 383.0828 -32.0548)
		(width 0.254)
		(layer "In7.Cu")
		(net "SCC_B_FULL_PWR_EN")
	)
	(segment
		(start 377.479052 -37.658548)
		(end 358.179878 -37.658548)
		(width 0.254)
		(layer "In7.Cu")
		(net "SCC_B_FULL_PWR_EN")
	)
	(segment
		(start 383.0828 -32.0548)
		(end 377.479052 -37.658548)
		(width 0.254)
		(layer "In7.Cu")
		(net "SCC_B_FULL_PWR_EN")
	)
	(segment
		(start 350.388682 -37.314378)
		(end 346.12199 -33.047686)
		(width 0.254)
		(layer "In7.Cu")
		(net "SCC_B_FULL_PWR_EN")
	)
	(segment
		(start 358.179878 -37.658548)
		(end 357.835708 -37.314378)
		(width 0.254)
		(layer "In7.Cu")
		(net "SCC_B_FULL_PWR_EN")
	)
	(segment
		(start 340.848188 -28.093416)
		(end 339.953854 -28.98775)
		(width 0.254)
		(layer "F.Cu")
		(net "SCC_B_FULL_PGOOD")
	)
	(segment
		(start 340.848188 -26.834846)
		(end 340.848188 -28.093416)
		(width 0.254)
		(layer "F.Cu")
		(net "SCC_B_FULL_PGOOD")
	)
	(segment
		(start 339.953854 -28.98775)
		(end 339.953854 -30.05709)
		(width 0.254)
		(layer "F.Cu")
		(net "SCC_B_FULL_PGOOD")
	)
	(via
		(at 243.15928 -195.533772)
		(size 0.5588)
		(drill 0.3048)
		(layers "F.Cu" "B.Cu")
		(net "SCC_B_FULL_PGOOD")
	)
	(via
		(at 340.848188 -26.834846)
		(size 0.5588)
		(drill 0.3048)
		(layers "F.Cu" "B.Cu")
		(net "SCC_B_FULL_PGOOD")
	)
	(via
		(at 334.264 -196.1388)
		(size 0.5588)
		(drill 0.3048)
		(layers "F.Cu" "B.Cu")
		(net "SCC_B_FULL_PGOOD")
	)
	(segment
		(start 319.84061 -196.760592)
		(end 315.384942 -201.21626)
		(width 0.254)
		(layer "In2.Cu")
		(net "SCC_B_FULL_PGOOD")
	)
	(segment
		(start 334.264 -196.1388)
		(end 334.228948 -196.173852)
		(width 0.254)
		(layer "In2.Cu")
		(net "SCC_B_FULL_PGOOD")
	)
	(segment
		(start 332.08976 -196.760592)
		(end 319.84061 -196.760592)
		(width 0.254)
		(layer "In2.Cu")
		(net "SCC_B_FULL_PGOOD")
	)
	(segment
		(start 334.228948 -196.173852)
		(end 332.6765 -196.173852)
		(width 0.254)
		(layer "In2.Cu")
		(net "SCC_B_FULL_PGOOD")
	)
	(segment
		(start 315.384942 -201.21626)
		(end 248.841768 -201.21626)
		(width 0.254)
		(layer "In2.Cu")
		(net "SCC_B_FULL_PGOOD")
	)
	(segment
		(start 332.6765 -196.173852)
		(end 332.08976 -196.760592)
		(width 0.254)
		(layer "In2.Cu")
		(net "SCC_B_FULL_PGOOD")
	)
	(segment
		(start 248.841768 -201.21626)
		(end 243.15928 -195.533772)
		(width 0.254)
		(layer "In2.Cu")
		(net "SCC_B_FULL_PGOOD")
	)
	(segment
		(start 214.488268 -385.152392)
		(end 214.488268 -324.926706)
		(width 0.254)
		(layer "In4.Cu")
		(net "SCC_B_FULL_PGOOD")
	)
	(segment
		(start 223.966278 -403.580346)
		(end 214.90686 -394.520928)
		(width 0.254)
		(layer "In4.Cu")
		(net "SCC_B_FULL_PGOOD")
	)
	(segment
		(start 340.211156 -75.161902)
		(end 341.664544 -76.61529)
		(width 0.254)
		(layer "In4.Cu")
		(net "SCC_B_FULL_PGOOD")
	)
	(segment
		(start 340.848188 -26.834846)
		(end 340.848188 -28.64104)
		(width 0.254)
		(layer "In4.Cu")
		(net "SCC_B_FULL_PGOOD")
	)
	(segment
		(start 323.902324 -160.612582)
		(end 323.902324 -170.782996)
		(width 0.254)
		(layer "In4.Cu")
		(net "SCC_B_FULL_PGOOD")
	)
	(segment
		(start 340.211156 -38.865302)
		(end 340.211156 -75.161902)
		(width 0.254)
		(layer "In4.Cu")
		(net "SCC_B_FULL_PGOOD")
	)
	(segment
		(start 325.789544 -151.893778)
		(end 326.908922 -153.013156)
		(width 0.254)
		(layer "In4.Cu")
		(net "SCC_B_FULL_PGOOD")
	)
	(segment
		(start 324.922134 -175.163734)
		(end 334.264 -184.5056)
		(width 0.254)
		(layer "In4.Cu")
		(net "SCC_B_FULL_PGOOD")
	)
	(segment
		(start 341.709248 -37.36721)
		(end 340.211156 -38.865302)
		(width 0.254)
		(layer "In4.Cu")
		(net "SCC_B_FULL_PGOOD")
	)
	(segment
		(start 326.932798 -147.69211)
		(end 325.789544 -148.835364)
		(width 0.254)
		(layer "In4.Cu")
		(net "SCC_B_FULL_PGOOD")
	)
	(segment
		(start 326.908922 -153.013156)
		(end 326.908922 -157.605984)
		(width 0.254)
		(layer "In4.Cu")
		(net "SCC_B_FULL_PGOOD")
	)
	(segment
		(start 214.90686 -394.520928)
		(end 214.90686 -385.570984)
		(width 0.254)
		(layer "In4.Cu")
		(net "SCC_B_FULL_PGOOD")
	)
	(segment
		(start 326.932798 -120.915938)
		(end 326.932798 -147.69211)
		(width 0.254)
		(layer "In4.Cu")
		(net "SCC_B_FULL_PGOOD")
	)
	(segment
		(start 326.908922 -157.605984)
		(end 323.902324 -160.612582)
		(width 0.254)
		(layer "In4.Cu")
		(net "SCC_B_FULL_PGOOD")
	)
	(segment
		(start 224.091754 -215.118188)
		(end 224.0915 -215.117934)
		(width 0.254)
		(layer "In4.Cu")
		(net "SCC_B_FULL_PGOOD")
	)
	(segment
		(start 224.0915 -209.4103)
		(end 237.2868 -196.215)
		(width 0.254)
		(layer "In4.Cu")
		(net "SCC_B_FULL_PGOOD")
	)
	(segment
		(start 224.0915 -215.117934)
		(end 224.0915 -209.4103)
		(width 0.254)
		(layer "In4.Cu")
		(net "SCC_B_FULL_PGOOD")
	)
	(segment
		(start 325.789544 -148.835364)
		(end 325.789544 -151.893778)
		(width 0.254)
		(layer "In4.Cu")
		(net "SCC_B_FULL_PGOOD")
	)
	(segment
		(start 214.90686 -385.570984)
		(end 214.488268 -385.152392)
		(width 0.254)
		(layer "In4.Cu")
		(net "SCC_B_FULL_PGOOD")
	)
	(segment
		(start 226.200208 -415.600134)
		(end 223.966278 -413.366204)
		(width 0.254)
		(layer "In4.Cu")
		(net "SCC_B_FULL_PGOOD")
	)
	(segment
		(start 214.488268 -324.926706)
		(end 220.878654 -318.53632)
		(width 0.254)
		(layer "In4.Cu")
		(net "SCC_B_FULL_PGOOD")
	)
	(segment
		(start 323.902324 -170.782996)
		(end 324.922134 -171.802806)
		(width 0.254)
		(layer "In4.Cu")
		(net "SCC_B_FULL_PGOOD")
	)
	(segment
		(start 242.478052 -196.215)
		(end 243.15928 -195.533772)
		(width 0.254)
		(layer "In4.Cu")
		(net "SCC_B_FULL_PGOOD")
	)
	(segment
		(start 223.0755 -216.555066)
		(end 224.091754 -215.538812)
		(width 0.254)
		(layer "In4.Cu")
		(net "SCC_B_FULL_PGOOD")
	)
	(segment
		(start 341.664544 -106.184192)
		(end 326.932798 -120.915938)
		(width 0.254)
		(layer "In4.Cu")
		(net "SCC_B_FULL_PGOOD")
	)
	(segment
		(start 237.2868 -196.215)
		(end 242.478052 -196.215)
		(width 0.254)
		(layer "In4.Cu")
		(net "SCC_B_FULL_PGOOD")
	)
	(segment
		(start 340.848188 -28.64104)
		(end 341.709248 -29.5021)
		(width 0.254)
		(layer "In4.Cu")
		(net "SCC_B_FULL_PGOOD")
	)
	(segment
		(start 223.0755 -218.7575)
		(end 223.0755 -216.555066)
		(width 0.254)
		(layer "In4.Cu")
		(net "SCC_B_FULL_PGOOD")
	)
	(segment
		(start 223.966278 -413.366204)
		(end 223.966278 -403.580346)
		(width 0.254)
		(layer "In4.Cu")
		(net "SCC_B_FULL_PGOOD")
	)
	(segment
		(start 220.878654 -220.954346)
		(end 223.0755 -218.7575)
		(width 0.254)
		(layer "In4.Cu")
		(net "SCC_B_FULL_PGOOD")
	)
	(segment
		(start 334.264 -184.5056)
		(end 334.264 -196.1388)
		(width 0.254)
		(layer "In4.Cu")
		(net "SCC_B_FULL_PGOOD")
	)
	(segment
		(start 324.922134 -171.802806)
		(end 324.922134 -175.163734)
		(width 0.254)
		(layer "In4.Cu")
		(net "SCC_B_FULL_PGOOD")
	)
	(segment
		(start 341.664544 -76.61529)
		(end 341.664544 -106.184192)
		(width 0.254)
		(layer "In4.Cu")
		(net "SCC_B_FULL_PGOOD")
	)
	(segment
		(start 341.709248 -29.5021)
		(end 341.709248 -37.36721)
		(width 0.254)
		(layer "In4.Cu")
		(net "SCC_B_FULL_PGOOD")
	)
	(segment
		(start 220.878654 -318.53632)
		(end 220.878654 -220.954346)
		(width 0.254)
		(layer "In4.Cu")
		(net "SCC_B_FULL_PGOOD")
	)
	(segment
		(start 224.091754 -215.538812)
		(end 224.091754 -215.118188)
		(width 0.254)
		(layer "In4.Cu")
		(net "SCC_B_FULL_PGOOD")
	)
	(via
		(at 140.611098 -341.890604)
		(size 0.5588)
		(drill 0.3048)
		(layers "F.Cu" "B.Cu")
		(net "SCC_A_STBY_PWR_EN")
	)
	(segment
		(start 165.668706 -342.519)
		(end 141.239494 -342.519)
		(width 0.254)
		(layer "In2.Cu")
		(net "SCC_A_STBY_PWR_EN")
	)
	(segment
		(start 245.957852 -348.22003)
		(end 244.617494 -346.879672)
		(width 0.254)
		(layer "In2.Cu")
		(net "SCC_A_STBY_PWR_EN")
	)
	(segment
		(start 235.27004 -346.879672)
		(end 234.564174 -346.173806)
		(width 0.254)
		(layer "In2.Cu")
		(net "SCC_A_STBY_PWR_EN")
	)
	(segment
		(start 234.564174 -346.173806)
		(end 225.015806 -346.173806)
		(width 0.254)
		(layer "In2.Cu")
		(net "SCC_A_STBY_PWR_EN")
	)
	(segment
		(start 267.6398 -355.1936)
		(end 260.66623 -348.22003)
		(width 0.254)
		(layer "In2.Cu")
		(net "SCC_A_STBY_PWR_EN")
	)
	(segment
		(start 225.015806 -346.173806)
		(end 223.6216 -344.7796)
		(width 0.254)
		(layer "In2.Cu")
		(net "SCC_A_STBY_PWR_EN")
	)
	(segment
		(start 281.836622 -355.905054)
		(end 281.125168 -355.1936)
		(width 0.254)
		(layer "In2.Cu")
		(net "SCC_A_STBY_PWR_EN")
	)
	(segment
		(start 281.125168 -355.1936)
		(end 267.6398 -355.1936)
		(width 0.254)
		(layer "In2.Cu")
		(net "SCC_A_STBY_PWR_EN")
	)
	(segment
		(start 209.725006 -339.550502)
		(end 168.637204 -339.550502)
		(width 0.254)
		(layer "In2.Cu")
		(net "SCC_A_STBY_PWR_EN")
	)
	(segment
		(start 214.954104 -344.7796)
		(end 209.725006 -339.550502)
		(width 0.254)
		(layer "In2.Cu")
		(net "SCC_A_STBY_PWR_EN")
	)
	(segment
		(start 141.239494 -342.519)
		(end 140.611098 -341.890604)
		(width 0.254)
		(layer "In2.Cu")
		(net "SCC_A_STBY_PWR_EN")
	)
	(segment
		(start 244.617494 -346.879672)
		(end 235.27004 -346.879672)
		(width 0.254)
		(layer "In2.Cu")
		(net "SCC_A_STBY_PWR_EN")
	)
	(segment
		(start 260.66623 -348.22003)
		(end 245.957852 -348.22003)
		(width 0.254)
		(layer "In2.Cu")
		(net "SCC_A_STBY_PWR_EN")
	)
	(segment
		(start 223.6216 -344.7796)
		(end 214.954104 -344.7796)
		(width 0.254)
		(layer "In2.Cu")
		(net "SCC_A_STBY_PWR_EN")
	)
	(segment
		(start 168.637204 -339.550502)
		(end 165.668706 -342.519)
		(width 0.254)
		(layer "In2.Cu")
		(net "SCC_A_STBY_PWR_EN")
	)
	(segment
		(start 143.360902 -266.231624)
		(end 141.925294 -267.667232)
		(width 0.254)
		(layer "In4.Cu")
		(net "SCC_A_STBY_PWR_EN")
	)
	(segment
		(start 127.386842 -157.926278)
		(end 135.61949 -166.158926)
		(width 0.254)
		(layer "In4.Cu")
		(net "SCC_A_STBY_PWR_EN")
	)
	(segment
		(start 125.222762 -147.130262)
		(end 127.386842 -149.294342)
		(width 0.254)
		(layer "In4.Cu")
		(net "SCC_A_STBY_PWR_EN")
	)
	(segment
		(start 130.679952 -89.889076)
		(end 130.679952 -123.828048)
		(width 0.254)
		(layer "In4.Cu")
		(net "SCC_A_STBY_PWR_EN")
	)
	(segment
		(start 135.848344 -339.886544)
		(end 137.0584 -341.0966)
		(width 0.254)
		(layer "In4.Cu")
		(net "SCC_A_STBY_PWR_EN")
	)
	(segment
		(start 143.360902 -248.86539)
		(end 143.360902 -266.231624)
		(width 0.254)
		(layer "In4.Cu")
		(net "SCC_A_STBY_PWR_EN")
	)
	(segment
		(start 139.817094 -341.0966)
		(end 140.611098 -341.890604)
		(width 0.254)
		(layer "In4.Cu")
		(net "SCC_A_STBY_PWR_EN")
	)
	(segment
		(start 137.046716 -25.461468)
		(end 137.046716 -43.039284)
		(width 0.254)
		(layer "In4.Cu")
		(net "SCC_A_STBY_PWR_EN")
	)
	(segment
		(start 125.222762 -129.285238)
		(end 125.222762 -147.130262)
		(width 0.254)
		(layer "In4.Cu")
		(net "SCC_A_STBY_PWR_EN")
	)
	(segment
		(start 141.925294 -311.413906)
		(end 135.848344 -317.490856)
		(width 0.254)
		(layer "In4.Cu")
		(net "SCC_A_STBY_PWR_EN")
	)
	(segment
		(start 135.848344 -317.490856)
		(end 135.848344 -339.886544)
		(width 0.254)
		(layer "In4.Cu")
		(net "SCC_A_STBY_PWR_EN")
	)
	(segment
		(start 136.056116 -44.029884)
		(end 136.056116 -84.512912)
		(width 0.254)
		(layer "In4.Cu")
		(net "SCC_A_STBY_PWR_EN")
	)
	(segment
		(start 141.925294 -267.667232)
		(end 141.925294 -311.413906)
		(width 0.254)
		(layer "In4.Cu")
		(net "SCC_A_STBY_PWR_EN")
	)
	(segment
		(start 130.679952 -123.828048)
		(end 125.222762 -129.285238)
		(width 0.254)
		(layer "In4.Cu")
		(net "SCC_A_STBY_PWR_EN")
	)
	(segment
		(start 137.0584 -341.0966)
		(end 139.817094 -341.0966)
		(width 0.254)
		(layer "In4.Cu")
		(net "SCC_A_STBY_PWR_EN")
	)
	(segment
		(start 149.390608 -193.966592)
		(end 149.390608 -242.835684)
		(width 0.254)
		(layer "In4.Cu")
		(net "SCC_A_STBY_PWR_EN")
	)
	(segment
		(start 136.056116 -84.512912)
		(end 130.679952 -89.889076)
		(width 0.254)
		(layer "In4.Cu")
		(net "SCC_A_STBY_PWR_EN")
	)
	(segment
		(start 137.94994 -24.550116)
		(end 137.94994 -24.558244)
		(width 0.254)
		(layer "In4.Cu")
		(net "SCC_A_STBY_PWR_EN")
	)
	(segment
		(start 146.886676 -191.46266)
		(end 149.390608 -193.966592)
		(width 0.254)
		(layer "In4.Cu")
		(net "SCC_A_STBY_PWR_EN")
	)
	(segment
		(start 146.886676 -184.426098)
		(end 146.886676 -191.46266)
		(width 0.254)
		(layer "In4.Cu")
		(net "SCC_A_STBY_PWR_EN")
	)
	(segment
		(start 137.046716 -43.039284)
		(end 136.056116 -44.029884)
		(width 0.254)
		(layer "In4.Cu")
		(net "SCC_A_STBY_PWR_EN")
	)
	(segment
		(start 149.390608 -242.835684)
		(end 143.360902 -248.86539)
		(width 0.254)
		(layer "In4.Cu")
		(net "SCC_A_STBY_PWR_EN")
	)
	(segment
		(start 135.61949 -166.158926)
		(end 135.61949 -173.158912)
		(width 0.254)
		(layer "In4.Cu")
		(net "SCC_A_STBY_PWR_EN")
	)
	(segment
		(start 137.94994 -24.558244)
		(end 137.046716 -25.461468)
		(width 0.254)
		(layer "In4.Cu")
		(net "SCC_A_STBY_PWR_EN")
	)
	(segment
		(start 135.61949 -173.158912)
		(end 146.886676 -184.426098)
		(width 0.254)
		(layer "In4.Cu")
		(net "SCC_A_STBY_PWR_EN")
	)
	(segment
		(start 127.386842 -149.294342)
		(end 127.386842 -157.926278)
		(width 0.254)
		(layer "In4.Cu")
		(net "SCC_A_STBY_PWR_EN")
	)
	(via
		(at 380.2888 -340.995)
		(size 0.5588)
		(drill 0.3048)
		(layers "F.Cu" "B.Cu")
		(net "SCC_A_HEARTBEAT")
	)
	(via
		(at 282.258516 7.87908)
		(size 0.5588)
		(drill 0.3048)
		(layers "F.Cu" "B.Cu")
		(net "SCC_A_HEARTBEAT")
	)
	(via
		(at 261.112 -358.394)
		(size 0.5588)
		(drill 0.3048)
		(layers "F.Cu" "B.Cu")
		(net "SCC_A_HEARTBEAT")
	)
	(via
		(at 290.2712 -44.357798)
		(size 0.5588)
		(drill 0.3048)
		(layers "F.Cu" "B.Cu")
		(net "SCC_A_HEARTBEAT")
	)
	(segment
		(start 325.733664 -51.149758)
		(end 318.699642 -51.149758)
		(width 0.13335)
		(layer "In2.Cu")
		(net "SCC_A_HEARTBEAT")
	)
	(segment
		(start 380.2888 -340.995)
		(end 295.783 -340.995)
		(width 0.13335)
		(layer "In2.Cu")
		(net "SCC_A_HEARTBEAT")
	)
	(segment
		(start 290.04895 -352.31705)
		(end 288.925 -353.441)
		(width 0.13335)
		(layer "In2.Cu")
		(net "SCC_A_HEARTBEAT")
	)
	(segment
		(start 295.783 -340.995)
		(end 290.04895 -346.72905)
		(width 0.13335)
		(layer "In2.Cu")
		(net "SCC_A_HEARTBEAT")
	)
	(segment
		(start 288.925 -353.441)
		(end 284.900878 -353.441)
		(width 0.13335)
		(layer "In2.Cu")
		(net "SCC_A_HEARTBEAT")
	)
	(segment
		(start 290.04895 -346.72905)
		(end 290.04895 -352.31705)
		(width 0.13335)
		(layer "In2.Cu")
		(net "SCC_A_HEARTBEAT")
	)
	(segment
		(start 385.750054 -26.950162)
		(end 385.102608 -27.597608)
		(width 0.13335)
		(layer "In2.Cu")
		(net "SCC_A_HEARTBEAT")
	)
	(segment
		(start 318.699642 -51.149758)
		(end 311.907682 -44.357798)
		(width 0.13335)
		(layer "In2.Cu")
		(net "SCC_A_HEARTBEAT")
	)
	(segment
		(start 311.907682 -44.357798)
		(end 290.2712 -44.357798)
		(width 0.13335)
		(layer "In2.Cu")
		(net "SCC_A_HEARTBEAT")
	)
	(segment
		(start 385.102608 -32.135572)
		(end 365.180372 -52.057808)
		(width 0.13335)
		(layer "In2.Cu")
		(net "SCC_A_HEARTBEAT")
	)
	(segment
		(start 284.900878 -353.441)
		(end 284.236668 -354.10521)
		(width 0.13335)
		(layer "In2.Cu")
		(net "SCC_A_HEARTBEAT")
	)
	(segment
		(start 365.180372 -52.057808)
		(end 326.641714 -52.057808)
		(width 0.13335)
		(layer "In2.Cu")
		(net "SCC_A_HEARTBEAT")
	)
	(segment
		(start 326.641714 -52.057808)
		(end 325.733664 -51.149758)
		(width 0.13335)
		(layer "In2.Cu")
		(net "SCC_A_HEARTBEAT")
	)
	(segment
		(start 385.102608 -27.597608)
		(end 385.102608 -32.135572)
		(width 0.13335)
		(layer "In2.Cu")
		(net "SCC_A_HEARTBEAT")
	)
	(segment
		(start 386.39115 -33.162494)
		(end 379.637798 -39.915846)
		(width 0.12065)
		(layer "In4.Cu")
		(net "SCC_A_HEARTBEAT")
	)
	(segment
		(start 380.3396 -293.3192)
		(end 380.3396 -340.9442)
		(width 0.12065)
		(layer "In4.Cu")
		(net "SCC_A_HEARTBEAT")
	)
	(segment
		(start 283.083 -355.2444)
		(end 276.99335 -355.2444)
		(width 0.12065)
		(layer "In4.Cu")
		(net "SCC_A_HEARTBEAT")
	)
	(segment
		(start 380.564898 -179.283106)
		(end 379.50775 -180.340254)
		(width 0.12065)
		(layer "In4.Cu")
		(net "SCC_A_HEARTBEAT")
	)
	(segment
		(start 381.5588 -285.877)
		(end 381.5588 -292.1)
		(width 0.12065)
		(layer "In4.Cu")
		(net "SCC_A_HEARTBEAT")
	)
	(segment
		(start 266.244578 -360.681524)
		(end 263.957054 -358.394)
		(width 0.12065)
		(layer "In4.Cu")
		(net "SCC_A_HEARTBEAT")
	)
	(segment
		(start 379.50775 -236.15015)
		(end 380.3396 -236.982)
		(width 0.12065)
		(layer "In4.Cu")
		(net "SCC_A_HEARTBEAT")
	)
	(segment
		(start 282.258516 7.87908)
		(end 282.258262 7.878826)
		(width 0.12065)
		(layer "In4.Cu")
		(net "SCC_A_HEARTBEAT")
	)
	(segment
		(start 282.258262 7.878826)
		(end 282.258262 6.107938)
		(width 0.12065)
		(layer "In4.Cu")
		(net "SCC_A_HEARTBEAT")
	)
	(segment
		(start 276.99335 -355.2444)
		(end 276.4536 -355.78415)
		(width 0.12065)
		(layer "In4.Cu")
		(net "SCC_A_HEARTBEAT")
	)
	(segment
		(start 282.258262 6.107938)
		(end 290.2712 -1.905)
		(width 0.12065)
		(layer "In4.Cu")
		(net "SCC_A_HEARTBEAT")
	)
	(segment
		(start 274.850352 -360.681524)
		(end 266.244578 -360.681524)
		(width 0.12065)
		(layer "In4.Cu")
		(net "SCC_A_HEARTBEAT")
	)
	(segment
		(start 381.5588 -292.1)
		(end 380.3396 -293.3192)
		(width 0.12065)
		(layer "In4.Cu")
		(net "SCC_A_HEARTBEAT")
	)
	(segment
		(start 379.50775 -180.340254)
		(end 379.50775 -236.15015)
		(width 0.12065)
		(layer "In4.Cu")
		(net "SCC_A_HEARTBEAT")
	)
	(segment
		(start 392.87069 -144.377918)
		(end 380.564898 -156.68371)
		(width 0.12065)
		(layer "In4.Cu")
		(net "SCC_A_HEARTBEAT")
	)
	(segment
		(start 380.3396 -284.6578)
		(end 381.5588 -285.877)
		(width 0.12065)
		(layer "In4.Cu")
		(net "SCC_A_HEARTBEAT")
	)
	(segment
		(start 392.87069 -128.409954)
		(end 392.87069 -144.377918)
		(width 0.12065)
		(layer "In4.Cu")
		(net "SCC_A_HEARTBEAT")
	)
	(segment
		(start 263.957054 -358.394)
		(end 261.112 -358.394)
		(width 0.12065)
		(layer "In4.Cu")
		(net "SCC_A_HEARTBEAT")
	)
	(segment
		(start 290.2712 -1.905)
		(end 290.2712 -44.357798)
		(width 0.12065)
		(layer "In4.Cu")
		(net "SCC_A_HEARTBEAT")
	)
	(segment
		(start 380.3396 -340.9442)
		(end 380.2888 -340.995)
		(width 0.12065)
		(layer "In4.Cu")
		(net "SCC_A_HEARTBEAT")
	)
	(segment
		(start 380.3396 -236.982)
		(end 380.3396 -284.6578)
		(width 0.12065)
		(layer "In4.Cu")
		(net "SCC_A_HEARTBEAT")
	)
	(segment
		(start 380.564898 -156.68371)
		(end 380.564898 -179.283106)
		(width 0.12065)
		(layer "In4.Cu")
		(net "SCC_A_HEARTBEAT")
	)
	(segment
		(start 284.22219 -354.10521)
		(end 283.083 -355.2444)
		(width 0.12065)
		(layer "In4.Cu")
		(net "SCC_A_HEARTBEAT")
	)
	(segment
		(start 379.637798 -115.177062)
		(end 392.87069 -128.409954)
		(width 0.12065)
		(layer "In4.Cu")
		(net "SCC_A_HEARTBEAT")
	)
	(segment
		(start 379.637798 -39.915846)
		(end 379.637798 -115.177062)
		(width 0.12065)
		(layer "In4.Cu")
		(net "SCC_A_HEARTBEAT")
	)
	(segment
		(start 276.4536 -355.78415)
		(end 276.4536 -359.078276)
		(width 0.12065)
		(layer "In4.Cu")
		(net "SCC_A_HEARTBEAT")
	)
	(segment
		(start 385.750054 -26.950162)
		(end 386.39115 -27.591258)
		(width 0.12065)
		(layer "In4.Cu")
		(net "SCC_A_HEARTBEAT")
	)
	(segment
		(start 284.236668 -354.10521)
		(end 284.22219 -354.10521)
		(width 0.12065)
		(layer "In4.Cu")
		(net "SCC_A_HEARTBEAT")
	)
	(segment
		(start 386.39115 -27.591258)
		(end 386.39115 -33.162494)
		(width 0.12065)
		(layer "In4.Cu")
		(net "SCC_A_HEARTBEAT")
	)
	(segment
		(start 276.4536 -359.078276)
		(end 274.850352 -360.681524)
		(width 0.12065)
		(layer "In4.Cu")
		(net "SCC_A_HEARTBEAT")
	)
	(segment
		(start 274.98421 8.912098)
		(end 281.225498 8.912098)
		(width 0.12065)
		(layer "In7.Cu")
		(net "SCC_A_HEARTBEAT")
	)
	(segment
		(start 143.63065 -32.43961)
		(end 159.39516 -16.6751)
		(width 0.12065)
		(layer "In7.Cu")
		(net "SCC_A_HEARTBEAT")
	)
	(segment
		(start 232.946448 -377.009152)
		(end 232.946448 -356.409752)
		(width 0.12065)
		(layer "In7.Cu")
		(net "SCC_A_HEARTBEAT")
	)
	(segment
		(start 142.079218 -32.43961)
		(end 143.63065 -32.43961)
		(width 0.12065)
		(layer "In7.Cu")
		(net "SCC_A_HEARTBEAT")
	)
	(segment
		(start 263.32942 1.43764)
		(end 271.088358 9.196578)
		(width 0.12065)
		(layer "In7.Cu")
		(net "SCC_A_HEARTBEAT")
	)
	(segment
		(start 234.518454 3.929126)
		(end 240.92281 3.929126)
		(width 0.12065)
		(layer "In7.Cu")
		(net "SCC_A_HEARTBEAT")
	)
	(segment
		(start 274.69973 9.196578)
		(end 274.98421 8.912098)
		(width 0.12065)
		(layer "In7.Cu")
		(net "SCC_A_HEARTBEAT")
	)
	(segment
		(start 140.884656 -26.684732)
		(end 140.884656 -31.245048)
		(width 0.12065)
		(layer "In7.Cu")
		(net "SCC_A_HEARTBEAT")
	)
	(segment
		(start 230.616252 -391.895838)
		(end 230.399082 -391.678668)
		(width 0.12065)
		(layer "In7.Cu")
		(net "SCC_A_HEARTBEAT")
	)
	(segment
		(start 166.556944 -16.6751)
		(end 179.702206 -3.529838)
		(width 0.12065)
		(layer "In7.Cu")
		(net "SCC_A_HEARTBEAT")
	)
	(segment
		(start 281.225498 8.912098)
		(end 282.258516 7.87908)
		(width 0.12065)
		(layer "In7.Cu")
		(net "SCC_A_HEARTBEAT")
	)
	(segment
		(start 240.92281 3.929126)
		(end 243.414296 1.43764)
		(width 0.12065)
		(layer "In7.Cu")
		(net "SCC_A_HEARTBEAT")
	)
	(segment
		(start 233.816398 -412.383732)
		(end 233.816398 -399.181574)
		(width 0.12065)
		(layer "In7.Cu")
		(net "SCC_A_HEARTBEAT")
	)
	(segment
		(start 232.946448 -356.409752)
		(end 239.176052 -350.180148)
		(width 0.12065)
		(layer "In7.Cu")
		(net "SCC_A_HEARTBEAT")
	)
	(segment
		(start 139.750038 -25.550114)
		(end 140.884656 -26.684732)
		(width 0.12065)
		(layer "In7.Cu")
		(net "SCC_A_HEARTBEAT")
	)
	(segment
		(start 222.04299 -3.529838)
		(end 222.428816 -3.144012)
		(width 0.12065)
		(layer "In7.Cu")
		(net "SCC_A_HEARTBEAT")
	)
	(segment
		(start 230.399082 -391.678668)
		(end 230.399082 -379.556518)
		(width 0.12065)
		(layer "In7.Cu")
		(net "SCC_A_HEARTBEAT")
	)
	(segment
		(start 222.428816 -3.144012)
		(end 227.445316 -3.144012)
		(width 0.12065)
		(layer "In7.Cu")
		(net "SCC_A_HEARTBEAT")
	)
	(segment
		(start 249.489976 -350.180148)
		(end 257.703828 -358.394)
		(width 0.12065)
		(layer "In7.Cu")
		(net "SCC_A_HEARTBEAT")
	)
	(segment
		(start 159.39516 -16.6751)
		(end 166.556944 -16.6751)
		(width 0.12065)
		(layer "In7.Cu")
		(net "SCC_A_HEARTBEAT")
	)
	(segment
		(start 140.884656 -31.245048)
		(end 142.079218 -32.43961)
		(width 0.12065)
		(layer "In7.Cu")
		(net "SCC_A_HEARTBEAT")
	)
	(segment
		(start 239.176052 -350.180148)
		(end 249.489976 -350.180148)
		(width 0.12065)
		(layer "In7.Cu")
		(net "SCC_A_HEARTBEAT")
	)
	(segment
		(start 233.816398 -399.181574)
		(end 230.616252 -395.981428)
		(width 0.12065)
		(layer "In7.Cu")
		(net "SCC_A_HEARTBEAT")
	)
	(segment
		(start 231.599994 -414.600136)
		(end 233.816398 -412.383732)
		(width 0.12065)
		(layer "In7.Cu")
		(net "SCC_A_HEARTBEAT")
	)
	(segment
		(start 257.703828 -358.394)
		(end 261.112 -358.394)
		(width 0.12065)
		(layer "In7.Cu")
		(net "SCC_A_HEARTBEAT")
	)
	(segment
		(start 230.616252 -395.981428)
		(end 230.616252 -391.895838)
		(width 0.12065)
		(layer "In7.Cu")
		(net "SCC_A_HEARTBEAT")
	)
	(segment
		(start 227.445316 -3.144012)
		(end 234.518454 3.929126)
		(width 0.12065)
		(layer "In7.Cu")
		(net "SCC_A_HEARTBEAT")
	)
	(segment
		(start 179.702206 -3.529838)
		(end 222.04299 -3.529838)
		(width 0.12065)
		(layer "In7.Cu")
		(net "SCC_A_HEARTBEAT")
	)
	(segment
		(start 271.088358 9.196578)
		(end 274.69973 9.196578)
		(width 0.12065)
		(layer "In7.Cu")
		(net "SCC_A_HEARTBEAT")
	)
	(segment
		(start 243.414296 1.43764)
		(end 263.32942 1.43764)
		(width 0.12065)
		(layer "In7.Cu")
		(net "SCC_A_HEARTBEAT")
	)
	(segment
		(start 230.399082 -379.556518)
		(end 232.946448 -377.009152)
		(width 0.12065)
		(layer "In7.Cu")
		(net "SCC_A_HEARTBEAT")
	)
	(segment
		(start 221.572582 -390.445498)
		(end 222.55226 -390.445498)
		(width 0.254)
		(layer "F.Cu")
		(net "SCC_A_FULL_PWR_EN")
	)
	(via
		(at 343.2048 -17.4244)
		(size 0.5588)
		(drill 0.3048)
		(layers "F.Cu" "B.Cu")
		(net "SCC_A_FULL_PWR_EN")
	)
	(via
		(at 345.178634 -33.014412)
		(size 0.5588)
		(drill 0.3048)
		(layers "F.Cu" "B.Cu")
		(net "SCC_A_FULL_PWR_EN")
	)
	(via
		(at 227.637848 -341.830152)
		(size 0.5588)
		(drill 0.3048)
		(layers "F.Cu" "B.Cu")
		(net "SCC_A_FULL_PWR_EN")
	)
	(via
		(at 222.55226 -390.445498)
		(size 0.5588)
		(drill 0.3048)
		(layers "F.Cu" "B.Cu")
		(net "SCC_A_FULL_PWR_EN")
	)
	(via
		(at 379.644148 -339.344)
		(size 0.5588)
		(drill 0.3048)
		(layers "F.Cu" "B.Cu")
		(net "SCC_A_FULL_PWR_EN")
	)
	(segment
		(start 139.486894 -32.259778)
		(end 144.854422 -32.259778)
		(width 0.254)
		(layer "In2.Cu")
		(net "SCC_A_FULL_PWR_EN")
	)
	(segment
		(start 209.12455 -16.177006)
		(end 213.76513 -11.536426)
		(width 0.254)
		(layer "In2.Cu")
		(net "SCC_A_FULL_PWR_EN")
	)
	(segment
		(start 282.83662 -343.30513)
		(end 281.79649 -342.265)
		(width 0.254)
		(layer "In2.Cu")
		(net "SCC_A_FULL_PWR_EN")
	)
	(segment
		(start 218.410028 -11.222736)
		(end 221.805754 -7.82701)
		(width 0.254)
		(layer "In2.Cu")
		(net "SCC_A_FULL_PWR_EN")
	)
	(segment
		(start 221.805754 -7.82701)
		(end 229.753414 -7.82701)
		(width 0.254)
		(layer "In2.Cu")
		(net "SCC_A_FULL_PWR_EN")
	)
	(segment
		(start 282.83662 -343.30513)
		(end 283.65069 -344.1192)
		(width 0.254)
		(layer "In2.Cu")
		(net "SCC_A_FULL_PWR_EN")
	)
	(segment
		(start 238.6076 -342.265)
		(end 238.310674 -342.561926)
		(width 0.254)
		(layer "In2.Cu")
		(net "SCC_A_FULL_PWR_EN")
	)
	(segment
		(start 225.039428 -417.800028)
		(end 226.200208 -417.800028)
		(width 0.254)
		(layer "In2.Cu")
		(net "SCC_A_FULL_PWR_EN")
	)
	(segment
		(start 205.78445 -23.848314)
		(end 209.124804 -20.50796)
		(width 0.254)
		(layer "In2.Cu")
		(net "SCC_A_FULL_PWR_EN")
	)
	(segment
		(start 209.124804 -16.597884)
		(end 209.12455 -16.59763)
		(width 0.254)
		(layer "In2.Cu")
		(net "SCC_A_FULL_PWR_EN")
	)
	(segment
		(start 238.310674 -342.561926)
		(end 228.369622 -342.561926)
		(width 0.254)
		(layer "In2.Cu")
		(net "SCC_A_FULL_PWR_EN")
	)
	(segment
		(start 313.013852 -10.713212)
		(end 313.013852 -15.748254)
		(width 0.254)
		(layer "In2.Cu")
		(net "SCC_A_FULL_PWR_EN")
	)
	(segment
		(start 223.432116 -400.800316)
		(end 223.432116 -416.192716)
		(width 0.254)
		(layer "In2.Cu")
		(net "SCC_A_FULL_PWR_EN")
	)
	(segment
		(start 214.042244 -11.259312)
		(end 214.07882 -11.222736)
		(width 0.254)
		(layer "In2.Cu")
		(net "SCC_A_FULL_PWR_EN")
	)
	(segment
		(start 220.4212 -397.7894)
		(end 223.432116 -400.800316)
		(width 0.254)
		(layer "In2.Cu")
		(net "SCC_A_FULL_PWR_EN")
	)
	(segment
		(start 283.65069 -344.1192)
		(end 289.433 -344.1192)
		(width 0.254)
		(layer "In2.Cu")
		(net "SCC_A_FULL_PWR_EN")
	)
	(segment
		(start 220.4212 -394.449554)
		(end 220.4212 -397.7894)
		(width 0.254)
		(layer "In2.Cu")
		(net "SCC_A_FULL_PWR_EN")
	)
	(segment
		(start 286.149034 4.1402)
		(end 296.134536 -5.845302)
		(width 0.254)
		(layer "In2.Cu")
		(net "SCC_A_FULL_PWR_EN")
	)
	(segment
		(start 222.55226 -392.318494)
		(end 220.4212 -394.449554)
		(width 0.254)
		(layer "In2.Cu")
		(net "SCC_A_FULL_PWR_EN")
	)
	(segment
		(start 223.432116 -416.192716)
		(end 225.039428 -417.800028)
		(width 0.254)
		(layer "In2.Cu")
		(net "SCC_A_FULL_PWR_EN")
	)
	(segment
		(start 138.764772 -28.96489)
		(end 138.764772 -31.537656)
		(width 0.254)
		(layer "In2.Cu")
		(net "SCC_A_FULL_PWR_EN")
	)
	(segment
		(start 222.55226 -390.445498)
		(end 222.55226 -392.318494)
		(width 0.254)
		(layer "In2.Cu")
		(net "SCC_A_FULL_PWR_EN")
	)
	(segment
		(start 377.698 -339.8266)
		(end 378.1806 -339.344)
		(width 0.254)
		(layer "In2.Cu")
		(net "SCC_A_FULL_PWR_EN")
	)
	(segment
		(start 253.29261 -1.068832)
		(end 258.501642 4.1402)
		(width 0.254)
		(layer "In2.Cu")
		(net "SCC_A_FULL_PWR_EN")
	)
	(segment
		(start 214.04199 -11.259312)
		(end 214.042244 -11.259312)
		(width 0.254)
		(layer "In2.Cu")
		(net "SCC_A_FULL_PWR_EN")
	)
	(segment
		(start 144.854422 -32.259778)
		(end 153.265886 -23.848314)
		(width 0.254)
		(layer "In2.Cu")
		(net "SCC_A_FULL_PWR_EN")
	)
	(segment
		(start 293.7256 -339.8266)
		(end 377.698 -339.8266)
		(width 0.254)
		(layer "In2.Cu")
		(net "SCC_A_FULL_PWR_EN")
	)
	(segment
		(start 258.501642 4.1402)
		(end 286.149034 4.1402)
		(width 0.254)
		(layer "In2.Cu")
		(net "SCC_A_FULL_PWR_EN")
	)
	(segment
		(start 138.764772 -31.537656)
		(end 139.486894 -32.259778)
		(width 0.254)
		(layer "In2.Cu")
		(net "SCC_A_FULL_PWR_EN")
	)
	(segment
		(start 209.124804 -20.50796)
		(end 209.124804 -16.597884)
		(width 0.254)
		(layer "In2.Cu")
		(net "SCC_A_FULL_PWR_EN")
	)
	(segment
		(start 214.07882 -11.222736)
		(end 218.410028 -11.222736)
		(width 0.254)
		(layer "In2.Cu")
		(net "SCC_A_FULL_PWR_EN")
	)
	(segment
		(start 313.013852 -15.748254)
		(end 315.112146 -17.846548)
		(width 0.254)
		(layer "In2.Cu")
		(net "SCC_A_FULL_PWR_EN")
	)
	(segment
		(start 315.112146 -17.846548)
		(end 337.355434 -17.846548)
		(width 0.254)
		(layer "In2.Cu")
		(net "SCC_A_FULL_PWR_EN")
	)
	(segment
		(start 308.145942 -5.845302)
		(end 313.013852 -10.713212)
		(width 0.254)
		(layer "In2.Cu")
		(net "SCC_A_FULL_PWR_EN")
	)
	(segment
		(start 137.94994 -28.150058)
		(end 138.764772 -28.96489)
		(width 0.254)
		(layer "In2.Cu")
		(net "SCC_A_FULL_PWR_EN")
	)
	(segment
		(start 153.265886 -23.848314)
		(end 205.78445 -23.848314)
		(width 0.254)
		(layer "In2.Cu")
		(net "SCC_A_FULL_PWR_EN")
	)
	(segment
		(start 228.369622 -342.561926)
		(end 227.637848 -341.830152)
		(width 0.254)
		(layer "In2.Cu")
		(net "SCC_A_FULL_PWR_EN")
	)
	(segment
		(start 337.777582 -17.4244)
		(end 343.2048 -17.4244)
		(width 0.254)
		(layer "In2.Cu")
		(net "SCC_A_FULL_PWR_EN")
	)
	(segment
		(start 337.355434 -17.846548)
		(end 337.777582 -17.4244)
		(width 0.254)
		(layer "In2.Cu")
		(net "SCC_A_FULL_PWR_EN")
	)
	(segment
		(start 209.12455 -16.59763)
		(end 209.12455 -16.177006)
		(width 0.254)
		(layer "In2.Cu")
		(net "SCC_A_FULL_PWR_EN")
	)
	(segment
		(start 229.753414 -7.82701)
		(end 236.511592 -1.068832)
		(width 0.254)
		(layer "In2.Cu")
		(net "SCC_A_FULL_PWR_EN")
	)
	(segment
		(start 213.76513 -11.536172)
		(end 214.04199 -11.259312)
		(width 0.254)
		(layer "In2.Cu")
		(net "SCC_A_FULL_PWR_EN")
	)
	(segment
		(start 213.76513 -11.536426)
		(end 213.76513 -11.536172)
		(width 0.254)
		(layer "In2.Cu")
		(net "SCC_A_FULL_PWR_EN")
	)
	(segment
		(start 378.1806 -339.344)
		(end 379.644148 -339.344)
		(width 0.254)
		(layer "In2.Cu")
		(net "SCC_A_FULL_PWR_EN")
	)
	(segment
		(start 289.433 -344.1192)
		(end 293.7256 -339.8266)
		(width 0.254)
		(layer "In2.Cu")
		(net "SCC_A_FULL_PWR_EN")
	)
	(segment
		(start 296.134536 -5.845302)
		(end 308.145942 -5.845302)
		(width 0.254)
		(layer "In2.Cu")
		(net "SCC_A_FULL_PWR_EN")
	)
	(segment
		(start 236.511592 -1.068832)
		(end 253.29261 -1.068832)
		(width 0.254)
		(layer "In2.Cu")
		(net "SCC_A_FULL_PWR_EN")
	)
	(segment
		(start 281.79649 -342.265)
		(end 238.6076 -342.265)
		(width 0.254)
		(layer "In2.Cu")
		(net "SCC_A_FULL_PWR_EN")
	)
	(segment
		(start 225.9838 -357.536242)
		(end 225.9838 -343.4842)
		(width 0.254)
		(layer "In4.Cu")
		(net "SCC_A_FULL_PWR_EN")
	)
	(segment
		(start 383.949956 -29.550106)
		(end 384.584956 -30.185106)
		(width 0.254)
		(layer "In4.Cu")
		(net "SCC_A_FULL_PWR_EN")
	)
	(segment
		(start 343.250266 -21.848826)
		(end 343.250266 -20.876514)
		(width 0.254)
		(layer "In4.Cu")
		(net "SCC_A_FULL_PWR_EN")
	)
	(segment
		(start 378.812298 -236.43844)
		(end 379.644148 -237.27029)
		(width 0.254)
		(layer "In4.Cu")
		(net "SCC_A_FULL_PWR_EN")
	)
	(segment
		(start 380.5174 -292.157658)
		(end 379.644148 -293.03091)
		(width 0.254)
		(layer "In4.Cu")
		(net "SCC_A_FULL_PWR_EN")
	)
	(segment
		(start 379.644148 -293.03091)
		(end 379.644148 -339.344)
		(width 0.254)
		(layer "In4.Cu")
		(net "SCC_A_FULL_PWR_EN")
	)
	(segment
		(start 378.942346 -115.465352)
		(end 392.175238 -128.698244)
		(width 0.254)
		(layer "In4.Cu")
		(net "SCC_A_FULL_PWR_EN")
	)
	(segment
		(start 392.175238 -144.089628)
		(end 378.812298 -157.452568)
		(width 0.254)
		(layer "In4.Cu")
		(net "SCC_A_FULL_PWR_EN")
	)
	(segment
		(start 224.7138 -386.375148)
		(end 224.7138 -385.960366)
		(width 0.254)
		(layer "In4.Cu")
		(net "SCC_A_FULL_PWR_EN")
	)
	(segment
		(start 343.250266 -20.876514)
		(end 343.2048 -20.831048)
		(width 0.254)
		(layer "In4.Cu")
		(net "SCC_A_FULL_PWR_EN")
	)
	(segment
		(start 225.17227 -368.09045)
		(end 227.395278 -365.867442)
		(width 0.254)
		(layer "In4.Cu")
		(net "SCC_A_FULL_PWR_EN")
	)
	(segment
		(start 384.584956 -33.9725)
		(end 378.942346 -39.61511)
		(width 0.254)
		(layer "In4.Cu")
		(net "SCC_A_FULL_PWR_EN")
	)
	(segment
		(start 345.178634 -33.014412)
		(end 345.149678 -32.985456)
		(width 0.254)
		(layer "In4.Cu")
		(net "SCC_A_FULL_PWR_EN")
	)
	(segment
		(start 225.17227 -376.811794)
		(end 225.17227 -368.09045)
		(width 0.254)
		(layer "In4.Cu")
		(net "SCC_A_FULL_PWR_EN")
	)
	(segment
		(start 224.7138 -385.960366)
		(end 224.6884 -385.934966)
		(width 0.254)
		(layer "In4.Cu")
		(net "SCC_A_FULL_PWR_EN")
	)
	(segment
		(start 379.644148 -237.27029)
		(end 379.644148 -289.7632)
		(width 0.254)
		(layer "In4.Cu")
		(net "SCC_A_FULL_PWR_EN")
	)
	(segment
		(start 224.6884 -377.295664)
		(end 225.17227 -376.811794)
		(width 0.254)
		(layer "In4.Cu")
		(net "SCC_A_FULL_PWR_EN")
	)
	(segment
		(start 227.395278 -365.867442)
		(end 227.395278 -358.94772)
		(width 0.254)
		(layer "In4.Cu")
		(net "SCC_A_FULL_PWR_EN")
	)
	(segment
		(start 378.812298 -157.452568)
		(end 378.812298 -236.43844)
		(width 0.254)
		(layer "In4.Cu")
		(net "SCC_A_FULL_PWR_EN")
	)
	(segment
		(start 380.5174 -290.636452)
		(end 380.5174 -292.157658)
		(width 0.254)
		(layer "In4.Cu")
		(net "SCC_A_FULL_PWR_EN")
	)
	(segment
		(start 345.149678 -32.985456)
		(end 345.149678 -23.748238)
		(width 0.254)
		(layer "In4.Cu")
		(net "SCC_A_FULL_PWR_EN")
	)
	(segment
		(start 379.644148 -289.7632)
		(end 380.5174 -290.636452)
		(width 0.254)
		(layer "In4.Cu")
		(net "SCC_A_FULL_PWR_EN")
	)
	(segment
		(start 225.9838 -343.4842)
		(end 227.637848 -341.830152)
		(width 0.254)
		(layer "In4.Cu")
		(net "SCC_A_FULL_PWR_EN")
	)
	(segment
		(start 392.175238 -128.698244)
		(end 392.175238 -144.089628)
		(width 0.254)
		(layer "In4.Cu")
		(net "SCC_A_FULL_PWR_EN")
	)
	(segment
		(start 227.395278 -358.94772)
		(end 225.9838 -357.536242)
		(width 0.254)
		(layer "In4.Cu")
		(net "SCC_A_FULL_PWR_EN")
	)
	(segment
		(start 224.6884 -385.934966)
		(end 224.6884 -377.295664)
		(width 0.254)
		(layer "In4.Cu")
		(net "SCC_A_FULL_PWR_EN")
	)
	(segment
		(start 345.149678 -23.748238)
		(end 343.250266 -21.848826)
		(width 0.254)
		(layer "In4.Cu")
		(net "SCC_A_FULL_PWR_EN")
	)
	(segment
		(start 222.55226 -390.445498)
		(end 222.55226 -388.536688)
		(width 0.254)
		(layer "In4.Cu")
		(net "SCC_A_FULL_PWR_EN")
	)
	(segment
		(start 343.2048 -20.831048)
		(end 343.2048 -17.4244)
		(width 0.254)
		(layer "In4.Cu")
		(net "SCC_A_FULL_PWR_EN")
	)
	(segment
		(start 384.584956 -30.185106)
		(end 384.584956 -33.9725)
		(width 0.254)
		(layer "In4.Cu")
		(net "SCC_A_FULL_PWR_EN")
	)
	(segment
		(start 378.942346 -39.61511)
		(end 378.942346 -115.465352)
		(width 0.254)
		(layer "In4.Cu")
		(net "SCC_A_FULL_PWR_EN")
	)
	(segment
		(start 222.55226 -388.536688)
		(end 224.7138 -386.375148)
		(width 0.254)
		(layer "In4.Cu")
		(net "SCC_A_FULL_PWR_EN")
	)
	(segment
		(start 358.526588 -40.4876)
		(end 354.558092 -40.4876)
		(width 0.254)
		(layer "In7.Cu")
		(net "SCC_A_FULL_PWR_EN")
	)
	(segment
		(start 384.6703 -30.27045)
		(end 384.6703 -33.5407)
		(width 0.254)
		(layer "In7.Cu")
		(net "SCC_A_FULL_PWR_EN")
	)
	(segment
		(start 354.55098 -40.480488)
		(end 352.64471 -40.480488)
		(width 0.254)
		(layer "In7.Cu")
		(net "SCC_A_FULL_PWR_EN")
	)
	(segment
		(start 380.044452 -38.166548)
		(end 360.84764 -38.166548)
		(width 0.254)
		(layer "In7.Cu")
		(net "SCC_A_FULL_PWR_EN")
	)
	(segment
		(start 360.84764 -38.166548)
		(end 358.526588 -40.4876)
		(width 0.254)
		(layer "In7.Cu")
		(net "SCC_A_FULL_PWR_EN")
	)
	(segment
		(start 352.64471 -40.480488)
		(end 345.178634 -33.014412)
		(width 0.254)
		(layer "In7.Cu")
		(net "SCC_A_FULL_PWR_EN")
	)
	(segment
		(start 383.949956 -29.550106)
		(end 384.6703 -30.27045)
		(width 0.254)
		(layer "In7.Cu")
		(net "SCC_A_FULL_PWR_EN")
	)
	(segment
		(start 384.6703 -33.5407)
		(end 380.044452 -38.166548)
		(width 0.254)
		(layer "In7.Cu")
		(net "SCC_A_FULL_PWR_EN")
	)
	(segment
		(start 354.558092 -40.4876)
		(end 354.55098 -40.480488)
		(width 0.254)
		(layer "In7.Cu")
		(net "SCC_A_FULL_PWR_EN")
	)
	(segment
		(start 86.411054 -30.094174)
		(end 86.411054 -27.86761)
		(width 0.254)
		(layer "F.Cu")
		(net "SCC_A_FULL_PGOOD")
	)
	(segment
		(start 86.642956 -31.399988)
		(end 86.411054 -31.168086)
		(width 0.254)
		(layer "F.Cu")
		(net "SCC_A_FULL_PGOOD")
	)
	(segment
		(start 86.411054 -31.168086)
		(end 86.411054 -30.094174)
		(width 0.254)
		(layer "F.Cu")
		(net "SCC_A_FULL_PGOOD")
	)
	(via
		(at 86.642956 -31.399988)
		(size 0.5588)
		(drill 0.3048)
		(layers "F.Cu" "B.Cu")
		(net "SCC_A_FULL_PGOOD")
	)
	(via
		(at 72.87895 -305.29403)
		(size 0.5588)
		(drill 0.3048)
		(layers "F.Cu" "B.Cu")
		(net "SCC_A_FULL_PGOOD")
	)
	(via
		(at 86.411054 -30.094174)
		(size 0.6604)
		(drill 0.3302)
		(layers "F.Cu" "B.Cu")
		(net "SCC_A_FULL_PGOOD")
	)
	(segment
		(start 265.033252 -294.463978)
		(end 259.332476 -300.164754)
		(width 0.254)
		(layer "In2.Cu")
		(net "SCC_A_FULL_PGOOD")
	)
	(segment
		(start 210.725258 -301.428658)
		(end 205.840838 -296.544238)
		(width 0.254)
		(layer "In2.Cu")
		(net "SCC_A_FULL_PGOOD")
	)
	(segment
		(start 205.840838 -296.544238)
		(end 199.111362 -296.544238)
		(width 0.254)
		(layer "In2.Cu")
		(net "SCC_A_FULL_PGOOD")
	)
	(segment
		(start 199.111362 -296.544238)
		(end 197.307454 -298.348146)
		(width 0.254)
		(layer "In2.Cu")
		(net "SCC_A_FULL_PGOOD")
	)
	(segment
		(start 72.889872 -305.283108)
		(end 72.87895 -305.29403)
		(width 0.254)
		(layer "In2.Cu")
		(net "SCC_A_FULL_PGOOD")
	)
	(segment
		(start 251.350526 -301.428658)
		(end 210.725258 -301.428658)
		(width 0.254)
		(layer "In2.Cu")
		(net "SCC_A_FULL_PGOOD")
	)
	(segment
		(start 259.332476 -300.164754)
		(end 252.61443 -300.164754)
		(width 0.254)
		(layer "In2.Cu")
		(net "SCC_A_FULL_PGOOD")
	)
	(segment
		(start 194.183254 -298.348146)
		(end 187.248292 -305.283108)
		(width 0.254)
		(layer "In2.Cu")
		(net "SCC_A_FULL_PGOOD")
	)
	(segment
		(start 280.933144 -293.8018)
		(end 276.4028 -293.8018)
		(width 0.254)
		(layer "In2.Cu")
		(net "SCC_A_FULL_PGOOD")
	)
	(segment
		(start 252.61443 -300.164754)
		(end 251.350526 -301.428658)
		(width 0.254)
		(layer "In2.Cu")
		(net "SCC_A_FULL_PGOOD")
	)
	(segment
		(start 187.248292 -305.283108)
		(end 72.889872 -305.283108)
		(width 0.254)
		(layer "In2.Cu")
		(net "SCC_A_FULL_PGOOD")
	)
	(segment
		(start 197.307454 -298.348146)
		(end 194.183254 -298.348146)
		(width 0.254)
		(layer "In2.Cu")
		(net "SCC_A_FULL_PGOOD")
	)
	(segment
		(start 275.740622 -294.463978)
		(end 265.033252 -294.463978)
		(width 0.254)
		(layer "In2.Cu")
		(net "SCC_A_FULL_PGOOD")
	)
	(segment
		(start 276.4028 -293.8018)
		(end 275.740622 -294.463978)
		(width 0.254)
		(layer "In2.Cu")
		(net "SCC_A_FULL_PGOOD")
	)
	(segment
		(start 281.836622 -294.705278)
		(end 280.933144 -293.8018)
		(width 0.254)
		(layer "In2.Cu")
		(net "SCC_A_FULL_PGOOD")
	)
	(segment
		(start 86.642956 -37.512244)
		(end 86.642956 -31.399988)
		(width 0.254)
		(layer "In4.Cu")
		(net "SCC_A_FULL_PGOOD")
	)
	(segment
		(start 79.052674 -155.939998)
		(end 79.052674 -141.596872)
		(width 0.254)
		(layer "In4.Cu")
		(net "SCC_A_FULL_PGOOD")
	)
	(segment
		(start 74.57567 -189.82309)
		(end 74.57567 -160.417002)
		(width 0.254)
		(layer "In4.Cu")
		(net "SCC_A_FULL_PGOOD")
	)
	(segment
		(start 72.87895 -305.29403)
		(end 73.129648 -305.043332)
		(width 0.254)
		(layer "In4.Cu")
		(net "SCC_A_FULL_PGOOD")
	)
	(segment
		(start 71.6534 -256.2098)
		(end 71.6534 -192.786)
		(width 0.254)
		(layer "In4.Cu")
		(net "SCC_A_FULL_PGOOD")
	)
	(segment
		(start 69.157342 -131.70154)
		(end 69.157342 -68.643754)
		(width 0.254)
		(layer "In4.Cu")
		(net "SCC_A_FULL_PGOOD")
	)
	(segment
		(start 71.6534 -192.786)
		(end 73.129648 -191.309752)
		(width 0.254)
		(layer "In4.Cu")
		(net "SCC_A_FULL_PGOOD")
	)
	(segment
		(start 73.129648 -191.309752)
		(end 73.129648 -191.269112)
		(width 0.254)
		(layer "In4.Cu")
		(net "SCC_A_FULL_PGOOD")
	)
	(segment
		(start 73.129648 -305.043332)
		(end 73.129648 -257.686048)
		(width 0.254)
		(layer "In4.Cu")
		(net "SCC_A_FULL_PGOOD")
	)
	(segment
		(start 69.088 -55.0672)
		(end 86.642956 -37.512244)
		(width 0.254)
		(layer "In4.Cu")
		(net "SCC_A_FULL_PGOOD")
	)
	(segment
		(start 74.57567 -160.417002)
		(end 79.052674 -155.939998)
		(width 0.254)
		(layer "In4.Cu")
		(net "SCC_A_FULL_PGOOD")
	)
	(segment
		(start 73.129648 -257.686048)
		(end 71.6534 -256.2098)
		(width 0.254)
		(layer "In4.Cu")
		(net "SCC_A_FULL_PGOOD")
	)
	(segment
		(start 79.052674 -141.596872)
		(end 69.157342 -131.70154)
		(width 0.254)
		(layer "In4.Cu")
		(net "SCC_A_FULL_PGOOD")
	)
	(segment
		(start 69.678804 -68.122292)
		(end 69.678804 -65.605914)
		(width 0.254)
		(layer "In4.Cu")
		(net "SCC_A_FULL_PGOOD")
	)
	(segment
		(start 69.678804 -65.605914)
		(end 69.088 -65.01511)
		(width 0.254)
		(layer "In4.Cu")
		(net "SCC_A_FULL_PGOOD")
	)
	(segment
		(start 69.088 -65.01511)
		(end 69.088 -55.0672)
		(width 0.254)
		(layer "In4.Cu")
		(net "SCC_A_FULL_PGOOD")
	)
	(segment
		(start 73.129648 -191.269112)
		(end 74.57567 -189.82309)
		(width 0.254)
		(layer "In4.Cu")
		(net "SCC_A_FULL_PGOOD")
	)
	(segment
		(start 69.157342 -68.643754)
		(end 69.678804 -68.122292)
		(width 0.254)
		(layer "In4.Cu")
		(net "SCC_A_FULL_PGOOD")
	)
	(segment
		(start 414.77692 -273.793966)
		(end 415.540698 -273.793966)
		(width 0.127)
		(layer "F.Cu")
		(net "PHY_SCC_A_TO_DRV_A_9_DP")
	)
	(segment
		(start 414.639252 -273.368516)
		(end 414.639252 -273.656298)
		(width 0.127)
		(layer "F.Cu")
		(net "PHY_SCC_A_TO_DRV_A_9_DP")
	)
	(segment
		(start 415.540698 -273.793966)
		(end 415.674048 -273.660616)
		(width 0.127)
		(layer "F.Cu")
		(net "PHY_SCC_A_TO_DRV_A_9_DP")
	)
	(segment
		(start 415.674048 -273.660616)
		(end 416.005264 -273.660616)
		(width 0.127)
		(layer "F.Cu")
		(net "PHY_SCC_A_TO_DRV_A_9_DP")
	)
	(segment
		(start 414.676336 -273.74596)
		(end 414.687258 -273.756882)
		(width 0.127)
		(layer "F.Cu")
		(net "PHY_SCC_A_TO_DRV_A_9_DP")
	)
	(arc
		(start 414.639252 -273.656298)
		(mid 414.648885 -273.704816)
		(end 414.676336 -273.74596)
		(width 0.127)
		(layer "F.Cu")
		(net "PHY_SCC_A_TO_DRV_A_9_DP")
	)
	(arc
		(start 414.687258 -273.756882)
		(mid 414.728409 -273.784315)
		(end 414.77692 -273.793966)
		(width 0.127)
		(layer "F.Cu")
		(net "PHY_SCC_A_TO_DRV_A_9_DP")
	)
	(segment
		(start 414.519618 -273.774916)
		(end 413.885888 -273.774916)
		(width 0.10795)
		(layer "In9.Cu")
		(net "PHY_SCC_A_TO_DRV_A_9_DP")
	)
	(segment
		(start 302.054006 -334.947514)
		(end 301.7647 -335.011776)
		(width 0.10795)
		(layer "In9.Cu")
		(net "PHY_SCC_A_TO_DRV_A_9_DP")
	)
	(segment
		(start 335.116678 -309.616094)
		(end 306.630578 -327.763632)
		(width 0.10795)
		(layer "In9.Cu")
		(net "PHY_SCC_A_TO_DRV_A_9_DP")
	)
	(segment
		(start 370.842794 -301.695358)
		(end 335.116678 -309.616094)
		(width 0.10795)
		(layer "In9.Cu")
		(net "PHY_SCC_A_TO_DRV_A_9_DP")
	)
	(segment
		(start 301.59071 -335.284826)
		(end 301.654972 -335.574132)
		(width 0.10795)
		(layer "In9.Cu")
		(net "PHY_SCC_A_TO_DRV_A_9_DP")
	)
	(segment
		(start 280.206196 -344.002868)
		(end 280.138886 -343.935558)
		(width 0.10795)
		(layer "In9.Cu")
		(net "PHY_SCC_A_TO_DRV_A_9_DP")
	)
	(segment
		(start 414.639252 -273.368516)
		(end 414.639252 -273.655282)
		(width 0.10795)
		(layer "In9.Cu")
		(net "PHY_SCC_A_TO_DRV_A_9_DP")
	)
	(segment
		(start 280.101802 -343.845896)
		(end 280.101802 -343.437972)
		(width 0.10795)
		(layer "In9.Cu")
		(net "PHY_SCC_A_TO_DRV_A_9_DP")
	)
	(segment
		(start 301.7647 -335.011776)
		(end 301.59071 -335.284826)
		(width 0.10795)
		(layer "In9.Cu")
		(net "PHY_SCC_A_TO_DRV_A_9_DP")
	)
	(segment
		(start 302.337978 -334.112108)
		(end 302.163988 -334.385158)
		(width 0.10795)
		(layer "In9.Cu")
		(net "PHY_SCC_A_TO_DRV_A_9_DP")
	)
	(segment
		(start 302.163988 -334.385158)
		(end 302.227996 -334.674464)
		(width 0.10795)
		(layer "In9.Cu")
		(net "PHY_SCC_A_TO_DRV_A_9_DP")
	)
	(segment
		(start 413.885888 -273.774916)
		(end 410.079698 -275.228558)
		(width 0.10795)
		(layer "In9.Cu")
		(net "PHY_SCC_A_TO_DRV_A_9_DP")
	)
	(segment
		(start 304.568098 -331.00137)
		(end 302.627284 -334.047846)
		(width 0.10795)
		(layer "In9.Cu")
		(net "PHY_SCC_A_TO_DRV_A_9_DP")
	)
	(segment
		(start 301.654972 -335.574132)
		(end 301.480982 -335.847436)
		(width 0.10795)
		(layer "In9.Cu")
		(net "PHY_SCC_A_TO_DRV_A_9_DP")
	)
	(segment
		(start 301.191676 -335.911444)
		(end 301.017432 -336.184748)
		(width 0.10795)
		(layer "In9.Cu")
		(net "PHY_SCC_A_TO_DRV_A_9_DP")
	)
	(segment
		(start 302.627284 -334.047846)
		(end 302.337978 -334.112108)
		(width 0.10795)
		(layer "In9.Cu")
		(net "PHY_SCC_A_TO_DRV_A_9_DP")
	)
	(segment
		(start 288.8742 -344.039952)
		(end 280.295858 -344.039952)
		(width 0.10795)
		(layer "In9.Cu")
		(net "PHY_SCC_A_TO_DRV_A_9_DP")
	)
	(segment
		(start 301.480982 -335.847436)
		(end 301.191676 -335.911444)
		(width 0.10795)
		(layer "In9.Cu")
		(net "PHY_SCC_A_TO_DRV_A_9_DP")
	)
	(segment
		(start 280.234644 -343.30513)
		(end 280.636726 -343.30513)
		(width 0.10795)
		(layer "In9.Cu")
		(net "PHY_SCC_A_TO_DRV_A_9_DP")
	)
	(segment
		(start 300.907704 -336.747104)
		(end 296.737278 -339.40369)
		(width 0.10795)
		(layer "In9.Cu")
		(net "PHY_SCC_A_TO_DRV_A_9_DP")
	)
	(segment
		(start 301.081694 -336.474054)
		(end 300.907704 -336.747104)
		(width 0.10795)
		(layer "In9.Cu")
		(net "PHY_SCC_A_TO_DRV_A_9_DP")
	)
	(segment
		(start 410.079698 -275.228558)
		(end 370.842794 -301.695358)
		(width 0.10795)
		(layer "In9.Cu")
		(net "PHY_SCC_A_TO_DRV_A_9_DP")
	)
	(segment
		(start 301.017432 -336.184748)
		(end 301.081694 -336.474054)
		(width 0.10795)
		(layer "In9.Cu")
		(net "PHY_SCC_A_TO_DRV_A_9_DP")
	)
	(segment
		(start 306.630578 -327.763632)
		(end 304.568098 -331.00137)
		(width 0.10795)
		(layer "In9.Cu")
		(net "PHY_SCC_A_TO_DRV_A_9_DP")
	)
	(segment
		(start 280.138886 -343.34831)
		(end 280.144982 -343.342214)
		(width 0.10795)
		(layer "In9.Cu")
		(net "PHY_SCC_A_TO_DRV_A_9_DP")
	)
	(segment
		(start 288.8742 -344.039698)
		(end 288.8742 -344.039952)
		(width 0.10795)
		(layer "In9.Cu")
		(net "PHY_SCC_A_TO_DRV_A_9_DP")
	)
	(segment
		(start 296.737278 -339.40369)
		(end 289.772344 -343.840816)
		(width 0.10795)
		(layer "In9.Cu")
		(net "PHY_SCC_A_TO_DRV_A_9_DP")
	)
	(segment
		(start 302.227996 -334.674464)
		(end 302.054006 -334.947514)
		(width 0.10795)
		(layer "In9.Cu")
		(net "PHY_SCC_A_TO_DRV_A_9_DP")
	)
	(segment
		(start 289.772344 -343.840816)
		(end 288.8742 -344.039698)
		(width 0.10795)
		(layer "In9.Cu")
		(net "PHY_SCC_A_TO_DRV_A_9_DP")
	)
	(arc
		(start 280.138886 -343.935558)
		(mid 280.111453 -343.894407)
		(end 280.101802 -343.845896)
		(width 0.10795)
		(layer "In9.Cu")
		(net "PHY_SCC_A_TO_DRV_A_9_DP")
	)
	(arc
		(start 414.639252 -273.655282)
		(mid 414.630145 -273.701064)
		(end 414.6042 -273.739864)
		(width 0.10795)
		(layer "In9.Cu")
		(net "PHY_SCC_A_TO_DRV_A_9_DP")
	)
	(arc
		(start 414.6042 -273.739864)
		(mid 414.565393 -273.765794)
		(end 414.519618 -273.774916)
		(width 0.10795)
		(layer "In9.Cu")
		(net "PHY_SCC_A_TO_DRV_A_9_DP")
	)
	(arc
		(start 280.101802 -343.437972)
		(mid 280.111435 -343.389454)
		(end 280.138886 -343.34831)
		(width 0.10795)
		(layer "In9.Cu")
		(net "PHY_SCC_A_TO_DRV_A_9_DP")
	)
	(arc
		(start 280.144982 -343.342214)
		(mid 280.186133 -343.314781)
		(end 280.234644 -343.30513)
		(width 0.10795)
		(layer "In9.Cu")
		(net "PHY_SCC_A_TO_DRV_A_9_DP")
	)
	(arc
		(start 280.295858 -344.039952)
		(mid 280.24734 -344.030319)
		(end 280.206196 -344.002868)
		(width 0.10795)
		(layer "In9.Cu")
		(net "PHY_SCC_A_TO_DRV_A_9_DP")
	)
	(segment
		(start 414.676336 -274.148296)
		(end 414.701482 -274.12315)
		(width 0.127)
		(layer "F.Cu")
		(net "PHY_SCC_A_TO_DRV_A_9_DN")
	)
	(segment
		(start 414.639252 -274.511516)
		(end 414.639252 -274.237958)
		(width 0.127)
		(layer "F.Cu")
		(net "PHY_SCC_A_TO_DRV_A_9_DN")
	)
	(segment
		(start 415.540698 -274.086066)
		(end 415.674048 -274.219416)
		(width 0.127)
		(layer "F.Cu")
		(net "PHY_SCC_A_TO_DRV_A_9_DN")
	)
	(segment
		(start 415.674048 -274.219416)
		(end 416.005264 -274.219416)
		(width 0.127)
		(layer "F.Cu")
		(net "PHY_SCC_A_TO_DRV_A_9_DN")
	)
	(segment
		(start 414.791144 -274.086066)
		(end 415.540698 -274.086066)
		(width 0.127)
		(layer "F.Cu")
		(net "PHY_SCC_A_TO_DRV_A_9_DN")
	)
	(arc
		(start 414.639252 -274.237958)
		(mid 414.648885 -274.18944)
		(end 414.676336 -274.148296)
		(width 0.127)
		(layer "F.Cu")
		(net "PHY_SCC_A_TO_DRV_A_9_DN")
	)
	(arc
		(start 414.701482 -274.12315)
		(mid 414.742633 -274.095717)
		(end 414.791144 -274.086066)
		(width 0.127)
		(layer "F.Cu")
		(net "PHY_SCC_A_TO_DRV_A_9_DN")
	)
	(segment
		(start 301.146972 -336.986372)
		(end 296.914824 -339.682328)
		(width 0.10795)
		(layer "In9.Cu")
		(net "PHY_SCC_A_TO_DRV_A_9_DN")
	)
	(segment
		(start 410.233114 -275.523706)
		(end 370.975382 -302.004222)
		(width 0.10795)
		(layer "In9.Cu")
		(net "PHY_SCC_A_TO_DRV_A_9_DN")
	)
	(segment
		(start 414.639252 -274.511516)
		(end 414.639252 -274.22475)
		(width 0.10795)
		(layer "In9.Cu")
		(net "PHY_SCC_A_TO_DRV_A_9_DN")
	)
	(segment
		(start 306.869846 -328.0029)
		(end 301.146972 -336.986372)
		(width 0.10795)
		(layer "In9.Cu")
		(net "PHY_SCC_A_TO_DRV_A_9_DN")
	)
	(segment
		(start 335.244948 -309.925974)
		(end 306.869846 -328.0029)
		(width 0.10795)
		(layer "In9.Cu")
		(net "PHY_SCC_A_TO_DRV_A_9_DN")
	)
	(segment
		(start 279.734518 -343.34831)
		(end 279.728422 -343.342214)
		(width 0.10795)
		(layer "In9.Cu")
		(net "PHY_SCC_A_TO_DRV_A_9_DN")
	)
	(segment
		(start 413.946848 -274.105116)
		(end 410.233114 -275.523706)
		(width 0.10795)
		(layer "In9.Cu")
		(net "PHY_SCC_A_TO_DRV_A_9_DN")
	)
	(segment
		(start 288.9377 -344.370152)
		(end 280.295858 -344.370152)
		(width 0.10795)
		(layer "In9.Cu")
		(net "PHY_SCC_A_TO_DRV_A_9_DN")
	)
	(segment
		(start 370.975382 -302.004222)
		(end 335.244948 -309.925974)
		(width 0.10795)
		(layer "In9.Cu")
		(net "PHY_SCC_A_TO_DRV_A_9_DN")
	)
	(segment
		(start 414.519618 -274.105116)
		(end 413.946848 -274.105116)
		(width 0.10795)
		(layer "In9.Cu")
		(net "PHY_SCC_A_TO_DRV_A_9_DN")
	)
	(segment
		(start 289.900614 -344.150696)
		(end 288.945574 -344.362278)
		(width 0.10795)
		(layer "In9.Cu")
		(net "PHY_SCC_A_TO_DRV_A_9_DN")
	)
	(segment
		(start 279.97277 -344.236548)
		(end 279.905206 -344.168984)
		(width 0.10795)
		(layer "In9.Cu")
		(net "PHY_SCC_A_TO_DRV_A_9_DN")
	)
	(segment
		(start 279.63876 -343.30513)
		(end 279.236678 -343.30513)
		(width 0.10795)
		(layer "In9.Cu")
		(net "PHY_SCC_A_TO_DRV_A_9_DN")
	)
	(segment
		(start 279.771602 -343.845896)
		(end 279.771602 -343.437972)
		(width 0.10795)
		(layer "In9.Cu")
		(net "PHY_SCC_A_TO_DRV_A_9_DN")
	)
	(segment
		(start 296.914824 -339.682328)
		(end 289.900614 -344.150696)
		(width 0.10795)
		(layer "In9.Cu")
		(net "PHY_SCC_A_TO_DRV_A_9_DN")
	)
	(segment
		(start 288.945574 -344.362278)
		(end 288.9377 -344.370152)
		(width 0.10795)
		(layer "In9.Cu")
		(net "PHY_SCC_A_TO_DRV_A_9_DN")
	)
	(arc
		(start 279.728422 -343.342214)
		(mid 279.687271 -343.314781)
		(end 279.63876 -343.30513)
		(width 0.10795)
		(layer "In9.Cu")
		(net "PHY_SCC_A_TO_DRV_A_9_DN")
	)
	(arc
		(start 414.639252 -274.22475)
		(mid 414.630145 -274.178968)
		(end 414.6042 -274.140168)
		(width 0.10795)
		(layer "In9.Cu")
		(net "PHY_SCC_A_TO_DRV_A_9_DN")
	)
	(arc
		(start 280.295858 -344.370152)
		(mid 280.121047 -344.335433)
		(end 279.97277 -344.236548)
		(width 0.10795)
		(layer "In9.Cu")
		(net "PHY_SCC_A_TO_DRV_A_9_DN")
	)
	(arc
		(start 279.771602 -343.437972)
		(mid 279.761969 -343.389454)
		(end 279.734518 -343.34831)
		(width 0.10795)
		(layer "In9.Cu")
		(net "PHY_SCC_A_TO_DRV_A_9_DN")
	)
	(arc
		(start 279.905206 -344.168984)
		(mid 279.80632 -344.020707)
		(end 279.771602 -343.845896)
		(width 0.10795)
		(layer "In9.Cu")
		(net "PHY_SCC_A_TO_DRV_A_9_DN")
	)
	(arc
		(start 414.6042 -274.140168)
		(mid 414.565393 -274.114238)
		(end 414.519618 -274.105116)
		(width 0.10795)
		(layer "In9.Cu")
		(net "PHY_SCC_A_TO_DRV_A_9_DN")
	)
	(segment
		(start 383.08915 -273.368516)
		(end 383.08915 -273.657314)
		(width 0.127)
		(layer "F.Cu")
		(net "PHY_SCC_A_TO_DRV_A_8_DP")
	)
	(segment
		(start 383.126234 -273.746976)
		(end 383.13614 -273.756882)
		(width 0.127)
		(layer "F.Cu")
		(net "PHY_SCC_A_TO_DRV_A_8_DP")
	)
	(segment
		(start 383.990596 -273.793966)
		(end 384.123946 -273.660616)
		(width 0.127)
		(layer "F.Cu")
		(net "PHY_SCC_A_TO_DRV_A_8_DP")
	)
	(segment
		(start 383.225802 -273.793966)
		(end 383.990596 -273.793966)
		(width 0.127)
		(layer "F.Cu")
		(net "PHY_SCC_A_TO_DRV_A_8_DP")
	)
	(segment
		(start 384.123946 -273.660616)
		(end 384.455162 -273.660616)
		(width 0.127)
		(layer "F.Cu")
		(net "PHY_SCC_A_TO_DRV_A_8_DP")
	)
	(arc
		(start 383.13614 -273.756882)
		(mid 383.177291 -273.784315)
		(end 383.225802 -273.793966)
		(width 0.127)
		(layer "F.Cu")
		(net "PHY_SCC_A_TO_DRV_A_8_DP")
	)
	(arc
		(start 383.08915 -273.657314)
		(mid 383.098783 -273.705832)
		(end 383.126234 -273.746976)
		(width 0.127)
		(layer "F.Cu")
		(net "PHY_SCC_A_TO_DRV_A_8_DP")
	)
	(segment
		(start 299.995844 -333.947262)
		(end 300.28515 -333.883)
		(width 0.10795)
		(layer "In9.Cu")
		(net "PHY_SCC_A_TO_DRV_A_8_DP")
	)
	(segment
		(start 299.885862 -334.509618)
		(end 299.821854 -334.220312)
		(width 0.10795)
		(layer "In9.Cu")
		(net "PHY_SCC_A_TO_DRV_A_8_DP")
	)
	(segment
		(start 299.711872 -334.782922)
		(end 299.885862 -334.509618)
		(width 0.10795)
		(layer "In9.Cu")
		(net "PHY_SCC_A_TO_DRV_A_8_DP")
	)
	(segment
		(start 378.594366 -274.52066)
		(end 381.954278 -273.774916)
		(width 0.10795)
		(layer "In9.Cu")
		(net "PHY_SCC_A_TO_DRV_A_8_DP")
	)
	(segment
		(start 324.09384 -312.82132)
		(end 328.480166 -306.446682)
		(width 0.10795)
		(layer "In9.Cu")
		(net "PHY_SCC_A_TO_DRV_A_8_DP")
	)
	(segment
		(start 328.480166 -306.446682)
		(end 378.594366 -274.52066)
		(width 0.10795)
		(layer "In9.Cu")
		(net "PHY_SCC_A_TO_DRV_A_8_DP")
	)
	(segment
		(start 287.99917 -342.239854)
		(end 289.01517 -342.01481)
		(width 0.10795)
		(layer "In9.Cu")
		(net "PHY_SCC_A_TO_DRV_A_8_DP")
	)
	(segment
		(start 279.101804 -341.642192)
		(end 279.101804 -342.075516)
		(width 0.10795)
		(layer "In9.Cu")
		(net "PHY_SCC_A_TO_DRV_A_8_DP")
	)
	(segment
		(start 279.266142 -342.239854)
		(end 287.99917 -342.239854)
		(width 0.10795)
		(layer "In9.Cu")
		(net "PHY_SCC_A_TO_DRV_A_8_DP")
	)
	(segment
		(start 299.422566 -334.84693)
		(end 299.711872 -334.782922)
		(width 0.10795)
		(layer "In9.Cu")
		(net "PHY_SCC_A_TO_DRV_A_8_DP")
	)
	(segment
		(start 300.394878 -333.320644)
		(end 300.568868 -333.047594)
		(width 0.10795)
		(layer "In9.Cu")
		(net "PHY_SCC_A_TO_DRV_A_8_DP")
	)
	(segment
		(start 381.954278 -273.774916)
		(end 382.969516 -273.774916)
		(width 0.10795)
		(layer "In9.Cu")
		(net "PHY_SCC_A_TO_DRV_A_8_DP")
	)
	(segment
		(start 289.01517 -342.01481)
		(end 290.031424 -341.789766)
		(width 0.10795)
		(layer "In9.Cu")
		(net "PHY_SCC_A_TO_DRV_A_8_DP")
	)
	(segment
		(start 300.858174 -332.983332)
		(end 302.580548 -330.28001)
		(width 0.10795)
		(layer "In9.Cu")
		(net "PHY_SCC_A_TO_DRV_A_8_DP")
	)
	(segment
		(start 290.031424 -341.789766)
		(end 298.811442 -336.196178)
		(width 0.10795)
		(layer "In9.Cu")
		(net "PHY_SCC_A_TO_DRV_A_8_DP")
	)
	(segment
		(start 299.248576 -335.11998)
		(end 299.422566 -334.84693)
		(width 0.10795)
		(layer "In9.Cu")
		(net "PHY_SCC_A_TO_DRV_A_8_DP")
	)
	(segment
		(start 279.138888 -342.165178)
		(end 279.17648 -342.20277)
		(width 0.10795)
		(layer "In9.Cu")
		(net "PHY_SCC_A_TO_DRV_A_8_DP")
	)
	(segment
		(start 306.350162 -324.36308)
		(end 324.09384 -312.82132)
		(width 0.10795)
		(layer "In9.Cu")
		(net "PHY_SCC_A_TO_DRV_A_8_DP")
	)
	(segment
		(start 300.28515 -333.883)
		(end 300.45914 -333.60995)
		(width 0.10795)
		(layer "In9.Cu")
		(net "PHY_SCC_A_TO_DRV_A_8_DP")
	)
	(segment
		(start 298.811442 -336.196178)
		(end 299.312584 -335.40954)
		(width 0.10795)
		(layer "In9.Cu")
		(net "PHY_SCC_A_TO_DRV_A_8_DP")
	)
	(segment
		(start 279.149302 -341.542116)
		(end 279.138888 -341.55253)
		(width 0.10795)
		(layer "In9.Cu")
		(net "PHY_SCC_A_TO_DRV_A_8_DP")
	)
	(segment
		(start 302.580548 -330.28001)
		(end 306.350162 -324.36308)
		(width 0.10795)
		(layer "In9.Cu")
		(net "PHY_SCC_A_TO_DRV_A_8_DP")
	)
	(segment
		(start 299.312584 -335.40954)
		(end 299.248576 -335.11998)
		(width 0.10795)
		(layer "In9.Cu")
		(net "PHY_SCC_A_TO_DRV_A_8_DP")
	)
	(segment
		(start 383.08915 -273.655282)
		(end 383.08915 -273.368516)
		(width 0.10795)
		(layer "In9.Cu")
		(net "PHY_SCC_A_TO_DRV_A_8_DP")
	)
	(segment
		(start 300.45914 -333.60995)
		(end 300.394878 -333.320644)
		(width 0.10795)
		(layer "In9.Cu")
		(net "PHY_SCC_A_TO_DRV_A_8_DP")
	)
	(segment
		(start 300.568868 -333.047594)
		(end 300.858174 -332.983332)
		(width 0.10795)
		(layer "In9.Cu")
		(net "PHY_SCC_A_TO_DRV_A_8_DP")
	)
	(segment
		(start 299.821854 -334.220312)
		(end 299.995844 -333.947262)
		(width 0.10795)
		(layer "In9.Cu")
		(net "PHY_SCC_A_TO_DRV_A_8_DP")
	)
	(segment
		(start 279.636728 -341.505032)
		(end 279.238964 -341.505032)
		(width 0.10795)
		(layer "In9.Cu")
		(net "PHY_SCC_A_TO_DRV_A_8_DP")
	)
	(arc
		(start 279.138888 -341.55253)
		(mid 279.111455 -341.593681)
		(end 279.101804 -341.642192)
		(width 0.10795)
		(layer "In9.Cu")
		(net "PHY_SCC_A_TO_DRV_A_8_DP")
	)
	(arc
		(start 279.17648 -342.20277)
		(mid 279.217631 -342.230203)
		(end 279.266142 -342.239854)
		(width 0.10795)
		(layer "In9.Cu")
		(net "PHY_SCC_A_TO_DRV_A_8_DP")
	)
	(arc
		(start 279.101804 -342.075516)
		(mid 279.111437 -342.124034)
		(end 279.138888 -342.165178)
		(width 0.10795)
		(layer "In9.Cu")
		(net "PHY_SCC_A_TO_DRV_A_8_DP")
	)
	(arc
		(start 279.238964 -341.505032)
		(mid 279.190446 -341.514665)
		(end 279.149302 -341.542116)
		(width 0.10795)
		(layer "In9.Cu")
		(net "PHY_SCC_A_TO_DRV_A_8_DP")
	)
	(arc
		(start 382.969516 -273.774916)
		(mid 383.015298 -273.765809)
		(end 383.054098 -273.739864)
		(width 0.10795)
		(layer "In9.Cu")
		(net "PHY_SCC_A_TO_DRV_A_8_DP")
	)
	(arc
		(start 383.054098 -273.739864)
		(mid 383.080028 -273.701057)
		(end 383.08915 -273.655282)
		(width 0.10795)
		(layer "In9.Cu")
		(net "PHY_SCC_A_TO_DRV_A_8_DP")
	)
	(segment
		(start 383.08915 -274.511516)
		(end 383.08915 -274.227544)
		(width 0.127)
		(layer "F.Cu")
		(net "PHY_SCC_A_TO_DRV_A_8_DN")
	)
	(segment
		(start 383.990596 -274.086066)
		(end 384.123946 -274.219416)
		(width 0.127)
		(layer "F.Cu")
		(net "PHY_SCC_A_TO_DRV_A_8_DN")
	)
	(segment
		(start 383.230628 -274.086066)
		(end 383.990596 -274.086066)
		(width 0.127)
		(layer "F.Cu")
		(net "PHY_SCC_A_TO_DRV_A_8_DN")
	)
	(segment
		(start 383.126234 -274.137882)
		(end 383.140966 -274.12315)
		(width 0.127)
		(layer "F.Cu")
		(net "PHY_SCC_A_TO_DRV_A_8_DN")
	)
	(segment
		(start 384.123946 -274.219416)
		(end 384.455162 -274.219416)
		(width 0.127)
		(layer "F.Cu")
		(net "PHY_SCC_A_TO_DRV_A_8_DN")
	)
	(arc
		(start 383.08915 -274.227544)
		(mid 383.098783 -274.179026)
		(end 383.126234 -274.137882)
		(width 0.127)
		(layer "F.Cu")
		(net "PHY_SCC_A_TO_DRV_A_8_DN")
	)
	(arc
		(start 383.140966 -274.12315)
		(mid 383.182117 -274.095717)
		(end 383.230628 -274.086066)
		(width 0.127)
		(layer "F.Cu")
		(net "PHY_SCC_A_TO_DRV_A_8_DN")
	)
	(segment
		(start 278.905208 -342.398604)
		(end 278.943054 -342.43645)
		(width 0.10795)
		(layer "In9.Cu")
		(net "PHY_SCC_A_TO_DRV_A_8_DN")
	)
	(segment
		(start 288.035492 -342.570054)
		(end 290.159694 -342.099646)
		(width 0.10795)
		(layer "In9.Cu")
		(net "PHY_SCC_A_TO_DRV_A_8_DN")
	)
	(segment
		(start 279.266142 -342.570054)
		(end 288.035492 -342.570054)
		(width 0.10795)
		(layer "In9.Cu")
		(net "PHY_SCC_A_TO_DRV_A_8_DN")
	)
	(segment
		(start 299.05071 -336.435446)
		(end 306.590446 -324.601078)
		(width 0.10795)
		(layer "In9.Cu")
		(net "PHY_SCC_A_TO_DRV_A_8_DN")
	)
	(segment
		(start 290.159694 -342.099646)
		(end 299.05071 -336.435446)
		(width 0.10795)
		(layer "In9.Cu")
		(net "PHY_SCC_A_TO_DRV_A_8_DN")
	)
	(segment
		(start 381.9906 -274.105116)
		(end 382.969516 -274.105116)
		(width 0.10795)
		(layer "In9.Cu")
		(net "PHY_SCC_A_TO_DRV_A_8_DN")
	)
	(segment
		(start 324.329044 -313.06262)
		(end 328.714354 -306.689252)
		(width 0.10795)
		(layer "In9.Cu")
		(net "PHY_SCC_A_TO_DRV_A_8_DN")
	)
	(segment
		(start 378.72289 -274.83054)
		(end 381.990346 -274.10537)
		(width 0.10795)
		(layer "In9.Cu")
		(net "PHY_SCC_A_TO_DRV_A_8_DN")
	)
	(segment
		(start 306.590446 -324.601078)
		(end 324.329044 -313.06262)
		(width 0.10795)
		(layer "In9.Cu")
		(net "PHY_SCC_A_TO_DRV_A_8_DN")
	)
	(segment
		(start 328.714354 -306.689252)
		(end 378.72289 -274.83054)
		(width 0.10795)
		(layer "In9.Cu")
		(net "PHY_SCC_A_TO_DRV_A_8_DN")
	)
	(segment
		(start 381.990346 -274.105624)
		(end 381.9906 -274.10537)
		(width 0.10795)
		(layer "In9.Cu")
		(net "PHY_SCC_A_TO_DRV_A_8_DN")
	)
	(segment
		(start 383.08915 -274.22475)
		(end 383.08915 -274.511516)
		(width 0.10795)
		(layer "In9.Cu")
		(net "PHY_SCC_A_TO_DRV_A_8_DN")
	)
	(segment
		(start 381.990346 -274.10537)
		(end 381.990346 -274.105624)
		(width 0.10795)
		(layer "In9.Cu")
		(net "PHY_SCC_A_TO_DRV_A_8_DN")
	)
	(segment
		(start 381.9906 -274.10537)
		(end 381.9906 -274.105116)
		(width 0.10795)
		(layer "In9.Cu")
		(net "PHY_SCC_A_TO_DRV_A_8_DN")
	)
	(segment
		(start 278.771604 -341.642192)
		(end 278.771604 -342.075516)
		(width 0.10795)
		(layer "In9.Cu")
		(net "PHY_SCC_A_TO_DRV_A_8_DN")
	)
	(segment
		(start 278.23668 -341.505032)
		(end 278.634444 -341.505032)
		(width 0.10795)
		(layer "In9.Cu")
		(net "PHY_SCC_A_TO_DRV_A_8_DN")
	)
	(segment
		(start 278.724106 -341.542116)
		(end 278.73452 -341.55253)
		(width 0.10795)
		(layer "In9.Cu")
		(net "PHY_SCC_A_TO_DRV_A_8_DN")
	)
	(arc
		(start 278.73452 -341.55253)
		(mid 278.761953 -341.593681)
		(end 278.771604 -341.642192)
		(width 0.10795)
		(layer "In9.Cu")
		(net "PHY_SCC_A_TO_DRV_A_8_DN")
	)
	(arc
		(start 278.771604 -342.075516)
		(mid 278.806323 -342.250327)
		(end 278.905208 -342.398604)
		(width 0.10795)
		(layer "In9.Cu")
		(net "PHY_SCC_A_TO_DRV_A_8_DN")
	)
	(arc
		(start 382.969516 -274.105116)
		(mid 383.015298 -274.114223)
		(end 383.054098 -274.140168)
		(width 0.10795)
		(layer "In9.Cu")
		(net "PHY_SCC_A_TO_DRV_A_8_DN")
	)
	(arc
		(start 278.943054 -342.43645)
		(mid 279.091331 -342.535336)
		(end 279.266142 -342.570054)
		(width 0.10795)
		(layer "In9.Cu")
		(net "PHY_SCC_A_TO_DRV_A_8_DN")
	)
	(arc
		(start 383.054098 -274.140168)
		(mid 383.080028 -274.178975)
		(end 383.08915 -274.22475)
		(width 0.10795)
		(layer "In9.Cu")
		(net "PHY_SCC_A_TO_DRV_A_8_DN")
	)
	(arc
		(start 278.634444 -341.505032)
		(mid 278.682962 -341.514665)
		(end 278.724106 -341.542116)
		(width 0.10795)
		(layer "In9.Cu")
		(net "PHY_SCC_A_TO_DRV_A_8_DN")
	)
	(segment
		(start 352.440748 -273.793966)
		(end 352.574098 -273.660616)
		(width 0.127)
		(layer "F.Cu")
		(net "PHY_SCC_A_TO_DRV_A_7_DP")
	)
	(segment
		(start 351.684082 -273.793966)
		(end 352.440748 -273.793966)
		(width 0.127)
		(layer "F.Cu")
		(net "PHY_SCC_A_TO_DRV_A_7_DP")
	)
	(segment
		(start 352.574098 -273.660616)
		(end 352.905314 -273.660616)
		(width 0.127)
		(layer "F.Cu")
		(net "PHY_SCC_A_TO_DRV_A_7_DP")
	)
	(segment
		(start 351.539302 -273.368516)
		(end 351.539302 -273.649186)
		(width 0.127)
		(layer "F.Cu")
		(net "PHY_SCC_A_TO_DRV_A_7_DP")
	)
	(segment
		(start 351.576386 -273.738848)
		(end 351.59442 -273.756882)
		(width 0.127)
		(layer "F.Cu")
		(net "PHY_SCC_A_TO_DRV_A_7_DP")
	)
	(arc
		(start 351.59442 -273.756882)
		(mid 351.635571 -273.784315)
		(end 351.684082 -273.793966)
		(width 0.127)
		(layer "F.Cu")
		(net "PHY_SCC_A_TO_DRV_A_7_DP")
	)
	(arc
		(start 351.539302 -273.649186)
		(mid 351.548935 -273.697704)
		(end 351.576386 -273.738848)
		(width 0.127)
		(layer "F.Cu")
		(net "PHY_SCC_A_TO_DRV_A_7_DP")
	)
	(segment
		(start 349.948246 -273.774916)
		(end 351.419668 -273.774916)
		(width 0.10795)
		(layer "In9.Cu")
		(net "PHY_SCC_A_TO_DRV_A_7_DP")
	)
	(segment
		(start 297.866308 -334.035146)
		(end 298.040298 -333.762096)
		(width 0.10795)
		(layer "In9.Cu")
		(net "PHY_SCC_A_TO_DRV_A_7_DP")
	)
	(segment
		(start 280.101802 -339.83803)
		(end 280.101802 -340.245954)
		(width 0.10795)
		(layer "In9.Cu")
		(net "PHY_SCC_A_TO_DRV_A_7_DP")
	)
	(segment
		(start 297.93057 -334.324452)
		(end 297.866308 -334.035146)
		(width 0.10795)
		(layer "In9.Cu")
		(net "PHY_SCC_A_TO_DRV_A_7_DP")
	)
	(segment
		(start 280.295858 -340.44001)
		(end 288.371788 -340.44001)
		(width 0.10795)
		(layer "In9.Cu")
		(net "PHY_SCC_A_TO_DRV_A_7_DP")
	)
	(segment
		(start 280.636726 -339.705188)
		(end 280.234644 -339.705188)
		(width 0.10795)
		(layer "In9.Cu")
		(net "PHY_SCC_A_TO_DRV_A_7_DP")
	)
	(segment
		(start 336.954876 -279.259538)
		(end 349.948246 -273.774916)
		(width 0.10795)
		(layer "In9.Cu")
		(net "PHY_SCC_A_TO_DRV_A_7_DP")
	)
	(segment
		(start 329.521566 -284.735016)
		(end 336.954876 -279.259538)
		(width 0.10795)
		(layer "In9.Cu")
		(net "PHY_SCC_A_TO_DRV_A_7_DP")
	)
	(segment
		(start 280.138886 -340.335616)
		(end 280.206196 -340.402926)
		(width 0.10795)
		(layer "In9.Cu")
		(net "PHY_SCC_A_TO_DRV_A_7_DP")
	)
	(segment
		(start 288.371788 -340.44001)
		(end 289.625532 -340.162134)
		(width 0.10795)
		(layer "In9.Cu")
		(net "PHY_SCC_A_TO_DRV_A_7_DP")
	)
	(segment
		(start 351.539302 -273.655282)
		(end 351.539302 -273.368516)
		(width 0.10795)
		(layer "In9.Cu")
		(net "PHY_SCC_A_TO_DRV_A_7_DP")
	)
	(segment
		(start 299.076872 -332.525116)
		(end 299.01261 -332.23581)
		(width 0.10795)
		(layer "In9.Cu")
		(net "PHY_SCC_A_TO_DRV_A_7_DP")
	)
	(segment
		(start 298.503594 -333.424784)
		(end 298.439586 -333.135478)
		(width 0.10795)
		(layer "In9.Cu")
		(net "PHY_SCC_A_TO_DRV_A_7_DP")
	)
	(segment
		(start 289.625532 -340.162134)
		(end 297.344592 -335.244186)
		(width 0.10795)
		(layer "In9.Cu")
		(net "PHY_SCC_A_TO_DRV_A_7_DP")
	)
	(segment
		(start 299.1866 -331.962506)
		(end 299.475906 -331.898498)
		(width 0.10795)
		(layer "In9.Cu")
		(net "PHY_SCC_A_TO_DRV_A_7_DP")
	)
	(segment
		(start 298.040298 -333.762096)
		(end 298.329604 -333.697834)
		(width 0.10795)
		(layer "In9.Cu")
		(net "PHY_SCC_A_TO_DRV_A_7_DP")
	)
	(segment
		(start 299.475906 -331.898498)
		(end 299.47616 -331.898498)
		(width 0.10795)
		(layer "In9.Cu")
		(net "PHY_SCC_A_TO_DRV_A_7_DP")
	)
	(segment
		(start 298.439586 -333.135478)
		(end 298.613576 -332.862428)
		(width 0.10795)
		(layer "In9.Cu")
		(net "PHY_SCC_A_TO_DRV_A_7_DP")
	)
	(segment
		(start 280.144982 -339.742272)
		(end 280.138886 -339.748368)
		(width 0.10795)
		(layer "In9.Cu")
		(net "PHY_SCC_A_TO_DRV_A_7_DP")
	)
	(segment
		(start 298.329604 -333.697834)
		(end 298.503594 -333.424784)
		(width 0.10795)
		(layer "In9.Cu")
		(net "PHY_SCC_A_TO_DRV_A_7_DP")
	)
	(segment
		(start 299.47616 -331.898498)
		(end 329.521566 -284.735016)
		(width 0.10795)
		(layer "In9.Cu")
		(net "PHY_SCC_A_TO_DRV_A_7_DP")
	)
	(segment
		(start 299.01261 -332.23581)
		(end 299.1866 -331.962506)
		(width 0.10795)
		(layer "In9.Cu")
		(net "PHY_SCC_A_TO_DRV_A_7_DP")
	)
	(segment
		(start 297.344592 -335.244186)
		(end 297.93057 -334.324452)
		(width 0.10795)
		(layer "In9.Cu")
		(net "PHY_SCC_A_TO_DRV_A_7_DP")
	)
	(segment
		(start 298.613576 -332.862428)
		(end 298.902882 -332.798166)
		(width 0.10795)
		(layer "In9.Cu")
		(net "PHY_SCC_A_TO_DRV_A_7_DP")
	)
	(segment
		(start 298.902882 -332.798166)
		(end 299.076872 -332.525116)
		(width 0.10795)
		(layer "In9.Cu")
		(net "PHY_SCC_A_TO_DRV_A_7_DP")
	)
	(arc
		(start 351.50425 -273.739864)
		(mid 351.53018 -273.701057)
		(end 351.539302 -273.655282)
		(width 0.10795)
		(layer "In9.Cu")
		(net "PHY_SCC_A_TO_DRV_A_7_DP")
	)
	(arc
		(start 280.101802 -340.245954)
		(mid 280.111435 -340.294472)
		(end 280.138886 -340.335616)
		(width 0.10795)
		(layer "In9.Cu")
		(net "PHY_SCC_A_TO_DRV_A_7_DP")
	)
	(arc
		(start 280.138886 -339.748368)
		(mid 280.111453 -339.789519)
		(end 280.101802 -339.83803)
		(width 0.10795)
		(layer "In9.Cu")
		(net "PHY_SCC_A_TO_DRV_A_7_DP")
	)
	(arc
		(start 351.419668 -273.774916)
		(mid 351.46545 -273.765809)
		(end 351.50425 -273.739864)
		(width 0.10795)
		(layer "In9.Cu")
		(net "PHY_SCC_A_TO_DRV_A_7_DP")
	)
	(arc
		(start 280.206196 -340.402926)
		(mid 280.247347 -340.430359)
		(end 280.295858 -340.44001)
		(width 0.10795)
		(layer "In9.Cu")
		(net "PHY_SCC_A_TO_DRV_A_7_DP")
	)
	(arc
		(start 280.234644 -339.705188)
		(mid 280.186126 -339.714821)
		(end 280.144982 -339.742272)
		(width 0.10795)
		(layer "In9.Cu")
		(net "PHY_SCC_A_TO_DRV_A_7_DP")
	)
	(segment
		(start 352.440748 -274.086066)
		(end 352.574098 -274.219416)
		(width 0.127)
		(layer "F.Cu")
		(net "PHY_SCC_A_TO_DRV_A_7_DN")
	)
	(segment
		(start 351.539302 -274.511516)
		(end 351.539302 -274.230592)
		(width 0.127)
		(layer "F.Cu")
		(net "PHY_SCC_A_TO_DRV_A_7_DN")
	)
	(segment
		(start 351.683828 -274.086066)
		(end 352.440748 -274.086066)
		(width 0.127)
		(layer "F.Cu")
		(net "PHY_SCC_A_TO_DRV_A_7_DN")
	)
	(segment
		(start 352.574098 -274.219416)
		(end 352.905314 -274.219416)
		(width 0.127)
		(layer "F.Cu")
		(net "PHY_SCC_A_TO_DRV_A_7_DN")
	)
	(segment
		(start 351.576386 -274.14093)
		(end 351.594166 -274.12315)
		(width 0.127)
		(layer "F.Cu")
		(net "PHY_SCC_A_TO_DRV_A_7_DN")
	)
	(arc
		(start 351.594166 -274.12315)
		(mid 351.635317 -274.095717)
		(end 351.683828 -274.086066)
		(width 0.127)
		(layer "F.Cu")
		(net "PHY_SCC_A_TO_DRV_A_7_DN")
	)
	(arc
		(start 351.539302 -274.230592)
		(mid 351.548935 -274.182074)
		(end 351.576386 -274.14093)
		(width 0.127)
		(layer "F.Cu")
		(net "PHY_SCC_A_TO_DRV_A_7_DN")
	)
	(segment
		(start 279.728422 -339.742272)
		(end 279.734518 -339.748368)
		(width 0.10795)
		(layer "In9.Cu")
		(net "PHY_SCC_A_TO_DRV_A_7_DN")
	)
	(segment
		(start 279.236678 -339.705188)
		(end 279.63876 -339.705188)
		(width 0.10795)
		(layer "In9.Cu")
		(net "PHY_SCC_A_TO_DRV_A_7_DN")
	)
	(segment
		(start 288.40811 -340.77021)
		(end 289.753802 -340.472014)
		(width 0.10795)
		(layer "In9.Cu")
		(net "PHY_SCC_A_TO_DRV_A_7_DN")
	)
	(segment
		(start 346.79128 -275.466048)
		(end 350.015302 -274.105116)
		(width 0.10795)
		(layer "In9.Cu")
		(net "PHY_SCC_A_TO_DRV_A_7_DN")
	)
	(segment
		(start 337.119468 -279.548844)
		(end 346.79128 -275.466048)
		(width 0.10795)
		(layer "In9.Cu")
		(net "PHY_SCC_A_TO_DRV_A_7_DN")
	)
	(segment
		(start 297.58386 -335.483454)
		(end 329.767184 -284.964632)
		(width 0.10795)
		(layer "In9.Cu")
		(net "PHY_SCC_A_TO_DRV_A_7_DN")
	)
	(segment
		(start 280.295858 -340.77021)
		(end 288.40811 -340.77021)
		(width 0.10795)
		(layer "In9.Cu")
		(net "PHY_SCC_A_TO_DRV_A_7_DN")
	)
	(segment
		(start 350.015302 -274.105116)
		(end 351.419668 -274.105116)
		(width 0.10795)
		(layer "In9.Cu")
		(net "PHY_SCC_A_TO_DRV_A_7_DN")
	)
	(segment
		(start 279.905206 -340.569042)
		(end 279.97277 -340.636606)
		(width 0.10795)
		(layer "In9.Cu")
		(net "PHY_SCC_A_TO_DRV_A_7_DN")
	)
	(segment
		(start 329.767184 -284.964632)
		(end 337.119468 -279.548844)
		(width 0.10795)
		(layer "In9.Cu")
		(net "PHY_SCC_A_TO_DRV_A_7_DN")
	)
	(segment
		(start 289.753802 -340.472014)
		(end 297.58386 -335.483454)
		(width 0.10795)
		(layer "In9.Cu")
		(net "PHY_SCC_A_TO_DRV_A_7_DN")
	)
	(segment
		(start 279.771602 -339.83803)
		(end 279.771602 -340.245954)
		(width 0.10795)
		(layer "In9.Cu")
		(net "PHY_SCC_A_TO_DRV_A_7_DN")
	)
	(segment
		(start 351.539302 -274.22475)
		(end 351.539302 -274.511516)
		(width 0.10795)
		(layer "In9.Cu")
		(net "PHY_SCC_A_TO_DRV_A_7_DN")
	)
	(arc
		(start 279.63876 -339.705188)
		(mid 279.687278 -339.714821)
		(end 279.728422 -339.742272)
		(width 0.10795)
		(layer "In9.Cu")
		(net "PHY_SCC_A_TO_DRV_A_7_DN")
	)
	(arc
		(start 351.50425 -274.140168)
		(mid 351.53018 -274.178975)
		(end 351.539302 -274.22475)
		(width 0.10795)
		(layer "In9.Cu")
		(net "PHY_SCC_A_TO_DRV_A_7_DN")
	)
	(arc
		(start 279.771602 -340.245954)
		(mid 279.806321 -340.420765)
		(end 279.905206 -340.569042)
		(width 0.10795)
		(layer "In9.Cu")
		(net "PHY_SCC_A_TO_DRV_A_7_DN")
	)
	(arc
		(start 279.97277 -340.636606)
		(mid 280.121047 -340.735492)
		(end 280.295858 -340.77021)
		(width 0.10795)
		(layer "In9.Cu")
		(net "PHY_SCC_A_TO_DRV_A_7_DN")
	)
	(arc
		(start 279.734518 -339.748368)
		(mid 279.761951 -339.789519)
		(end 279.771602 -339.83803)
		(width 0.10795)
		(layer "In9.Cu")
		(net "PHY_SCC_A_TO_DRV_A_7_DN")
	)
	(arc
		(start 351.419668 -274.105116)
		(mid 351.46545 -274.114223)
		(end 351.50425 -274.140168)
		(width 0.10795)
		(layer "In9.Cu")
		(net "PHY_SCC_A_TO_DRV_A_7_DN")
	)
	(segment
		(start 321.023996 -273.660616)
		(end 321.355212 -273.660616)
		(width 0.127)
		(layer "F.Cu")
		(net "PHY_SCC_A_TO_DRV_A_6_DP")
	)
	(segment
		(start 320.890646 -273.793966)
		(end 321.023996 -273.660616)
		(width 0.127)
		(layer "F.Cu")
		(net "PHY_SCC_A_TO_DRV_A_6_DP")
	)
	(segment
		(start 320.133218 -273.793966)
		(end 320.890646 -273.793966)
		(width 0.127)
		(layer "F.Cu")
		(net "PHY_SCC_A_TO_DRV_A_6_DP")
	)
	(segment
		(start 319.9892 -273.368516)
		(end 319.9892 -273.649948)
		(width 0.127)
		(layer "F.Cu")
		(net "PHY_SCC_A_TO_DRV_A_6_DP")
	)
	(segment
		(start 320.026284 -273.73961)
		(end 320.043556 -273.756882)
		(width 0.127)
		(layer "F.Cu")
		(net "PHY_SCC_A_TO_DRV_A_6_DP")
	)
	(arc
		(start 320.043556 -273.756882)
		(mid 320.084707 -273.784315)
		(end 320.133218 -273.793966)
		(width 0.127)
		(layer "F.Cu")
		(net "PHY_SCC_A_TO_DRV_A_6_DP")
	)
	(arc
		(start 319.9892 -273.649948)
		(mid 319.998833 -273.698466)
		(end 320.026284 -273.73961)
		(width 0.127)
		(layer "F.Cu")
		(net "PHY_SCC_A_TO_DRV_A_6_DP")
	)
	(segment
		(start 279.238964 -337.90509)
		(end 279.636728 -337.90509)
		(width 0.10795)
		(layer "In9.Cu")
		(net "PHY_SCC_A_TO_DRV_A_6_DP")
	)
	(segment
		(start 319.891918 -273.774916)
		(end 319.354454 -273.774916)
		(width 0.10795)
		(layer "In9.Cu")
		(net "PHY_SCC_A_TO_DRV_A_6_DP")
	)
	(segment
		(start 292.310566 -335.917032)
		(end 288.306002 -338.468208)
		(width 0.10795)
		(layer "In9.Cu")
		(net "PHY_SCC_A_TO_DRV_A_6_DP")
	)
	(segment
		(start 293.706296 -333.336138)
		(end 293.770304 -333.625444)
		(width 0.10795)
		(layer "In9.Cu")
		(net "PHY_SCC_A_TO_DRV_A_6_DP")
	)
	(segment
		(start 294.74287 -332.099158)
		(end 294.453564 -332.16342)
		(width 0.10795)
		(layer "In9.Cu")
		(net "PHY_SCC_A_TO_DRV_A_6_DP")
	)
	(segment
		(start 293.880286 -333.063088)
		(end 293.706296 -333.336138)
		(width 0.10795)
		(layer "In9.Cu")
		(net "PHY_SCC_A_TO_DRV_A_6_DP")
	)
	(segment
		(start 294.169592 -332.998826)
		(end 293.880286 -333.063088)
		(width 0.10795)
		(layer "In9.Cu")
		(net "PHY_SCC_A_TO_DRV_A_6_DP")
	)
	(segment
		(start 312.182002 -304.725324)
		(end 294.74287 -332.099158)
		(width 0.10795)
		(layer "In9.Cu")
		(net "PHY_SCC_A_TO_DRV_A_6_DP")
	)
	(segment
		(start 319.149984 -273.908266)
		(end 319.11163 -273.939254)
		(width 0.10795)
		(layer "In9.Cu")
		(net "PHY_SCC_A_TO_DRV_A_6_DP")
	)
	(segment
		(start 279.101804 -338.475574)
		(end 279.101804 -338.04225)
		(width 0.10795)
		(layer "In9.Cu")
		(net "PHY_SCC_A_TO_DRV_A_6_DP")
	)
	(segment
		(start 293.770304 -333.625444)
		(end 293.596314 -333.898748)
		(width 0.10795)
		(layer "In9.Cu")
		(net "PHY_SCC_A_TO_DRV_A_6_DP")
	)
	(segment
		(start 319.960752 -273.746468)
		(end 319.960498 -273.746722)
		(width 0.10795)
		(layer "In9.Cu")
		(net "PHY_SCC_A_TO_DRV_A_6_DP")
	)
	(segment
		(start 318.984122 -274.041616)
		(end 312.182002 -304.725324)
		(width 0.10795)
		(layer "In9.Cu")
		(net "PHY_SCC_A_TO_DRV_A_6_DP")
	)
	(segment
		(start 287.531302 -338.639912)
		(end 279.266142 -338.639912)
		(width 0.10795)
		(layer "In9.Cu")
		(net "PHY_SCC_A_TO_DRV_A_6_DP")
	)
	(segment
		(start 293.596314 -333.898748)
		(end 293.307008 -333.962756)
		(width 0.10795)
		(layer "In9.Cu")
		(net "PHY_SCC_A_TO_DRV_A_6_DP")
	)
	(segment
		(start 293.19728 -334.525366)
		(end 292.310566 -335.917032)
		(width 0.10795)
		(layer "In9.Cu")
		(net "PHY_SCC_A_TO_DRV_A_6_DP")
	)
	(segment
		(start 294.343582 -332.725776)
		(end 294.169592 -332.998826)
		(width 0.10795)
		(layer "In9.Cu")
		(net "PHY_SCC_A_TO_DRV_A_6_DP")
	)
	(segment
		(start 293.307008 -333.962756)
		(end 293.133018 -334.23606)
		(width 0.10795)
		(layer "In9.Cu")
		(net "PHY_SCC_A_TO_DRV_A_6_DP")
	)
	(segment
		(start 279.138888 -337.952588)
		(end 279.149302 -337.942174)
		(width 0.10795)
		(layer "In9.Cu")
		(net "PHY_SCC_A_TO_DRV_A_6_DP")
	)
	(segment
		(start 319.287144 -273.798538)
		(end 319.149984 -273.908266)
		(width 0.10795)
		(layer "In9.Cu")
		(net "PHY_SCC_A_TO_DRV_A_6_DP")
	)
	(segment
		(start 294.453564 -332.16342)
		(end 294.279574 -332.43647)
		(width 0.10795)
		(layer "In9.Cu")
		(net "PHY_SCC_A_TO_DRV_A_6_DP")
	)
	(segment
		(start 319.11163 -273.939254)
		(end 318.984122 -274.041616)
		(width 0.10795)
		(layer "In9.Cu")
		(net "PHY_SCC_A_TO_DRV_A_6_DP")
	)
	(segment
		(start 293.133018 -334.23606)
		(end 293.19728 -334.525366)
		(width 0.10795)
		(layer "In9.Cu")
		(net "PHY_SCC_A_TO_DRV_A_6_DP")
	)
	(segment
		(start 288.306002 -338.468208)
		(end 287.531302 -338.639912)
		(width 0.10795)
		(layer "In9.Cu")
		(net "PHY_SCC_A_TO_DRV_A_6_DP")
	)
	(segment
		(start 279.17648 -338.602828)
		(end 279.138888 -338.565236)
		(width 0.10795)
		(layer "In9.Cu")
		(net "PHY_SCC_A_TO_DRV_A_6_DP")
	)
	(segment
		(start 319.9892 -273.368516)
		(end 319.9892 -273.67738)
		(width 0.10795)
		(layer "In9.Cu")
		(net "PHY_SCC_A_TO_DRV_A_6_DP")
	)
	(segment
		(start 294.279574 -332.43647)
		(end 294.343582 -332.725776)
		(width 0.10795)
		(layer "In9.Cu")
		(net "PHY_SCC_A_TO_DRV_A_6_DP")
	)
	(arc
		(start 319.354454 -273.774916)
		(mid 319.318787 -273.780994)
		(end 319.287144 -273.798538)
		(width 0.10795)
		(layer "In9.Cu")
		(net "PHY_SCC_A_TO_DRV_A_6_DP")
	)
	(arc
		(start 279.149302 -337.942174)
		(mid 279.190453 -337.914741)
		(end 279.238964 -337.90509)
		(width 0.10795)
		(layer "In9.Cu")
		(net "PHY_SCC_A_TO_DRV_A_6_DP")
	)
	(arc
		(start 279.138888 -338.565236)
		(mid 279.111455 -338.524085)
		(end 279.101804 -338.475574)
		(width 0.10795)
		(layer "In9.Cu")
		(net "PHY_SCC_A_TO_DRV_A_6_DP")
	)
	(arc
		(start 279.101804 -338.04225)
		(mid 279.111437 -337.993732)
		(end 279.138888 -337.952588)
		(width 0.10795)
		(layer "In9.Cu")
		(net "PHY_SCC_A_TO_DRV_A_6_DP")
	)
	(arc
		(start 279.266142 -338.639912)
		(mid 279.217624 -338.630279)
		(end 279.17648 -338.602828)
		(width 0.10795)
		(layer "In9.Cu")
		(net "PHY_SCC_A_TO_DRV_A_6_DP")
	)
	(arc
		(start 319.960498 -273.746722)
		(mid 319.928991 -273.767586)
		(end 319.891918 -273.774916)
		(width 0.10795)
		(layer "In9.Cu")
		(net "PHY_SCC_A_TO_DRV_A_6_DP")
	)
	(arc
		(start 319.9892 -273.67738)
		(mid 319.981859 -273.714759)
		(end 319.960752 -273.746468)
		(width 0.10795)
		(layer "In9.Cu")
		(net "PHY_SCC_A_TO_DRV_A_6_DP")
	)
	(segment
		(start 321.023996 -274.219416)
		(end 321.355212 -274.219416)
		(width 0.127)
		(layer "F.Cu")
		(net "PHY_SCC_A_TO_DRV_A_6_DN")
	)
	(segment
		(start 319.9892 -274.511516)
		(end 319.9892 -274.230338)
		(width 0.127)
		(layer "F.Cu")
		(net "PHY_SCC_A_TO_DRV_A_6_DN")
	)
	(segment
		(start 320.133472 -274.086066)
		(end 320.890646 -274.086066)
		(width 0.127)
		(layer "F.Cu")
		(net "PHY_SCC_A_TO_DRV_A_6_DN")
	)
	(segment
		(start 320.890646 -274.086066)
		(end 321.023996 -274.219416)
		(width 0.127)
		(layer "F.Cu")
		(net "PHY_SCC_A_TO_DRV_A_6_DN")
	)
	(segment
		(start 320.026284 -274.140676)
		(end 320.04381 -274.12315)
		(width 0.127)
		(layer "F.Cu")
		(net "PHY_SCC_A_TO_DRV_A_6_DN")
	)
	(arc
		(start 319.9892 -274.230338)
		(mid 319.998833 -274.18182)
		(end 320.026284 -274.140676)
		(width 0.127)
		(layer "F.Cu")
		(net "PHY_SCC_A_TO_DRV_A_6_DN")
	)
	(arc
		(start 320.04381 -274.12315)
		(mid 320.084961 -274.095717)
		(end 320.133472 -274.086066)
		(width 0.127)
		(layer "F.Cu")
		(net "PHY_SCC_A_TO_DRV_A_6_DN")
	)
	(segment
		(start 278.23668 -337.90509)
		(end 278.634444 -337.90509)
		(width 0.10795)
		(layer "In9.Cu")
		(net "PHY_SCC_A_TO_DRV_A_6_DN")
	)
	(segment
		(start 279.266142 -338.970112)
		(end 287.567624 -338.970112)
		(width 0.10795)
		(layer "In9.Cu")
		(net "PHY_SCC_A_TO_DRV_A_6_DN")
	)
	(segment
		(start 312.491882 -304.853594)
		(end 319.281556 -274.226528)
		(width 0.10795)
		(layer "In9.Cu")
		(net "PHY_SCC_A_TO_DRV_A_6_DN")
	)
	(segment
		(start 278.905208 -338.798662)
		(end 278.943054 -338.836508)
		(width 0.10795)
		(layer "In9.Cu")
		(net "PHY_SCC_A_TO_DRV_A_6_DN")
	)
	(segment
		(start 288.434272 -338.778088)
		(end 292.549834 -336.1563)
		(width 0.10795)
		(layer "In9.Cu")
		(net "PHY_SCC_A_TO_DRV_A_6_DN")
	)
	(segment
		(start 278.724106 -337.942174)
		(end 278.73452 -337.952588)
		(width 0.10795)
		(layer "In9.Cu")
		(net "PHY_SCC_A_TO_DRV_A_6_DN")
	)
	(segment
		(start 292.549834 -336.1563)
		(end 312.491882 -304.853594)
		(width 0.10795)
		(layer "In9.Cu")
		(net "PHY_SCC_A_TO_DRV_A_6_DN")
	)
	(segment
		(start 278.771604 -338.04225)
		(end 278.771604 -338.475574)
		(width 0.10795)
		(layer "In9.Cu")
		(net "PHY_SCC_A_TO_DRV_A_6_DN")
	)
	(segment
		(start 319.432686 -274.105116)
		(end 319.865248 -274.105116)
		(width 0.10795)
		(layer "In9.Cu")
		(net "PHY_SCC_A_TO_DRV_A_6_DN")
	)
	(segment
		(start 287.567624 -338.970112)
		(end 288.434272 -338.778088)
		(width 0.10795)
		(layer "In9.Cu")
		(net "PHY_SCC_A_TO_DRV_A_6_DN")
	)
	(segment
		(start 319.281556 -274.226528)
		(end 319.432686 -274.105116)
		(width 0.10795)
		(layer "In9.Cu")
		(net "PHY_SCC_A_TO_DRV_A_6_DN")
	)
	(segment
		(start 319.9892 -274.229068)
		(end 319.9892 -274.511516)
		(width 0.10795)
		(layer "In9.Cu")
		(net "PHY_SCC_A_TO_DRV_A_6_DN")
	)
	(arc
		(start 278.771604 -338.475574)
		(mid 278.806323 -338.650385)
		(end 278.905208 -338.798662)
		(width 0.10795)
		(layer "In9.Cu")
		(net "PHY_SCC_A_TO_DRV_A_6_DN")
	)
	(arc
		(start 319.865248 -274.105116)
		(mid 319.912682 -274.114551)
		(end 319.952878 -274.141438)
		(width 0.10795)
		(layer "In9.Cu")
		(net "PHY_SCC_A_TO_DRV_A_6_DN")
	)
	(arc
		(start 278.73452 -337.952588)
		(mid 278.761953 -337.993739)
		(end 278.771604 -338.04225)
		(width 0.10795)
		(layer "In9.Cu")
		(net "PHY_SCC_A_TO_DRV_A_6_DN")
	)
	(arc
		(start 278.634444 -337.90509)
		(mid 278.682962 -337.914723)
		(end 278.724106 -337.942174)
		(width 0.10795)
		(layer "In9.Cu")
		(net "PHY_SCC_A_TO_DRV_A_6_DN")
	)
	(arc
		(start 278.943054 -338.836508)
		(mid 279.091331 -338.935394)
		(end 279.266142 -338.970112)
		(width 0.10795)
		(layer "In9.Cu")
		(net "PHY_SCC_A_TO_DRV_A_6_DN")
	)
	(arc
		(start 319.952878 -274.141438)
		(mid 319.979742 -274.181643)
		(end 319.9892 -274.229068)
		(width 0.10795)
		(layer "In9.Cu")
		(net "PHY_SCC_A_TO_DRV_A_6_DN")
	)
	(segment
		(start 191.099186 -273.834098)
		(end 191.636142 -273.834098)
		(width 0.127)
		(layer "F.Cu")
		(net "PHY_SCC_A_TO_DRV_A_5_DP")
	)
	(segment
		(start 229.877874 -327.7616)
		(end 270.62303 -349.52178)
		(width 0.127)
		(layer "F.Cu")
		(net "PHY_SCC_A_TO_DRV_A_5_DP")
	)
	(segment
		(start 270.62303 -349.52178)
		(end 272.26895 -349.52178)
		(width 0.127)
		(layer "F.Cu")
		(net "PHY_SCC_A_TO_DRV_A_5_DP")
	)
	(segment
		(start 225.943414 -325.660258)
		(end 229.878128 -327.7616)
		(width 0.127)
		(layer "F.Cu")
		(net "PHY_SCC_A_TO_DRV_A_5_DP")
	)
	(segment
		(start 229.878128 -327.7616)
		(end 229.877874 -327.7616)
		(width 0.127)
		(layer "F.Cu")
		(net "PHY_SCC_A_TO_DRV_A_5_DP")
	)
	(segment
		(start 225.94316 -325.660004)
		(end 225.943414 -325.660258)
		(width 0.127)
		(layer "F.Cu")
		(net "PHY_SCC_A_TO_DRV_A_5_DP")
	)
	(segment
		(start 272.68805 -349.94088)
		(end 272.68805 -350.378014)
		(width 0.127)
		(layer "F.Cu")
		(net "PHY_SCC_A_TO_DRV_A_5_DP")
	)
	(segment
		(start 190.492888 -273.660616)
		(end 190.925704 -273.660616)
		(width 0.127)
		(layer "F.Cu")
		(net "PHY_SCC_A_TO_DRV_A_5_DP")
	)
	(segment
		(start 190.925704 -273.660616)
		(end 191.099186 -273.834098)
		(width 0.127)
		(layer "F.Cu")
		(net "PHY_SCC_A_TO_DRV_A_5_DP")
	)
	(segment
		(start 225.436938 -325.389748)
		(end 225.94316 -325.660004)
		(width 0.127)
		(layer "F.Cu")
		(net "PHY_SCC_A_TO_DRV_A_5_DP")
	)
	(segment
		(start 191.636142 -273.834098)
		(end 193.61023 -275.085556)
		(width 0.127)
		(layer "F.Cu")
		(net "PHY_SCC_A_TO_DRV_A_5_DP")
	)
	(segment
		(start 272.81505 -350.505014)
		(end 273.1135 -350.505014)
		(width 0.127)
		(layer "F.Cu")
		(net "PHY_SCC_A_TO_DRV_A_5_DP")
	)
	(segment
		(start 193.61023 -275.085556)
		(end 225.436938 -325.389748)
		(width 0.127)
		(layer "F.Cu")
		(net "PHY_SCC_A_TO_DRV_A_5_DP")
	)
	(arc
		(start 272.26895 -349.52178)
		(mid 272.565298 -349.644532)
		(end 272.68805 -349.94088)
		(width 0.127)
		(layer "F.Cu")
		(net "PHY_SCC_A_TO_DRV_A_5_DP")
	)
	(arc
		(start 272.68805 -350.378014)
		(mid 272.725247 -350.467817)
		(end 272.81505 -350.505014)
		(width 0.127)
		(layer "F.Cu")
		(net "PHY_SCC_A_TO_DRV_A_5_DP")
	)
	(segment
		(start 272.68805 -350.175322)
		(end 272.68805 -350.323912)
		(width 0.127)
		(layer "B.Cu")
		(net "PHY_SCC_A_TO_DRV_A_5_DP")
	)
	(segment
		(start 272.869152 -350.505014)
		(end 273.1135 -350.505014)
		(width 0.127)
		(layer "B.Cu")
		(net "PHY_SCC_A_TO_DRV_A_5_DP")
	)
	(segment
		(start 279.636728 -348.70517)
		(end 279.209754 -348.70517)
		(width 0.127)
		(layer "B.Cu")
		(net "PHY_SCC_A_TO_DRV_A_5_DP")
	)
	(segment
		(start 279.082754 -348.83217)
		(end 279.082754 -349.083122)
		(width 0.127)
		(layer "B.Cu")
		(net "PHY_SCC_A_TO_DRV_A_5_DP")
	)
	(segment
		(start 278.329136 -349.751142)
		(end 273.11223 -349.751142)
		(width 0.127)
		(layer "B.Cu")
		(net "PHY_SCC_A_TO_DRV_A_5_DP")
	)
	(arc
		(start 279.082754 -349.083122)
		(mid 279.04852 -349.284315)
		(end 278.949658 -349.462852)
		(width 0.127)
		(layer "B.Cu")
		(net "PHY_SCC_A_TO_DRV_A_5_DP")
	)
	(arc
		(start 273.11223 -349.751142)
		(mid 272.812289 -349.875381)
		(end 272.68805 -350.175322)
		(width 0.127)
		(layer "B.Cu")
		(net "PHY_SCC_A_TO_DRV_A_5_DP")
	)
	(arc
		(start 279.209754 -348.70517)
		(mid 279.119951 -348.742367)
		(end 279.082754 -348.83217)
		(width 0.127)
		(layer "B.Cu")
		(net "PHY_SCC_A_TO_DRV_A_5_DP")
	)
	(arc
		(start 278.9047 -349.513144)
		(mid 278.640599 -349.689425)
		(end 278.329136 -349.751142)
		(width 0.127)
		(layer "B.Cu")
		(net "PHY_SCC_A_TO_DRV_A_5_DP")
	)
	(arc
		(start 278.949658 -349.462852)
		(mid 278.927871 -349.488617)
		(end 278.9047 -349.513144)
		(width 0.127)
		(layer "B.Cu")
		(net "PHY_SCC_A_TO_DRV_A_5_DP")
	)
	(arc
		(start 272.68805 -350.323912)
		(mid 272.741094 -350.45197)
		(end 272.869152 -350.505014)
		(width 0.127)
		(layer "B.Cu")
		(net "PHY_SCC_A_TO_DRV_A_5_DP")
	)
	(segment
		(start 229.135432 -327.696322)
		(end 229.197916 -327.90257)
		(width 0.127)
		(layer "F.Cu")
		(net "PHY_SCC_A_TO_DRV_A_5_DN")
	)
	(segment
		(start 272.39595 -349.94088)
		(end 272.39595 -350.378014)
		(width 0.127)
		(layer "F.Cu")
		(net "PHY_SCC_A_TO_DRV_A_5_DN")
	)
	(segment
		(start 190.492888 -274.219416)
		(end 190.925704 -274.219416)
		(width 0.127)
		(layer "F.Cu")
		(net "PHY_SCC_A_TO_DRV_A_5_DN")
	)
	(segment
		(start 228.79939 -327.516744)
		(end 229.135432 -327.696322)
		(width 0.127)
		(layer "F.Cu")
		(net "PHY_SCC_A_TO_DRV_A_5_DN")
	)
	(segment
		(start 229.74046 -328.01941)
		(end 270.549878 -349.81388)
		(width 0.127)
		(layer "F.Cu")
		(net "PHY_SCC_A_TO_DRV_A_5_DN")
	)
	(segment
		(start 190.925704 -274.219416)
		(end 191.018922 -274.126198)
		(width 0.127)
		(layer "F.Cu")
		(net "PHY_SCC_A_TO_DRV_A_5_DN")
	)
	(segment
		(start 228.2571 -327.399904)
		(end 228.593142 -327.579482)
		(width 0.127)
		(layer "F.Cu")
		(net "PHY_SCC_A_TO_DRV_A_5_DN")
	)
	(segment
		(start 226.91725 -326.511666)
		(end 227.253292 -326.691244)
		(width 0.127)
		(layer "F.Cu")
		(net "PHY_SCC_A_TO_DRV_A_5_DN")
	)
	(segment
		(start 191.018922 -274.126198)
		(end 191.551306 -274.126198)
		(width 0.127)
		(layer "F.Cu")
		(net "PHY_SCC_A_TO_DRV_A_5_DN")
	)
	(segment
		(start 228.194362 -327.193656)
		(end 228.2571 -327.399904)
		(width 0.127)
		(layer "F.Cu")
		(net "PHY_SCC_A_TO_DRV_A_5_DN")
	)
	(segment
		(start 225.231198 -325.611236)
		(end 226.312476 -326.188578)
		(width 0.127)
		(layer "F.Cu")
		(net "PHY_SCC_A_TO_DRV_A_5_DN")
	)
	(segment
		(start 270.549878 -349.81388)
		(end 272.26895 -349.81388)
		(width 0.127)
		(layer "F.Cu")
		(net "PHY_SCC_A_TO_DRV_A_5_DN")
	)
	(segment
		(start 226.312476 -326.188578)
		(end 226.37496 -326.394826)
		(width 0.127)
		(layer "F.Cu")
		(net "PHY_SCC_A_TO_DRV_A_5_DN")
	)
	(segment
		(start 229.197916 -327.90257)
		(end 229.534212 -328.082148)
		(width 0.127)
		(layer "F.Cu")
		(net "PHY_SCC_A_TO_DRV_A_5_DN")
	)
	(segment
		(start 226.711002 -326.574404)
		(end 226.91725 -326.511666)
		(width 0.127)
		(layer "F.Cu")
		(net "PHY_SCC_A_TO_DRV_A_5_DN")
	)
	(segment
		(start 227.652072 -327.076816)
		(end 227.85832 -327.014332)
		(width 0.127)
		(layer "F.Cu")
		(net "PHY_SCC_A_TO_DRV_A_5_DN")
	)
	(segment
		(start 226.37496 -326.394826)
		(end 226.711002 -326.574404)
		(width 0.127)
		(layer "F.Cu")
		(net "PHY_SCC_A_TO_DRV_A_5_DN")
	)
	(segment
		(start 191.551306 -274.126198)
		(end 193.398394 -275.297138)
		(width 0.127)
		(layer "F.Cu")
		(net "PHY_SCC_A_TO_DRV_A_5_DN")
	)
	(segment
		(start 272.26895 -350.505014)
		(end 271.9705 -350.505014)
		(width 0.127)
		(layer "F.Cu")
		(net "PHY_SCC_A_TO_DRV_A_5_DN")
	)
	(segment
		(start 228.593142 -327.579482)
		(end 228.79939 -327.516744)
		(width 0.127)
		(layer "F.Cu")
		(net "PHY_SCC_A_TO_DRV_A_5_DN")
	)
	(segment
		(start 227.253292 -326.691244)
		(end 227.31603 -326.897492)
		(width 0.127)
		(layer "F.Cu")
		(net "PHY_SCC_A_TO_DRV_A_5_DN")
	)
	(segment
		(start 193.398394 -275.297138)
		(end 225.231198 -325.611236)
		(width 0.127)
		(layer "F.Cu")
		(net "PHY_SCC_A_TO_DRV_A_5_DN")
	)
	(segment
		(start 229.534212 -328.082148)
		(end 229.74046 -328.01941)
		(width 0.127)
		(layer "F.Cu")
		(net "PHY_SCC_A_TO_DRV_A_5_DN")
	)
	(segment
		(start 227.31603 -326.897492)
		(end 227.652072 -327.076816)
		(width 0.127)
		(layer "F.Cu")
		(net "PHY_SCC_A_TO_DRV_A_5_DN")
	)
	(segment
		(start 227.85832 -327.014332)
		(end 228.194362 -327.193656)
		(width 0.127)
		(layer "F.Cu")
		(net "PHY_SCC_A_TO_DRV_A_5_DN")
	)
	(arc
		(start 272.39595 -350.378014)
		(mid 272.358753 -350.467817)
		(end 272.26895 -350.505014)
		(width 0.127)
		(layer "F.Cu")
		(net "PHY_SCC_A_TO_DRV_A_5_DN")
	)
	(arc
		(start 272.26895 -349.81388)
		(mid 272.358753 -349.851077)
		(end 272.39595 -349.94088)
		(width 0.127)
		(layer "F.Cu")
		(net "PHY_SCC_A_TO_DRV_A_5_DN")
	)
	(segment
		(start 271.9705 -350.505014)
		(end 272.214848 -350.505014)
		(width 0.127)
		(layer "B.Cu")
		(net "PHY_SCC_A_TO_DRV_A_5_DN")
	)
	(segment
		(start 278.790654 -349.082614)
		(end 278.790654 -348.83217)
		(width 0.127)
		(layer "B.Cu")
		(net "PHY_SCC_A_TO_DRV_A_5_DN")
	)
	(segment
		(start 272.39595 -350.323912)
		(end 272.39595 -350.175322)
		(width 0.127)
		(layer "B.Cu")
		(net "PHY_SCC_A_TO_DRV_A_5_DN")
	)
	(segment
		(start 273.11223 -349.459042)
		(end 278.32939 -349.459042)
		(width 0.127)
		(layer "B.Cu")
		(net "PHY_SCC_A_TO_DRV_A_5_DN")
	)
	(segment
		(start 278.663654 -348.70517)
		(end 278.23668 -348.70517)
		(width 0.127)
		(layer "B.Cu")
		(net "PHY_SCC_A_TO_DRV_A_5_DN")
	)
	(arc
		(start 272.214848 -350.505014)
		(mid 272.342906 -350.45197)
		(end 272.39595 -350.323912)
		(width 0.127)
		(layer "B.Cu")
		(net "PHY_SCC_A_TO_DRV_A_5_DN")
	)
	(arc
		(start 278.721312 -349.280226)
		(mid 278.772819 -349.187327)
		(end 278.790654 -349.082614)
		(width 0.127)
		(layer "B.Cu")
		(net "PHY_SCC_A_TO_DRV_A_5_DN")
	)
	(arc
		(start 278.790654 -348.83217)
		(mid 278.753457 -348.742367)
		(end 278.663654 -348.70517)
		(width 0.127)
		(layer "B.Cu")
		(net "PHY_SCC_A_TO_DRV_A_5_DN")
	)
	(arc
		(start 272.39595 -350.175322)
		(mid 272.605744 -349.668836)
		(end 273.11223 -349.459042)
		(width 0.127)
		(layer "B.Cu")
		(net "PHY_SCC_A_TO_DRV_A_5_DN")
	)
	(arc
		(start 278.32939 -349.459042)
		(mid 278.528848 -349.419367)
		(end 278.697944 -349.306388)
		(width 0.127)
		(layer "B.Cu")
		(net "PHY_SCC_A_TO_DRV_A_5_DN")
	)
	(arc
		(start 278.697944 -349.306388)
		(mid 278.709988 -349.293628)
		(end 278.721312 -349.280226)
		(width 0.127)
		(layer "B.Cu")
		(net "PHY_SCC_A_TO_DRV_A_5_DN")
	)
	(segment
		(start 237.094522 -333.378302)
		(end 270.56334 -351.25787)
		(width 0.127)
		(layer "F.Cu")
		(net "PHY_SCC_A_TO_DRV_A_4_DP")
	)
	(segment
		(start 182.840376 -312.377074)
		(end 237.094522 -333.378302)
		(width 0.127)
		(layer "F.Cu")
		(net "PHY_SCC_A_TO_DRV_A_4_DP")
	)
	(segment
		(start 161.49828 -274.598892)
		(end 169.625264 -296.639234)
		(width 0.127)
		(layer "F.Cu")
		(net "PHY_SCC_A_TO_DRV_A_4_DP")
	)
	(segment
		(start 270.56334 -351.25787)
		(end 272.26895 -351.25787)
		(width 0.127)
		(layer "F.Cu")
		(net "PHY_SCC_A_TO_DRV_A_4_DP")
	)
	(segment
		(start 169.625264 -296.639234)
		(end 177.662586 -309.014622)
		(width 0.127)
		(layer "F.Cu")
		(net "PHY_SCC_A_TO_DRV_A_4_DP")
	)
	(segment
		(start 272.81505 -352.305112)
		(end 273.1135 -352.305112)
		(width 0.127)
		(layer "F.Cu")
		(net "PHY_SCC_A_TO_DRV_A_4_DP")
	)
	(segment
		(start 158.942786 -273.660616)
		(end 159.401002 -273.660616)
		(width 0.127)
		(layer "F.Cu")
		(net "PHY_SCC_A_TO_DRV_A_4_DP")
	)
	(segment
		(start 160.297876 -273.839178)
		(end 161.49828 -274.598892)
		(width 0.127)
		(layer "F.Cu")
		(net "PHY_SCC_A_TO_DRV_A_4_DP")
	)
	(segment
		(start 177.662586 -309.014622)
		(end 182.840376 -312.377074)
		(width 0.127)
		(layer "F.Cu")
		(net "PHY_SCC_A_TO_DRV_A_4_DP")
	)
	(segment
		(start 272.68805 -351.67697)
		(end 272.68805 -352.178112)
		(width 0.127)
		(layer "F.Cu")
		(net "PHY_SCC_A_TO_DRV_A_4_DP")
	)
	(segment
		(start 159.579564 -273.839178)
		(end 160.297876 -273.839178)
		(width 0.127)
		(layer "F.Cu")
		(net "PHY_SCC_A_TO_DRV_A_4_DP")
	)
	(segment
		(start 159.401002 -273.660616)
		(end 159.579564 -273.839178)
		(width 0.127)
		(layer "F.Cu")
		(net "PHY_SCC_A_TO_DRV_A_4_DP")
	)
	(arc
		(start 272.26895 -351.25787)
		(mid 272.565298 -351.380622)
		(end 272.68805 -351.67697)
		(width 0.127)
		(layer "F.Cu")
		(net "PHY_SCC_A_TO_DRV_A_4_DP")
	)
	(arc
		(start 272.68805 -352.178112)
		(mid 272.725247 -352.267915)
		(end 272.81505 -352.305112)
		(width 0.127)
		(layer "F.Cu")
		(net "PHY_SCC_A_TO_DRV_A_4_DP")
	)
	(segment
		(start 273.11223 -351.55124)
		(end 279.329134 -351.55124)
		(width 0.127)
		(layer "B.Cu")
		(net "PHY_SCC_A_TO_DRV_A_4_DP")
	)
	(segment
		(start 272.68805 -352.12401)
		(end 272.68805 -351.97542)
		(width 0.127)
		(layer "B.Cu")
		(net "PHY_SCC_A_TO_DRV_A_4_DP")
	)
	(segment
		(start 280.082752 -350.88322)
		(end 280.082752 -350.632268)
		(width 0.127)
		(layer "B.Cu")
		(net "PHY_SCC_A_TO_DRV_A_4_DP")
	)
	(segment
		(start 273.1135 -352.305112)
		(end 272.869152 -352.305112)
		(width 0.127)
		(layer "B.Cu")
		(net "PHY_SCC_A_TO_DRV_A_4_DP")
	)
	(segment
		(start 280.209752 -350.505268)
		(end 280.636726 -350.505268)
		(width 0.127)
		(layer "B.Cu")
		(net "PHY_SCC_A_TO_DRV_A_4_DP")
	)
	(arc
		(start 279.949656 -351.26295)
		(mid 280.048501 -351.084407)
		(end 280.082752 -350.88322)
		(width 0.127)
		(layer "B.Cu")
		(net "PHY_SCC_A_TO_DRV_A_4_DP")
	)
	(arc
		(start 272.68805 -351.97542)
		(mid 272.812289 -351.675479)
		(end 273.11223 -351.55124)
		(width 0.127)
		(layer "B.Cu")
		(net "PHY_SCC_A_TO_DRV_A_4_DP")
	)
	(arc
		(start 272.869152 -352.305112)
		(mid 272.741094 -352.252068)
		(end 272.68805 -352.12401)
		(width 0.127)
		(layer "B.Cu")
		(net "PHY_SCC_A_TO_DRV_A_4_DP")
	)
	(arc
		(start 279.904698 -351.313242)
		(mid 279.92788 -351.288724)
		(end 279.949656 -351.26295)
		(width 0.127)
		(layer "B.Cu")
		(net "PHY_SCC_A_TO_DRV_A_4_DP")
	)
	(arc
		(start 280.082752 -350.632268)
		(mid 280.119949 -350.542465)
		(end 280.209752 -350.505268)
		(width 0.127)
		(layer "B.Cu")
		(net "PHY_SCC_A_TO_DRV_A_4_DP")
	)
	(arc
		(start 279.329134 -351.55124)
		(mid 279.640578 -351.489477)
		(end 279.904698 -351.313242)
		(width 0.127)
		(layer "B.Cu")
		(net "PHY_SCC_A_TO_DRV_A_4_DP")
	)
	(segment
		(start 235.931202 -333.404972)
		(end 236.286548 -333.542386)
		(width 0.127)
		(layer "F.Cu")
		(net "PHY_SCC_A_TO_DRV_A_4_DN")
	)
	(segment
		(start 233.498898 -332.300072)
		(end 233.854244 -332.437486)
		(width 0.127)
		(layer "F.Cu")
		(net "PHY_SCC_A_TO_DRV_A_4_DN")
	)
	(segment
		(start 272.39595 -351.67697)
		(end 272.39595 -352.178112)
		(width 0.127)
		(layer "F.Cu")
		(net "PHY_SCC_A_TO_DRV_A_4_DN")
	)
	(segment
		(start 169.362374 -296.77106)
		(end 177.451258 -309.22595)
		(width 0.127)
		(layer "F.Cu")
		(net "PHY_SCC_A_TO_DRV_A_4_DN")
	)
	(segment
		(start 236.483652 -333.455264)
		(end 236.972348 -333.644494)
		(width 0.127)
		(layer "F.Cu")
		(net "PHY_SCC_A_TO_DRV_A_4_DN")
	)
	(segment
		(start 177.451258 -309.22595)
		(end 182.710328 -312.64098)
		(width 0.127)
		(layer "F.Cu")
		(net "PHY_SCC_A_TO_DRV_A_4_DN")
	)
	(segment
		(start 272.26895 -352.305112)
		(end 271.9705 -352.305112)
		(width 0.127)
		(layer "F.Cu")
		(net "PHY_SCC_A_TO_DRV_A_4_DN")
	)
	(segment
		(start 235.488734 -333.0702)
		(end 235.84408 -333.207868)
		(width 0.127)
		(layer "F.Cu")
		(net "PHY_SCC_A_TO_DRV_A_4_DN")
	)
	(segment
		(start 235.29163 -333.157322)
		(end 235.488734 -333.0702)
		(width 0.127)
		(layer "F.Cu")
		(net "PHY_SCC_A_TO_DRV_A_4_DN")
	)
	(segment
		(start 182.710328 -312.64098)
		(end 232.859326 -332.052422)
		(width 0.127)
		(layer "F.Cu")
		(net "PHY_SCC_A_TO_DRV_A_4_DN")
	)
	(segment
		(start 232.946448 -332.249526)
		(end 233.301794 -332.387194)
		(width 0.127)
		(layer "F.Cu")
		(net "PHY_SCC_A_TO_DRV_A_4_DN")
	)
	(segment
		(start 234.296712 -332.772258)
		(end 234.493816 -332.685136)
		(width 0.127)
		(layer "F.Cu")
		(net "PHY_SCC_A_TO_DRV_A_4_DN")
	)
	(segment
		(start 234.936284 -333.019908)
		(end 235.29163 -333.157322)
		(width 0.127)
		(layer "F.Cu")
		(net "PHY_SCC_A_TO_DRV_A_4_DN")
	)
	(segment
		(start 233.854244 -332.437486)
		(end 233.941366 -332.63459)
		(width 0.127)
		(layer "F.Cu")
		(net "PHY_SCC_A_TO_DRV_A_4_DN")
	)
	(segment
		(start 159.401002 -274.219416)
		(end 159.48914 -274.131278)
		(width 0.127)
		(layer "F.Cu")
		(net "PHY_SCC_A_TO_DRV_A_4_DN")
	)
	(segment
		(start 158.942786 -274.219416)
		(end 159.401002 -274.219416)
		(width 0.127)
		(layer "F.Cu")
		(net "PHY_SCC_A_TO_DRV_A_4_DN")
	)
	(segment
		(start 236.972348 -333.644494)
		(end 270.490188 -351.54997)
		(width 0.127)
		(layer "F.Cu")
		(net "PHY_SCC_A_TO_DRV_A_4_DN")
	)
	(segment
		(start 270.490188 -351.54997)
		(end 272.26895 -351.54997)
		(width 0.127)
		(layer "F.Cu")
		(net "PHY_SCC_A_TO_DRV_A_4_DN")
	)
	(segment
		(start 233.941366 -332.63459)
		(end 234.296712 -332.772258)
		(width 0.127)
		(layer "F.Cu")
		(net "PHY_SCC_A_TO_DRV_A_4_DN")
	)
	(segment
		(start 233.301794 -332.387194)
		(end 233.498898 -332.300072)
		(width 0.127)
		(layer "F.Cu")
		(net "PHY_SCC_A_TO_DRV_A_4_DN")
	)
	(segment
		(start 160.21304 -274.131278)
		(end 161.25825 -274.792948)
		(width 0.127)
		(layer "F.Cu")
		(net "PHY_SCC_A_TO_DRV_A_4_DN")
	)
	(segment
		(start 234.493816 -332.685136)
		(end 234.849162 -332.82255)
		(width 0.127)
		(layer "F.Cu")
		(net "PHY_SCC_A_TO_DRV_A_4_DN")
	)
	(segment
		(start 236.286548 -333.542386)
		(end 236.483652 -333.455264)
		(width 0.127)
		(layer "F.Cu")
		(net "PHY_SCC_A_TO_DRV_A_4_DN")
	)
	(segment
		(start 234.849162 -332.82255)
		(end 234.936284 -333.019908)
		(width 0.127)
		(layer "F.Cu")
		(net "PHY_SCC_A_TO_DRV_A_4_DN")
	)
	(segment
		(start 235.84408 -333.207868)
		(end 235.931202 -333.404972)
		(width 0.127)
		(layer "F.Cu")
		(net "PHY_SCC_A_TO_DRV_A_4_DN")
	)
	(segment
		(start 161.25825 -274.792948)
		(end 169.362374 -296.77106)
		(width 0.127)
		(layer "F.Cu")
		(net "PHY_SCC_A_TO_DRV_A_4_DN")
	)
	(segment
		(start 159.48914 -274.131278)
		(end 160.21304 -274.131278)
		(width 0.127)
		(layer "F.Cu")
		(net "PHY_SCC_A_TO_DRV_A_4_DN")
	)
	(segment
		(start 232.859326 -332.052422)
		(end 232.946448 -332.249526)
		(width 0.127)
		(layer "F.Cu")
		(net "PHY_SCC_A_TO_DRV_A_4_DN")
	)
	(arc
		(start 272.26895 -351.54997)
		(mid 272.358753 -351.587167)
		(end 272.39595 -351.67697)
		(width 0.127)
		(layer "F.Cu")
		(net "PHY_SCC_A_TO_DRV_A_4_DN")
	)
	(arc
		(start 272.39595 -352.178112)
		(mid 272.358753 -352.267915)
		(end 272.26895 -352.305112)
		(width 0.127)
		(layer "F.Cu")
		(net "PHY_SCC_A_TO_DRV_A_4_DN")
	)
	(segment
		(start 279.790652 -350.882712)
		(end 279.790652 -350.632268)
		(width 0.127)
		(layer "B.Cu")
		(net "PHY_SCC_A_TO_DRV_A_4_DN")
	)
	(segment
		(start 279.663652 -350.505268)
		(end 279.236678 -350.505268)
		(width 0.127)
		(layer "B.Cu")
		(net "PHY_SCC_A_TO_DRV_A_4_DN")
	)
	(segment
		(start 271.9705 -352.305112)
		(end 272.214848 -352.305112)
		(width 0.127)
		(layer "B.Cu")
		(net "PHY_SCC_A_TO_DRV_A_4_DN")
	)
	(segment
		(start 273.11223 -351.25914)
		(end 279.329388 -351.25914)
		(width 0.127)
		(layer "B.Cu")
		(net "PHY_SCC_A_TO_DRV_A_4_DN")
	)
	(segment
		(start 272.39595 -352.12401)
		(end 272.39595 -351.97542)
		(width 0.127)
		(layer "B.Cu")
		(net "PHY_SCC_A_TO_DRV_A_4_DN")
	)
	(arc
		(start 279.697942 -351.106486)
		(mid 279.709986 -351.093726)
		(end 279.72131 -351.080324)
		(width 0.127)
		(layer "B.Cu")
		(net "PHY_SCC_A_TO_DRV_A_4_DN")
	)
	(arc
		(start 279.329388 -351.25914)
		(mid 279.528846 -351.219465)
		(end 279.697942 -351.106486)
		(width 0.127)
		(layer "B.Cu")
		(net "PHY_SCC_A_TO_DRV_A_4_DN")
	)
	(arc
		(start 279.72131 -351.080324)
		(mid 279.772817 -350.987425)
		(end 279.790652 -350.882712)
		(width 0.127)
		(layer "B.Cu")
		(net "PHY_SCC_A_TO_DRV_A_4_DN")
	)
	(arc
		(start 272.214848 -352.305112)
		(mid 272.342906 -352.252068)
		(end 272.39595 -352.12401)
		(width 0.127)
		(layer "B.Cu")
		(net "PHY_SCC_A_TO_DRV_A_4_DN")
	)
	(arc
		(start 279.790652 -350.632268)
		(mid 279.753455 -350.542465)
		(end 279.663652 -350.505268)
		(width 0.127)
		(layer "B.Cu")
		(net "PHY_SCC_A_TO_DRV_A_4_DN")
	)
	(arc
		(start 272.39595 -351.97542)
		(mid 272.605744 -351.468934)
		(end 273.11223 -351.25914)
		(width 0.127)
		(layer "B.Cu")
		(net "PHY_SCC_A_TO_DRV_A_4_DN")
	)
	(segment
		(start 478.773998 -43.660568)
		(end 479.105214 -43.660568)
		(width 0.127)
		(layer "F.Cu")
		(net "PHY_SCC_A_TO_DRV_A_35_DP")
	)
	(segment
		(start 477.776286 -43.744896)
		(end 477.788224 -43.756834)
		(width 0.127)
		(layer "F.Cu")
		(net "PHY_SCC_A_TO_DRV_A_35_DP")
	)
	(segment
		(start 477.877886 -43.793918)
		(end 478.640648 -43.793918)
		(width 0.127)
		(layer "F.Cu")
		(net "PHY_SCC_A_TO_DRV_A_35_DP")
	)
	(segment
		(start 477.739202 -43.368468)
		(end 477.739202 -43.655234)
		(width 0.127)
		(layer "F.Cu")
		(net "PHY_SCC_A_TO_DRV_A_35_DP")
	)
	(segment
		(start 478.640648 -43.793918)
		(end 478.773998 -43.660568)
		(width 0.127)
		(layer "F.Cu")
		(net "PHY_SCC_A_TO_DRV_A_35_DP")
	)
	(arc
		(start 477.788224 -43.756834)
		(mid 477.829375 -43.784267)
		(end 477.877886 -43.793918)
		(width 0.127)
		(layer "F.Cu")
		(net "PHY_SCC_A_TO_DRV_A_35_DP")
	)
	(arc
		(start 477.739202 -43.655234)
		(mid 477.748835 -43.703752)
		(end 477.776286 -43.744896)
		(width 0.127)
		(layer "F.Cu")
		(net "PHY_SCC_A_TO_DRV_A_35_DP")
	)
	(segment
		(start 373.902732 -95.114872)
		(end 397.46682 -79.811118)
		(width 0.10795)
		(layer "In9.Cu")
		(net "PHY_SCC_A_TO_DRV_A_35_DP")
	)
	(segment
		(start 298.209462 -297.868848)
		(end 298.388278 -297.598846)
		(width 0.10795)
		(layer "In9.Cu")
		(net "PHY_SCC_A_TO_DRV_A_35_DP")
	)
	(segment
		(start 280.138886 -304.335688)
		(end 280.206196 -304.402998)
		(width 0.10795)
		(layer "In9.Cu")
		(net "PHY_SCC_A_TO_DRV_A_35_DP")
	)
	(segment
		(start 297.501056 -299.318934)
		(end 297.679872 -299.048678)
		(width 0.10795)
		(layer "In9.Cu")
		(net "PHY_SCC_A_TO_DRV_A_35_DP")
	)
	(segment
		(start 297.679872 -299.048678)
		(end 297.62069 -298.758356)
		(width 0.10795)
		(layer "In9.Cu")
		(net "PHY_SCC_A_TO_DRV_A_35_DP")
	)
	(segment
		(start 316.167008 -160.09239)
		(end 350.320102 -110.430564)
		(width 0.10795)
		(layer "In9.Cu")
		(net "PHY_SCC_A_TO_DRV_A_35_DP")
	)
	(segment
		(start 476.8469 -43.774868)
		(end 477.619568 -43.774868)
		(width 0.10795)
		(layer "In9.Cu")
		(net "PHY_SCC_A_TO_DRV_A_35_DP")
	)
	(segment
		(start 297.031918 -299.647864)
		(end 297.210734 -299.377862)
		(width 0.10795)
		(layer "In9.Cu")
		(net "PHY_SCC_A_TO_DRV_A_35_DP")
	)
	(segment
		(start 298.6786 -297.539664)
		(end 304.525172 -288.706814)
		(width 0.10795)
		(layer "In9.Cu")
		(net "PHY_SCC_A_TO_DRV_A_35_DP")
	)
	(segment
		(start 397.46682 -79.811118)
		(end 443.388496 -64.823086)
		(width 0.10795)
		(layer "In9.Cu")
		(net "PHY_SCC_A_TO_DRV_A_35_DP")
	)
	(segment
		(start 298.268644 -298.15917)
		(end 298.209462 -297.868848)
		(width 0.10795)
		(layer "In9.Cu")
		(net "PHY_SCC_A_TO_DRV_A_35_DP")
	)
	(segment
		(start 280.636726 -303.70526)
		(end 280.234644 -303.70526)
		(width 0.10795)
		(layer "In9.Cu")
		(net "PHY_SCC_A_TO_DRV_A_35_DP")
	)
	(segment
		(start 280.101802 -303.838102)
		(end 280.101802 -304.246026)
		(width 0.10795)
		(layer "In9.Cu")
		(net "PHY_SCC_A_TO_DRV_A_35_DP")
	)
	(segment
		(start 298.089828 -298.429172)
		(end 298.268644 -298.15917)
		(width 0.10795)
		(layer "In9.Cu")
		(net "PHY_SCC_A_TO_DRV_A_35_DP")
	)
	(segment
		(start 309.562754 -265.981942)
		(end 314.600844 -243.256816)
		(width 0.10795)
		(layer "In9.Cu")
		(net "PHY_SCC_A_TO_DRV_A_35_DP")
	)
	(segment
		(start 448.28333 -60.884816)
		(end 448.283584 -60.884562)
		(width 0.10795)
		(layer "In9.Cu")
		(net "PHY_SCC_A_TO_DRV_A_35_DP")
	)
	(segment
		(start 288.83737 -304.440082)
		(end 291.03701 -303.951894)
		(width 0.10795)
		(layer "In9.Cu")
		(net "PHY_SCC_A_TO_DRV_A_35_DP")
	)
	(segment
		(start 477.739202 -43.655234)
		(end 477.739202 -43.368468)
		(width 0.10795)
		(layer "In9.Cu")
		(net "PHY_SCC_A_TO_DRV_A_35_DP")
	)
	(segment
		(start 280.144982 -303.742344)
		(end 280.138886 -303.74844)
		(width 0.10795)
		(layer "In9.Cu")
		(net "PHY_SCC_A_TO_DRV_A_35_DP")
	)
	(segment
		(start 314.600844 -243.256816)
		(end 306.166774 -205.204314)
		(width 0.10795)
		(layer "In9.Cu")
		(net "PHY_SCC_A_TO_DRV_A_35_DP")
	)
	(segment
		(start 304.525172 -288.706814)
		(end 309.562754 -265.981942)
		(width 0.10795)
		(layer "In9.Cu")
		(net "PHY_SCC_A_TO_DRV_A_35_DP")
	)
	(segment
		(start 463.06359 -48.99279)
		(end 476.8469 -43.774868)
		(width 0.10795)
		(layer "In9.Cu")
		(net "PHY_SCC_A_TO_DRV_A_35_DP")
	)
	(segment
		(start 306.166774 -205.204314)
		(end 316.167008 -160.09239)
		(width 0.10795)
		(layer "In9.Cu")
		(net "PHY_SCC_A_TO_DRV_A_35_DP")
	)
	(segment
		(start 297.62069 -298.758356)
		(end 297.799506 -298.488354)
		(width 0.10795)
		(layer "In9.Cu")
		(net "PHY_SCC_A_TO_DRV_A_35_DP")
	)
	(segment
		(start 280.295858 -304.440082)
		(end 288.83737 -304.440082)
		(width 0.10795)
		(layer "In9.Cu")
		(net "PHY_SCC_A_TO_DRV_A_35_DP")
	)
	(segment
		(start 297.799506 -298.488354)
		(end 298.089828 -298.429172)
		(width 0.10795)
		(layer "In9.Cu")
		(net "PHY_SCC_A_TO_DRV_A_35_DP")
	)
	(segment
		(start 350.320102 -110.430564)
		(end 373.902732 -95.114872)
		(width 0.10795)
		(layer "In9.Cu")
		(net "PHY_SCC_A_TO_DRV_A_35_DP")
	)
	(segment
		(start 296.912284 -300.208442)
		(end 297.0911 -299.93844)
		(width 0.10795)
		(layer "In9.Cu")
		(net "PHY_SCC_A_TO_DRV_A_35_DP")
	)
	(segment
		(start 448.283584 -60.884562)
		(end 463.06359 -48.99279)
		(width 0.10795)
		(layer "In9.Cu")
		(net "PHY_SCC_A_TO_DRV_A_35_DP")
	)
	(segment
		(start 298.388278 -297.598846)
		(end 298.6786 -297.539664)
		(width 0.10795)
		(layer "In9.Cu")
		(net "PHY_SCC_A_TO_DRV_A_35_DP")
	)
	(segment
		(start 443.388496 -64.823086)
		(end 448.28333 -60.884816)
		(width 0.10795)
		(layer "In9.Cu")
		(net "PHY_SCC_A_TO_DRV_A_35_DP")
	)
	(segment
		(start 297.0911 -299.93844)
		(end 297.031918 -299.647864)
		(width 0.10795)
		(layer "In9.Cu")
		(net "PHY_SCC_A_TO_DRV_A_35_DP")
	)
	(segment
		(start 291.03701 -303.951894)
		(end 296.912284 -300.208442)
		(width 0.10795)
		(layer "In9.Cu")
		(net "PHY_SCC_A_TO_DRV_A_35_DP")
	)
	(segment
		(start 297.210734 -299.377862)
		(end 297.501056 -299.318934)
		(width 0.10795)
		(layer "In9.Cu")
		(net "PHY_SCC_A_TO_DRV_A_35_DP")
	)
	(arc
		(start 280.234644 -303.70526)
		(mid 280.186126 -303.714893)
		(end 280.144982 -303.742344)
		(width 0.10795)
		(layer "In9.Cu")
		(net "PHY_SCC_A_TO_DRV_A_35_DP")
	)
	(arc
		(start 477.70415 -43.739816)
		(mid 477.73008 -43.701009)
		(end 477.739202 -43.655234)
		(width 0.10795)
		(layer "In9.Cu")
		(net "PHY_SCC_A_TO_DRV_A_35_DP")
	)
	(arc
		(start 280.206196 -304.402998)
		(mid 280.247347 -304.430431)
		(end 280.295858 -304.440082)
		(width 0.10795)
		(layer "In9.Cu")
		(net "PHY_SCC_A_TO_DRV_A_35_DP")
	)
	(arc
		(start 477.619568 -43.774868)
		(mid 477.66535 -43.765761)
		(end 477.70415 -43.739816)
		(width 0.10795)
		(layer "In9.Cu")
		(net "PHY_SCC_A_TO_DRV_A_35_DP")
	)
	(arc
		(start 280.138886 -303.74844)
		(mid 280.111453 -303.789591)
		(end 280.101802 -303.838102)
		(width 0.10795)
		(layer "In9.Cu")
		(net "PHY_SCC_A_TO_DRV_A_35_DP")
	)
	(arc
		(start 280.101802 -304.246026)
		(mid 280.111435 -304.294544)
		(end 280.138886 -304.335688)
		(width 0.10795)
		(layer "In9.Cu")
		(net "PHY_SCC_A_TO_DRV_A_35_DP")
	)
	(segment
		(start 478.640648 -44.086018)
		(end 478.773998 -44.219368)
		(width 0.127)
		(layer "F.Cu")
		(net "PHY_SCC_A_TO_DRV_A_35_DN")
	)
	(segment
		(start 477.89338 -44.086018)
		(end 478.640648 -44.086018)
		(width 0.127)
		(layer "F.Cu")
		(net "PHY_SCC_A_TO_DRV_A_35_DN")
	)
	(segment
		(start 477.739202 -44.511468)
		(end 477.739202 -44.240196)
		(width 0.127)
		(layer "F.Cu")
		(net "PHY_SCC_A_TO_DRV_A_35_DN")
	)
	(segment
		(start 478.773998 -44.219368)
		(end 479.105214 -44.219368)
		(width 0.127)
		(layer "F.Cu")
		(net "PHY_SCC_A_TO_DRV_A_35_DN")
	)
	(segment
		(start 477.776286 -44.150534)
		(end 477.803718 -44.123102)
		(width 0.127)
		(layer "F.Cu")
		(net "PHY_SCC_A_TO_DRV_A_35_DN")
	)
	(arc
		(start 477.739202 -44.240196)
		(mid 477.748835 -44.191678)
		(end 477.776286 -44.150534)
		(width 0.127)
		(layer "F.Cu")
		(net "PHY_SCC_A_TO_DRV_A_35_DN")
	)
	(arc
		(start 477.803718 -44.123102)
		(mid 477.844869 -44.095669)
		(end 477.89338 -44.086018)
		(width 0.127)
		(layer "F.Cu")
		(net "PHY_SCC_A_TO_DRV_A_35_DN")
	)
	(segment
		(start 304.83429 -288.838132)
		(end 312.404252 -254.69088)
		(width 0.10795)
		(layer "In9.Cu")
		(net "PHY_SCC_A_TO_DRV_A_35_DN")
	)
	(segment
		(start 312.404252 -254.69088)
		(end 314.939172 -243.256816)
		(width 0.10795)
		(layer "In9.Cu")
		(net "PHY_SCC_A_TO_DRV_A_35_DN")
	)
	(segment
		(start 279.728422 -303.742344)
		(end 279.734518 -303.74844)
		(width 0.10795)
		(layer "In9.Cu")
		(net "PHY_SCC_A_TO_DRV_A_35_DN")
	)
	(segment
		(start 280.295858 -304.770282)
		(end 288.873692 -304.770282)
		(width 0.10795)
		(layer "In9.Cu")
		(net "PHY_SCC_A_TO_DRV_A_35_DN")
	)
	(segment
		(start 463.229706 -49.283112)
		(end 476.907352 -44.105068)
		(width 0.10795)
		(layer "In9.Cu")
		(net "PHY_SCC_A_TO_DRV_A_35_DN")
	)
	(segment
		(start 297.149012 -300.449234)
		(end 304.83429 -288.838132)
		(width 0.10795)
		(layer "In9.Cu")
		(net "PHY_SCC_A_TO_DRV_A_35_DN")
	)
	(segment
		(start 476.907352 -44.105068)
		(end 477.619568 -44.105068)
		(width 0.10795)
		(layer "In9.Cu")
		(net "PHY_SCC_A_TO_DRV_A_35_DN")
	)
	(segment
		(start 279.236678 -303.70526)
		(end 279.63876 -303.70526)
		(width 0.10795)
		(layer "In9.Cu")
		(net "PHY_SCC_A_TO_DRV_A_35_DN")
	)
	(segment
		(start 397.610584 -80.111854)
		(end 443.548516 -65.118234)
		(width 0.10795)
		(layer "In9.Cu")
		(net "PHY_SCC_A_TO_DRV_A_35_DN")
	)
	(segment
		(start 314.939172 -243.256816)
		(end 306.505102 -205.204314)
		(width 0.10795)
		(layer "In9.Cu")
		(net "PHY_SCC_A_TO_DRV_A_35_DN")
	)
	(segment
		(start 350.555052 -110.671864)
		(end 397.610584 -80.111854)
		(width 0.10795)
		(layer "In9.Cu")
		(net "PHY_SCC_A_TO_DRV_A_35_DN")
	)
	(segment
		(start 279.905206 -304.569114)
		(end 279.97277 -304.636678)
		(width 0.10795)
		(layer "In9.Cu")
		(net "PHY_SCC_A_TO_DRV_A_35_DN")
	)
	(segment
		(start 443.548516 -65.118234)
		(end 463.229706 -49.283112)
		(width 0.10795)
		(layer "In9.Cu")
		(net "PHY_SCC_A_TO_DRV_A_35_DN")
	)
	(segment
		(start 288.873692 -304.770282)
		(end 291.165534 -304.261774)
		(width 0.10795)
		(layer "In9.Cu")
		(net "PHY_SCC_A_TO_DRV_A_35_DN")
	)
	(segment
		(start 291.165534 -304.261774)
		(end 297.149012 -300.449234)
		(width 0.10795)
		(layer "In9.Cu")
		(net "PHY_SCC_A_TO_DRV_A_35_DN")
	)
	(segment
		(start 477.739202 -44.224702)
		(end 477.739202 -44.511468)
		(width 0.10795)
		(layer "In9.Cu")
		(net "PHY_SCC_A_TO_DRV_A_35_DN")
	)
	(segment
		(start 316.475618 -160.226756)
		(end 350.555052 -110.671864)
		(width 0.10795)
		(layer "In9.Cu")
		(net "PHY_SCC_A_TO_DRV_A_35_DN")
	)
	(segment
		(start 306.505102 -205.204314)
		(end 316.475618 -160.226756)
		(width 0.10795)
		(layer "In9.Cu")
		(net "PHY_SCC_A_TO_DRV_A_35_DN")
	)
	(segment
		(start 279.771602 -303.838102)
		(end 279.771602 -304.246026)
		(width 0.10795)
		(layer "In9.Cu")
		(net "PHY_SCC_A_TO_DRV_A_35_DN")
	)
	(arc
		(start 477.70415 -44.14012)
		(mid 477.73008 -44.178927)
		(end 477.739202 -44.224702)
		(width 0.10795)
		(layer "In9.Cu")
		(net "PHY_SCC_A_TO_DRV_A_35_DN")
	)
	(arc
		(start 477.619568 -44.105068)
		(mid 477.66535 -44.114175)
		(end 477.70415 -44.14012)
		(width 0.10795)
		(layer "In9.Cu")
		(net "PHY_SCC_A_TO_DRV_A_35_DN")
	)
	(arc
		(start 279.63876 -303.70526)
		(mid 279.687278 -303.714893)
		(end 279.728422 -303.742344)
		(width 0.10795)
		(layer "In9.Cu")
		(net "PHY_SCC_A_TO_DRV_A_35_DN")
	)
	(arc
		(start 279.97277 -304.636678)
		(mid 280.121047 -304.735564)
		(end 280.295858 -304.770282)
		(width 0.10795)
		(layer "In9.Cu")
		(net "PHY_SCC_A_TO_DRV_A_35_DN")
	)
	(arc
		(start 279.734518 -303.74844)
		(mid 279.761951 -303.789591)
		(end 279.771602 -303.838102)
		(width 0.10795)
		(layer "In9.Cu")
		(net "PHY_SCC_A_TO_DRV_A_35_DN")
	)
	(arc
		(start 279.771602 -304.246026)
		(mid 279.806321 -304.420837)
		(end 279.905206 -304.569114)
		(width 0.10795)
		(layer "In9.Cu")
		(net "PHY_SCC_A_TO_DRV_A_35_DN")
	)
	(segment
		(start 446.1891 -43.368468)
		(end 446.1891 -43.654472)
		(width 0.127)
		(layer "F.Cu")
		(net "PHY_SCC_A_TO_DRV_A_34_DP")
	)
	(segment
		(start 447.090546 -43.793918)
		(end 447.223896 -43.660568)
		(width 0.127)
		(layer "F.Cu")
		(net "PHY_SCC_A_TO_DRV_A_34_DP")
	)
	(segment
		(start 446.328546 -43.793918)
		(end 447.090546 -43.793918)
		(width 0.127)
		(layer "F.Cu")
		(net "PHY_SCC_A_TO_DRV_A_34_DP")
	)
	(segment
		(start 446.226184 -43.744134)
		(end 446.238884 -43.756834)
		(width 0.127)
		(layer "F.Cu")
		(net "PHY_SCC_A_TO_DRV_A_34_DP")
	)
	(segment
		(start 447.223896 -43.660568)
		(end 447.555112 -43.660568)
		(width 0.127)
		(layer "F.Cu")
		(net "PHY_SCC_A_TO_DRV_A_34_DP")
	)
	(arc
		(start 446.238884 -43.756834)
		(mid 446.280035 -43.784267)
		(end 446.328546 -43.793918)
		(width 0.127)
		(layer "F.Cu")
		(net "PHY_SCC_A_TO_DRV_A_34_DP")
	)
	(arc
		(start 446.1891 -43.654472)
		(mid 446.198733 -43.70299)
		(end 446.226184 -43.744134)
		(width 0.127)
		(layer "F.Cu")
		(net "PHY_SCC_A_TO_DRV_A_34_DP")
	)
	(segment
		(start 445.040258 -43.774868)
		(end 433.126388 -47.663608)
		(width 0.10795)
		(layer "In9.Cu")
		(net "PHY_SCC_A_TO_DRV_A_34_DP")
	)
	(segment
		(start 295.035224 -299.479462)
		(end 293.111936 -300.705266)
		(width 0.10795)
		(layer "In9.Cu")
		(net "PHY_SCC_A_TO_DRV_A_34_DP")
	)
	(segment
		(start 303.024032 -287.7566)
		(end 297.198542 -296.5577)
		(width 0.10795)
		(layer "In9.Cu")
		(net "PHY_SCC_A_TO_DRV_A_34_DP")
	)
	(segment
		(start 296.020998 -298.33697)
		(end 295.730676 -298.395898)
		(width 0.10795)
		(layer "In9.Cu")
		(net "PHY_SCC_A_TO_DRV_A_34_DP")
	)
	(segment
		(start 296.90822 -296.616882)
		(end 296.729404 -296.886884)
		(width 0.10795)
		(layer "In9.Cu")
		(net "PHY_SCC_A_TO_DRV_A_34_DP")
	)
	(segment
		(start 296.140632 -297.776392)
		(end 296.199814 -298.066714)
		(width 0.10795)
		(layer "In9.Cu")
		(net "PHY_SCC_A_TO_DRV_A_34_DP")
	)
	(segment
		(start 314.69584 -159.090614)
		(end 304.11166 -206.82966)
		(width 0.10795)
		(layer "In9.Cu")
		(net "PHY_SCC_A_TO_DRV_A_34_DP")
	)
	(segment
		(start 297.198542 -296.5577)
		(end 296.90822 -296.616882)
		(width 0.10795)
		(layer "In9.Cu")
		(net "PHY_SCC_A_TO_DRV_A_34_DP")
	)
	(segment
		(start 295.730676 -298.395898)
		(end 295.55186 -298.6659)
		(width 0.10795)
		(layer "In9.Cu")
		(net "PHY_SCC_A_TO_DRV_A_34_DP")
	)
	(segment
		(start 295.611042 -298.956476)
		(end 295.432226 -299.226478)
		(width 0.10795)
		(layer "In9.Cu")
		(net "PHY_SCC_A_TO_DRV_A_34_DP")
	)
	(segment
		(start 279.101804 -302.475646)
		(end 279.101804 -302.042322)
		(width 0.10795)
		(layer "In9.Cu")
		(net "PHY_SCC_A_TO_DRV_A_34_DP")
	)
	(segment
		(start 279.17648 -302.6029)
		(end 279.138888 -302.565308)
		(width 0.10795)
		(layer "In9.Cu")
		(net "PHY_SCC_A_TO_DRV_A_34_DP")
	)
	(segment
		(start 433.126388 -47.663608)
		(end 391.047478 -81.520284)
		(width 0.10795)
		(layer "In9.Cu")
		(net "PHY_SCC_A_TO_DRV_A_34_DP")
	)
	(segment
		(start 295.432226 -299.226478)
		(end 295.035224 -299.479462)
		(width 0.10795)
		(layer "In9.Cu")
		(net "PHY_SCC_A_TO_DRV_A_34_DP")
	)
	(segment
		(start 279.238964 -301.905162)
		(end 279.636728 -301.905162)
		(width 0.10795)
		(layer "In9.Cu")
		(net "PHY_SCC_A_TO_DRV_A_34_DP")
	)
	(segment
		(start 293.111936 -300.705266)
		(end 290.792154 -302.184054)
		(width 0.10795)
		(layer "In9.Cu")
		(net "PHY_SCC_A_TO_DRV_A_34_DP")
	)
	(segment
		(start 296.788586 -297.177206)
		(end 296.60977 -297.447208)
		(width 0.10795)
		(layer "In9.Cu")
		(net "PHY_SCC_A_TO_DRV_A_34_DP")
	)
	(segment
		(start 446.1891 -43.368468)
		(end 446.1891 -43.655234)
		(width 0.10795)
		(layer "In9.Cu")
		(net "PHY_SCC_A_TO_DRV_A_34_DP")
	)
	(segment
		(start 446.069466 -43.774868)
		(end 445.040258 -43.774868)
		(width 0.10795)
		(layer "In9.Cu")
		(net "PHY_SCC_A_TO_DRV_A_34_DP")
	)
	(segment
		(start 296.319448 -297.50639)
		(end 296.140632 -297.776392)
		(width 0.10795)
		(layer "In9.Cu")
		(net "PHY_SCC_A_TO_DRV_A_34_DP")
	)
	(segment
		(start 296.729404 -296.886884)
		(end 296.788586 -297.177206)
		(width 0.10795)
		(layer "In9.Cu")
		(net "PHY_SCC_A_TO_DRV_A_34_DP")
	)
	(segment
		(start 290.792154 -302.184054)
		(end 288.736278 -302.639984)
		(width 0.10795)
		(layer "In9.Cu")
		(net "PHY_SCC_A_TO_DRV_A_34_DP")
	)
	(segment
		(start 288.736278 -302.639984)
		(end 279.266142 -302.639984)
		(width 0.10795)
		(layer "In9.Cu")
		(net "PHY_SCC_A_TO_DRV_A_34_DP")
	)
	(segment
		(start 296.199814 -298.066714)
		(end 296.020998 -298.33697)
		(width 0.10795)
		(layer "In9.Cu")
		(net "PHY_SCC_A_TO_DRV_A_34_DP")
	)
	(segment
		(start 312.538872 -244.845586)
		(end 303.024032 -287.7566)
		(width 0.10795)
		(layer "In9.Cu")
		(net "PHY_SCC_A_TO_DRV_A_34_DP")
	)
	(segment
		(start 295.55186 -298.6659)
		(end 295.611042 -298.956476)
		(width 0.10795)
		(layer "In9.Cu")
		(net "PHY_SCC_A_TO_DRV_A_34_DP")
	)
	(segment
		(start 391.047478 -81.520284)
		(end 349.547688 -108.469938)
		(width 0.10795)
		(layer "In9.Cu")
		(net "PHY_SCC_A_TO_DRV_A_34_DP")
	)
	(segment
		(start 296.60977 -297.447208)
		(end 296.319448 -297.50639)
		(width 0.10795)
		(layer "In9.Cu")
		(net "PHY_SCC_A_TO_DRV_A_34_DP")
	)
	(segment
		(start 279.138888 -301.95266)
		(end 279.149302 -301.942246)
		(width 0.10795)
		(layer "In9.Cu")
		(net "PHY_SCC_A_TO_DRV_A_34_DP")
	)
	(segment
		(start 304.11166 -206.82966)
		(end 312.538872 -244.845586)
		(width 0.10795)
		(layer "In9.Cu")
		(net "PHY_SCC_A_TO_DRV_A_34_DP")
	)
	(segment
		(start 349.547688 -108.469938)
		(end 314.69584 -159.090614)
		(width 0.10795)
		(layer "In9.Cu")
		(net "PHY_SCC_A_TO_DRV_A_34_DP")
	)
	(arc
		(start 279.149302 -301.942246)
		(mid 279.190453 -301.914813)
		(end 279.238964 -301.905162)
		(width 0.10795)
		(layer "In9.Cu")
		(net "PHY_SCC_A_TO_DRV_A_34_DP")
	)
	(arc
		(start 446.154048 -43.739816)
		(mid 446.115241 -43.765746)
		(end 446.069466 -43.774868)
		(width 0.10795)
		(layer "In9.Cu")
		(net "PHY_SCC_A_TO_DRV_A_34_DP")
	)
	(arc
		(start 279.138888 -302.565308)
		(mid 279.111455 -302.524157)
		(end 279.101804 -302.475646)
		(width 0.10795)
		(layer "In9.Cu")
		(net "PHY_SCC_A_TO_DRV_A_34_DP")
	)
	(arc
		(start 446.1891 -43.655234)
		(mid 446.179993 -43.701016)
		(end 446.154048 -43.739816)
		(width 0.10795)
		(layer "In9.Cu")
		(net "PHY_SCC_A_TO_DRV_A_34_DP")
	)
	(arc
		(start 279.266142 -302.639984)
		(mid 279.217624 -302.630351)
		(end 279.17648 -302.6029)
		(width 0.10795)
		(layer "In9.Cu")
		(net "PHY_SCC_A_TO_DRV_A_34_DP")
	)
	(arc
		(start 279.101804 -302.042322)
		(mid 279.111437 -301.993804)
		(end 279.138888 -301.95266)
		(width 0.10795)
		(layer "In9.Cu")
		(net "PHY_SCC_A_TO_DRV_A_34_DP")
	)
	(segment
		(start 447.090546 -44.086018)
		(end 447.223896 -44.219368)
		(width 0.127)
		(layer "F.Cu")
		(net "PHY_SCC_A_TO_DRV_A_34_DN")
	)
	(segment
		(start 446.357248 -44.086018)
		(end 447.090546 -44.086018)
		(width 0.127)
		(layer "F.Cu")
		(net "PHY_SCC_A_TO_DRV_A_34_DN")
	)
	(segment
		(start 447.223896 -44.219368)
		(end 447.555112 -44.219368)
		(width 0.127)
		(layer "F.Cu")
		(net "PHY_SCC_A_TO_DRV_A_34_DN")
	)
	(segment
		(start 446.1891 -44.511468)
		(end 446.1891 -44.254166)
		(width 0.127)
		(layer "F.Cu")
		(net "PHY_SCC_A_TO_DRV_A_34_DN")
	)
	(segment
		(start 446.226184 -44.164504)
		(end 446.267586 -44.123102)
		(width 0.127)
		(layer "F.Cu")
		(net "PHY_SCC_A_TO_DRV_A_34_DN")
	)
	(arc
		(start 446.267586 -44.123102)
		(mid 446.308737 -44.095669)
		(end 446.357248 -44.086018)
		(width 0.127)
		(layer "F.Cu")
		(net "PHY_SCC_A_TO_DRV_A_34_DN")
	)
	(arc
		(start 446.1891 -44.254166)
		(mid 446.198733 -44.205648)
		(end 446.226184 -44.164504)
		(width 0.127)
		(layer "F.Cu")
		(net "PHY_SCC_A_TO_DRV_A_34_DN")
	)
	(segment
		(start 439.189622 -46.032166)
		(end 439.189622 -46.031912)
		(width 0.10795)
		(layer "In9.Cu")
		(net "PHY_SCC_A_TO_DRV_A_34_DN")
	)
	(segment
		(start 349.782638 -108.711238)
		(end 331.549756 -135.193532)
		(width 0.10795)
		(layer "In9.Cu")
		(net "PHY_SCC_A_TO_DRV_A_34_DN")
	)
	(segment
		(start 290.920424 -302.493934)
		(end 288.7726 -302.970184)
		(width 0.10795)
		(layer "In9.Cu")
		(net "PHY_SCC_A_TO_DRV_A_34_DN")
	)
	(segment
		(start 331.549756 -135.193532)
		(end 315.00445 -159.22498)
		(width 0.10795)
		(layer "In9.Cu")
		(net "PHY_SCC_A_TO_DRV_A_34_DN")
	)
	(segment
		(start 278.634444 -301.905162)
		(end 278.23668 -301.905162)
		(width 0.10795)
		(layer "In9.Cu")
		(net "PHY_SCC_A_TO_DRV_A_34_DN")
	)
	(segment
		(start 446.069466 -44.105068)
		(end 445.092836 -44.105068)
		(width 0.10795)
		(layer "In9.Cu")
		(net "PHY_SCC_A_TO_DRV_A_34_DN")
	)
	(segment
		(start 295.668954 -299.46727)
		(end 290.920424 -302.493934)
		(width 0.10795)
		(layer "In9.Cu")
		(net "PHY_SCC_A_TO_DRV_A_34_DN")
	)
	(segment
		(start 312.8772 -244.845586)
		(end 303.33315 -287.887918)
		(width 0.10795)
		(layer "In9.Cu")
		(net "PHY_SCC_A_TO_DRV_A_34_DN")
	)
	(segment
		(start 278.73452 -301.95266)
		(end 278.724106 -301.942246)
		(width 0.10795)
		(layer "In9.Cu")
		(net "PHY_SCC_A_TO_DRV_A_34_DN")
	)
	(segment
		(start 304.449988 -206.82966)
		(end 312.8772 -244.845586)
		(width 0.10795)
		(layer "In9.Cu")
		(net "PHY_SCC_A_TO_DRV_A_34_DN")
	)
	(segment
		(start 314.699396 -160.601152)
		(end 304.449988 -206.82966)
		(width 0.10795)
		(layer "In9.Cu")
		(net "PHY_SCC_A_TO_DRV_A_34_DN")
	)
	(segment
		(start 433.286408 -47.958756)
		(end 391.241534 -81.788254)
		(width 0.10795)
		(layer "In9.Cu")
		(net "PHY_SCC_A_TO_DRV_A_34_DN")
	)
	(segment
		(start 288.7726 -302.970184)
		(end 279.266142 -302.970184)
		(width 0.10795)
		(layer "In9.Cu")
		(net "PHY_SCC_A_TO_DRV_A_34_DN")
	)
	(segment
		(start 278.771604 -302.475646)
		(end 278.771604 -302.042322)
		(width 0.10795)
		(layer "In9.Cu")
		(net "PHY_SCC_A_TO_DRV_A_34_DN")
	)
	(segment
		(start 446.1891 -44.511468)
		(end 446.1891 -44.224702)
		(width 0.10795)
		(layer "In9.Cu")
		(net "PHY_SCC_A_TO_DRV_A_34_DN")
	)
	(segment
		(start 278.943054 -302.83658)
		(end 278.905208 -302.798734)
		(width 0.10795)
		(layer "In9.Cu")
		(net "PHY_SCC_A_TO_DRV_A_34_DN")
	)
	(segment
		(start 391.241534 -81.788254)
		(end 349.782638 -108.711238)
		(width 0.10795)
		(layer "In9.Cu")
		(net "PHY_SCC_A_TO_DRV_A_34_DN")
	)
	(segment
		(start 439.189622 -46.031912)
		(end 433.286408 -47.958756)
		(width 0.10795)
		(layer "In9.Cu")
		(net "PHY_SCC_A_TO_DRV_A_34_DN")
	)
	(segment
		(start 315.00445 -159.22498)
		(end 314.699396 -160.601152)
		(width 0.10795)
		(layer "In9.Cu")
		(net "PHY_SCC_A_TO_DRV_A_34_DN")
	)
	(segment
		(start 445.092836 -44.105068)
		(end 439.189622 -46.032166)
		(width 0.10795)
		(layer "In9.Cu")
		(net "PHY_SCC_A_TO_DRV_A_34_DN")
	)
	(segment
		(start 303.33315 -287.887918)
		(end 295.668954 -299.46727)
		(width 0.10795)
		(layer "In9.Cu")
		(net "PHY_SCC_A_TO_DRV_A_34_DN")
	)
	(arc
		(start 278.724106 -301.942246)
		(mid 278.682955 -301.914813)
		(end 278.634444 -301.905162)
		(width 0.10795)
		(layer "In9.Cu")
		(net "PHY_SCC_A_TO_DRV_A_34_DN")
	)
	(arc
		(start 446.1891 -44.224702)
		(mid 446.179993 -44.17892)
		(end 446.154048 -44.14012)
		(width 0.10795)
		(layer "In9.Cu")
		(net "PHY_SCC_A_TO_DRV_A_34_DN")
	)
	(arc
		(start 446.154048 -44.14012)
		(mid 446.115241 -44.11419)
		(end 446.069466 -44.105068)
		(width 0.10795)
		(layer "In9.Cu")
		(net "PHY_SCC_A_TO_DRV_A_34_DN")
	)
	(arc
		(start 279.266142 -302.970184)
		(mid 279.091331 -302.935465)
		(end 278.943054 -302.83658)
		(width 0.10795)
		(layer "In9.Cu")
		(net "PHY_SCC_A_TO_DRV_A_34_DN")
	)
	(arc
		(start 278.771604 -302.042322)
		(mid 278.761971 -301.993804)
		(end 278.73452 -301.95266)
		(width 0.10795)
		(layer "In9.Cu")
		(net "PHY_SCC_A_TO_DRV_A_34_DN")
	)
	(arc
		(start 278.905208 -302.798734)
		(mid 278.806322 -302.650457)
		(end 278.771604 -302.475646)
		(width 0.10795)
		(layer "In9.Cu")
		(net "PHY_SCC_A_TO_DRV_A_34_DN")
	)
	(segment
		(start 414.639252 -43.368468)
		(end 414.639252 -43.652694)
		(width 0.127)
		(layer "F.Cu")
		(net "PHY_SCC_A_TO_DRV_A_33_DP")
	)
	(segment
		(start 415.540698 -43.793918)
		(end 415.674048 -43.660568)
		(width 0.127)
		(layer "F.Cu")
		(net "PHY_SCC_A_TO_DRV_A_33_DP")
	)
	(segment
		(start 414.676336 -43.742356)
		(end 414.690814 -43.756834)
		(width 0.127)
		(layer "F.Cu")
		(net "PHY_SCC_A_TO_DRV_A_33_DP")
	)
	(segment
		(start 415.674048 -43.660568)
		(end 416.005264 -43.660568)
		(width 0.127)
		(layer "F.Cu")
		(net "PHY_SCC_A_TO_DRV_A_33_DP")
	)
	(segment
		(start 414.780476 -43.793918)
		(end 415.540698 -43.793918)
		(width 0.127)
		(layer "F.Cu")
		(net "PHY_SCC_A_TO_DRV_A_33_DP")
	)
	(arc
		(start 414.690814 -43.756834)
		(mid 414.731965 -43.784267)
		(end 414.780476 -43.793918)
		(width 0.127)
		(layer "F.Cu")
		(net "PHY_SCC_A_TO_DRV_A_33_DP")
	)
	(arc
		(start 414.639252 -43.652694)
		(mid 414.648885 -43.701212)
		(end 414.676336 -43.742356)
		(width 0.127)
		(layer "F.Cu")
		(net "PHY_SCC_A_TO_DRV_A_33_DP")
	)
	(segment
		(start 312.78195 -159.188658)
		(end 302.377348 -206.124556)
		(width 0.10795)
		(layer "In9.Cu")
		(net "PHY_SCC_A_TO_DRV_A_33_DP")
	)
	(segment
		(start 293.76624 -298.410884)
		(end 290.751514 -300.331124)
		(width 0.10795)
		(layer "In9.Cu")
		(net "PHY_SCC_A_TO_DRV_A_33_DP")
	)
	(segment
		(start 280.138886 -300.148244)
		(end 280.144982 -300.142148)
		(width 0.10795)
		(layer "In9.Cu")
		(net "PHY_SCC_A_TO_DRV_A_33_DP")
	)
	(segment
		(start 295.610534 -295.624504)
		(end 295.319958 -295.683686)
		(width 0.10795)
		(layer "In9.Cu")
		(net "PHY_SCC_A_TO_DRV_A_33_DP")
	)
	(segment
		(start 295.021508 -296.514266)
		(end 294.731186 -296.573194)
		(width 0.10795)
		(layer "In9.Cu")
		(net "PHY_SCC_A_TO_DRV_A_33_DP")
	)
	(segment
		(start 302.377348 -206.124556)
		(end 310.982106 -244.93093)
		(width 0.10795)
		(layer "In9.Cu")
		(net "PHY_SCC_A_TO_DRV_A_33_DP")
	)
	(segment
		(start 414.519618 -43.774868)
		(end 413.700976 -43.774868)
		(width 0.10795)
		(layer "In9.Cu")
		(net "PHY_SCC_A_TO_DRV_A_33_DP")
	)
	(segment
		(start 294.55237 -296.84345)
		(end 294.611552 -297.133772)
		(width 0.10795)
		(layer "In9.Cu")
		(net "PHY_SCC_A_TO_DRV_A_33_DP")
	)
	(segment
		(start 301.820326 -286.242506)
		(end 295.610534 -295.624504)
		(width 0.10795)
		(layer "In9.Cu")
		(net "PHY_SCC_A_TO_DRV_A_33_DP")
	)
	(segment
		(start 306.088288 -266.996164)
		(end 301.820326 -286.242506)
		(width 0.10795)
		(layer "In9.Cu")
		(net "PHY_SCC_A_TO_DRV_A_33_DP")
	)
	(segment
		(start 295.319958 -295.683686)
		(end 295.141396 -295.953688)
		(width 0.10795)
		(layer "In9.Cu")
		(net "PHY_SCC_A_TO_DRV_A_33_DP")
	)
	(segment
		(start 388.194042 -59.300618)
		(end 373.147082 -71.407528)
		(width 0.10795)
		(layer "In9.Cu")
		(net "PHY_SCC_A_TO_DRV_A_33_DP")
	)
	(segment
		(start 294.611552 -297.133772)
		(end 294.432736 -297.403774)
		(width 0.10795)
		(layer "In9.Cu")
		(net "PHY_SCC_A_TO_DRV_A_33_DP")
	)
	(segment
		(start 413.700976 -43.774868)
		(end 403.250908 -47.18558)
		(width 0.10795)
		(layer "In9.Cu")
		(net "PHY_SCC_A_TO_DRV_A_33_DP")
	)
	(segment
		(start 294.142414 -297.462956)
		(end 293.963598 -297.732958)
		(width 0.10795)
		(layer "In9.Cu")
		(net "PHY_SCC_A_TO_DRV_A_33_DP")
	)
	(segment
		(start 403.250908 -47.18558)
		(end 388.194296 -59.300364)
		(width 0.10795)
		(layer "In9.Cu")
		(net "PHY_SCC_A_TO_DRV_A_33_DP")
	)
	(segment
		(start 295.141396 -295.953688)
		(end 295.200324 -296.244264)
		(width 0.10795)
		(layer "In9.Cu")
		(net "PHY_SCC_A_TO_DRV_A_33_DP")
	)
	(segment
		(start 294.432736 -297.403774)
		(end 294.142414 -297.462956)
		(width 0.10795)
		(layer "In9.Cu")
		(net "PHY_SCC_A_TO_DRV_A_33_DP")
	)
	(segment
		(start 294.02278 -298.02328)
		(end 293.76624 -298.410884)
		(width 0.10795)
		(layer "In9.Cu")
		(net "PHY_SCC_A_TO_DRV_A_33_DP")
	)
	(segment
		(start 295.200324 -296.244264)
		(end 295.021508 -296.514266)
		(width 0.10795)
		(layer "In9.Cu")
		(net "PHY_SCC_A_TO_DRV_A_33_DP")
	)
	(segment
		(start 373.147082 -71.407528)
		(end 312.78195 -159.188658)
		(width 0.10795)
		(layer "In9.Cu")
		(net "PHY_SCC_A_TO_DRV_A_33_DP")
	)
	(segment
		(start 293.963598 -297.732958)
		(end 294.02278 -298.02328)
		(width 0.10795)
		(layer "In9.Cu")
		(net "PHY_SCC_A_TO_DRV_A_33_DP")
	)
	(segment
		(start 414.639252 -43.368468)
		(end 414.639252 -43.655234)
		(width 0.10795)
		(layer "In9.Cu")
		(net "PHY_SCC_A_TO_DRV_A_33_DP")
	)
	(segment
		(start 294.731186 -296.573194)
		(end 294.55237 -296.84345)
		(width 0.10795)
		(layer "In9.Cu")
		(net "PHY_SCC_A_TO_DRV_A_33_DP")
	)
	(segment
		(start 280.101802 -300.64583)
		(end 280.101802 -300.237906)
		(width 0.10795)
		(layer "In9.Cu")
		(net "PHY_SCC_A_TO_DRV_A_33_DP")
	)
	(segment
		(start 388.194296 -59.300364)
		(end 388.194042 -59.300618)
		(width 0.10795)
		(layer "In9.Cu")
		(net "PHY_SCC_A_TO_DRV_A_33_DP")
	)
	(segment
		(start 280.206196 -300.802802)
		(end 280.138886 -300.735492)
		(width 0.10795)
		(layer "In9.Cu")
		(net "PHY_SCC_A_TO_DRV_A_33_DP")
	)
	(segment
		(start 280.234644 -300.105064)
		(end 280.636726 -300.105064)
		(width 0.10795)
		(layer "In9.Cu")
		(net "PHY_SCC_A_TO_DRV_A_33_DP")
	)
	(segment
		(start 290.751514 -300.331124)
		(end 288.458402 -300.839886)
		(width 0.10795)
		(layer "In9.Cu")
		(net "PHY_SCC_A_TO_DRV_A_33_DP")
	)
	(segment
		(start 310.982106 -244.93093)
		(end 306.088288 -266.996164)
		(width 0.10795)
		(layer "In9.Cu")
		(net "PHY_SCC_A_TO_DRV_A_33_DP")
	)
	(segment
		(start 288.458402 -300.839886)
		(end 280.295858 -300.839886)
		(width 0.10795)
		(layer "In9.Cu")
		(net "PHY_SCC_A_TO_DRV_A_33_DP")
	)
	(arc
		(start 414.6042 -43.739816)
		(mid 414.565393 -43.765746)
		(end 414.519618 -43.774868)
		(width 0.10795)
		(layer "In9.Cu")
		(net "PHY_SCC_A_TO_DRV_A_33_DP")
	)
	(arc
		(start 280.295858 -300.839886)
		(mid 280.24734 -300.830253)
		(end 280.206196 -300.802802)
		(width 0.10795)
		(layer "In9.Cu")
		(net "PHY_SCC_A_TO_DRV_A_33_DP")
	)
	(arc
		(start 280.144982 -300.142148)
		(mid 280.186133 -300.114715)
		(end 280.234644 -300.105064)
		(width 0.10795)
		(layer "In9.Cu")
		(net "PHY_SCC_A_TO_DRV_A_33_DP")
	)
	(arc
		(start 280.138886 -300.735492)
		(mid 280.111453 -300.694341)
		(end 280.101802 -300.64583)
		(width 0.10795)
		(layer "In9.Cu")
		(net "PHY_SCC_A_TO_DRV_A_33_DP")
	)
	(arc
		(start 414.639252 -43.655234)
		(mid 414.630145 -43.701016)
		(end 414.6042 -43.739816)
		(width 0.10795)
		(layer "In9.Cu")
		(net "PHY_SCC_A_TO_DRV_A_33_DP")
	)
	(arc
		(start 280.101802 -300.237906)
		(mid 280.111435 -300.189388)
		(end 280.138886 -300.148244)
		(width 0.10795)
		(layer "In9.Cu")
		(net "PHY_SCC_A_TO_DRV_A_33_DP")
	)
	(segment
		(start 414.639252 -44.511468)
		(end 414.639252 -44.250102)
		(width 0.127)
		(layer "F.Cu")
		(net "PHY_SCC_A_TO_DRV_A_33_DN")
	)
	(segment
		(start 414.676336 -44.16044)
		(end 414.713674 -44.123102)
		(width 0.127)
		(layer "F.Cu")
		(net "PHY_SCC_A_TO_DRV_A_33_DN")
	)
	(segment
		(start 415.540698 -44.086018)
		(end 415.674048 -44.219368)
		(width 0.127)
		(layer "F.Cu")
		(net "PHY_SCC_A_TO_DRV_A_33_DN")
	)
	(segment
		(start 415.674048 -44.219368)
		(end 416.005264 -44.219368)
		(width 0.127)
		(layer "F.Cu")
		(net "PHY_SCC_A_TO_DRV_A_33_DN")
	)
	(segment
		(start 414.803336 -44.086018)
		(end 415.540698 -44.086018)
		(width 0.127)
		(layer "F.Cu")
		(net "PHY_SCC_A_TO_DRV_A_33_DN")
	)
	(arc
		(start 414.639252 -44.250102)
		(mid 414.648885 -44.201584)
		(end 414.676336 -44.16044)
		(width 0.127)
		(layer "F.Cu")
		(net "PHY_SCC_A_TO_DRV_A_33_DN")
	)
	(arc
		(start 414.713674 -44.123102)
		(mid 414.754825 -44.095669)
		(end 414.803336 -44.086018)
		(width 0.127)
		(layer "F.Cu")
		(net "PHY_SCC_A_TO_DRV_A_33_DN")
	)
	(segment
		(start 304.27676 -276.690836)
		(end 302.129444 -286.373824)
		(width 0.10795)
		(layer "In9.Cu")
		(net "PHY_SCC_A_TO_DRV_A_33_DN")
	)
	(segment
		(start 290.861242 -300.645068)
		(end 288.506154 -301.167546)
		(width 0.10795)
		(layer "In9.Cu")
		(net "PHY_SCC_A_TO_DRV_A_33_DN")
	)
	(segment
		(start 302.129444 -286.373824)
		(end 294.002968 -298.651676)
		(width 0.10795)
		(layer "In9.Cu")
		(net "PHY_SCC_A_TO_DRV_A_33_DN")
	)
	(segment
		(start 279.771602 -300.64583)
		(end 279.771602 -300.237906)
		(width 0.10795)
		(layer "In9.Cu")
		(net "PHY_SCC_A_TO_DRV_A_33_DN")
	)
	(segment
		(start 293.868856 -298.737274)
		(end 292.436296 -299.649642)
		(width 0.10795)
		(layer "In9.Cu")
		(net "PHY_SCC_A_TO_DRV_A_33_DN")
	)
	(segment
		(start 311.320434 -244.93093)
		(end 306.410868 -267.067792)
		(width 0.10795)
		(layer "In9.Cu")
		(net "PHY_SCC_A_TO_DRV_A_33_DN")
	)
	(segment
		(start 288.482786 -301.170086)
		(end 280.295858 -301.170086)
		(width 0.10795)
		(layer "In9.Cu")
		(net "PHY_SCC_A_TO_DRV_A_33_DN")
	)
	(segment
		(start 279.63876 -300.105064)
		(end 279.236678 -300.105064)
		(width 0.10795)
		(layer "In9.Cu")
		(net "PHY_SCC_A_TO_DRV_A_33_DN")
	)
	(segment
		(start 373.391938 -71.634604)
		(end 313.091068 -159.322262)
		(width 0.10795)
		(layer "In9.Cu")
		(net "PHY_SCC_A_TO_DRV_A_33_DN")
	)
	(segment
		(start 313.091068 -159.322262)
		(end 302.715676 -206.124556)
		(width 0.10795)
		(layer "In9.Cu")
		(net "PHY_SCC_A_TO_DRV_A_33_DN")
	)
	(segment
		(start 292.436296 -299.649642)
		(end 290.895786 -300.630844)
		(width 0.10795)
		(layer "In9.Cu")
		(net "PHY_SCC_A_TO_DRV_A_33_DN")
	)
	(segment
		(start 414.639252 -44.511468)
		(end 414.639252 -44.224702)
		(width 0.10795)
		(layer "In9.Cu")
		(net "PHY_SCC_A_TO_DRV_A_33_DN")
	)
	(segment
		(start 279.734518 -300.148244)
		(end 279.728422 -300.142148)
		(width 0.10795)
		(layer "In9.Cu")
		(net "PHY_SCC_A_TO_DRV_A_33_DN")
	)
	(segment
		(start 302.715676 -206.124556)
		(end 311.320434 -244.93093)
		(width 0.10795)
		(layer "In9.Cu")
		(net "PHY_SCC_A_TO_DRV_A_33_DN")
	)
	(segment
		(start 403.410928 -47.480728)
		(end 373.391938 -71.634604)
		(width 0.10795)
		(layer "In9.Cu")
		(net "PHY_SCC_A_TO_DRV_A_33_DN")
	)
	(segment
		(start 306.410868 -267.067792)
		(end 304.27676 -276.690836)
		(width 0.10795)
		(layer "In9.Cu")
		(net "PHY_SCC_A_TO_DRV_A_33_DN")
	)
	(segment
		(start 413.753554 -44.105068)
		(end 403.410928 -47.480728)
		(width 0.10795)
		(layer "In9.Cu")
		(net "PHY_SCC_A_TO_DRV_A_33_DN")
	)
	(segment
		(start 414.519618 -44.105068)
		(end 413.753554 -44.105068)
		(width 0.10795)
		(layer "In9.Cu")
		(net "PHY_SCC_A_TO_DRV_A_33_DN")
	)
	(segment
		(start 294.002968 -298.651676)
		(end 293.868856 -298.737274)
		(width 0.10795)
		(layer "In9.Cu")
		(net "PHY_SCC_A_TO_DRV_A_33_DN")
	)
	(segment
		(start 279.97277 -301.036482)
		(end 279.905206 -300.968918)
		(width 0.10795)
		(layer "In9.Cu")
		(net "PHY_SCC_A_TO_DRV_A_33_DN")
	)
	(arc
		(start 290.895786 -300.630844)
		(mid 290.87913 -300.639449)
		(end 290.861242 -300.645068)
		(width 0.10795)
		(layer "In9.Cu")
		(net "PHY_SCC_A_TO_DRV_A_33_DN")
	)
	(arc
		(start 279.771602 -300.237906)
		(mid 279.761969 -300.189388)
		(end 279.734518 -300.148244)
		(width 0.10795)
		(layer "In9.Cu")
		(net "PHY_SCC_A_TO_DRV_A_33_DN")
	)
	(arc
		(start 414.639252 -44.224702)
		(mid 414.630145 -44.17892)
		(end 414.6042 -44.14012)
		(width 0.10795)
		(layer "In9.Cu")
		(net "PHY_SCC_A_TO_DRV_A_33_DN")
	)
	(arc
		(start 288.506154 -301.167546)
		(mid 288.49454 -301.169463)
		(end 288.482786 -301.170086)
		(width 0.10795)
		(layer "In9.Cu")
		(net "PHY_SCC_A_TO_DRV_A_33_DN")
	)
	(arc
		(start 280.295858 -301.170086)
		(mid 280.121047 -301.135367)
		(end 279.97277 -301.036482)
		(width 0.10795)
		(layer "In9.Cu")
		(net "PHY_SCC_A_TO_DRV_A_33_DN")
	)
	(arc
		(start 279.728422 -300.142148)
		(mid 279.687271 -300.114715)
		(end 279.63876 -300.105064)
		(width 0.10795)
		(layer "In9.Cu")
		(net "PHY_SCC_A_TO_DRV_A_33_DN")
	)
	(arc
		(start 279.905206 -300.968918)
		(mid 279.80632 -300.820641)
		(end 279.771602 -300.64583)
		(width 0.10795)
		(layer "In9.Cu")
		(net "PHY_SCC_A_TO_DRV_A_33_DN")
	)
	(arc
		(start 414.6042 -44.14012)
		(mid 414.565393 -44.11419)
		(end 414.519618 -44.105068)
		(width 0.10795)
		(layer "In9.Cu")
		(net "PHY_SCC_A_TO_DRV_A_33_DN")
	)
	(segment
		(start 383.14376 -46.114716)
		(end 383.153666 -46.10481)
		(width 0.127)
		(layer "F.Cu")
		(net "PHY_SCC_A_TO_DRV_A_32_DP")
	)
	(segment
		(start 384.123946 -43.660568)
		(end 384.455162 -43.660568)
		(width 0.127)
		(layer "F.Cu")
		(net "PHY_SCC_A_TO_DRV_A_32_DP")
	)
	(segment
		(start 383.19075 -46.015148)
		(end 383.19075 -44.106592)
		(width 0.127)
		(layer "F.Cu")
		(net "PHY_SCC_A_TO_DRV_A_32_DP")
	)
	(segment
		(start 383.19075 -44.106592)
		(end 383.503424 -43.793918)
		(width 0.127)
		(layer "F.Cu")
		(net "PHY_SCC_A_TO_DRV_A_32_DP")
	)
	(segment
		(start 383.990596 -43.793918)
		(end 384.123946 -43.660568)
		(width 0.127)
		(layer "F.Cu")
		(net "PHY_SCC_A_TO_DRV_A_32_DP")
	)
	(segment
		(start 382.7653 -46.1518)
		(end 383.054098 -46.1518)
		(width 0.127)
		(layer "F.Cu")
		(net "PHY_SCC_A_TO_DRV_A_32_DP")
	)
	(segment
		(start 383.503424 -43.793918)
		(end 383.990596 -43.793918)
		(width 0.127)
		(layer "F.Cu")
		(net "PHY_SCC_A_TO_DRV_A_32_DP")
	)
	(arc
		(start 383.054098 -46.1518)
		(mid 383.102616 -46.142167)
		(end 383.14376 -46.114716)
		(width 0.127)
		(layer "F.Cu")
		(net "PHY_SCC_A_TO_DRV_A_32_DP")
	)
	(arc
		(start 383.153666 -46.10481)
		(mid 383.181099 -46.063659)
		(end 383.19075 -46.015148)
		(width 0.127)
		(layer "F.Cu")
		(net "PHY_SCC_A_TO_DRV_A_32_DP")
	)
	(segment
		(start 292.852348 -296.672254)
		(end 289.781996 -298.628054)
		(width 0.10795)
		(layer "In9.Cu")
		(net "PHY_SCC_A_TO_DRV_A_32_DP")
	)
	(segment
		(start 382.7653 -46.1518)
		(end 383.06502 -46.1518)
		(width 0.10795)
		(layer "In9.Cu")
		(net "PHY_SCC_A_TO_DRV_A_32_DP")
	)
	(segment
		(start 294.208708 -294.622982)
		(end 294.029892 -294.892984)
		(width 0.10795)
		(layer "In9.Cu")
		(net "PHY_SCC_A_TO_DRV_A_32_DP")
	)
	(segment
		(start 279.238964 -298.30522)
		(end 279.636728 -298.30522)
		(width 0.10795)
		(layer "In9.Cu")
		(net "PHY_SCC_A_TO_DRV_A_32_DP")
	)
	(segment
		(start 279.101804 -298.875704)
		(end 279.101804 -298.44238)
		(width 0.10795)
		(layer "In9.Cu")
		(net "PHY_SCC_A_TO_DRV_A_32_DP")
	)
	(segment
		(start 310.749696 -159.699452)
		(end 300.867572 -204.28585)
		(width 0.10795)
		(layer "In9.Cu")
		(net "PHY_SCC_A_TO_DRV_A_32_DP")
	)
	(segment
		(start 279.138888 -298.352718)
		(end 279.149302 -298.342304)
		(width 0.10795)
		(layer "In9.Cu")
		(net "PHY_SCC_A_TO_DRV_A_32_DP")
	)
	(segment
		(start 289.781996 -298.628054)
		(end 289.781996 -298.6278)
		(width 0.10795)
		(layer "In9.Cu")
		(net "PHY_SCC_A_TO_DRV_A_32_DP")
	)
	(segment
		(start 293.031164 -296.402252)
		(end 292.852348 -296.672254)
		(width 0.10795)
		(layer "In9.Cu")
		(net "PHY_SCC_A_TO_DRV_A_32_DP")
	)
	(segment
		(start 294.618664 -294.003476)
		(end 294.328342 -294.062658)
		(width 0.10795)
		(layer "In9.Cu")
		(net "PHY_SCC_A_TO_DRV_A_32_DP")
	)
	(segment
		(start 296.145458 -291.696648)
		(end 294.618664 -294.003476)
		(width 0.10795)
		(layer "In9.Cu")
		(net "PHY_SCC_A_TO_DRV_A_32_DP")
	)
	(segment
		(start 279.17648 -299.002958)
		(end 279.138888 -298.965366)
		(width 0.10795)
		(layer "In9.Cu")
		(net "PHY_SCC_A_TO_DRV_A_32_DP")
	)
	(segment
		(start 378.839222 -56.90235)
		(end 374.485154 -67.021964)
		(width 0.10795)
		(layer "In9.Cu")
		(net "PHY_SCC_A_TO_DRV_A_32_DP")
	)
	(segment
		(start 293.560754 -295.222168)
		(end 293.619936 -295.51249)
		(width 0.10795)
		(layer "In9.Cu")
		(net "PHY_SCC_A_TO_DRV_A_32_DP")
	)
	(segment
		(start 293.73957 -294.952166)
		(end 293.560754 -295.222168)
		(width 0.10795)
		(layer "In9.Cu")
		(net "PHY_SCC_A_TO_DRV_A_32_DP")
	)
	(segment
		(start 300.867572 -204.28585)
		(end 309.778908 -244.489732)
		(width 0.10795)
		(layer "In9.Cu")
		(net "PHY_SCC_A_TO_DRV_A_32_DP")
	)
	(segment
		(start 383.194052 -46.782736)
		(end 378.839222 -56.90235)
		(width 0.10795)
		(layer "In9.Cu")
		(net "PHY_SCC_A_TO_DRV_A_32_DP")
	)
	(segment
		(start 287.922208 -299.040042)
		(end 279.266142 -299.040042)
		(width 0.10795)
		(layer "In9.Cu")
		(net "PHY_SCC_A_TO_DRV_A_32_DP")
	)
	(segment
		(start 292.971982 -296.111676)
		(end 293.031164 -296.402252)
		(width 0.10795)
		(layer "In9.Cu")
		(net "PHY_SCC_A_TO_DRV_A_32_DP")
	)
	(segment
		(start 383.154682 -46.188884)
		(end 383.156968 -46.19117)
		(width 0.10795)
		(layer "In9.Cu")
		(net "PHY_SCC_A_TO_DRV_A_32_DP")
	)
	(segment
		(start 374.485154 -67.021964)
		(end 310.749696 -159.699452)
		(width 0.10795)
		(layer "In9.Cu")
		(net "PHY_SCC_A_TO_DRV_A_32_DP")
	)
	(segment
		(start 293.619936 -295.51249)
		(end 293.44112 -295.782746)
		(width 0.10795)
		(layer "In9.Cu")
		(net "PHY_SCC_A_TO_DRV_A_32_DP")
	)
	(segment
		(start 309.778908 -244.489732)
		(end 301.008796 -284.348936)
		(width 0.10795)
		(layer "In9.Cu")
		(net "PHY_SCC_A_TO_DRV_A_32_DP")
	)
	(segment
		(start 301.008796 -284.348936)
		(end 296.145458 -291.696648)
		(width 0.10795)
		(layer "In9.Cu")
		(net "PHY_SCC_A_TO_DRV_A_32_DP")
	)
	(segment
		(start 383.194052 -46.280832)
		(end 383.194052 -46.782736)
		(width 0.10795)
		(layer "In9.Cu")
		(net "PHY_SCC_A_TO_DRV_A_32_DP")
	)
	(segment
		(start 293.150798 -295.841674)
		(end 292.971982 -296.111676)
		(width 0.10795)
		(layer "In9.Cu")
		(net "PHY_SCC_A_TO_DRV_A_32_DP")
	)
	(segment
		(start 294.149526 -294.33266)
		(end 294.208708 -294.622982)
		(width 0.10795)
		(layer "In9.Cu")
		(net "PHY_SCC_A_TO_DRV_A_32_DP")
	)
	(segment
		(start 294.029892 -294.892984)
		(end 293.73957 -294.952166)
		(width 0.10795)
		(layer "In9.Cu")
		(net "PHY_SCC_A_TO_DRV_A_32_DP")
	)
	(segment
		(start 289.781996 -298.6278)
		(end 287.922208 -299.040042)
		(width 0.10795)
		(layer "In9.Cu")
		(net "PHY_SCC_A_TO_DRV_A_32_DP")
	)
	(segment
		(start 293.44112 -295.782746)
		(end 293.150798 -295.841674)
		(width 0.10795)
		(layer "In9.Cu")
		(net "PHY_SCC_A_TO_DRV_A_32_DP")
	)
	(segment
		(start 294.328342 -294.062658)
		(end 294.149526 -294.33266)
		(width 0.10795)
		(layer "In9.Cu")
		(net "PHY_SCC_A_TO_DRV_A_32_DP")
	)
	(arc
		(start 279.101804 -298.44238)
		(mid 279.111437 -298.393862)
		(end 279.138888 -298.352718)
		(width 0.10795)
		(layer "In9.Cu")
		(net "PHY_SCC_A_TO_DRV_A_32_DP")
	)
	(arc
		(start 279.266142 -299.040042)
		(mid 279.217624 -299.030409)
		(end 279.17648 -299.002958)
		(width 0.10795)
		(layer "In9.Cu")
		(net "PHY_SCC_A_TO_DRV_A_32_DP")
	)
	(arc
		(start 279.138888 -298.965366)
		(mid 279.111455 -298.924215)
		(end 279.101804 -298.875704)
		(width 0.10795)
		(layer "In9.Cu")
		(net "PHY_SCC_A_TO_DRV_A_32_DP")
	)
	(arc
		(start 383.156968 -46.19117)
		(mid 383.184401 -46.232321)
		(end 383.194052 -46.280832)
		(width 0.10795)
		(layer "In9.Cu")
		(net "PHY_SCC_A_TO_DRV_A_32_DP")
	)
	(arc
		(start 383.06502 -46.1518)
		(mid 383.113538 -46.161433)
		(end 383.154682 -46.188884)
		(width 0.10795)
		(layer "In9.Cu")
		(net "PHY_SCC_A_TO_DRV_A_32_DP")
	)
	(arc
		(start 279.149302 -298.342304)
		(mid 279.190453 -298.314871)
		(end 279.238964 -298.30522)
		(width 0.10795)
		(layer "In9.Cu")
		(net "PHY_SCC_A_TO_DRV_A_32_DP")
	)
	(segment
		(start 383.48285 -44.22775)
		(end 383.624582 -44.086018)
		(width 0.127)
		(layer "F.Cu")
		(net "PHY_SCC_A_TO_DRV_A_32_DN")
	)
	(segment
		(start 384.123946 -44.219368)
		(end 384.455162 -44.219368)
		(width 0.127)
		(layer "F.Cu")
		(net "PHY_SCC_A_TO_DRV_A_32_DN")
	)
	(segment
		(start 383.9083 -46.1518)
		(end 383.611882 -46.1518)
		(width 0.127)
		(layer "F.Cu")
		(net "PHY_SCC_A_TO_DRV_A_32_DN")
	)
	(segment
		(start 383.48285 -46.022768)
		(end 383.48285 -44.22775)
		(width 0.127)
		(layer "F.Cu")
		(net "PHY_SCC_A_TO_DRV_A_32_DN")
	)
	(segment
		(start 383.624582 -44.086018)
		(end 383.990596 -44.086018)
		(width 0.127)
		(layer "F.Cu")
		(net "PHY_SCC_A_TO_DRV_A_32_DN")
	)
	(segment
		(start 383.52222 -46.114716)
		(end 383.519934 -46.11243)
		(width 0.127)
		(layer "F.Cu")
		(net "PHY_SCC_A_TO_DRV_A_32_DN")
	)
	(segment
		(start 383.990596 -44.086018)
		(end 384.123946 -44.219368)
		(width 0.127)
		(layer "F.Cu")
		(net "PHY_SCC_A_TO_DRV_A_32_DN")
	)
	(arc
		(start 383.611882 -46.1518)
		(mid 383.563364 -46.142167)
		(end 383.52222 -46.114716)
		(width 0.127)
		(layer "F.Cu")
		(net "PHY_SCC_A_TO_DRV_A_32_DN")
	)
	(arc
		(start 383.519934 -46.11243)
		(mid 383.492501 -46.071279)
		(end 383.48285 -46.022768)
		(width 0.127)
		(layer "F.Cu")
		(net "PHY_SCC_A_TO_DRV_A_32_DN")
	)
	(segment
		(start 311.058306 -159.833818)
		(end 301.2059 -204.286104)
		(width 0.10795)
		(layer "In9.Cu")
		(net "PHY_SCC_A_TO_DRV_A_32_DN")
	)
	(segment
		(start 383.524252 -46.850808)
		(end 379.142752 -57.032906)
		(width 0.10795)
		(layer "In9.Cu")
		(net "PHY_SCC_A_TO_DRV_A_32_DN")
	)
	(segment
		(start 310.117236 -244.489478)
		(end 301.318168 -284.48)
		(width 0.10795)
		(layer "In9.Cu")
		(net "PHY_SCC_A_TO_DRV_A_32_DN")
	)
	(segment
		(start 293.089076 -296.913046)
		(end 289.910266 -298.937934)
		(width 0.10795)
		(layer "In9.Cu")
		(net "PHY_SCC_A_TO_DRV_A_32_DN")
	)
	(segment
		(start 383.57683 -46.188884)
		(end 383.561336 -46.204378)
		(width 0.10795)
		(layer "In9.Cu")
		(net "PHY_SCC_A_TO_DRV_A_32_DN")
	)
	(segment
		(start 287.946592 -299.370242)
		(end 279.266142 -299.370242)
		(width 0.10795)
		(layer "In9.Cu")
		(net "PHY_SCC_A_TO_DRV_A_32_DN")
	)
	(segment
		(start 301.318168 -284.48)
		(end 293.089076 -296.913046)
		(width 0.10795)
		(layer "In9.Cu")
		(net "PHY_SCC_A_TO_DRV_A_32_DN")
	)
	(segment
		(start 383.524252 -46.29404)
		(end 383.524252 -46.850808)
		(width 0.10795)
		(layer "In9.Cu")
		(net "PHY_SCC_A_TO_DRV_A_32_DN")
	)
	(segment
		(start 379.142752 -57.032906)
		(end 376.965718 -62.092332)
		(width 0.10795)
		(layer "In9.Cu")
		(net "PHY_SCC_A_TO_DRV_A_32_DN")
	)
	(segment
		(start 301.2059 -204.286104)
		(end 310.117236 -244.489478)
		(width 0.10795)
		(layer "In9.Cu")
		(net "PHY_SCC_A_TO_DRV_A_32_DN")
	)
	(segment
		(start 383.9083 -46.1518)
		(end 383.666492 -46.1518)
		(width 0.10795)
		(layer "In9.Cu")
		(net "PHY_SCC_A_TO_DRV_A_32_DN")
	)
	(segment
		(start 278.943054 -299.236638)
		(end 278.905208 -299.198792)
		(width 0.10795)
		(layer "In9.Cu")
		(net "PHY_SCC_A_TO_DRV_A_32_DN")
	)
	(segment
		(start 288.7472 -299.19549)
		(end 287.96996 -299.367702)
		(width 0.10795)
		(layer "In9.Cu")
		(net "PHY_SCC_A_TO_DRV_A_32_DN")
	)
	(segment
		(start 278.771604 -298.875704)
		(end 278.771604 -298.44238)
		(width 0.10795)
		(layer "In9.Cu")
		(net "PHY_SCC_A_TO_DRV_A_32_DN")
	)
	(segment
		(start 278.634444 -298.30522)
		(end 278.23668 -298.30522)
		(width 0.10795)
		(layer "In9.Cu")
		(net "PHY_SCC_A_TO_DRV_A_32_DN")
	)
	(segment
		(start 376.965718 -62.092332)
		(end 374.77573 -67.182238)
		(width 0.10795)
		(layer "In9.Cu")
		(net "PHY_SCC_A_TO_DRV_A_32_DN")
	)
	(segment
		(start 278.73452 -298.352718)
		(end 278.724106 -298.342304)
		(width 0.10795)
		(layer "In9.Cu")
		(net "PHY_SCC_A_TO_DRV_A_32_DN")
	)
	(segment
		(start 289.910266 -298.937934)
		(end 288.7472 -299.19549)
		(width 0.10795)
		(layer "In9.Cu")
		(net "PHY_SCC_A_TO_DRV_A_32_DN")
	)
	(segment
		(start 374.77573 -67.182238)
		(end 311.058306 -159.833818)
		(width 0.10795)
		(layer "In9.Cu")
		(net "PHY_SCC_A_TO_DRV_A_32_DN")
	)
	(arc
		(start 383.561336 -46.204378)
		(mid 383.533903 -46.245529)
		(end 383.524252 -46.29404)
		(width 0.10795)
		(layer "In9.Cu")
		(net "PHY_SCC_A_TO_DRV_A_32_DN")
	)
	(arc
		(start 278.905208 -299.198792)
		(mid 278.806322 -299.050515)
		(end 278.771604 -298.875704)
		(width 0.10795)
		(layer "In9.Cu")
		(net "PHY_SCC_A_TO_DRV_A_32_DN")
	)
	(arc
		(start 279.266142 -299.370242)
		(mid 279.091331 -299.335523)
		(end 278.943054 -299.236638)
		(width 0.10795)
		(layer "In9.Cu")
		(net "PHY_SCC_A_TO_DRV_A_32_DN")
	)
	(arc
		(start 287.96996 -299.367702)
		(mid 287.958346 -299.369619)
		(end 287.946592 -299.370242)
		(width 0.10795)
		(layer "In9.Cu")
		(net "PHY_SCC_A_TO_DRV_A_32_DN")
	)
	(arc
		(start 278.724106 -298.342304)
		(mid 278.682955 -298.314871)
		(end 278.634444 -298.30522)
		(width 0.10795)
		(layer "In9.Cu")
		(net "PHY_SCC_A_TO_DRV_A_32_DN")
	)
	(arc
		(start 278.771604 -298.44238)
		(mid 278.761971 -298.393862)
		(end 278.73452 -298.352718)
		(width 0.10795)
		(layer "In9.Cu")
		(net "PHY_SCC_A_TO_DRV_A_32_DN")
	)
	(arc
		(start 383.666492 -46.1518)
		(mid 383.617974 -46.161433)
		(end 383.57683 -46.188884)
		(width 0.10795)
		(layer "In9.Cu")
		(net "PHY_SCC_A_TO_DRV_A_32_DN")
	)
	(segment
		(start 351.508822 -43.561762)
		(end 351.508822 -42.754042)
		(width 0.127)
		(layer "F.Cu")
		(net "PHY_SCC_A_TO_DRV_A_31_DP")
	)
	(segment
		(start 351.635822 -42.627042)
		(end 351.907602 -42.627042)
		(width 0.127)
		(layer "F.Cu")
		(net "PHY_SCC_A_TO_DRV_A_31_DP")
	)
	(segment
		(start 352.905314 -43.660568)
		(end 352.421698 -43.660568)
		(width 0.127)
		(layer "F.Cu")
		(net "PHY_SCC_A_TO_DRV_A_31_DP")
	)
	(segment
		(start 352.297746 -43.78452)
		(end 351.73158 -43.78452)
		(width 0.127)
		(layer "F.Cu")
		(net "PHY_SCC_A_TO_DRV_A_31_DP")
	)
	(segment
		(start 352.421698 -43.660568)
		(end 352.297746 -43.78452)
		(width 0.127)
		(layer "F.Cu")
		(net "PHY_SCC_A_TO_DRV_A_31_DP")
	)
	(segment
		(start 351.73158 -43.78452)
		(end 351.508822 -43.561762)
		(width 0.127)
		(layer "F.Cu")
		(net "PHY_SCC_A_TO_DRV_A_31_DP")
	)
	(arc
		(start 351.508822 -42.754042)
		(mid 351.546019 -42.664239)
		(end 351.635822 -42.627042)
		(width 0.127)
		(layer "F.Cu")
		(net "PHY_SCC_A_TO_DRV_A_31_DP")
	)
	(segment
		(start 288.023046 -295.7703)
		(end 280.26868 -295.7703)
		(width 0.1016)
		(layer "In7.Cu")
		(net "PHY_SCC_A_TO_DRV_A_31_DP")
	)
	(segment
		(start 294.430196 -291.82822)
		(end 294.128444 -291.781992)
		(width 0.1016)
		(layer "In7.Cu")
		(net "PHY_SCC_A_TO_DRV_A_31_DP")
	)
	(segment
		(start 295.51503 -291.031168)
		(end 295.269412 -291.211762)
		(width 0.1016)
		(layer "In7.Cu")
		(net "PHY_SCC_A_TO_DRV_A_31_DP")
	)
	(segment
		(start 295.806876 -290.548822)
		(end 295.561258 -290.729416)
		(width 0.1016)
		(layer "In7.Cu")
		(net "PHY_SCC_A_TO_DRV_A_31_DP")
	)
	(segment
		(start 296.354246 -290.41471)
		(end 296.108628 -290.59505)
		(width 0.1016)
		(layer "In7.Cu")
		(net "PHY_SCC_A_TO_DRV_A_31_DP")
	)
	(segment
		(start 294.96766 -291.165534)
		(end 294.722042 -291.345874)
		(width 0.1016)
		(layer "In7.Cu")
		(net "PHY_SCC_A_TO_DRV_A_31_DP")
	)
	(segment
		(start 333.440786 -132.849874)
		(end 345.03614 -190.553594)
		(width 0.1016)
		(layer "In7.Cu")
		(net "PHY_SCC_A_TO_DRV_A_31_DP")
	)
	(segment
		(start 294.675814 -291.64788)
		(end 294.430196 -291.82822)
		(width 0.1016)
		(layer "In7.Cu")
		(net "PHY_SCC_A_TO_DRV_A_31_DP")
	)
	(segment
		(start 295.269412 -291.211762)
		(end 294.96766 -291.165534)
		(width 0.1016)
		(layer "In7.Cu")
		(net "PHY_SCC_A_TO_DRV_A_31_DP")
	)
	(segment
		(start 294.128444 -291.781992)
		(end 289.241738 -295.372028)
		(width 0.1016)
		(layer "In7.Cu")
		(net "PHY_SCC_A_TO_DRV_A_31_DP")
	)
	(segment
		(start 351.907602 -42.627042)
		(end 351.602802 -42.627042)
		(width 0.1016)
		(layer "In7.Cu")
		(net "PHY_SCC_A_TO_DRV_A_31_DP")
	)
	(segment
		(start 345.03614 -190.553594)
		(end 333.873348 -240.118138)
		(width 0.1016)
		(layer "In7.Cu")
		(net "PHY_SCC_A_TO_DRV_A_31_DP")
	)
	(segment
		(start 321.098418 -260.170676)
		(end 300.157642 -287.352486)
		(width 0.1016)
		(layer "In7.Cu")
		(net "PHY_SCC_A_TO_DRV_A_31_DP")
	)
	(segment
		(start 300.157642 -287.352486)
		(end 296.400474 -290.112704)
		(width 0.1016)
		(layer "In7.Cu")
		(net "PHY_SCC_A_TO_DRV_A_31_DP")
	)
	(segment
		(start 351.501202 -42.728642)
		(end 351.501202 -44.879514)
		(width 0.1016)
		(layer "In7.Cu")
		(net "PHY_SCC_A_TO_DRV_A_31_DP")
	)
	(segment
		(start 289.241738 -295.372028)
		(end 288.023046 -295.7703)
		(width 0.1016)
		(layer "In7.Cu")
		(net "PHY_SCC_A_TO_DRV_A_31_DP")
	)
	(segment
		(start 333.873348 -240.118138)
		(end 321.098418 -260.170676)
		(width 0.1016)
		(layer "In7.Cu")
		(net "PHY_SCC_A_TO_DRV_A_31_DP")
	)
	(segment
		(start 296.108628 -290.59505)
		(end 295.806876 -290.548822)
		(width 0.1016)
		(layer "In7.Cu")
		(net "PHY_SCC_A_TO_DRV_A_31_DP")
	)
	(segment
		(start 280.104088 -295.934892)
		(end 280.104088 -296.378122)
		(width 0.1016)
		(layer "In7.Cu")
		(net "PHY_SCC_A_TO_DRV_A_31_DP")
	)
	(segment
		(start 294.722042 -291.345874)
		(end 294.675814 -291.64788)
		(width 0.1016)
		(layer "In7.Cu")
		(net "PHY_SCC_A_TO_DRV_A_31_DP")
	)
	(segment
		(start 351.501202 -44.879514)
		(end 348.76105 -51.2318)
		(width 0.1016)
		(layer "In7.Cu")
		(net "PHY_SCC_A_TO_DRV_A_31_DP")
	)
	(segment
		(start 348.76105 -51.2318)
		(end 333.440786 -132.849874)
		(width 0.1016)
		(layer "In7.Cu")
		(net "PHY_SCC_A_TO_DRV_A_31_DP")
	)
	(segment
		(start 295.561258 -290.729416)
		(end 295.51503 -291.031168)
		(width 0.1016)
		(layer "In7.Cu")
		(net "PHY_SCC_A_TO_DRV_A_31_DP")
	)
	(segment
		(start 280.231088 -296.505122)
		(end 280.636726 -296.505122)
		(width 0.1016)
		(layer "In7.Cu")
		(net "PHY_SCC_A_TO_DRV_A_31_DP")
	)
	(segment
		(start 296.400474 -290.112704)
		(end 296.354246 -290.41471)
		(width 0.1016)
		(layer "In7.Cu")
		(net "PHY_SCC_A_TO_DRV_A_31_DP")
	)
	(arc
		(start 280.26868 -295.7703)
		(mid 280.152296 -295.818508)
		(end 280.104088 -295.934892)
		(width 0.1016)
		(layer "In7.Cu")
		(net "PHY_SCC_A_TO_DRV_A_31_DP")
	)
	(arc
		(start 280.104088 -296.378122)
		(mid 280.141285 -296.467925)
		(end 280.231088 -296.505122)
		(width 0.1016)
		(layer "In7.Cu")
		(net "PHY_SCC_A_TO_DRV_A_31_DP")
	)
	(arc
		(start 351.602802 -42.627042)
		(mid 351.53096 -42.6568)
		(end 351.501202 -42.728642)
		(width 0.1016)
		(layer "In7.Cu")
		(net "PHY_SCC_A_TO_DRV_A_31_DP")
	)
	(segment
		(start 352.27895 -44.07662)
		(end 351.610422 -44.07662)
		(width 0.127)
		(layer "F.Cu")
		(net "PHY_SCC_A_TO_DRV_A_31_DN")
	)
	(segment
		(start 351.610422 -44.07662)
		(end 351.216722 -43.68292)
		(width 0.127)
		(layer "F.Cu")
		(net "PHY_SCC_A_TO_DRV_A_31_DN")
	)
	(segment
		(start 351.216722 -43.68292)
		(end 351.216722 -42.754042)
		(width 0.127)
		(layer "F.Cu")
		(net "PHY_SCC_A_TO_DRV_A_31_DN")
	)
	(segment
		(start 351.089722 -42.627042)
		(end 350.764602 -42.627042)
		(width 0.127)
		(layer "F.Cu")
		(net "PHY_SCC_A_TO_DRV_A_31_DN")
	)
	(segment
		(start 352.905314 -44.219368)
		(end 352.421698 -44.219368)
		(width 0.127)
		(layer "F.Cu")
		(net "PHY_SCC_A_TO_DRV_A_31_DN")
	)
	(segment
		(start 352.421698 -44.219368)
		(end 352.27895 -44.07662)
		(width 0.127)
		(layer "F.Cu")
		(net "PHY_SCC_A_TO_DRV_A_31_DN")
	)
	(arc
		(start 351.216722 -42.754042)
		(mid 351.179525 -42.664239)
		(end 351.089722 -42.627042)
		(width 0.127)
		(layer "F.Cu")
		(net "PHY_SCC_A_TO_DRV_A_31_DN")
	)
	(segment
		(start 344.69832 -190.549784)
		(end 339.130894 -215.269826)
		(width 0.1016)
		(layer "In7.Cu")
		(net "PHY_SCC_A_TO_DRV_A_31_DN")
	)
	(segment
		(start 320.827654 -259.980684)
		(end 299.92447 -287.11398)
		(width 0.1016)
		(layer "In7.Cu")
		(net "PHY_SCC_A_TO_DRV_A_31_DN")
	)
	(segment
		(start 351.170748 -44.811188)
		(end 350.829626 -45.602144)
		(width 0.1016)
		(layer "In7.Cu")
		(net "PHY_SCC_A_TO_DRV_A_31_DN")
	)
	(segment
		(start 287.970214 -295.4401)
		(end 280.26868 -295.4401)
		(width 0.1016)
		(layer "In7.Cu")
		(net "PHY_SCC_A_TO_DRV_A_31_DN")
	)
	(segment
		(start 350.829626 -45.602144)
		(end 348.443042 -51.134772)
		(width 0.1016)
		(layer "In7.Cu")
		(net "PHY_SCC_A_TO_DRV_A_31_DN")
	)
	(segment
		(start 339.13064 -215.269826)
		(end 333.563722 -239.98936)
		(width 0.1016)
		(layer "In7.Cu")
		(net "PHY_SCC_A_TO_DRV_A_31_DN")
	)
	(segment
		(start 279.646888 -296.505122)
		(end 279.236678 -296.505122)
		(width 0.1016)
		(layer "In7.Cu")
		(net "PHY_SCC_A_TO_DRV_A_31_DN")
	)
	(segment
		(start 350.764602 -42.627042)
		(end 351.069402 -42.627042)
		(width 0.1016)
		(layer "In7.Cu")
		(net "PHY_SCC_A_TO_DRV_A_31_DN")
	)
	(segment
		(start 279.773888 -295.934892)
		(end 279.773888 -296.378122)
		(width 0.1016)
		(layer "In7.Cu")
		(net "PHY_SCC_A_TO_DRV_A_31_DN")
	)
	(segment
		(start 351.171002 -44.811188)
		(end 351.170748 -44.811188)
		(width 0.1016)
		(layer "In7.Cu")
		(net "PHY_SCC_A_TO_DRV_A_31_DN")
	)
	(segment
		(start 333.563722 -239.98936)
		(end 320.827654 -259.980684)
		(width 0.1016)
		(layer "In7.Cu")
		(net "PHY_SCC_A_TO_DRV_A_31_DN")
	)
	(segment
		(start 289.08883 -295.074594)
		(end 287.970214 -295.4401)
		(width 0.1016)
		(layer "In7.Cu")
		(net "PHY_SCC_A_TO_DRV_A_31_DN")
	)
	(segment
		(start 339.130894 -215.269826)
		(end 339.13064 -215.269826)
		(width 0.1016)
		(layer "In7.Cu")
		(net "PHY_SCC_A_TO_DRV_A_31_DN")
	)
	(segment
		(start 333.104236 -132.851906)
		(end 344.69832 -190.549784)
		(width 0.1016)
		(layer "In7.Cu")
		(net "PHY_SCC_A_TO_DRV_A_31_DN")
	)
	(segment
		(start 348.443042 -51.134772)
		(end 333.104236 -132.851906)
		(width 0.1016)
		(layer "In7.Cu")
		(net "PHY_SCC_A_TO_DRV_A_31_DN")
	)
	(segment
		(start 351.171002 -42.728642)
		(end 351.171002 -44.811188)
		(width 0.1016)
		(layer "In7.Cu")
		(net "PHY_SCC_A_TO_DRV_A_31_DN")
	)
	(segment
		(start 299.92447 -287.11398)
		(end 289.08883 -295.074594)
		(width 0.1016)
		(layer "In7.Cu")
		(net "PHY_SCC_A_TO_DRV_A_31_DN")
	)
	(arc
		(start 351.069402 -42.627042)
		(mid 351.141244 -42.6568)
		(end 351.171002 -42.728642)
		(width 0.1016)
		(layer "In7.Cu")
		(net "PHY_SCC_A_TO_DRV_A_31_DN")
	)
	(arc
		(start 280.26868 -295.4401)
		(mid 279.918809 -295.585021)
		(end 279.773888 -295.934892)
		(width 0.1016)
		(layer "In7.Cu")
		(net "PHY_SCC_A_TO_DRV_A_31_DN")
	)
	(arc
		(start 279.773888 -296.378122)
		(mid 279.736691 -296.467925)
		(end 279.646888 -296.505122)
		(width 0.1016)
		(layer "In7.Cu")
		(net "PHY_SCC_A_TO_DRV_A_31_DN")
	)
	(segment
		(start 319.93205 -43.535092)
		(end 319.93205 -42.851832)
		(width 0.127)
		(layer "F.Cu")
		(net "PHY_SCC_A_TO_DRV_A_30_DP")
	)
	(segment
		(start 321.355212 -43.660568)
		(end 321.127882 -43.660568)
		(width 0.127)
		(layer "F.Cu")
		(net "PHY_SCC_A_TO_DRV_A_30_DP")
	)
	(segment
		(start 321.028568 -43.759882)
		(end 320.15684 -43.759882)
		(width 0.127)
		(layer "F.Cu")
		(net "PHY_SCC_A_TO_DRV_A_30_DP")
	)
	(segment
		(start 320.15684 -42.627042)
		(end 320.3575 -42.627042)
		(width 0.127)
		(layer "F.Cu")
		(net "PHY_SCC_A_TO_DRV_A_30_DP")
	)
	(segment
		(start 321.127882 -43.660568)
		(end 321.028568 -43.759882)
		(width 0.127)
		(layer "F.Cu")
		(net "PHY_SCC_A_TO_DRV_A_30_DP")
	)
	(segment
		(start 320.15684 -43.759882)
		(end 319.93205 -43.535092)
		(width 0.127)
		(layer "F.Cu")
		(net "PHY_SCC_A_TO_DRV_A_30_DP")
	)
	(arc
		(start 319.93205 -42.851832)
		(mid 319.997889 -42.692881)
		(end 320.15684 -42.627042)
		(width 0.127)
		(layer "F.Cu")
		(net "PHY_SCC_A_TO_DRV_A_30_DP")
	)
	(segment
		(start 283.160724 -292.88867)
		(end 283.450538 -292.794182)
		(width 0.1016)
		(layer "In7.Cu")
		(net "PHY_SCC_A_TO_DRV_A_30_DP")
	)
	(segment
		(start 287.036002 -291.398198)
		(end 288.383218 -290.40836)
		(width 0.1016)
		(layer "In7.Cu")
		(net "PHY_SCC_A_TO_DRV_A_30_DP")
	)
	(segment
		(start 312.368438 -264.050018)
		(end 318.969898 -234.769406)
		(width 0.1016)
		(layer "In7.Cu")
		(net "PHY_SCC_A_TO_DRV_A_30_DP")
	)
	(segment
		(start 288.843466 -290.070286)
		(end 289.14217 -289.85083)
		(width 0.1016)
		(layer "In7.Cu")
		(net "PHY_SCC_A_TO_DRV_A_30_DP")
	)
	(segment
		(start 284.578806 -292.199314)
		(end 284.86862 -292.104826)
		(width 0.1016)
		(layer "In7.Cu")
		(net "PHY_SCC_A_TO_DRV_A_30_DP")
	)
	(segment
		(start 308.681374 -136.53135)
		(end 304.224436 -114.355118)
		(width 0.1016)
		(layer "In7.Cu")
		(net "PHY_SCC_A_TO_DRV_A_30_DP")
	)
	(segment
		(start 320.0527 -42.627042)
		(end 320.3575 -42.627042)
		(width 0.1016)
		(layer "In7.Cu")
		(net "PHY_SCC_A_TO_DRV_A_30_DP")
	)
	(segment
		(start 284.150816 -292.56609)
		(end 284.44063 -292.471602)
		(width 0.1016)
		(layer "In7.Cu")
		(net "PHY_SCC_A_TO_DRV_A_30_DP")
	)
	(segment
		(start 284.86862 -292.104826)
		(end 285.140908 -292.243256)
		(width 0.1016)
		(layer "In7.Cu")
		(net "PHY_SCC_A_TO_DRV_A_30_DP")
	)
	(segment
		(start 279.101804 -294.603678)
		(end 279.101804 -294.162226)
		(width 0.1016)
		(layer "In7.Cu")
		(net "PHY_SCC_A_TO_DRV_A_30_DP")
	)
	(segment
		(start 305.31816 -166.831518)
		(end 310.17591 -143.9672)
		(width 0.1016)
		(layer "In7.Cu")
		(net "PHY_SCC_A_TO_DRV_A_30_DP")
	)
	(segment
		(start 285.140908 -292.243256)
		(end 285.430722 -292.148768)
		(width 0.1016)
		(layer "In7.Cu")
		(net "PHY_SCC_A_TO_DRV_A_30_DP")
	)
	(segment
		(start 285.569152 -291.87648)
		(end 287.036002 -291.398198)
		(width 0.1016)
		(layer "In7.Cu")
		(net "PHY_SCC_A_TO_DRV_A_30_DP")
	)
	(segment
		(start 288.383218 -290.40836)
		(end 288.383472 -290.40836)
		(width 0.1016)
		(layer "In7.Cu")
		(net "PHY_SCC_A_TO_DRV_A_30_DP")
	)
	(segment
		(start 279.101804 -294.162226)
		(end 279.364694 -293.899336)
		(width 0.1016)
		(layer "In7.Cu")
		(net "PHY_SCC_A_TO_DRV_A_30_DP")
	)
	(segment
		(start 279.636728 -294.705278)
		(end 279.203404 -294.705278)
		(width 0.1016)
		(layer "In7.Cu")
		(net "PHY_SCC_A_TO_DRV_A_30_DP")
	)
	(segment
		(start 284.44063 -292.471602)
		(end 284.578806 -292.199314)
		(width 0.1016)
		(layer "In7.Cu")
		(net "PHY_SCC_A_TO_DRV_A_30_DP")
	)
	(segment
		(start 283.878528 -292.42766)
		(end 284.150816 -292.56609)
		(width 0.1016)
		(layer "In7.Cu")
		(net "PHY_SCC_A_TO_DRV_A_30_DP")
	)
	(segment
		(start 279.364694 -293.899336)
		(end 282.888436 -292.750494)
		(width 0.1016)
		(layer "In7.Cu")
		(net "PHY_SCC_A_TO_DRV_A_30_DP")
	)
	(segment
		(start 310.17591 -143.9672)
		(end 308.681374 -136.53135)
		(width 0.1016)
		(layer "In7.Cu")
		(net "PHY_SCC_A_TO_DRV_A_30_DP")
	)
	(segment
		(start 285.430722 -292.148768)
		(end 285.569152 -291.87648)
		(width 0.1016)
		(layer "In7.Cu")
		(net "PHY_SCC_A_TO_DRV_A_30_DP")
	)
	(segment
		(start 283.588714 -292.522148)
		(end 283.878528 -292.42766)
		(width 0.1016)
		(layer "In7.Cu")
		(net "PHY_SCC_A_TO_DRV_A_30_DP")
	)
	(segment
		(start 319.9511 -44.441872)
		(end 319.9511 -42.728642)
		(width 0.1016)
		(layer "In7.Cu")
		(net "PHY_SCC_A_TO_DRV_A_30_DP")
	)
	(segment
		(start 289.14217 -289.85083)
		(end 297.640248 -283.607764)
		(width 0.1016)
		(layer "In7.Cu")
		(net "PHY_SCC_A_TO_DRV_A_30_DP")
	)
	(segment
		(start 318.969898 -234.769406)
		(end 305.31816 -166.831518)
		(width 0.1016)
		(layer "In7.Cu")
		(net "PHY_SCC_A_TO_DRV_A_30_DP")
	)
	(segment
		(start 288.383472 -290.40836)
		(end 288.843466 -290.070286)
		(width 0.1016)
		(layer "In7.Cu")
		(net "PHY_SCC_A_TO_DRV_A_30_DP")
	)
	(segment
		(start 297.640248 -283.607764)
		(end 312.368438 -264.050018)
		(width 0.1016)
		(layer "In7.Cu")
		(net "PHY_SCC_A_TO_DRV_A_30_DP")
	)
	(segment
		(start 283.450538 -292.794182)
		(end 283.588714 -292.522148)
		(width 0.1016)
		(layer "In7.Cu")
		(net "PHY_SCC_A_TO_DRV_A_30_DP")
	)
	(segment
		(start 282.888436 -292.750494)
		(end 283.160724 -292.88867)
		(width 0.1016)
		(layer "In7.Cu")
		(net "PHY_SCC_A_TO_DRV_A_30_DP")
	)
	(segment
		(start 304.224436 -114.355118)
		(end 319.9511 -44.441872)
		(width 0.1016)
		(layer "In7.Cu")
		(net "PHY_SCC_A_TO_DRV_A_30_DP")
	)
	(arc
		(start 319.9511 -42.728642)
		(mid 319.980858 -42.6568)
		(end 320.0527 -42.627042)
		(width 0.1016)
		(layer "In7.Cu")
		(net "PHY_SCC_A_TO_DRV_A_30_DP")
	)
	(arc
		(start 279.203404 -294.705278)
		(mid 279.131562 -294.67552)
		(end 279.101804 -294.603678)
		(width 0.1016)
		(layer "In7.Cu")
		(net "PHY_SCC_A_TO_DRV_A_30_DP")
	)
	(segment
		(start 319.63995 -43.65625)
		(end 319.63995 -42.851832)
		(width 0.127)
		(layer "F.Cu")
		(net "PHY_SCC_A_TO_DRV_A_30_DN")
	)
	(segment
		(start 321.025774 -44.051982)
		(end 320.035682 -44.051982)
		(width 0.127)
		(layer "F.Cu")
		(net "PHY_SCC_A_TO_DRV_A_30_DN")
	)
	(segment
		(start 321.355212 -44.219368)
		(end 321.19316 -44.219368)
		(width 0.127)
		(layer "F.Cu")
		(net "PHY_SCC_A_TO_DRV_A_30_DN")
	)
	(segment
		(start 320.035682 -44.051982)
		(end 319.63995 -43.65625)
		(width 0.127)
		(layer "F.Cu")
		(net "PHY_SCC_A_TO_DRV_A_30_DN")
	)
	(segment
		(start 319.41516 -42.627042)
		(end 319.2145 -42.627042)
		(width 0.127)
		(layer "F.Cu")
		(net "PHY_SCC_A_TO_DRV_A_30_DN")
	)
	(segment
		(start 321.19316 -44.219368)
		(end 321.025774 -44.051982)
		(width 0.127)
		(layer "F.Cu")
		(net "PHY_SCC_A_TO_DRV_A_30_DN")
	)
	(arc
		(start 319.63995 -42.851832)
		(mid 319.574111 -42.692881)
		(end 319.41516 -42.627042)
		(width 0.127)
		(layer "F.Cu")
		(net "PHY_SCC_A_TO_DRV_A_30_DN")
	)
	(segment
		(start 288.94659 -289.584638)
		(end 297.405552 -283.370274)
		(width 0.1016)
		(layer "In7.Cu")
		(net "PHY_SCC_A_TO_DRV_A_30_DN")
	)
	(segment
		(start 288.27476 -290.07816)
		(end 288.275014 -290.07816)
		(width 0.1016)
		(layer "In7.Cu")
		(net "PHY_SCC_A_TO_DRV_A_30_DN")
	)
	(segment
		(start 303.886616 -114.351308)
		(end 319.6209 -44.405042)
		(width 0.1016)
		(layer "In7.Cu")
		(net "PHY_SCC_A_TO_DRV_A_30_DN")
	)
	(segment
		(start 304.980848 -166.82974)
		(end 309.838598 -143.965422)
		(width 0.1016)
		(layer "In7.Cu")
		(net "PHY_SCC_A_TO_DRV_A_30_DN")
	)
	(segment
		(start 309.838598 -143.965422)
		(end 303.886616 -114.351308)
		(width 0.1016)
		(layer "In7.Cu")
		(net "PHY_SCC_A_TO_DRV_A_30_DN")
	)
	(segment
		(start 288.647886 -289.804094)
		(end 288.94659 -289.584638)
		(width 0.1016)
		(layer "In7.Cu")
		(net "PHY_SCC_A_TO_DRV_A_30_DN")
	)
	(segment
		(start 319.6209 -44.405042)
		(end 319.6209 -42.728642)
		(width 0.1016)
		(layer "In7.Cu")
		(net "PHY_SCC_A_TO_DRV_A_30_DN")
	)
	(segment
		(start 278.771604 -294.02532)
		(end 279.186894 -293.609776)
		(width 0.1016)
		(layer "In7.Cu")
		(net "PHY_SCC_A_TO_DRV_A_30_DN")
	)
	(segment
		(start 318.632078 -234.765342)
		(end 304.980848 -166.82974)
		(width 0.1016)
		(layer "In7.Cu")
		(net "PHY_SCC_A_TO_DRV_A_30_DN")
	)
	(segment
		(start 312.06186 -263.908032)
		(end 318.632078 -234.765342)
		(width 0.1016)
		(layer "In7.Cu")
		(net "PHY_SCC_A_TO_DRV_A_30_DN")
	)
	(segment
		(start 278.771604 -294.603678)
		(end 278.771604 -294.02532)
		(width 0.1016)
		(layer "In7.Cu")
		(net "PHY_SCC_A_TO_DRV_A_30_DN")
	)
	(segment
		(start 319.5193 -42.627042)
		(end 319.2145 -42.627042)
		(width 0.1016)
		(layer "In7.Cu")
		(net "PHY_SCC_A_TO_DRV_A_30_DN")
	)
	(segment
		(start 286.883094 -291.10051)
		(end 288.27476 -290.07816)
		(width 0.1016)
		(layer "In7.Cu")
		(net "PHY_SCC_A_TO_DRV_A_30_DN")
	)
	(segment
		(start 288.275014 -290.07816)
		(end 288.647886 -289.804094)
		(width 0.1016)
		(layer "In7.Cu")
		(net "PHY_SCC_A_TO_DRV_A_30_DN")
	)
	(segment
		(start 278.23668 -294.705278)
		(end 278.670004 -294.705278)
		(width 0.1016)
		(layer "In7.Cu")
		(net "PHY_SCC_A_TO_DRV_A_30_DN")
	)
	(segment
		(start 279.186894 -293.609776)
		(end 286.883094 -291.10051)
		(width 0.1016)
		(layer "In7.Cu")
		(net "PHY_SCC_A_TO_DRV_A_30_DN")
	)
	(segment
		(start 297.405552 -283.370274)
		(end 312.06186 -263.908032)
		(width 0.1016)
		(layer "In7.Cu")
		(net "PHY_SCC_A_TO_DRV_A_30_DN")
	)
	(arc
		(start 319.6209 -42.728642)
		(mid 319.591142 -42.6568)
		(end 319.5193 -42.627042)
		(width 0.1016)
		(layer "In7.Cu")
		(net "PHY_SCC_A_TO_DRV_A_30_DN")
	)
	(arc
		(start 278.670004 -294.705278)
		(mid 278.741846 -294.67552)
		(end 278.771604 -294.603678)
		(width 0.1016)
		(layer "In7.Cu")
		(net "PHY_SCC_A_TO_DRV_A_30_DN")
	)
	(segment
		(start 237.437676 -335.307432)
		(end 237.43793 -335.307432)
		(width 0.127)
		(layer "F.Cu")
		(net "PHY_SCC_A_TO_DRV_A_3_DP")
	)
	(segment
		(start 137.296652 -291.151818)
		(end 136.597136 -294.306244)
		(width 0.127)
		(layer "F.Cu")
		(net "PHY_SCC_A_TO_DRV_A_3_DP")
	)
	(segment
		(start 137.459974 -283.342588)
		(end 136.512808 -287.616646)
		(width 0.127)
		(layer "F.Cu")
		(net "PHY_SCC_A_TO_DRV_A_3_DP")
	)
	(segment
		(start 136.597136 -294.306244)
		(end 138.570716 -303.209706)
		(width 0.127)
		(layer "F.Cu")
		(net "PHY_SCC_A_TO_DRV_A_3_DP")
	)
	(segment
		(start 272.81505 -354.104956)
		(end 273.1135 -354.104956)
		(width 0.127)
		(layer "F.Cu")
		(net "PHY_SCC_A_TO_DRV_A_3_DP")
	)
	(segment
		(start 138.570716 -303.209706)
		(end 138.570716 -303.210214)
		(width 0.127)
		(layer "F.Cu")
		(net "PHY_SCC_A_TO_DRV_A_3_DP")
	)
	(segment
		(start 135.702802 -278.524208)
		(end 136.757664 -280.177748)
		(width 0.127)
		(layer "F.Cu")
		(net "PHY_SCC_A_TO_DRV_A_3_DP")
	)
	(segment
		(start 152.713436 -335.43875)
		(end 155.470352 -337.119214)
		(width 0.127)
		(layer "F.Cu")
		(net "PHY_SCC_A_TO_DRV_A_3_DP")
	)
	(segment
		(start 146.863562 -316.228222)
		(end 150.27402 -331.609192)
		(width 0.127)
		(layer "F.Cu")
		(net "PHY_SCC_A_TO_DRV_A_3_DP")
	)
	(segment
		(start 159.078422 -337.841336)
		(end 204.333856 -328.679048)
		(width 0.127)
		(layer "F.Cu")
		(net "PHY_SCC_A_TO_DRV_A_3_DP")
	)
	(segment
		(start 136.512808 -287.616646)
		(end 137.296652 -291.151818)
		(width 0.127)
		(layer "F.Cu")
		(net "PHY_SCC_A_TO_DRV_A_3_DP")
	)
	(segment
		(start 150.27402 -331.609192)
		(end 152.713436 -335.43875)
		(width 0.127)
		(layer "F.Cu")
		(net "PHY_SCC_A_TO_DRV_A_3_DP")
	)
	(segment
		(start 128.36017 -273.84121)
		(end 135.702802 -278.524208)
		(width 0.127)
		(layer "F.Cu")
		(net "PHY_SCC_A_TO_DRV_A_3_DP")
	)
	(segment
		(start 155.470352 -337.119214)
		(end 159.078422 -337.841336)
		(width 0.127)
		(layer "F.Cu")
		(net "PHY_SCC_A_TO_DRV_A_3_DP")
	)
	(segment
		(start 136.757664 -280.177748)
		(end 137.459974 -283.342588)
		(width 0.127)
		(layer "F.Cu")
		(net "PHY_SCC_A_TO_DRV_A_3_DP")
	)
	(segment
		(start 270.787368 -353.121722)
		(end 272.26895 -353.121722)
		(width 0.127)
		(layer "F.Cu")
		(net "PHY_SCC_A_TO_DRV_A_3_DP")
	)
	(segment
		(start 128.056894 -273.84121)
		(end 128.36017 -273.84121)
		(width 0.127)
		(layer "F.Cu")
		(net "PHY_SCC_A_TO_DRV_A_3_DP")
	)
	(segment
		(start 127.392684 -273.660616)
		(end 127.8763 -273.660616)
		(width 0.127)
		(layer "F.Cu")
		(net "PHY_SCC_A_TO_DRV_A_3_DP")
	)
	(segment
		(start 127.8763 -273.660616)
		(end 128.056894 -273.84121)
		(width 0.127)
		(layer "F.Cu")
		(net "PHY_SCC_A_TO_DRV_A_3_DP")
	)
	(segment
		(start 272.68805 -353.540822)
		(end 272.68805 -353.977956)
		(width 0.127)
		(layer "F.Cu")
		(net "PHY_SCC_A_TO_DRV_A_3_DP")
	)
	(segment
		(start 138.570716 -303.210214)
		(end 146.863562 -316.228222)
		(width 0.127)
		(layer "F.Cu")
		(net "PHY_SCC_A_TO_DRV_A_3_DP")
	)
	(segment
		(start 204.333856 -328.679048)
		(end 237.437676 -335.307432)
		(width 0.127)
		(layer "F.Cu")
		(net "PHY_SCC_A_TO_DRV_A_3_DP")
	)
	(segment
		(start 237.43793 -335.307432)
		(end 270.787368 -353.121722)
		(width 0.127)
		(layer "F.Cu")
		(net "PHY_SCC_A_TO_DRV_A_3_DP")
	)
	(arc
		(start 272.26895 -353.121722)
		(mid 272.565298 -353.244474)
		(end 272.68805 -353.540822)
		(width 0.127)
		(layer "F.Cu")
		(net "PHY_SCC_A_TO_DRV_A_3_DP")
	)
	(arc
		(start 272.68805 -353.977956)
		(mid 272.725247 -354.067759)
		(end 272.81505 -354.104956)
		(width 0.127)
		(layer "F.Cu")
		(net "PHY_SCC_A_TO_DRV_A_3_DP")
	)
	(segment
		(start 279.082754 -352.432112)
		(end 279.082754 -352.683064)
		(width 0.127)
		(layer "B.Cu")
		(net "PHY_SCC_A_TO_DRV_A_3_DP")
	)
	(segment
		(start 279.636728 -352.305112)
		(end 279.209754 -352.305112)
		(width 0.127)
		(layer "B.Cu")
		(net "PHY_SCC_A_TO_DRV_A_3_DP")
	)
	(segment
		(start 278.329136 -353.351084)
		(end 273.11223 -353.351084)
		(width 0.127)
		(layer "B.Cu")
		(net "PHY_SCC_A_TO_DRV_A_3_DP")
	)
	(segment
		(start 272.68805 -353.775264)
		(end 272.68805 -353.923854)
		(width 0.127)
		(layer "B.Cu")
		(net "PHY_SCC_A_TO_DRV_A_3_DP")
	)
	(segment
		(start 272.869152 -354.104956)
		(end 273.1135 -354.104956)
		(width 0.127)
		(layer "B.Cu")
		(net "PHY_SCC_A_TO_DRV_A_3_DP")
	)
	(arc
		(start 273.11223 -353.351084)
		(mid 272.812289 -353.475323)
		(end 272.68805 -353.775264)
		(width 0.127)
		(layer "B.Cu")
		(net "PHY_SCC_A_TO_DRV_A_3_DP")
	)
	(arc
		(start 278.949658 -353.062794)
		(mid 278.927871 -353.088559)
		(end 278.9047 -353.113086)
		(width 0.127)
		(layer "B.Cu")
		(net "PHY_SCC_A_TO_DRV_A_3_DP")
	)
	(arc
		(start 278.9047 -353.113086)
		(mid 278.640599 -353.289367)
		(end 278.329136 -353.351084)
		(width 0.127)
		(layer "B.Cu")
		(net "PHY_SCC_A_TO_DRV_A_3_DP")
	)
	(arc
		(start 272.68805 -353.923854)
		(mid 272.741094 -354.051912)
		(end 272.869152 -354.104956)
		(width 0.127)
		(layer "B.Cu")
		(net "PHY_SCC_A_TO_DRV_A_3_DP")
	)
	(arc
		(start 279.082754 -352.683064)
		(mid 279.04852 -352.884257)
		(end 278.949658 -353.062794)
		(width 0.127)
		(layer "B.Cu")
		(net "PHY_SCC_A_TO_DRV_A_3_DP")
	)
	(arc
		(start 279.209754 -352.305112)
		(mid 279.119951 -352.342309)
		(end 279.082754 -352.432112)
		(width 0.127)
		(layer "B.Cu")
		(net "PHY_SCC_A_TO_DRV_A_3_DP")
	)
	(segment
		(start 136.213596 -287.616646)
		(end 136.99744 -291.151818)
		(width 0.127)
		(layer "F.Cu")
		(net "PHY_SCC_A_TO_DRV_A_3_DN")
	)
	(segment
		(start 128.274826 -274.13331)
		(end 135.49122 -278.73579)
		(width 0.127)
		(layer "F.Cu")
		(net "PHY_SCC_A_TO_DRV_A_3_DN")
	)
	(segment
		(start 208.518252 -329.814936)
		(end 237.338108 -335.585562)
		(width 0.127)
		(layer "F.Cu")
		(net "PHY_SCC_A_TO_DRV_A_3_DN")
	)
	(segment
		(start 205.380082 -329.186794)
		(end 205.753716 -329.26147)
		(width 0.127)
		(layer "F.Cu")
		(net "PHY_SCC_A_TO_DRV_A_3_DN")
	)
	(segment
		(start 138.271504 -303.20996)
		(end 138.259312 -303.265332)
		(width 0.127)
		(layer "F.Cu")
		(net "PHY_SCC_A_TO_DRV_A_3_DN")
	)
	(segment
		(start 207.845914 -329.680316)
		(end 207.965294 -329.85964)
		(width 0.127)
		(layer "F.Cu")
		(net "PHY_SCC_A_TO_DRV_A_3_DN")
	)
	(segment
		(start 146.589496 -316.342268)
		(end 149.999954 -331.72273)
		(width 0.127)
		(layer "F.Cu")
		(net "PHY_SCC_A_TO_DRV_A_3_DN")
	)
	(segment
		(start 206.919322 -329.650344)
		(end 207.292956 -329.72502)
		(width 0.127)
		(layer "F.Cu")
		(net "PHY_SCC_A_TO_DRV_A_3_DN")
	)
	(segment
		(start 137.160762 -283.342588)
		(end 136.213596 -287.616646)
		(width 0.127)
		(layer "F.Cu")
		(net "PHY_SCC_A_TO_DRV_A_3_DN")
	)
	(segment
		(start 155.362402 -337.395566)
		(end 159.078676 -338.139532)
		(width 0.127)
		(layer "F.Cu")
		(net "PHY_SCC_A_TO_DRV_A_3_DN")
	)
	(segment
		(start 135.49122 -278.73579)
		(end 136.483598 -280.291286)
		(width 0.127)
		(layer "F.Cu")
		(net "PHY_SCC_A_TO_DRV_A_3_DN")
	)
	(segment
		(start 272.39595 -353.540822)
		(end 272.39595 -353.977956)
		(width 0.127)
		(layer "F.Cu")
		(net "PHY_SCC_A_TO_DRV_A_3_DN")
	)
	(segment
		(start 159.078676 -338.139532)
		(end 204.33411 -328.977244)
		(width 0.127)
		(layer "F.Cu")
		(net "PHY_SCC_A_TO_DRV_A_3_DN")
	)
	(segment
		(start 205.87335 -329.440794)
		(end 206.24673 -329.515724)
		(width 0.127)
		(layer "F.Cu")
		(net "PHY_SCC_A_TO_DRV_A_3_DN")
	)
	(segment
		(start 208.338928 -329.93457)
		(end 208.518252 -329.814936)
		(width 0.127)
		(layer "F.Cu")
		(net "PHY_SCC_A_TO_DRV_A_3_DN")
	)
	(segment
		(start 149.999954 -331.72273)
		(end 152.503378 -335.652872)
		(width 0.127)
		(layer "F.Cu")
		(net "PHY_SCC_A_TO_DRV_A_3_DN")
	)
	(segment
		(start 206.426308 -329.39609)
		(end 206.799688 -329.47102)
		(width 0.127)
		(layer "F.Cu")
		(net "PHY_SCC_A_TO_DRV_A_3_DN")
	)
	(segment
		(start 136.483598 -280.291286)
		(end 137.160762 -283.342588)
		(width 0.127)
		(layer "F.Cu")
		(net "PHY_SCC_A_TO_DRV_A_3_DN")
	)
	(segment
		(start 204.707744 -329.05192)
		(end 204.827124 -329.231498)
		(width 0.127)
		(layer "F.Cu")
		(net "PHY_SCC_A_TO_DRV_A_3_DN")
	)
	(segment
		(start 138.259312 -303.265332)
		(end 146.589496 -316.342268)
		(width 0.127)
		(layer "F.Cu")
		(net "PHY_SCC_A_TO_DRV_A_3_DN")
	)
	(segment
		(start 206.24673 -329.515724)
		(end 206.426308 -329.39609)
		(width 0.127)
		(layer "F.Cu")
		(net "PHY_SCC_A_TO_DRV_A_3_DN")
	)
	(segment
		(start 207.47228 -329.60564)
		(end 207.845914 -329.680316)
		(width 0.127)
		(layer "F.Cu")
		(net "PHY_SCC_A_TO_DRV_A_3_DN")
	)
	(segment
		(start 152.503378 -335.652872)
		(end 155.362402 -337.395566)
		(width 0.127)
		(layer "F.Cu")
		(net "PHY_SCC_A_TO_DRV_A_3_DN")
	)
	(segment
		(start 206.799688 -329.47102)
		(end 206.919322 -329.650344)
		(width 0.127)
		(layer "F.Cu")
		(net "PHY_SCC_A_TO_DRV_A_3_DN")
	)
	(segment
		(start 272.26895 -354.104956)
		(end 271.9705 -354.104956)
		(width 0.127)
		(layer "F.Cu")
		(net "PHY_SCC_A_TO_DRV_A_3_DN")
	)
	(segment
		(start 127.392684 -274.219416)
		(end 127.8763 -274.219416)
		(width 0.127)
		(layer "F.Cu")
		(net "PHY_SCC_A_TO_DRV_A_3_DN")
	)
	(segment
		(start 136.99744 -291.151818)
		(end 136.297924 -294.306244)
		(width 0.127)
		(layer "F.Cu")
		(net "PHY_SCC_A_TO_DRV_A_3_DN")
	)
	(segment
		(start 127.962406 -274.13331)
		(end 128.274826 -274.13331)
		(width 0.127)
		(layer "F.Cu")
		(net "PHY_SCC_A_TO_DRV_A_3_DN")
	)
	(segment
		(start 207.292956 -329.72502)
		(end 207.47228 -329.60564)
		(width 0.127)
		(layer "F.Cu")
		(net "PHY_SCC_A_TO_DRV_A_3_DN")
	)
	(segment
		(start 136.297924 -294.306244)
		(end 138.271504 -303.20996)
		(width 0.127)
		(layer "F.Cu")
		(net "PHY_SCC_A_TO_DRV_A_3_DN")
	)
	(segment
		(start 270.714216 -353.413822)
		(end 272.26895 -353.413822)
		(width 0.127)
		(layer "F.Cu")
		(net "PHY_SCC_A_TO_DRV_A_3_DN")
	)
	(segment
		(start 127.8763 -274.219416)
		(end 127.962406 -274.13331)
		(width 0.127)
		(layer "F.Cu")
		(net "PHY_SCC_A_TO_DRV_A_3_DN")
	)
	(segment
		(start 204.827124 -329.231498)
		(end 205.200758 -329.306174)
		(width 0.127)
		(layer "F.Cu")
		(net "PHY_SCC_A_TO_DRV_A_3_DN")
	)
	(segment
		(start 207.965294 -329.85964)
		(end 208.338928 -329.93457)
		(width 0.127)
		(layer "F.Cu")
		(net "PHY_SCC_A_TO_DRV_A_3_DN")
	)
	(segment
		(start 237.338108 -335.585562)
		(end 270.714216 -353.413822)
		(width 0.127)
		(layer "F.Cu")
		(net "PHY_SCC_A_TO_DRV_A_3_DN")
	)
	(segment
		(start 204.33411 -328.977244)
		(end 204.707744 -329.05192)
		(width 0.127)
		(layer "F.Cu")
		(net "PHY_SCC_A_TO_DRV_A_3_DN")
	)
	(segment
		(start 205.753716 -329.26147)
		(end 205.87335 -329.440794)
		(width 0.127)
		(layer "F.Cu")
		(net "PHY_SCC_A_TO_DRV_A_3_DN")
	)
	(segment
		(start 205.200758 -329.306174)
		(end 205.380082 -329.186794)
		(width 0.127)
		(layer "F.Cu")
		(net "PHY_SCC_A_TO_DRV_A_3_DN")
	)
	(arc
		(start 272.39595 -353.977956)
		(mid 272.358753 -354.067759)
		(end 272.26895 -354.104956)
		(width 0.127)
		(layer "F.Cu")
		(net "PHY_SCC_A_TO_DRV_A_3_DN")
	)
	(arc
		(start 272.26895 -353.413822)
		(mid 272.358753 -353.451019)
		(end 272.39595 -353.540822)
		(width 0.127)
		(layer "F.Cu")
		(net "PHY_SCC_A_TO_DRV_A_3_DN")
	)
	(segment
		(start 271.9705 -354.104956)
		(end 272.214848 -354.104956)
		(width 0.127)
		(layer "B.Cu")
		(net "PHY_SCC_A_TO_DRV_A_3_DN")
	)
	(segment
		(start 273.11223 -353.058984)
		(end 278.32939 -353.058984)
		(width 0.127)
		(layer "B.Cu")
		(net "PHY_SCC_A_TO_DRV_A_3_DN")
	)
	(segment
		(start 278.790654 -352.682556)
		(end 278.790654 -352.432112)
		(width 0.127)
		(layer "B.Cu")
		(net "PHY_SCC_A_TO_DRV_A_3_DN")
	)
	(segment
		(start 278.663654 -352.305112)
		(end 278.23668 -352.305112)
		(width 0.127)
		(layer "B.Cu")
		(net "PHY_SCC_A_TO_DRV_A_3_DN")
	)
	(segment
		(start 272.39595 -353.923854)
		(end 272.39595 -353.775264)
		(width 0.127)
		(layer "B.Cu")
		(net "PHY_SCC_A_TO_DRV_A_3_DN")
	)
	(arc
		(start 272.214848 -354.104956)
		(mid 272.342906 -354.051912)
		(end 272.39595 -353.923854)
		(width 0.127)
		(layer "B.Cu")
		(net "PHY_SCC_A_TO_DRV_A_3_DN")
	)
	(arc
		(start 278.32939 -353.058984)
		(mid 278.528848 -353.019309)
		(end 278.697944 -352.90633)
		(width 0.127)
		(layer "B.Cu")
		(net "PHY_SCC_A_TO_DRV_A_3_DN")
	)
	(arc
		(start 278.790654 -352.432112)
		(mid 278.753457 -352.342309)
		(end 278.663654 -352.305112)
		(width 0.127)
		(layer "B.Cu")
		(net "PHY_SCC_A_TO_DRV_A_3_DN")
	)
	(arc
		(start 272.39595 -353.775264)
		(mid 272.605744 -353.268778)
		(end 273.11223 -353.058984)
		(width 0.127)
		(layer "B.Cu")
		(net "PHY_SCC_A_TO_DRV_A_3_DN")
	)
	(arc
		(start 278.721312 -352.880168)
		(mid 278.772819 -352.787269)
		(end 278.790654 -352.682556)
		(width 0.127)
		(layer "B.Cu")
		(net "PHY_SCC_A_TO_DRV_A_3_DN")
	)
	(arc
		(start 278.697944 -352.90633)
		(mid 278.709988 -352.89357)
		(end 278.721312 -352.880168)
		(width 0.127)
		(layer "B.Cu")
		(net "PHY_SCC_A_TO_DRV_A_3_DN")
	)
	(segment
		(start 215.899238 -197.366128)
		(end 218.590876 -186.462162)
		(width 0.127)
		(layer "F.Cu")
		(net "PHY_SCC_A_TO_DRV_A_29_DP")
	)
	(segment
		(start 195.528438 -48.513238)
		(end 192.931034 -44.625006)
		(width 0.127)
		(layer "F.Cu")
		(net "PHY_SCC_A_TO_DRV_A_29_DP")
	)
	(segment
		(start 273.1135 -307.304948)
		(end 272.81505 -307.304948)
		(width 0.127)
		(layer "F.Cu")
		(net "PHY_SCC_A_TO_DRV_A_29_DP")
	)
	(segment
		(start 192.931034 -44.625006)
		(end 191.6684 -43.825922)
		(width 0.127)
		(layer "F.Cu")
		(net "PHY_SCC_A_TO_DRV_A_29_DP")
	)
	(segment
		(start 239.91316 -297.559984)
		(end 228.08311 -278.862536)
		(width 0.127)
		(layer "F.Cu")
		(net "PHY_SCC_A_TO_DRV_A_29_DP")
	)
	(segment
		(start 196.404992 -52.68595)
		(end 195.528438 -48.513238)
		(width 0.127)
		(layer "F.Cu")
		(net "PHY_SCC_A_TO_DRV_A_29_DP")
	)
	(segment
		(start 272.26895 -306.321714)
		(end 259.375656 -306.321714)
		(width 0.127)
		(layer "F.Cu")
		(net "PHY_SCC_A_TO_DRV_A_29_DP")
	)
	(segment
		(start 272.68805 -307.177948)
		(end 272.68805 -306.740814)
		(width 0.127)
		(layer "F.Cu")
		(net "PHY_SCC_A_TO_DRV_A_29_DP")
	)
	(segment
		(start 213.240874 -208.134712)
		(end 215.899238 -197.366128)
		(width 0.127)
		(layer "F.Cu")
		(net "PHY_SCC_A_TO_DRV_A_29_DP")
	)
	(segment
		(start 191.045338 -43.825922)
		(end 190.879984 -43.660568)
		(width 0.127)
		(layer "F.Cu")
		(net "PHY_SCC_A_TO_DRV_A_29_DP")
	)
	(segment
		(start 191.6684 -43.825922)
		(end 191.045338 -43.825922)
		(width 0.127)
		(layer "F.Cu")
		(net "PHY_SCC_A_TO_DRV_A_29_DP")
	)
	(segment
		(start 218.590876 -186.462162)
		(end 190.731648 -75.670918)
		(width 0.127)
		(layer "F.Cu")
		(net "PHY_SCC_A_TO_DRV_A_29_DP")
	)
	(segment
		(start 228.08311 -278.862536)
		(end 213.240874 -208.134712)
		(width 0.127)
		(layer "F.Cu")
		(net "PHY_SCC_A_TO_DRV_A_29_DP")
	)
	(segment
		(start 190.879984 -43.660568)
		(end 190.492888 -43.660568)
		(width 0.127)
		(layer "F.Cu")
		(net "PHY_SCC_A_TO_DRV_A_29_DP")
	)
	(segment
		(start 244.534436 -301.201582)
		(end 239.91316 -297.559984)
		(width 0.127)
		(layer "F.Cu")
		(net "PHY_SCC_A_TO_DRV_A_29_DP")
	)
	(segment
		(start 190.731648 -75.670918)
		(end 196.404992 -52.68595)
		(width 0.127)
		(layer "F.Cu")
		(net "PHY_SCC_A_TO_DRV_A_29_DP")
	)
	(segment
		(start 259.375656 -306.321714)
		(end 244.534436 -301.201582)
		(width 0.127)
		(layer "F.Cu")
		(net "PHY_SCC_A_TO_DRV_A_29_DP")
	)
	(arc
		(start 272.81505 -307.304948)
		(mid 272.725247 -307.267751)
		(end 272.68805 -307.177948)
		(width 0.127)
		(layer "F.Cu")
		(net "PHY_SCC_A_TO_DRV_A_29_DP")
	)
	(arc
		(start 272.68805 -306.740814)
		(mid 272.565298 -306.444466)
		(end 272.26895 -306.321714)
		(width 0.127)
		(layer "F.Cu")
		(net "PHY_SCC_A_TO_DRV_A_29_DP")
	)
	(segment
		(start 278.329136 -306.551076)
		(end 273.11223 -306.551076)
		(width 0.127)
		(layer "B.Cu")
		(net "PHY_SCC_A_TO_DRV_A_29_DP")
	)
	(segment
		(start 279.082754 -305.632104)
		(end 279.082754 -305.883056)
		(width 0.127)
		(layer "B.Cu")
		(net "PHY_SCC_A_TO_DRV_A_29_DP")
	)
	(segment
		(start 272.869152 -307.304948)
		(end 273.1135 -307.304948)
		(width 0.127)
		(layer "B.Cu")
		(net "PHY_SCC_A_TO_DRV_A_29_DP")
	)
	(segment
		(start 272.68805 -306.975256)
		(end 272.68805 -307.123846)
		(width 0.127)
		(layer "B.Cu")
		(net "PHY_SCC_A_TO_DRV_A_29_DP")
	)
	(segment
		(start 279.636728 -305.505104)
		(end 279.209754 -305.505104)
		(width 0.127)
		(layer "B.Cu")
		(net "PHY_SCC_A_TO_DRV_A_29_DP")
	)
	(arc
		(start 279.082754 -305.883056)
		(mid 279.04852 -306.084249)
		(end 278.949658 -306.262786)
		(width 0.127)
		(layer "B.Cu")
		(net "PHY_SCC_A_TO_DRV_A_29_DP")
	)
	(arc
		(start 279.209754 -305.505104)
		(mid 279.119951 -305.542301)
		(end 279.082754 -305.632104)
		(width 0.127)
		(layer "B.Cu")
		(net "PHY_SCC_A_TO_DRV_A_29_DP")
	)
	(arc
		(start 273.11223 -306.551076)
		(mid 272.812289 -306.675315)
		(end 272.68805 -306.975256)
		(width 0.127)
		(layer "B.Cu")
		(net "PHY_SCC_A_TO_DRV_A_29_DP")
	)
	(arc
		(start 278.9047 -306.313078)
		(mid 278.640599 -306.489359)
		(end 278.329136 -306.551076)
		(width 0.127)
		(layer "B.Cu")
		(net "PHY_SCC_A_TO_DRV_A_29_DP")
	)
	(arc
		(start 278.949658 -306.262786)
		(mid 278.927871 -306.288551)
		(end 278.9047 -306.313078)
		(width 0.127)
		(layer "B.Cu")
		(net "PHY_SCC_A_TO_DRV_A_29_DP")
	)
	(arc
		(start 272.68805 -307.123846)
		(mid 272.741094 -307.251904)
		(end 272.869152 -307.304948)
		(width 0.127)
		(layer "B.Cu")
		(net "PHY_SCC_A_TO_DRV_A_29_DP")
	)
	(segment
		(start 267.961872 -306.613814)
		(end 267.809472 -306.766214)
		(width 0.127)
		(layer "F.Cu")
		(net "PHY_SCC_A_TO_DRV_A_29_DN")
	)
	(segment
		(start 272.39595 -307.177948)
		(end 272.39595 -306.740814)
		(width 0.127)
		(layer "F.Cu")
		(net "PHY_SCC_A_TO_DRV_A_29_DN")
	)
	(segment
		(start 244.39245 -301.461678)
		(end 244.353588 -301.431198)
		(width 0.127)
		(layer "F.Cu")
		(net "PHY_SCC_A_TO_DRV_A_29_DN")
	)
	(segment
		(start 244.353842 -301.431198)
		(end 242.04295 -299.610272)
		(width 0.127)
		(layer "F.Cu")
		(net "PHY_SCC_A_TO_DRV_A_29_DN")
	)
	(segment
		(start 212.941154 -208.129378)
		(end 218.289632 -186.462924)
		(width 0.127)
		(layer "F.Cu")
		(net "PHY_SCC_A_TO_DRV_A_29_DN")
	)
	(segment
		(start 266.361672 -306.766214)
		(end 266.209272 -306.613814)
		(width 0.127)
		(layer "F.Cu")
		(net "PHY_SCC_A_TO_DRV_A_29_DN")
	)
	(segment
		(start 191.05245 -44.118022)
		(end 190.951104 -44.219368)
		(width 0.127)
		(layer "F.Cu")
		(net "PHY_SCC_A_TO_DRV_A_29_DN")
	)
	(segment
		(start 266.209272 -306.613814)
		(end 259.326634 -306.613814)
		(width 0.127)
		(layer "F.Cu")
		(net "PHY_SCC_A_TO_DRV_A_29_DN")
	)
	(segment
		(start 266.895072 -306.613814)
		(end 266.742672 -306.766214)
		(width 0.127)
		(layer "F.Cu")
		(net "PHY_SCC_A_TO_DRV_A_29_DN")
	)
	(segment
		(start 269.028672 -306.613814)
		(end 268.876272 -306.766214)
		(width 0.127)
		(layer "F.Cu")
		(net "PHY_SCC_A_TO_DRV_A_29_DN")
	)
	(segment
		(start 268.876272 -306.766214)
		(end 268.495272 -306.766214)
		(width 0.127)
		(layer "F.Cu")
		(net "PHY_SCC_A_TO_DRV_A_29_DN")
	)
	(segment
		(start 192.722246 -44.838874)
		(end 191.583564 -44.118022)
		(width 0.127)
		(layer "F.Cu")
		(net "PHY_SCC_A_TO_DRV_A_29_DN")
	)
	(segment
		(start 267.276072 -306.613814)
		(end 266.895072 -306.613814)
		(width 0.127)
		(layer "F.Cu")
		(net "PHY_SCC_A_TO_DRV_A_29_DN")
	)
	(segment
		(start 259.326634 -306.613814)
		(end 244.39245 -301.461678)
		(width 0.127)
		(layer "F.Cu")
		(net "PHY_SCC_A_TO_DRV_A_29_DN")
	)
	(segment
		(start 267.428472 -306.766214)
		(end 267.276072 -306.613814)
		(width 0.127)
		(layer "F.Cu")
		(net "PHY_SCC_A_TO_DRV_A_29_DN")
	)
	(segment
		(start 190.951104 -44.219368)
		(end 190.492888 -44.219368)
		(width 0.127)
		(layer "F.Cu")
		(net "PHY_SCC_A_TO_DRV_A_29_DN")
	)
	(segment
		(start 196.105272 -52.680616)
		(end 195.679568 -50.654458)
		(width 0.127)
		(layer "F.Cu")
		(net "PHY_SCC_A_TO_DRV_A_29_DN")
	)
	(segment
		(start 195.254118 -48.628554)
		(end 192.722246 -44.838874)
		(width 0.127)
		(layer "F.Cu")
		(net "PHY_SCC_A_TO_DRV_A_29_DN")
	)
	(segment
		(start 268.342872 -306.613814)
		(end 267.961872 -306.613814)
		(width 0.127)
		(layer "F.Cu")
		(net "PHY_SCC_A_TO_DRV_A_29_DN")
	)
	(segment
		(start 268.495272 -306.766214)
		(end 268.342872 -306.613814)
		(width 0.127)
		(layer "F.Cu")
		(net "PHY_SCC_A_TO_DRV_A_29_DN")
	)
	(segment
		(start 191.583564 -44.118022)
		(end 191.05245 -44.118022)
		(width 0.127)
		(layer "F.Cu")
		(net "PHY_SCC_A_TO_DRV_A_29_DN")
	)
	(segment
		(start 269.943072 -306.766214)
		(end 269.562072 -306.766214)
		(width 0.127)
		(layer "F.Cu")
		(net "PHY_SCC_A_TO_DRV_A_29_DN")
	)
	(segment
		(start 271.9705 -307.304948)
		(end 272.26895 -307.304948)
		(width 0.127)
		(layer "F.Cu")
		(net "PHY_SCC_A_TO_DRV_A_29_DN")
	)
	(segment
		(start 266.742672 -306.766214)
		(end 266.361672 -306.766214)
		(width 0.127)
		(layer "F.Cu")
		(net "PHY_SCC_A_TO_DRV_A_29_DN")
	)
	(segment
		(start 227.797106 -278.92248)
		(end 212.941154 -208.129378)
		(width 0.127)
		(layer "F.Cu")
		(net "PHY_SCC_A_TO_DRV_A_29_DN")
	)
	(segment
		(start 242.04295 -299.610272)
		(end 239.692942 -297.758612)
		(width 0.127)
		(layer "F.Cu")
		(net "PHY_SCC_A_TO_DRV_A_29_DN")
	)
	(segment
		(start 227.807774 -278.974296)
		(end 227.796852 -278.92248)
		(width 0.127)
		(layer "F.Cu")
		(net "PHY_SCC_A_TO_DRV_A_29_DN")
	)
	(segment
		(start 272.26895 -306.613814)
		(end 270.095472 -306.613814)
		(width 0.127)
		(layer "F.Cu")
		(net "PHY_SCC_A_TO_DRV_A_29_DN")
	)
	(segment
		(start 267.809472 -306.766214)
		(end 267.428472 -306.766214)
		(width 0.127)
		(layer "F.Cu")
		(net "PHY_SCC_A_TO_DRV_A_29_DN")
	)
	(segment
		(start 190.430404 -75.67168)
		(end 196.105272 -52.680616)
		(width 0.127)
		(layer "F.Cu")
		(net "PHY_SCC_A_TO_DRV_A_29_DN")
	)
	(segment
		(start 195.679568 -50.654458)
		(end 195.679568 -50.654204)
		(width 0.127)
		(layer "F.Cu")
		(net "PHY_SCC_A_TO_DRV_A_29_DN")
	)
	(segment
		(start 269.409672 -306.613814)
		(end 269.028672 -306.613814)
		(width 0.127)
		(layer "F.Cu")
		(net "PHY_SCC_A_TO_DRV_A_29_DN")
	)
	(segment
		(start 218.289632 -186.462924)
		(end 190.430404 -75.67168)
		(width 0.127)
		(layer "F.Cu")
		(net "PHY_SCC_A_TO_DRV_A_29_DN")
	)
	(segment
		(start 195.679568 -50.654204)
		(end 195.254118 -48.628554)
		(width 0.127)
		(layer "F.Cu")
		(net "PHY_SCC_A_TO_DRV_A_29_DN")
	)
	(segment
		(start 244.353588 -301.431198)
		(end 244.353842 -301.431198)
		(width 0.127)
		(layer "F.Cu")
		(net "PHY_SCC_A_TO_DRV_A_29_DN")
	)
	(segment
		(start 269.562072 -306.766214)
		(end 269.409672 -306.613814)
		(width 0.127)
		(layer "F.Cu")
		(net "PHY_SCC_A_TO_DRV_A_29_DN")
	)
	(segment
		(start 227.796852 -278.92248)
		(end 227.797106 -278.92248)
		(width 0.127)
		(layer "F.Cu")
		(net "PHY_SCC_A_TO_DRV_A_29_DN")
	)
	(segment
		(start 270.095472 -306.613814)
		(end 269.943072 -306.766214)
		(width 0.127)
		(layer "F.Cu")
		(net "PHY_SCC_A_TO_DRV_A_29_DN")
	)
	(segment
		(start 239.692942 -297.758612)
		(end 227.807774 -278.974296)
		(width 0.127)
		(layer "F.Cu")
		(net "PHY_SCC_A_TO_DRV_A_29_DN")
	)
	(arc
		(start 272.26895 -307.304948)
		(mid 272.358753 -307.267751)
		(end 272.39595 -307.177948)
		(width 0.127)
		(layer "F.Cu")
		(net "PHY_SCC_A_TO_DRV_A_29_DN")
	)
	(arc
		(start 272.39595 -306.740814)
		(mid 272.358753 -306.651011)
		(end 272.26895 -306.613814)
		(width 0.127)
		(layer "F.Cu")
		(net "PHY_SCC_A_TO_DRV_A_29_DN")
	)
	(segment
		(start 271.9705 -307.304948)
		(end 272.214848 -307.304948)
		(width 0.127)
		(layer "B.Cu")
		(net "PHY_SCC_A_TO_DRV_A_29_DN")
	)
	(segment
		(start 278.790654 -305.882548)
		(end 278.790654 -305.632104)
		(width 0.127)
		(layer "B.Cu")
		(net "PHY_SCC_A_TO_DRV_A_29_DN")
	)
	(segment
		(start 272.39595 -307.123846)
		(end 272.39595 -306.975256)
		(width 0.127)
		(layer "B.Cu")
		(net "PHY_SCC_A_TO_DRV_A_29_DN")
	)
	(segment
		(start 278.663654 -305.505104)
		(end 278.23668 -305.505104)
		(width 0.127)
		(layer "B.Cu")
		(net "PHY_SCC_A_TO_DRV_A_29_DN")
	)
	(segment
		(start 273.11223 -306.258976)
		(end 278.32939 -306.258976)
		(width 0.127)
		(layer "B.Cu")
		(net "PHY_SCC_A_TO_DRV_A_29_DN")
	)
	(arc
		(start 278.721312 -306.08016)
		(mid 278.772819 -305.987261)
		(end 278.790654 -305.882548)
		(width 0.127)
		(layer "B.Cu")
		(net "PHY_SCC_A_TO_DRV_A_29_DN")
	)
	(arc
		(start 272.39595 -306.975256)
		(mid 272.605744 -306.46877)
		(end 273.11223 -306.258976)
		(width 0.127)
		(layer "B.Cu")
		(net "PHY_SCC_A_TO_DRV_A_29_DN")
	)
	(arc
		(start 278.697944 -306.106322)
		(mid 278.709988 -306.093562)
		(end 278.721312 -306.08016)
		(width 0.127)
		(layer "B.Cu")
		(net "PHY_SCC_A_TO_DRV_A_29_DN")
	)
	(arc
		(start 272.214848 -307.304948)
		(mid 272.342906 -307.251904)
		(end 272.39595 -307.123846)
		(width 0.127)
		(layer "B.Cu")
		(net "PHY_SCC_A_TO_DRV_A_29_DN")
	)
	(arc
		(start 278.790654 -305.632104)
		(mid 278.753457 -305.542301)
		(end 278.663654 -305.505104)
		(width 0.127)
		(layer "B.Cu")
		(net "PHY_SCC_A_TO_DRV_A_29_DN")
	)
	(arc
		(start 278.32939 -306.258976)
		(mid 278.528848 -306.219301)
		(end 278.697944 -306.106322)
		(width 0.127)
		(layer "B.Cu")
		(net "PHY_SCC_A_TO_DRV_A_29_DN")
	)
	(segment
		(start 192.273936 -127.668782)
		(end 161.755328 -44.905422)
		(width 0.127)
		(layer "F.Cu")
		(net "PHY_SCC_A_TO_DRV_A_28_DP")
	)
	(segment
		(start 160.032446 -43.814492)
		(end 159.504126 -43.814492)
		(width 0.127)
		(layer "F.Cu")
		(net "PHY_SCC_A_TO_DRV_A_28_DP")
	)
	(segment
		(start 238.662464 -298.563538)
		(end 225.87077 -278.34463)
		(width 0.127)
		(layer "F.Cu")
		(net "PHY_SCC_A_TO_DRV_A_28_DP")
	)
	(segment
		(start 211.323428 -208.991454)
		(end 216.901268 -186.396884)
		(width 0.127)
		(layer "F.Cu")
		(net "PHY_SCC_A_TO_DRV_A_28_DP")
	)
	(segment
		(start 243.81587 -302.624236)
		(end 238.662464 -298.563538)
		(width 0.127)
		(layer "F.Cu")
		(net "PHY_SCC_A_TO_DRV_A_28_DP")
	)
	(segment
		(start 272.68805 -308.978046)
		(end 272.68805 -308.540912)
		(width 0.127)
		(layer "F.Cu")
		(net "PHY_SCC_A_TO_DRV_A_28_DP")
	)
	(segment
		(start 209.650838 -157.475936)
		(end 192.273936 -127.668782)
		(width 0.127)
		(layer "F.Cu")
		(net "PHY_SCC_A_TO_DRV_A_28_DP")
	)
	(segment
		(start 159.350202 -43.660568)
		(end 158.942786 -43.660568)
		(width 0.127)
		(layer "F.Cu")
		(net "PHY_SCC_A_TO_DRV_A_28_DP")
	)
	(segment
		(start 272.26895 -308.121812)
		(end 259.753354 -308.121812)
		(width 0.127)
		(layer "F.Cu")
		(net "PHY_SCC_A_TO_DRV_A_28_DP")
	)
	(segment
		(start 216.901268 -186.396884)
		(end 209.650838 -157.475936)
		(width 0.127)
		(layer "F.Cu")
		(net "PHY_SCC_A_TO_DRV_A_28_DP")
	)
	(segment
		(start 159.504126 -43.814492)
		(end 159.350202 -43.660568)
		(width 0.127)
		(layer "F.Cu")
		(net "PHY_SCC_A_TO_DRV_A_28_DP")
	)
	(segment
		(start 259.753354 -308.121812)
		(end 243.81587 -302.624236)
		(width 0.127)
		(layer "F.Cu")
		(net "PHY_SCC_A_TO_DRV_A_28_DP")
	)
	(segment
		(start 161.755328 -44.905422)
		(end 160.032446 -43.814492)
		(width 0.127)
		(layer "F.Cu")
		(net "PHY_SCC_A_TO_DRV_A_28_DP")
	)
	(segment
		(start 225.87077 -278.34463)
		(end 211.323428 -208.991454)
		(width 0.127)
		(layer "F.Cu")
		(net "PHY_SCC_A_TO_DRV_A_28_DP")
	)
	(segment
		(start 273.1135 -309.105046)
		(end 272.81505 -309.105046)
		(width 0.127)
		(layer "F.Cu")
		(net "PHY_SCC_A_TO_DRV_A_28_DP")
	)
	(arc
		(start 272.81505 -309.105046)
		(mid 272.725247 -309.067849)
		(end 272.68805 -308.978046)
		(width 0.127)
		(layer "F.Cu")
		(net "PHY_SCC_A_TO_DRV_A_28_DP")
	)
	(arc
		(start 272.68805 -308.540912)
		(mid 272.565298 -308.244564)
		(end 272.26895 -308.121812)
		(width 0.127)
		(layer "F.Cu")
		(net "PHY_SCC_A_TO_DRV_A_28_DP")
	)
	(segment
		(start 280.209752 -307.305202)
		(end 280.636726 -307.305202)
		(width 0.127)
		(layer "B.Cu")
		(net "PHY_SCC_A_TO_DRV_A_28_DP")
	)
	(segment
		(start 280.082752 -307.683154)
		(end 280.082752 -307.432202)
		(width 0.127)
		(layer "B.Cu")
		(net "PHY_SCC_A_TO_DRV_A_28_DP")
	)
	(segment
		(start 272.68805 -308.923944)
		(end 272.68805 -308.775354)
		(width 0.127)
		(layer "B.Cu")
		(net "PHY_SCC_A_TO_DRV_A_28_DP")
	)
	(segment
		(start 273.1135 -309.105046)
		(end 272.869152 -309.105046)
		(width 0.127)
		(layer "B.Cu")
		(net "PHY_SCC_A_TO_DRV_A_28_DP")
	)
	(segment
		(start 273.11223 -308.351174)
		(end 279.329134 -308.351174)
		(width 0.127)
		(layer "B.Cu")
		(net "PHY_SCC_A_TO_DRV_A_28_DP")
	)
	(arc
		(start 279.904698 -308.113176)
		(mid 279.92788 -308.088658)
		(end 279.949656 -308.062884)
		(width 0.127)
		(layer "B.Cu")
		(net "PHY_SCC_A_TO_DRV_A_28_DP")
	)
	(arc
		(start 280.082752 -307.432202)
		(mid 280.119949 -307.342399)
		(end 280.209752 -307.305202)
		(width 0.127)
		(layer "B.Cu")
		(net "PHY_SCC_A_TO_DRV_A_28_DP")
	)
	(arc
		(start 279.329134 -308.351174)
		(mid 279.640578 -308.289411)
		(end 279.904698 -308.113176)
		(width 0.127)
		(layer "B.Cu")
		(net "PHY_SCC_A_TO_DRV_A_28_DP")
	)
	(arc
		(start 279.949656 -308.062884)
		(mid 280.048501 -307.884341)
		(end 280.082752 -307.683154)
		(width 0.127)
		(layer "B.Cu")
		(net "PHY_SCC_A_TO_DRV_A_28_DP")
	)
	(arc
		(start 272.869152 -309.105046)
		(mid 272.741094 -309.052002)
		(end 272.68805 -308.923944)
		(width 0.127)
		(layer "B.Cu")
		(net "PHY_SCC_A_TO_DRV_A_28_DP")
	)
	(arc
		(start 272.68805 -308.775354)
		(mid 272.812289 -308.475413)
		(end 273.11223 -308.351174)
		(width 0.127)
		(layer "B.Cu")
		(net "PHY_SCC_A_TO_DRV_A_28_DP")
	)
	(segment
		(start 266.701524 -308.413912)
		(end 266.549124 -308.566312)
		(width 0.127)
		(layer "F.Cu")
		(net "PHY_SCC_A_TO_DRV_A_28_DN")
	)
	(segment
		(start 271.9705 -309.105046)
		(end 272.26895 -309.105046)
		(width 0.127)
		(layer "F.Cu")
		(net "PHY_SCC_A_TO_DRV_A_28_DN")
	)
	(segment
		(start 159.350202 -44.219368)
		(end 158.942786 -44.219368)
		(width 0.127)
		(layer "F.Cu")
		(net "PHY_SCC_A_TO_DRV_A_28_DN")
	)
	(segment
		(start 238.442246 -298.761912)
		(end 238.441738 -298.761404)
		(width 0.127)
		(layer "F.Cu")
		(net "PHY_SCC_A_TO_DRV_A_28_DN")
	)
	(segment
		(start 268.301724 -308.566312)
		(end 268.149324 -308.413912)
		(width 0.127)
		(layer "F.Cu")
		(net "PHY_SCC_A_TO_DRV_A_28_DN")
	)
	(segment
		(start 266.549124 -308.566312)
		(end 266.168124 -308.566312)
		(width 0.127)
		(layer "F.Cu")
		(net "PHY_SCC_A_TO_DRV_A_28_DN")
	)
	(segment
		(start 209.377534 -157.587188)
		(end 200.69302 -142.690596)
		(width 0.127)
		(layer "F.Cu")
		(net "PHY_SCC_A_TO_DRV_A_28_DN")
	)
	(segment
		(start 238.441738 -298.761404)
		(end 225.595434 -278.45639)
		(width 0.127)
		(layer "F.Cu")
		(net "PHY_SCC_A_TO_DRV_A_28_DN")
	)
	(segment
		(start 269.216124 -308.413912)
		(end 268.835124 -308.413912)
		(width 0.127)
		(layer "F.Cu")
		(net "PHY_SCC_A_TO_DRV_A_28_DN")
	)
	(segment
		(start 159.94761 -44.106592)
		(end 159.462978 -44.106592)
		(width 0.127)
		(layer "F.Cu")
		(net "PHY_SCC_A_TO_DRV_A_28_DN")
	)
	(segment
		(start 266.015724 -308.413912)
		(end 259.704332 -308.413912)
		(width 0.127)
		(layer "F.Cu")
		(net "PHY_SCC_A_TO_DRV_A_28_DN")
	)
	(segment
		(start 269.749524 -308.566312)
		(end 269.368524 -308.566312)
		(width 0.127)
		(layer "F.Cu")
		(net "PHY_SCC_A_TO_DRV_A_28_DN")
	)
	(segment
		(start 266.168124 -308.566312)
		(end 266.015724 -308.413912)
		(width 0.127)
		(layer "F.Cu")
		(net "PHY_SCC_A_TO_DRV_A_28_DN")
	)
	(segment
		(start 159.462978 -44.106592)
		(end 159.350202 -44.219368)
		(width 0.127)
		(layer "F.Cu")
		(net "PHY_SCC_A_TO_DRV_A_28_DN")
	)
	(segment
		(start 272.26895 -308.413912)
		(end 269.901924 -308.413912)
		(width 0.127)
		(layer "F.Cu")
		(net "PHY_SCC_A_TO_DRV_A_28_DN")
	)
	(segment
		(start 192.008506 -127.794004)
		(end 161.515298 -45.099478)
		(width 0.127)
		(layer "F.Cu")
		(net "PHY_SCC_A_TO_DRV_A_28_DN")
	)
	(segment
		(start 268.835124 -308.413912)
		(end 268.682724 -308.566312)
		(width 0.127)
		(layer "F.Cu")
		(net "PHY_SCC_A_TO_DRV_A_28_DN")
	)
	(segment
		(start 267.234924 -308.566312)
		(end 267.082524 -308.413912)
		(width 0.127)
		(layer "F.Cu")
		(net "PHY_SCC_A_TO_DRV_A_28_DN")
	)
	(segment
		(start 269.368524 -308.566312)
		(end 269.216124 -308.413912)
		(width 0.127)
		(layer "F.Cu")
		(net "PHY_SCC_A_TO_DRV_A_28_DN")
	)
	(segment
		(start 267.768324 -308.413912)
		(end 267.615924 -308.566312)
		(width 0.127)
		(layer "F.Cu")
		(net "PHY_SCC_A_TO_DRV_A_28_DN")
	)
	(segment
		(start 267.082524 -308.413912)
		(end 266.701524 -308.413912)
		(width 0.127)
		(layer "F.Cu")
		(net "PHY_SCC_A_TO_DRV_A_28_DN")
	)
	(segment
		(start 268.149324 -308.413912)
		(end 267.768324 -308.413912)
		(width 0.127)
		(layer "F.Cu")
		(net "PHY_SCC_A_TO_DRV_A_28_DN")
	)
	(segment
		(start 216.600024 -186.397392)
		(end 209.377534 -157.587188)
		(width 0.127)
		(layer "F.Cu")
		(net "PHY_SCC_A_TO_DRV_A_28_DN")
	)
	(segment
		(start 269.901924 -308.413912)
		(end 269.749524 -308.566312)
		(width 0.127)
		(layer "F.Cu")
		(net "PHY_SCC_A_TO_DRV_A_28_DN")
	)
	(segment
		(start 161.515298 -45.099478)
		(end 159.94761 -44.106592)
		(width 0.127)
		(layer "F.Cu")
		(net "PHY_SCC_A_TO_DRV_A_28_DN")
	)
	(segment
		(start 272.39595 -308.978046)
		(end 272.39595 -308.540912)
		(width 0.127)
		(layer "F.Cu")
		(net "PHY_SCC_A_TO_DRV_A_28_DN")
	)
	(segment
		(start 200.69302 -142.690596)
		(end 200.69302 -142.690342)
		(width 0.127)
		(layer "F.Cu")
		(net "PHY_SCC_A_TO_DRV_A_28_DN")
	)
	(segment
		(start 225.595434 -278.45639)
		(end 211.023708 -208.98612)
		(width 0.127)
		(layer "F.Cu")
		(net "PHY_SCC_A_TO_DRV_A_28_DN")
	)
	(segment
		(start 200.69302 -142.690342)
		(end 192.008506 -127.794004)
		(width 0.127)
		(layer "F.Cu")
		(net "PHY_SCC_A_TO_DRV_A_28_DN")
	)
	(segment
		(start 267.615924 -308.566312)
		(end 267.234924 -308.566312)
		(width 0.127)
		(layer "F.Cu")
		(net "PHY_SCC_A_TO_DRV_A_28_DN")
	)
	(segment
		(start 243.673884 -302.884332)
		(end 238.442246 -298.761912)
		(width 0.127)
		(layer "F.Cu")
		(net "PHY_SCC_A_TO_DRV_A_28_DN")
	)
	(segment
		(start 259.704332 -308.413912)
		(end 243.673884 -302.884332)
		(width 0.127)
		(layer "F.Cu")
		(net "PHY_SCC_A_TO_DRV_A_28_DN")
	)
	(segment
		(start 211.023708 -208.98612)
		(end 216.600024 -186.397392)
		(width 0.127)
		(layer "F.Cu")
		(net "PHY_SCC_A_TO_DRV_A_28_DN")
	)
	(segment
		(start 268.682724 -308.566312)
		(end 268.301724 -308.566312)
		(width 0.127)
		(layer "F.Cu")
		(net "PHY_SCC_A_TO_DRV_A_28_DN")
	)
	(arc
		(start 272.26895 -309.105046)
		(mid 272.358753 -309.067849)
		(end 272.39595 -308.978046)
		(width 0.127)
		(layer "F.Cu")
		(net "PHY_SCC_A_TO_DRV_A_28_DN")
	)
	(arc
		(start 272.39595 -308.540912)
		(mid 272.358753 -308.451109)
		(end 272.26895 -308.413912)
		(width 0.127)
		(layer "F.Cu")
		(net "PHY_SCC_A_TO_DRV_A_28_DN")
	)
	(segment
		(start 271.9705 -309.105046)
		(end 272.214848 -309.105046)
		(width 0.127)
		(layer "B.Cu")
		(net "PHY_SCC_A_TO_DRV_A_28_DN")
	)
	(segment
		(start 273.11223 -308.059074)
		(end 279.329388 -308.059074)
		(width 0.127)
		(layer "B.Cu")
		(net "PHY_SCC_A_TO_DRV_A_28_DN")
	)
	(segment
		(start 279.663652 -307.305202)
		(end 279.236678 -307.305202)
		(width 0.127)
		(layer "B.Cu")
		(net "PHY_SCC_A_TO_DRV_A_28_DN")
	)
	(segment
		(start 279.790652 -307.682646)
		(end 279.790652 -307.432202)
		(width 0.127)
		(layer "B.Cu")
		(net "PHY_SCC_A_TO_DRV_A_28_DN")
	)
	(segment
		(start 272.39595 -308.923944)
		(end 272.39595 -308.775354)
		(width 0.127)
		(layer "B.Cu")
		(net "PHY_SCC_A_TO_DRV_A_28_DN")
	)
	(arc
		(start 279.72131 -307.880258)
		(mid 279.772817 -307.787359)
		(end 279.790652 -307.682646)
		(width 0.127)
		(layer "B.Cu")
		(net "PHY_SCC_A_TO_DRV_A_28_DN")
	)
	(arc
		(start 272.214848 -309.105046)
		(mid 272.342906 -309.052002)
		(end 272.39595 -308.923944)
		(width 0.127)
		(layer "B.Cu")
		(net "PHY_SCC_A_TO_DRV_A_28_DN")
	)
	(arc
		(start 279.790652 -307.432202)
		(mid 279.753455 -307.342399)
		(end 279.663652 -307.305202)
		(width 0.127)
		(layer "B.Cu")
		(net "PHY_SCC_A_TO_DRV_A_28_DN")
	)
	(arc
		(start 279.697942 -307.90642)
		(mid 279.709986 -307.89366)
		(end 279.72131 -307.880258)
		(width 0.127)
		(layer "B.Cu")
		(net "PHY_SCC_A_TO_DRV_A_28_DN")
	)
	(arc
		(start 272.39595 -308.775354)
		(mid 272.605744 -308.268868)
		(end 273.11223 -308.059074)
		(width 0.127)
		(layer "B.Cu")
		(net "PHY_SCC_A_TO_DRV_A_28_DN")
	)
	(arc
		(start 279.329388 -308.059074)
		(mid 279.528846 -308.019399)
		(end 279.697942 -307.90642)
		(width 0.127)
		(layer "B.Cu")
		(net "PHY_SCC_A_TO_DRV_A_28_DN")
	)
	(segment
		(start 153.592022 -106.542586)
		(end 153.125424 -105.840022)
		(width 0.127)
		(layer "F.Cu")
		(net "PHY_SCC_A_TO_DRV_A_27_DP")
	)
	(segment
		(start 272.26895 -309.921656)
		(end 260.184646 -309.921656)
		(width 0.127)
		(layer "F.Cu")
		(net "PHY_SCC_A_TO_DRV_A_27_DP")
	)
	(segment
		(start 237.236762 -299.399452)
		(end 224.128838 -278.681942)
		(width 0.127)
		(layer "F.Cu")
		(net "PHY_SCC_A_TO_DRV_A_27_DP")
	)
	(segment
		(start 151.413972 -103.263192)
		(end 129.718308 -44.425616)
		(width 0.127)
		(layer "F.Cu")
		(net "PHY_SCC_A_TO_DRV_A_27_DP")
	)
	(segment
		(start 216.541858 -242.535964)
		(end 209.57921 -209.36458)
		(width 0.127)
		(layer "F.Cu")
		(net "PHY_SCC_A_TO_DRV_A_27_DP")
	)
	(segment
		(start 215.275922 -186.284108)
		(end 208.203546 -158.05785)
		(width 0.127)
		(layer "F.Cu")
		(net "PHY_SCC_A_TO_DRV_A_27_DP")
	)
	(segment
		(start 260.184646 -309.921656)
		(end 243.118132 -304.03419)
		(width 0.127)
		(layer "F.Cu")
		(net "PHY_SCC_A_TO_DRV_A_27_DP")
	)
	(segment
		(start 194.498468 -135.198104)
		(end 154.317954 -107.635294)
		(width 0.127)
		(layer "F.Cu")
		(net "PHY_SCC_A_TO_DRV_A_27_DP")
	)
	(segment
		(start 216.542112 -242.535964)
		(end 216.541858 -242.535964)
		(width 0.127)
		(layer "F.Cu")
		(net "PHY_SCC_A_TO_DRV_A_27_DP")
	)
	(segment
		(start 243.118132 -304.03419)
		(end 237.236762 -299.399452)
		(width 0.127)
		(layer "F.Cu")
		(net "PHY_SCC_A_TO_DRV_A_27_DP")
	)
	(segment
		(start 209.57921 -209.36458)
		(end 211.527898 -201.469498)
		(width 0.127)
		(layer "F.Cu")
		(net "PHY_SCC_A_TO_DRV_A_27_DP")
	)
	(segment
		(start 208.203546 -158.05785)
		(end 194.498468 -135.198104)
		(width 0.127)
		(layer "F.Cu")
		(net "PHY_SCC_A_TO_DRV_A_27_DP")
	)
	(segment
		(start 153.125424 -105.840022)
		(end 151.413972 -103.263192)
		(width 0.127)
		(layer "F.Cu")
		(net "PHY_SCC_A_TO_DRV_A_27_DP")
	)
	(segment
		(start 129.718308 -44.425616)
		(end 128.771142 -43.825922)
		(width 0.127)
		(layer "F.Cu")
		(net "PHY_SCC_A_TO_DRV_A_27_DP")
	)
	(segment
		(start 211.527898 -201.469498)
		(end 212.06079 -199.310752)
		(width 0.127)
		(layer "F.Cu")
		(net "PHY_SCC_A_TO_DRV_A_27_DP")
	)
	(segment
		(start 272.68805 -310.77789)
		(end 272.68805 -310.340756)
		(width 0.127)
		(layer "F.Cu")
		(net "PHY_SCC_A_TO_DRV_A_27_DP")
	)
	(segment
		(start 273.1135 -310.90489)
		(end 272.81505 -310.90489)
		(width 0.127)
		(layer "F.Cu")
		(net "PHY_SCC_A_TO_DRV_A_27_DP")
	)
	(segment
		(start 224.128838 -278.681942)
		(end 216.542112 -242.535964)
		(width 0.127)
		(layer "F.Cu")
		(net "PHY_SCC_A_TO_DRV_A_27_DP")
	)
	(segment
		(start 127.80518 -43.660568)
		(end 127.392684 -43.660568)
		(width 0.127)
		(layer "F.Cu")
		(net "PHY_SCC_A_TO_DRV_A_27_DP")
	)
	(segment
		(start 154.317954 -107.635294)
		(end 153.592022 -106.542586)
		(width 0.127)
		(layer "F.Cu")
		(net "PHY_SCC_A_TO_DRV_A_27_DP")
	)
	(segment
		(start 128.771142 -43.825922)
		(end 127.970534 -43.825922)
		(width 0.127)
		(layer "F.Cu")
		(net "PHY_SCC_A_TO_DRV_A_27_DP")
	)
	(segment
		(start 212.06079 -199.310752)
		(end 215.275922 -186.284108)
		(width 0.127)
		(layer "F.Cu")
		(net "PHY_SCC_A_TO_DRV_A_27_DP")
	)
	(segment
		(start 127.970534 -43.825922)
		(end 127.80518 -43.660568)
		(width 0.127)
		(layer "F.Cu")
		(net "PHY_SCC_A_TO_DRV_A_27_DP")
	)
	(arc
		(start 272.68805 -310.340756)
		(mid 272.565298 -310.044408)
		(end 272.26895 -309.921656)
		(width 0.127)
		(layer "F.Cu")
		(net "PHY_SCC_A_TO_DRV_A_27_DP")
	)
	(arc
		(start 272.81505 -310.90489)
		(mid 272.725247 -310.867693)
		(end 272.68805 -310.77789)
		(width 0.127)
		(layer "F.Cu")
		(net "PHY_SCC_A_TO_DRV_A_27_DP")
	)
	(segment
		(start 279.082754 -309.232046)
		(end 279.082754 -309.482998)
		(width 0.127)
		(layer "B.Cu")
		(net "PHY_SCC_A_TO_DRV_A_27_DP")
	)
	(segment
		(start 272.869152 -310.90489)
		(end 273.1135 -310.90489)
		(width 0.127)
		(layer "B.Cu")
		(net "PHY_SCC_A_TO_DRV_A_27_DP")
	)
	(segment
		(start 272.68805 -310.575198)
		(end 272.68805 -310.723788)
		(width 0.127)
		(layer "B.Cu")
		(net "PHY_SCC_A_TO_DRV_A_27_DP")
	)
	(segment
		(start 279.636728 -309.105046)
		(end 279.209754 -309.105046)
		(width 0.127)
		(layer "B.Cu")
		(net "PHY_SCC_A_TO_DRV_A_27_DP")
	)
	(segment
		(start 278.329136 -310.151018)
		(end 273.11223 -310.151018)
		(width 0.127)
		(layer "B.Cu")
		(net "PHY_SCC_A_TO_DRV_A_27_DP")
	)
	(arc
		(start 278.949658 -309.862728)
		(mid 278.927871 -309.888493)
		(end 278.9047 -309.91302)
		(width 0.127)
		(layer "B.Cu")
		(net "PHY_SCC_A_TO_DRV_A_27_DP")
	)
	(arc
		(start 279.209754 -309.105046)
		(mid 279.119951 -309.142243)
		(end 279.082754 -309.232046)
		(width 0.127)
		(layer "B.Cu")
		(net "PHY_SCC_A_TO_DRV_A_27_DP")
	)
	(arc
		(start 273.11223 -310.151018)
		(mid 272.812289 -310.275257)
		(end 272.68805 -310.575198)
		(width 0.127)
		(layer "B.Cu")
		(net "PHY_SCC_A_TO_DRV_A_27_DP")
	)
	(arc
		(start 272.68805 -310.723788)
		(mid 272.741094 -310.851846)
		(end 272.869152 -310.90489)
		(width 0.127)
		(layer "B.Cu")
		(net "PHY_SCC_A_TO_DRV_A_27_DP")
	)
	(arc
		(start 279.082754 -309.482998)
		(mid 279.04852 -309.684191)
		(end 278.949658 -309.862728)
		(width 0.127)
		(layer "B.Cu")
		(net "PHY_SCC_A_TO_DRV_A_27_DP")
	)
	(arc
		(start 278.9047 -309.91302)
		(mid 278.640599 -310.089301)
		(end 278.329136 -310.151018)
		(width 0.127)
		(layer "B.Cu")
		(net "PHY_SCC_A_TO_DRV_A_27_DP")
	)
	(segment
		(start 269.243048 -310.213756)
		(end 268.862048 -310.213756)
		(width 0.127)
		(layer "F.Cu")
		(net "PHY_SCC_A_TO_DRV_A_27_DN")
	)
	(segment
		(start 153.16708 -106.431334)
		(end 152.62225 -105.611168)
		(width 0.127)
		(layer "F.Cu")
		(net "PHY_SCC_A_TO_DRV_A_27_DN")
	)
	(segment
		(start 220.049598 -260.669024)
		(end 216.304876 -242.828064)
		(width 0.127)
		(layer "F.Cu")
		(net "PHY_SCC_A_TO_DRV_A_27_DN")
	)
	(segment
		(start 214.974678 -186.284616)
		(end 207.930496 -158.17088)
		(width 0.127)
		(layer "F.Cu")
		(net "PHY_SCC_A_TO_DRV_A_27_DN")
	)
	(segment
		(start 267.261848 -310.366156)
		(end 267.109448 -310.213756)
		(width 0.127)
		(layer "F.Cu")
		(net "PHY_SCC_A_TO_DRV_A_27_DN")
	)
	(segment
		(start 268.176248 -310.213756)
		(end 267.795248 -310.213756)
		(width 0.127)
		(layer "F.Cu")
		(net "PHY_SCC_A_TO_DRV_A_27_DN")
	)
	(segment
		(start 127.977646 -44.118022)
		(end 127.8763 -44.219368)
		(width 0.127)
		(layer "F.Cu")
		(net "PHY_SCC_A_TO_DRV_A_27_DN")
	)
	(segment
		(start 151.714454 -104.243886)
		(end 151.15159 -103.396542)
		(width 0.127)
		(layer "F.Cu")
		(net "PHY_SCC_A_TO_DRV_A_27_DN")
	)
	(segment
		(start 129.478278 -44.619672)
		(end 128.686306 -44.118022)
		(width 0.127)
		(layer "F.Cu")
		(net "PHY_SCC_A_TO_DRV_A_27_DN")
	)
	(segment
		(start 209.27949 -209.359246)
		(end 210.711288 -203.558648)
		(width 0.127)
		(layer "F.Cu")
		(net "PHY_SCC_A_TO_DRV_A_27_DN")
	)
	(segment
		(start 210.711288 -203.558648)
		(end 211.777072 -199.240648)
		(width 0.127)
		(layer "F.Cu")
		(net "PHY_SCC_A_TO_DRV_A_27_DN")
	)
	(segment
		(start 216.304876 -242.828064)
		(end 216.304622 -242.828064)
		(width 0.127)
		(layer "F.Cu")
		(net "PHY_SCC_A_TO_DRV_A_27_DN")
	)
	(segment
		(start 260.135624 -310.213756)
		(end 242.976146 -304.294286)
		(width 0.127)
		(layer "F.Cu")
		(net "PHY_SCC_A_TO_DRV_A_27_DN")
	)
	(segment
		(start 269.395448 -310.366156)
		(end 269.243048 -310.213756)
		(width 0.127)
		(layer "F.Cu")
		(net "PHY_SCC_A_TO_DRV_A_27_DN")
	)
	(segment
		(start 269.776448 -310.366156)
		(end 269.395448 -310.366156)
		(width 0.127)
		(layer "F.Cu")
		(net "PHY_SCC_A_TO_DRV_A_27_DN")
	)
	(segment
		(start 267.795248 -310.213756)
		(end 267.642848 -310.366156)
		(width 0.127)
		(layer "F.Cu")
		(net "PHY_SCC_A_TO_DRV_A_27_DN")
	)
	(segment
		(start 272.26895 -310.213756)
		(end 269.928848 -310.213756)
		(width 0.127)
		(layer "F.Cu")
		(net "PHY_SCC_A_TO_DRV_A_27_DN")
	)
	(segment
		(start 237.016544 -299.597826)
		(end 223.853502 -278.793702)
		(width 0.127)
		(layer "F.Cu")
		(net "PHY_SCC_A_TO_DRV_A_27_DN")
	)
	(segment
		(start 128.686306 -44.118022)
		(end 127.977646 -44.118022)
		(width 0.127)
		(layer "F.Cu")
		(net "PHY_SCC_A_TO_DRV_A_27_DN")
	)
	(segment
		(start 223.853502 -278.793702)
		(end 220.049598 -260.669024)
		(width 0.127)
		(layer "F.Cu")
		(net "PHY_SCC_A_TO_DRV_A_27_DN")
	)
	(segment
		(start 151.15159 -103.396542)
		(end 129.478278 -44.619672)
		(width 0.127)
		(layer "F.Cu")
		(net "PHY_SCC_A_TO_DRV_A_27_DN")
	)
	(segment
		(start 194.280536 -135.403082)
		(end 154.105864 -107.844336)
		(width 0.127)
		(layer "F.Cu")
		(net "PHY_SCC_A_TO_DRV_A_27_DN")
	)
	(segment
		(start 271.9705 -310.90489)
		(end 272.26895 -310.90489)
		(width 0.127)
		(layer "F.Cu")
		(net "PHY_SCC_A_TO_DRV_A_27_DN")
	)
	(segment
		(start 272.39595 -310.77789)
		(end 272.39595 -310.340756)
		(width 0.127)
		(layer "F.Cu")
		(net "PHY_SCC_A_TO_DRV_A_27_DN")
	)
	(segment
		(start 266.576048 -310.366156)
		(end 266.195048 -310.366156)
		(width 0.127)
		(layer "F.Cu")
		(net "PHY_SCC_A_TO_DRV_A_27_DN")
	)
	(segment
		(start 154.105864 -107.844336)
		(end 153.348436 -106.704384)
		(width 0.127)
		(layer "F.Cu")
		(net "PHY_SCC_A_TO_DRV_A_27_DN")
	)
	(segment
		(start 266.042648 -310.213756)
		(end 260.135624 -310.213756)
		(width 0.127)
		(layer "F.Cu")
		(net "PHY_SCC_A_TO_DRV_A_27_DN")
	)
	(segment
		(start 268.328648 -310.366156)
		(end 268.176248 -310.213756)
		(width 0.127)
		(layer "F.Cu")
		(net "PHY_SCC_A_TO_DRV_A_27_DN")
	)
	(segment
		(start 267.109448 -310.213756)
		(end 266.728448 -310.213756)
		(width 0.127)
		(layer "F.Cu")
		(net "PHY_SCC_A_TO_DRV_A_27_DN")
	)
	(segment
		(start 152.622504 -105.611168)
		(end 151.714454 -104.243886)
		(width 0.127)
		(layer "F.Cu")
		(net "PHY_SCC_A_TO_DRV_A_27_DN")
	)
	(segment
		(start 153.167334 -106.431588)
		(end 153.16708 -106.431334)
		(width 0.127)
		(layer "F.Cu")
		(net "PHY_SCC_A_TO_DRV_A_27_DN")
	)
	(segment
		(start 153.348436 -106.704384)
		(end 153.167334 -106.431588)
		(width 0.127)
		(layer "F.Cu")
		(net "PHY_SCC_A_TO_DRV_A_27_DN")
	)
	(segment
		(start 268.862048 -310.213756)
		(end 268.709648 -310.366156)
		(width 0.127)
		(layer "F.Cu")
		(net "PHY_SCC_A_TO_DRV_A_27_DN")
	)
	(segment
		(start 216.304622 -242.828064)
		(end 209.27949 -209.359246)
		(width 0.127)
		(layer "F.Cu")
		(net "PHY_SCC_A_TO_DRV_A_27_DN")
	)
	(segment
		(start 267.642848 -310.366156)
		(end 267.261848 -310.366156)
		(width 0.127)
		(layer "F.Cu")
		(net "PHY_SCC_A_TO_DRV_A_27_DN")
	)
	(segment
		(start 269.928848 -310.213756)
		(end 269.776448 -310.366156)
		(width 0.127)
		(layer "F.Cu")
		(net "PHY_SCC_A_TO_DRV_A_27_DN")
	)
	(segment
		(start 242.976146 -304.294286)
		(end 237.016544 -299.597826)
		(width 0.127)
		(layer "F.Cu")
		(net "PHY_SCC_A_TO_DRV_A_27_DN")
	)
	(segment
		(start 211.777072 -199.240648)
		(end 213.375494 -192.762886)
		(width 0.127)
		(layer "F.Cu")
		(net "PHY_SCC_A_TO_DRV_A_27_DN")
	)
	(segment
		(start 152.62225 -105.611168)
		(end 152.622504 -105.611168)
		(width 0.127)
		(layer "F.Cu")
		(net "PHY_SCC_A_TO_DRV_A_27_DN")
	)
	(segment
		(start 266.728448 -310.213756)
		(end 266.576048 -310.366156)
		(width 0.127)
		(layer "F.Cu")
		(net "PHY_SCC_A_TO_DRV_A_27_DN")
	)
	(segment
		(start 266.195048 -310.366156)
		(end 266.042648 -310.213756)
		(width 0.127)
		(layer "F.Cu")
		(net "PHY_SCC_A_TO_DRV_A_27_DN")
	)
	(segment
		(start 127.8763 -44.219368)
		(end 127.392684 -44.219368)
		(width 0.127)
		(layer "F.Cu")
		(net "PHY_SCC_A_TO_DRV_A_27_DN")
	)
	(segment
		(start 207.930496 -158.17088)
		(end 194.280536 -135.403082)
		(width 0.127)
		(layer "F.Cu")
		(net "PHY_SCC_A_TO_DRV_A_27_DN")
	)
	(segment
		(start 268.709648 -310.366156)
		(end 268.328648 -310.366156)
		(width 0.127)
		(layer "F.Cu")
		(net "PHY_SCC_A_TO_DRV_A_27_DN")
	)
	(segment
		(start 213.375748 -192.762886)
		(end 214.974678 -186.284616)
		(width 0.127)
		(layer "F.Cu")
		(net "PHY_SCC_A_TO_DRV_A_27_DN")
	)
	(segment
		(start 213.375494 -192.762886)
		(end 213.375748 -192.762886)
		(width 0.127)
		(layer "F.Cu")
		(net "PHY_SCC_A_TO_DRV_A_27_DN")
	)
	(arc
		(start 272.39595 -310.340756)
		(mid 272.358753 -310.250953)
		(end 272.26895 -310.213756)
		(width 0.127)
		(layer "F.Cu")
		(net "PHY_SCC_A_TO_DRV_A_27_DN")
	)
	(arc
		(start 272.26895 -310.90489)
		(mid 272.358753 -310.867693)
		(end 272.39595 -310.77789)
		(width 0.127)
		(layer "F.Cu")
		(net "PHY_SCC_A_TO_DRV_A_27_DN")
	)
	(segment
		(start 272.39595 -310.723788)
		(end 272.39595 -310.575198)
		(width 0.127)
		(layer "B.Cu")
		(net "PHY_SCC_A_TO_DRV_A_27_DN")
	)
	(segment
		(start 278.790654 -309.48249)
		(end 278.790654 -309.232046)
		(width 0.127)
		(layer "B.Cu")
		(net "PHY_SCC_A_TO_DRV_A_27_DN")
	)
	(segment
		(start 271.9705 -310.90489)
		(end 272.214848 -310.90489)
		(width 0.127)
		(layer "B.Cu")
		(net "PHY_SCC_A_TO_DRV_A_27_DN")
	)
	(segment
		(start 273.11223 -309.858918)
		(end 278.32939 -309.858918)
		(width 0.127)
		(layer "B.Cu")
		(net "PHY_SCC_A_TO_DRV_A_27_DN")
	)
	(segment
		(start 278.663654 -309.105046)
		(end 278.23668 -309.105046)
		(width 0.127)
		(layer "B.Cu")
		(net "PHY_SCC_A_TO_DRV_A_27_DN")
	)
	(arc
		(start 278.721312 -309.680102)
		(mid 278.772819 -309.587203)
		(end 278.790654 -309.48249)
		(width 0.127)
		(layer "B.Cu")
		(net "PHY_SCC_A_TO_DRV_A_27_DN")
	)
	(arc
		(start 278.790654 -309.232046)
		(mid 278.753457 -309.142243)
		(end 278.663654 -309.105046)
		(width 0.127)
		(layer "B.Cu")
		(net "PHY_SCC_A_TO_DRV_A_27_DN")
	)
	(arc
		(start 278.32939 -309.858918)
		(mid 278.528848 -309.819243)
		(end 278.697944 -309.706264)
		(width 0.127)
		(layer "B.Cu")
		(net "PHY_SCC_A_TO_DRV_A_27_DN")
	)
	(arc
		(start 272.214848 -310.90489)
		(mid 272.342906 -310.851846)
		(end 272.39595 -310.723788)
		(width 0.127)
		(layer "B.Cu")
		(net "PHY_SCC_A_TO_DRV_A_27_DN")
	)
	(arc
		(start 272.39595 -310.575198)
		(mid 272.605744 -310.068712)
		(end 273.11223 -309.858918)
		(width 0.127)
		(layer "B.Cu")
		(net "PHY_SCC_A_TO_DRV_A_27_DN")
	)
	(arc
		(start 278.697944 -309.706264)
		(mid 278.709988 -309.693504)
		(end 278.721312 -309.680102)
		(width 0.127)
		(layer "B.Cu")
		(net "PHY_SCC_A_TO_DRV_A_27_DN")
	)
	(segment
		(start 98.224594 -44.741084)
		(end 96.785938 -43.830494)
		(width 0.127)
		(layer "F.Cu")
		(net "PHY_SCC_A_TO_DRV_A_26_DP")
	)
	(segment
		(start 239.13084 -302.91024)
		(end 236.01299 -300.453298)
		(width 0.127)
		(layer "F.Cu")
		(net "PHY_SCC_A_TO_DRV_A_26_DP")
	)
	(segment
		(start 117.453156 -83.189064)
		(end 114.755422 -79.03464)
		(width 0.127)
		(layer "F.Cu")
		(net "PHY_SCC_A_TO_DRV_A_26_DP")
	)
	(segment
		(start 272.68805 -312.577988)
		(end 272.68805 -312.140854)
		(width 0.127)
		(layer "F.Cu")
		(net "PHY_SCC_A_TO_DRV_A_26_DP")
	)
	(segment
		(start 96.301052 -43.660568)
		(end 95.842836 -43.660568)
		(width 0.127)
		(layer "F.Cu")
		(net "PHY_SCC_A_TO_DRV_A_26_DP")
	)
	(segment
		(start 120.151144 -87.343742)
		(end 118.801896 -85.266276)
		(width 0.127)
		(layer "F.Cu")
		(net "PHY_SCC_A_TO_DRV_A_26_DP")
	)
	(segment
		(start 206.762096 -158.659068)
		(end 200.706228 -148.557742)
		(width 0.127)
		(layer "F.Cu")
		(net "PHY_SCC_A_TO_DRV_A_26_DP")
	)
	(segment
		(start 236.01299 -300.453298)
		(end 222.508064 -279.108408)
		(width 0.127)
		(layer "F.Cu")
		(net "PHY_SCC_A_TO_DRV_A_26_DP")
	)
	(segment
		(start 222.508064 -279.108408)
		(end 207.896714 -209.482182)
		(width 0.127)
		(layer "F.Cu")
		(net "PHY_SCC_A_TO_DRV_A_26_DP")
	)
	(segment
		(start 105.758742 -65.179448)
		(end 98.224594 -44.741084)
		(width 0.127)
		(layer "F.Cu")
		(net "PHY_SCC_A_TO_DRV_A_26_DP")
	)
	(segment
		(start 118.801896 -85.266276)
		(end 117.453156 -83.189064)
		(width 0.127)
		(layer "F.Cu")
		(net "PHY_SCC_A_TO_DRV_A_26_DP")
	)
	(segment
		(start 200.706228 -148.557742)
		(end 194.639946 -138.439144)
		(width 0.127)
		(layer "F.Cu")
		(net "PHY_SCC_A_TO_DRV_A_26_DP")
	)
	(segment
		(start 207.896714 -209.482182)
		(end 213.651592 -186.163204)
		(width 0.127)
		(layer "F.Cu")
		(net "PHY_SCC_A_TO_DRV_A_26_DP")
	)
	(segment
		(start 242.249452 -305.36769)
		(end 239.13084 -302.91024)
		(width 0.127)
		(layer "F.Cu")
		(net "PHY_SCC_A_TO_DRV_A_26_DP")
	)
	(segment
		(start 213.651592 -186.163204)
		(end 206.762096 -158.659068)
		(width 0.127)
		(layer "F.Cu")
		(net "PHY_SCC_A_TO_DRV_A_26_DP")
	)
	(segment
		(start 272.26895 -311.721754)
		(end 260.667246 -311.721754)
		(width 0.127)
		(layer "F.Cu")
		(net "PHY_SCC_A_TO_DRV_A_26_DP")
	)
	(segment
		(start 107.627166 -68.057014)
		(end 107.627166 -68.05676)
		(width 0.127)
		(layer "F.Cu")
		(net "PHY_SCC_A_TO_DRV_A_26_DP")
	)
	(segment
		(start 96.785938 -43.830494)
		(end 96.470978 -43.830494)
		(width 0.127)
		(layer "F.Cu")
		(net "PHY_SCC_A_TO_DRV_A_26_DP")
	)
	(segment
		(start 114.755422 -79.03464)
		(end 107.627166 -68.057014)
		(width 0.127)
		(layer "F.Cu")
		(net "PHY_SCC_A_TO_DRV_A_26_DP")
	)
	(segment
		(start 273.1135 -312.704988)
		(end 272.81505 -312.704988)
		(width 0.127)
		(layer "F.Cu")
		(net "PHY_SCC_A_TO_DRV_A_26_DP")
	)
	(segment
		(start 96.470978 -43.830494)
		(end 96.301052 -43.660568)
		(width 0.127)
		(layer "F.Cu")
		(net "PHY_SCC_A_TO_DRV_A_26_DP")
	)
	(segment
		(start 260.667246 -311.721754)
		(end 242.249452 -305.36769)
		(width 0.127)
		(layer "F.Cu")
		(net "PHY_SCC_A_TO_DRV_A_26_DP")
	)
	(segment
		(start 194.639946 -138.439144)
		(end 120.151144 -87.343742)
		(width 0.127)
		(layer "F.Cu")
		(net "PHY_SCC_A_TO_DRV_A_26_DP")
	)
	(segment
		(start 107.627166 -68.05676)
		(end 105.758742 -65.179448)
		(width 0.127)
		(layer "F.Cu")
		(net "PHY_SCC_A_TO_DRV_A_26_DP")
	)
	(arc
		(start 272.81505 -312.704988)
		(mid 272.725247 -312.667791)
		(end 272.68805 -312.577988)
		(width 0.127)
		(layer "F.Cu")
		(net "PHY_SCC_A_TO_DRV_A_26_DP")
	)
	(arc
		(start 272.68805 -312.140854)
		(mid 272.565298 -311.844506)
		(end 272.26895 -311.721754)
		(width 0.127)
		(layer "F.Cu")
		(net "PHY_SCC_A_TO_DRV_A_26_DP")
	)
	(segment
		(start 273.11223 -311.951116)
		(end 279.329134 -311.951116)
		(width 0.127)
		(layer "B.Cu")
		(net "PHY_SCC_A_TO_DRV_A_26_DP")
	)
	(segment
		(start 272.68805 -312.523886)
		(end 272.68805 -312.375296)
		(width 0.127)
		(layer "B.Cu")
		(net "PHY_SCC_A_TO_DRV_A_26_DP")
	)
	(segment
		(start 280.209752 -310.905144)
		(end 280.636726 -310.905144)
		(width 0.127)
		(layer "B.Cu")
		(net "PHY_SCC_A_TO_DRV_A_26_DP")
	)
	(segment
		(start 280.082752 -311.283096)
		(end 280.082752 -311.032144)
		(width 0.127)
		(layer "B.Cu")
		(net "PHY_SCC_A_TO_DRV_A_26_DP")
	)
	(segment
		(start 273.1135 -312.704988)
		(end 272.869152 -312.704988)
		(width 0.127)
		(layer "B.Cu")
		(net "PHY_SCC_A_TO_DRV_A_26_DP")
	)
	(arc
		(start 280.082752 -311.032144)
		(mid 280.119949 -310.942341)
		(end 280.209752 -310.905144)
		(width 0.127)
		(layer "B.Cu")
		(net "PHY_SCC_A_TO_DRV_A_26_DP")
	)
	(arc
		(start 279.904698 -311.713118)
		(mid 279.92788 -311.6886)
		(end 279.949656 -311.662826)
		(width 0.127)
		(layer "B.Cu")
		(net "PHY_SCC_A_TO_DRV_A_26_DP")
	)
	(arc
		(start 272.869152 -312.704988)
		(mid 272.741094 -312.651944)
		(end 272.68805 -312.523886)
		(width 0.127)
		(layer "B.Cu")
		(net "PHY_SCC_A_TO_DRV_A_26_DP")
	)
	(arc
		(start 272.68805 -312.375296)
		(mid 272.812289 -312.075355)
		(end 273.11223 -311.951116)
		(width 0.127)
		(layer "B.Cu")
		(net "PHY_SCC_A_TO_DRV_A_26_DP")
	)
	(arc
		(start 279.329134 -311.951116)
		(mid 279.640578 -311.889353)
		(end 279.904698 -311.713118)
		(width 0.127)
		(layer "B.Cu")
		(net "PHY_SCC_A_TO_DRV_A_26_DP")
	)
	(arc
		(start 279.949656 -311.662826)
		(mid 280.048501 -311.484283)
		(end 280.082752 -311.283096)
		(width 0.127)
		(layer "B.Cu")
		(net "PHY_SCC_A_TO_DRV_A_26_DP")
	)
	(segment
		(start 272.26895 -312.013854)
		(end 269.929102 -312.013854)
		(width 0.127)
		(layer "F.Cu")
		(net "PHY_SCC_A_TO_DRV_A_26_DN")
	)
	(segment
		(start 268.709902 -312.166254)
		(end 268.328902 -312.166254)
		(width 0.127)
		(layer "F.Cu")
		(net "PHY_SCC_A_TO_DRV_A_26_DN")
	)
	(segment
		(start 237.721394 -302.171862)
		(end 237.39094 -301.911258)
		(width 0.127)
		(layer "F.Cu")
		(net "PHY_SCC_A_TO_DRV_A_26_DN")
	)
	(segment
		(start 207.596994 -209.476848)
		(end 213.350348 -186.163712)
		(width 0.127)
		(layer "F.Cu")
		(net "PHY_SCC_A_TO_DRV_A_26_DN")
	)
	(segment
		(start 267.262102 -312.166254)
		(end 267.109702 -312.013854)
		(width 0.127)
		(layer "F.Cu")
		(net "PHY_SCC_A_TO_DRV_A_26_DN")
	)
	(segment
		(start 268.328902 -312.166254)
		(end 268.176502 -312.013854)
		(width 0.127)
		(layer "F.Cu")
		(net "PHY_SCC_A_TO_DRV_A_26_DN")
	)
	(segment
		(start 267.643102 -312.166254)
		(end 267.262102 -312.166254)
		(width 0.127)
		(layer "F.Cu")
		(net "PHY_SCC_A_TO_DRV_A_26_DN")
	)
	(segment
		(start 267.109702 -312.013854)
		(end 266.728702 -312.013854)
		(width 0.127)
		(layer "F.Cu")
		(net "PHY_SCC_A_TO_DRV_A_26_DN")
	)
	(segment
		(start 114.510312 -79.193898)
		(end 107.335066 -68.143628)
		(width 0.127)
		(layer "F.Cu")
		(net "PHY_SCC_A_TO_DRV_A_26_DN")
	)
	(segment
		(start 268.862302 -312.013854)
		(end 268.709902 -312.166254)
		(width 0.127)
		(layer "F.Cu")
		(net "PHY_SCC_A_TO_DRV_A_26_DN")
	)
	(segment
		(start 269.243302 -312.013854)
		(end 268.862302 -312.013854)
		(width 0.127)
		(layer "F.Cu")
		(net "PHY_SCC_A_TO_DRV_A_26_DN")
	)
	(segment
		(start 235.792772 -300.651926)
		(end 222.232728 -279.220168)
		(width 0.127)
		(layer "F.Cu")
		(net "PHY_SCC_A_TO_DRV_A_26_DN")
	)
	(segment
		(start 96.397826 -44.122594)
		(end 96.301052 -44.219368)
		(width 0.127)
		(layer "F.Cu")
		(net "PHY_SCC_A_TO_DRV_A_26_DN")
	)
	(segment
		(start 266.728702 -312.013854)
		(end 266.576302 -312.166254)
		(width 0.127)
		(layer "F.Cu")
		(net "PHY_SCC_A_TO_DRV_A_26_DN")
	)
	(segment
		(start 194.422014 -138.644122)
		(end 119.937784 -87.551768)
		(width 0.127)
		(layer "F.Cu")
		(net "PHY_SCC_A_TO_DRV_A_26_DN")
	)
	(segment
		(start 272.39595 -312.577988)
		(end 272.39595 -312.140854)
		(width 0.127)
		(layer "F.Cu")
		(net "PHY_SCC_A_TO_DRV_A_26_DN")
	)
	(segment
		(start 268.176502 -312.013854)
		(end 267.795502 -312.013854)
		(width 0.127)
		(layer "F.Cu")
		(net "PHY_SCC_A_TO_DRV_A_26_DN")
	)
	(segment
		(start 269.395702 -312.166254)
		(end 269.243302 -312.013854)
		(width 0.127)
		(layer "F.Cu")
		(net "PHY_SCC_A_TO_DRV_A_26_DN")
	)
	(segment
		(start 269.929102 -312.013854)
		(end 269.776702 -312.166254)
		(width 0.127)
		(layer "F.Cu")
		(net "PHY_SCC_A_TO_DRV_A_26_DN")
	)
	(segment
		(start 107.335066 -68.143374)
		(end 105.495852 -65.31102)
		(width 0.127)
		(layer "F.Cu")
		(net "PHY_SCC_A_TO_DRV_A_26_DN")
	)
	(segment
		(start 240.509298 -304.368708)
		(end 238.949992 -303.139856)
		(width 0.127)
		(layer "F.Cu")
		(net "PHY_SCC_A_TO_DRV_A_26_DN")
	)
	(segment
		(start 222.232728 -279.220168)
		(end 207.596994 -209.476848)
		(width 0.127)
		(layer "F.Cu")
		(net "PHY_SCC_A_TO_DRV_A_26_DN")
	)
	(segment
		(start 97.984564 -44.93514)
		(end 96.701102 -44.122594)
		(width 0.127)
		(layer "F.Cu")
		(net "PHY_SCC_A_TO_DRV_A_26_DN")
	)
	(segment
		(start 96.301052 -44.219368)
		(end 95.842836 -44.219368)
		(width 0.127)
		(layer "F.Cu")
		(net "PHY_SCC_A_TO_DRV_A_26_DN")
	)
	(segment
		(start 242.108228 -305.628294)
		(end 242.068858 -305.597306)
		(width 0.127)
		(layer "F.Cu")
		(net "PHY_SCC_A_TO_DRV_A_26_DN")
	)
	(segment
		(start 238.949992 -303.139856)
		(end 237.721394 -302.171862)
		(width 0.127)
		(layer "F.Cu")
		(net "PHY_SCC_A_TO_DRV_A_26_DN")
	)
	(segment
		(start 115.859052 -81.270602)
		(end 114.510312 -79.193898)
		(width 0.127)
		(layer "F.Cu")
		(net "PHY_SCC_A_TO_DRV_A_26_DN")
	)
	(segment
		(start 237.39094 -301.911258)
		(end 235.792772 -300.651926)
		(width 0.127)
		(layer "F.Cu")
		(net "PHY_SCC_A_TO_DRV_A_26_DN")
	)
	(segment
		(start 271.9705 -312.704988)
		(end 272.26895 -312.704988)
		(width 0.127)
		(layer "F.Cu")
		(net "PHY_SCC_A_TO_DRV_A_26_DN")
	)
	(segment
		(start 269.776702 -312.166254)
		(end 269.395702 -312.166254)
		(width 0.127)
		(layer "F.Cu")
		(net "PHY_SCC_A_TO_DRV_A_26_DN")
	)
	(segment
		(start 260.618224 -312.013854)
		(end 242.108228 -305.628294)
		(width 0.127)
		(layer "F.Cu")
		(net "PHY_SCC_A_TO_DRV_A_26_DN")
	)
	(segment
		(start 105.495852 -65.31102)
		(end 97.984564 -44.93514)
		(width 0.127)
		(layer "F.Cu")
		(net "PHY_SCC_A_TO_DRV_A_26_DN")
	)
	(segment
		(start 213.350348 -186.163712)
		(end 206.489046 -158.772098)
		(width 0.127)
		(layer "F.Cu")
		(net "PHY_SCC_A_TO_DRV_A_26_DN")
	)
	(segment
		(start 266.195302 -312.166254)
		(end 266.042902 -312.013854)
		(width 0.127)
		(layer "F.Cu")
		(net "PHY_SCC_A_TO_DRV_A_26_DN")
	)
	(segment
		(start 266.042902 -312.013854)
		(end 260.618224 -312.013854)
		(width 0.127)
		(layer "F.Cu")
		(net "PHY_SCC_A_TO_DRV_A_26_DN")
	)
	(segment
		(start 200.45553 -148.70811)
		(end 197.422516 -143.648684)
		(width 0.127)
		(layer "F.Cu")
		(net "PHY_SCC_A_TO_DRV_A_26_DN")
	)
	(segment
		(start 267.795502 -312.013854)
		(end 267.643102 -312.166254)
		(width 0.127)
		(layer "F.Cu")
		(net "PHY_SCC_A_TO_DRV_A_26_DN")
	)
	(segment
		(start 242.068858 -305.597306)
		(end 240.509298 -304.368708)
		(width 0.127)
		(layer "F.Cu")
		(net "PHY_SCC_A_TO_DRV_A_26_DN")
	)
	(segment
		(start 107.335066 -68.143628)
		(end 107.335066 -68.143374)
		(width 0.127)
		(layer "F.Cu")
		(net "PHY_SCC_A_TO_DRV_A_26_DN")
	)
	(segment
		(start 197.422516 -143.648684)
		(end 194.422014 -138.644122)
		(width 0.127)
		(layer "F.Cu")
		(net "PHY_SCC_A_TO_DRV_A_26_DN")
	)
	(segment
		(start 266.576302 -312.166254)
		(end 266.195302 -312.166254)
		(width 0.127)
		(layer "F.Cu")
		(net "PHY_SCC_A_TO_DRV_A_26_DN")
	)
	(segment
		(start 206.489046 -158.772098)
		(end 200.45553 -148.70811)
		(width 0.127)
		(layer "F.Cu")
		(net "PHY_SCC_A_TO_DRV_A_26_DN")
	)
	(segment
		(start 96.701102 -44.122594)
		(end 96.397826 -44.122594)
		(width 0.127)
		(layer "F.Cu")
		(net "PHY_SCC_A_TO_DRV_A_26_DN")
	)
	(segment
		(start 119.937784 -87.551768)
		(end 117.208046 -83.348322)
		(width 0.127)
		(layer "F.Cu")
		(net "PHY_SCC_A_TO_DRV_A_26_DN")
	)
	(segment
		(start 117.208046 -83.348322)
		(end 115.859052 -81.270602)
		(width 0.127)
		(layer "F.Cu")
		(net "PHY_SCC_A_TO_DRV_A_26_DN")
	)
	(arc
		(start 272.26895 -312.704988)
		(mid 272.358753 -312.667791)
		(end 272.39595 -312.577988)
		(width 0.127)
		(layer "F.Cu")
		(net "PHY_SCC_A_TO_DRV_A_26_DN")
	)
	(arc
		(start 272.39595 -312.140854)
		(mid 272.358753 -312.051051)
		(end 272.26895 -312.013854)
		(width 0.127)
		(layer "F.Cu")
		(net "PHY_SCC_A_TO_DRV_A_26_DN")
	)
	(segment
		(start 271.9705 -312.704988)
		(end 272.214848 -312.704988)
		(width 0.127)
		(layer "B.Cu")
		(net "PHY_SCC_A_TO_DRV_A_26_DN")
	)
	(segment
		(start 279.663652 -310.905144)
		(end 279.236678 -310.905144)
		(width 0.127)
		(layer "B.Cu")
		(net "PHY_SCC_A_TO_DRV_A_26_DN")
	)
	(segment
		(start 279.790652 -311.282588)
		(end 279.790652 -311.032144)
		(width 0.127)
		(layer "B.Cu")
		(net "PHY_SCC_A_TO_DRV_A_26_DN")
	)
	(segment
		(start 272.39595 -312.523886)
		(end 272.39595 -312.375296)
		(width 0.127)
		(layer "B.Cu")
		(net "PHY_SCC_A_TO_DRV_A_26_DN")
	)
	(segment
		(start 273.11223 -311.659016)
		(end 279.329388 -311.659016)
		(width 0.127)
		(layer "B.Cu")
		(net "PHY_SCC_A_TO_DRV_A_26_DN")
	)
	(arc
		(start 279.329388 -311.659016)
		(mid 279.528846 -311.619341)
		(end 279.697942 -311.506362)
		(width 0.127)
		(layer "B.Cu")
		(net "PHY_SCC_A_TO_DRV_A_26_DN")
	)
	(arc
		(start 272.39595 -312.375296)
		(mid 272.605744 -311.86881)
		(end 273.11223 -311.659016)
		(width 0.127)
		(layer "B.Cu")
		(net "PHY_SCC_A_TO_DRV_A_26_DN")
	)
	(arc
		(start 272.214848 -312.704988)
		(mid 272.342906 -312.651944)
		(end 272.39595 -312.523886)
		(width 0.127)
		(layer "B.Cu")
		(net "PHY_SCC_A_TO_DRV_A_26_DN")
	)
	(arc
		(start 279.72131 -311.4802)
		(mid 279.772817 -311.387301)
		(end 279.790652 -311.282588)
		(width 0.127)
		(layer "B.Cu")
		(net "PHY_SCC_A_TO_DRV_A_26_DN")
	)
	(arc
		(start 279.697942 -311.506362)
		(mid 279.709986 -311.493602)
		(end 279.72131 -311.4802)
		(width 0.127)
		(layer "B.Cu")
		(net "PHY_SCC_A_TO_DRV_A_26_DN")
	)
	(arc
		(start 279.790652 -311.032144)
		(mid 279.753455 -310.942341)
		(end 279.663652 -310.905144)
		(width 0.127)
		(layer "B.Cu")
		(net "PHY_SCC_A_TO_DRV_A_26_DN")
	)
	(segment
		(start 185.126884 -134.125462)
		(end 183.226202 -132.833364)
		(width 0.127)
		(layer "F.Cu")
		(net "PHY_SCC_A_TO_DRV_A_25_DP")
	)
	(segment
		(start 64.75095 -43.660568)
		(end 64.292734 -43.660568)
		(width 0.127)
		(layer "F.Cu")
		(net "PHY_SCC_A_TO_DRV_A_25_DP")
	)
	(segment
		(start 272.68805 -314.378086)
		(end 272.68805 -313.940952)
		(width 0.127)
		(layer "F.Cu")
		(net "PHY_SCC_A_TO_DRV_A_25_DP")
	)
	(segment
		(start 210.697826 -180.777642)
		(end 200.064116 -165.18001)
		(width 0.127)
		(layer "F.Cu")
		(net "PHY_SCC_A_TO_DRV_A_25_DP")
	)
	(segment
		(start 200.064116 -165.18001)
		(end 185.126884 -134.125462)
		(width 0.127)
		(layer "F.Cu")
		(net "PHY_SCC_A_TO_DRV_A_25_DP")
	)
	(segment
		(start 241.548666 -306.803806)
		(end 234.672378 -301.385732)
		(width 0.127)
		(layer "F.Cu")
		(net "PHY_SCC_A_TO_DRV_A_25_DP")
	)
	(segment
		(start 73.45299 -63.63843)
		(end 66.377566 -44.444412)
		(width 0.127)
		(layer "F.Cu")
		(net "PHY_SCC_A_TO_DRV_A_25_DP")
	)
	(segment
		(start 66.377566 -44.444412)
		(end 65.386712 -43.817032)
		(width 0.127)
		(layer "F.Cu")
		(net "PHY_SCC_A_TO_DRV_A_25_DP")
	)
	(segment
		(start 147.884134 -108.8644)
		(end 139.949428 -103.48341)
		(width 0.127)
		(layer "F.Cu")
		(net "PHY_SCC_A_TO_DRV_A_25_DP")
	)
	(segment
		(start 211.584794 -184.316116)
		(end 210.697826 -180.777642)
		(width 0.127)
		(layer "F.Cu")
		(net "PHY_SCC_A_TO_DRV_A_25_DP")
	)
	(segment
		(start 234.672378 -301.385732)
		(end 221.00159 -279.777444)
		(width 0.127)
		(layer "F.Cu")
		(net "PHY_SCC_A_TO_DRV_A_25_DP")
	)
	(segment
		(start 212.039962 -186.131962)
		(end 211.584794 -184.316116)
		(width 0.127)
		(layer "F.Cu")
		(net "PHY_SCC_A_TO_DRV_A_25_DP")
	)
	(segment
		(start 273.1135 -314.505086)
		(end 272.81505 -314.505086)
		(width 0.127)
		(layer "F.Cu")
		(net "PHY_SCC_A_TO_DRV_A_25_DP")
	)
	(segment
		(start 139.949428 -103.48341)
		(end 139.949428 -103.483156)
		(width 0.127)
		(layer "F.Cu")
		(net "PHY_SCC_A_TO_DRV_A_25_DP")
	)
	(segment
		(start 65.386712 -43.817032)
		(end 64.907414 -43.817032)
		(width 0.127)
		(layer "F.Cu")
		(net "PHY_SCC_A_TO_DRV_A_25_DP")
	)
	(segment
		(start 221.00159 -279.777444)
		(end 206.26197 -209.541364)
		(width 0.127)
		(layer "F.Cu")
		(net "PHY_SCC_A_TO_DRV_A_25_DP")
	)
	(segment
		(start 272.26895 -313.521852)
		(end 261.021576 -313.521852)
		(width 0.127)
		(layer "F.Cu")
		(net "PHY_SCC_A_TO_DRV_A_25_DP")
	)
	(segment
		(start 206.26197 -209.541364)
		(end 212.039962 -186.131962)
		(width 0.127)
		(layer "F.Cu")
		(net "PHY_SCC_A_TO_DRV_A_25_DP")
	)
	(segment
		(start 88.062562 -82.060796)
		(end 83.271868 -78.758288)
		(width 0.127)
		(layer "F.Cu")
		(net "PHY_SCC_A_TO_DRV_A_25_DP")
	)
	(segment
		(start 118.033546 -88.619584)
		(end 88.062562 -82.060796)
		(width 0.127)
		(layer "F.Cu")
		(net "PHY_SCC_A_TO_DRV_A_25_DP")
	)
	(segment
		(start 261.021576 -313.521852)
		(end 241.548666 -306.803806)
		(width 0.127)
		(layer "F.Cu")
		(net "PHY_SCC_A_TO_DRV_A_25_DP")
	)
	(segment
		(start 83.271868 -78.758288)
		(end 73.45299 -63.63843)
		(width 0.127)
		(layer "F.Cu")
		(net "PHY_SCC_A_TO_DRV_A_25_DP")
	)
	(segment
		(start 139.949428 -103.483156)
		(end 118.033546 -88.619584)
		(width 0.127)
		(layer "F.Cu")
		(net "PHY_SCC_A_TO_DRV_A_25_DP")
	)
	(segment
		(start 64.907414 -43.817032)
		(end 64.75095 -43.660568)
		(width 0.127)
		(layer "F.Cu")
		(net "PHY_SCC_A_TO_DRV_A_25_DP")
	)
	(segment
		(start 183.226202 -132.833364)
		(end 147.884134 -108.8644)
		(width 0.127)
		(layer "F.Cu")
		(net "PHY_SCC_A_TO_DRV_A_25_DP")
	)
	(arc
		(start 272.81505 -314.505086)
		(mid 272.725247 -314.467889)
		(end 272.68805 -314.378086)
		(width 0.127)
		(layer "F.Cu")
		(net "PHY_SCC_A_TO_DRV_A_25_DP")
	)
	(arc
		(start 272.68805 -313.940952)
		(mid 272.565298 -313.644604)
		(end 272.26895 -313.521852)
		(width 0.127)
		(layer "F.Cu")
		(net "PHY_SCC_A_TO_DRV_A_25_DP")
	)
	(segment
		(start 272.869152 -314.505086)
		(end 273.1135 -314.505086)
		(width 0.127)
		(layer "B.Cu")
		(net "PHY_SCC_A_TO_DRV_A_25_DP")
	)
	(segment
		(start 272.68805 -314.175394)
		(end 272.68805 -314.323984)
		(width 0.127)
		(layer "B.Cu")
		(net "PHY_SCC_A_TO_DRV_A_25_DP")
	)
	(segment
		(start 279.636728 -312.705242)
		(end 279.636474 -312.704988)
		(width 0.127)
		(layer "B.Cu")
		(net "PHY_SCC_A_TO_DRV_A_25_DP")
	)
	(segment
		(start 278.329136 -313.75096)
		(end 278.328882 -313.751214)
		(width 0.127)
		(layer "B.Cu")
		(net "PHY_SCC_A_TO_DRV_A_25_DP")
	)
	(segment
		(start 278.328882 -313.751214)
		(end 273.11223 -313.751214)
		(width 0.127)
		(layer "B.Cu")
		(net "PHY_SCC_A_TO_DRV_A_25_DP")
	)
	(segment
		(start 279.082754 -312.831988)
		(end 279.082754 -313.08294)
		(width 0.127)
		(layer "B.Cu")
		(net "PHY_SCC_A_TO_DRV_A_25_DP")
	)
	(segment
		(start 279.636474 -312.704988)
		(end 279.209754 -312.704988)
		(width 0.127)
		(layer "B.Cu")
		(net "PHY_SCC_A_TO_DRV_A_25_DP")
	)
	(arc
		(start 272.68805 -314.323984)
		(mid 272.741094 -314.452042)
		(end 272.869152 -314.505086)
		(width 0.127)
		(layer "B.Cu")
		(net "PHY_SCC_A_TO_DRV_A_25_DP")
	)
	(arc
		(start 273.11223 -313.751214)
		(mid 272.812289 -313.875453)
		(end 272.68805 -314.175394)
		(width 0.127)
		(layer "B.Cu")
		(net "PHY_SCC_A_TO_DRV_A_25_DP")
	)
	(arc
		(start 278.949658 -313.46267)
		(mid 278.927871 -313.488435)
		(end 278.9047 -313.512962)
		(width 0.127)
		(layer "B.Cu")
		(net "PHY_SCC_A_TO_DRV_A_25_DP")
	)
	(arc
		(start 279.209754 -312.704988)
		(mid 279.130631 -312.732375)
		(end 279.085802 -312.803032)
		(width 0.127)
		(layer "B.Cu")
		(net "PHY_SCC_A_TO_DRV_A_25_DP")
	)
	(arc
		(start 279.085802 -312.803032)
		(mid 279.08345 -312.817423)
		(end 279.082754 -312.831988)
		(width 0.127)
		(layer "B.Cu")
		(net "PHY_SCC_A_TO_DRV_A_25_DP")
	)
	(arc
		(start 279.082754 -313.08294)
		(mid 279.04852 -313.284133)
		(end 278.949658 -313.46267)
		(width 0.127)
		(layer "B.Cu")
		(net "PHY_SCC_A_TO_DRV_A_25_DP")
	)
	(arc
		(start 278.9047 -313.512962)
		(mid 278.640599 -313.689243)
		(end 278.329136 -313.75096)
		(width 0.127)
		(layer "B.Cu")
		(net "PHY_SCC_A_TO_DRV_A_25_DP")
	)
	(segment
		(start 272.39595 -314.378086)
		(end 272.39595 -313.940952)
		(width 0.127)
		(layer "F.Cu")
		(net "PHY_SCC_A_TO_DRV_A_25_DN")
	)
	(segment
		(start 117.915944 -88.893142)
		(end 87.943944 -82.3341)
		(width 0.127)
		(layer "F.Cu")
		(net "PHY_SCC_A_TO_DRV_A_25_DN")
	)
	(segment
		(start 220.726254 -279.889204)
		(end 205.96225 -209.53603)
		(width 0.127)
		(layer "F.Cu")
		(net "PHY_SCC_A_TO_DRV_A_25_DN")
	)
	(segment
		(start 271.9705 -314.505086)
		(end 272.26895 -314.505086)
		(width 0.127)
		(layer "F.Cu")
		(net "PHY_SCC_A_TO_DRV_A_25_DN")
	)
	(segment
		(start 269.776956 -313.966352)
		(end 269.395956 -313.966352)
		(width 0.127)
		(layer "F.Cu")
		(net "PHY_SCC_A_TO_DRV_A_25_DN")
	)
	(segment
		(start 269.929356 -313.813952)
		(end 269.776956 -313.966352)
		(width 0.127)
		(layer "F.Cu")
		(net "PHY_SCC_A_TO_DRV_A_25_DN")
	)
	(segment
		(start 83.058254 -78.96606)
		(end 73.1901 -63.770002)
		(width 0.127)
		(layer "F.Cu")
		(net "PHY_SCC_A_TO_DRV_A_25_DN")
	)
	(segment
		(start 141.769084 -105.070402)
		(end 139.785344 -103.725218)
		(width 0.127)
		(layer "F.Cu")
		(net "PHY_SCC_A_TO_DRV_A_25_DN")
	)
	(segment
		(start 268.329156 -313.966352)
		(end 268.176756 -313.813952)
		(width 0.127)
		(layer "F.Cu")
		(net "PHY_SCC_A_TO_DRV_A_25_DN")
	)
	(segment
		(start 199.810624 -165.327584)
		(end 184.897522 -134.323074)
		(width 0.127)
		(layer "F.Cu")
		(net "PHY_SCC_A_TO_DRV_A_25_DN")
	)
	(segment
		(start 241.40668 -307.063902)
		(end 234.45216 -301.58436)
		(width 0.127)
		(layer "F.Cu")
		(net "PHY_SCC_A_TO_DRV_A_25_DN")
	)
	(segment
		(start 147.72005 -109.106462)
		(end 141.769084 -105.070402)
		(width 0.127)
		(layer "F.Cu")
		(net "PHY_SCC_A_TO_DRV_A_25_DN")
	)
	(segment
		(start 66.137536 -44.638468)
		(end 65.301876 -44.109132)
		(width 0.127)
		(layer "F.Cu")
		(net "PHY_SCC_A_TO_DRV_A_25_DN")
	)
	(segment
		(start 267.262356 -313.966352)
		(end 267.109956 -313.813952)
		(width 0.127)
		(layer "F.Cu")
		(net "PHY_SCC_A_TO_DRV_A_25_DN")
	)
	(segment
		(start 268.176756 -313.813952)
		(end 267.795756 -313.813952)
		(width 0.127)
		(layer "F.Cu")
		(net "PHY_SCC_A_TO_DRV_A_25_DN")
	)
	(segment
		(start 205.96225 -209.53603)
		(end 211.738718 -186.13247)
		(width 0.127)
		(layer "F.Cu")
		(net "PHY_SCC_A_TO_DRV_A_25_DN")
	)
	(segment
		(start 211.738718 -186.13247)
		(end 211.30133 -184.387236)
		(width 0.127)
		(layer "F.Cu")
		(net "PHY_SCC_A_TO_DRV_A_25_DN")
	)
	(segment
		(start 267.109956 -313.813952)
		(end 266.728956 -313.813952)
		(width 0.127)
		(layer "F.Cu")
		(net "PHY_SCC_A_TO_DRV_A_25_DN")
	)
	(segment
		(start 267.795756 -313.813952)
		(end 267.643356 -313.966352)
		(width 0.127)
		(layer "F.Cu")
		(net "PHY_SCC_A_TO_DRV_A_25_DN")
	)
	(segment
		(start 268.710156 -313.966352)
		(end 268.329156 -313.966352)
		(width 0.127)
		(layer "F.Cu")
		(net "PHY_SCC_A_TO_DRV_A_25_DN")
	)
	(segment
		(start 272.26895 -313.813952)
		(end 269.929356 -313.813952)
		(width 0.127)
		(layer "F.Cu")
		(net "PHY_SCC_A_TO_DRV_A_25_DN")
	)
	(segment
		(start 210.427062 -180.899308)
		(end 199.810624 -165.327584)
		(width 0.127)
		(layer "F.Cu")
		(net "PHY_SCC_A_TO_DRV_A_25_DN")
	)
	(segment
		(start 267.643356 -313.966352)
		(end 267.262356 -313.966352)
		(width 0.127)
		(layer "F.Cu")
		(net "PHY_SCC_A_TO_DRV_A_25_DN")
	)
	(segment
		(start 266.576556 -313.966352)
		(end 266.195556 -313.966352)
		(width 0.127)
		(layer "F.Cu")
		(net "PHY_SCC_A_TO_DRV_A_25_DN")
	)
	(segment
		(start 268.862556 -313.813952)
		(end 268.710156 -313.966352)
		(width 0.127)
		(layer "F.Cu")
		(net "PHY_SCC_A_TO_DRV_A_25_DN")
	)
	(segment
		(start 73.1901 -63.770002)
		(end 66.137536 -44.638468)
		(width 0.127)
		(layer "F.Cu")
		(net "PHY_SCC_A_TO_DRV_A_25_DN")
	)
	(segment
		(start 211.30133 -184.386982)
		(end 210.427062 -180.899308)
		(width 0.127)
		(layer "F.Cu")
		(net "PHY_SCC_A_TO_DRV_A_25_DN")
	)
	(segment
		(start 65.301876 -44.109132)
		(end 64.861186 -44.109132)
		(width 0.127)
		(layer "F.Cu")
		(net "PHY_SCC_A_TO_DRV_A_25_DN")
	)
	(segment
		(start 211.30133 -184.387236)
		(end 211.30133 -184.386982)
		(width 0.127)
		(layer "F.Cu")
		(net "PHY_SCC_A_TO_DRV_A_25_DN")
	)
	(segment
		(start 260.972554 -313.813952)
		(end 241.40668 -307.063902)
		(width 0.127)
		(layer "F.Cu")
		(net "PHY_SCC_A_TO_DRV_A_25_DN")
	)
	(segment
		(start 139.785344 -103.725218)
		(end 117.915944 -88.893142)
		(width 0.127)
		(layer "F.Cu")
		(net "PHY_SCC_A_TO_DRV_A_25_DN")
	)
	(segment
		(start 269.243556 -313.813952)
		(end 268.862556 -313.813952)
		(width 0.127)
		(layer "F.Cu")
		(net "PHY_SCC_A_TO_DRV_A_25_DN")
	)
	(segment
		(start 234.45216 -301.58436)
		(end 220.726254 -279.889204)
		(width 0.127)
		(layer "F.Cu")
		(net "PHY_SCC_A_TO_DRV_A_25_DN")
	)
	(segment
		(start 266.195556 -313.966352)
		(end 266.043156 -313.813952)
		(width 0.127)
		(layer "F.Cu")
		(net "PHY_SCC_A_TO_DRV_A_25_DN")
	)
	(segment
		(start 266.728956 -313.813952)
		(end 266.576556 -313.966352)
		(width 0.127)
		(layer "F.Cu")
		(net "PHY_SCC_A_TO_DRV_A_25_DN")
	)
	(segment
		(start 87.943944 -82.3341)
		(end 83.058254 -78.96606)
		(width 0.127)
		(layer "F.Cu")
		(net "PHY_SCC_A_TO_DRV_A_25_DN")
	)
	(segment
		(start 64.861186 -44.109132)
		(end 64.75095 -44.219368)
		(width 0.127)
		(layer "F.Cu")
		(net "PHY_SCC_A_TO_DRV_A_25_DN")
	)
	(segment
		(start 266.043156 -313.813952)
		(end 260.972554 -313.813952)
		(width 0.127)
		(layer "F.Cu")
		(net "PHY_SCC_A_TO_DRV_A_25_DN")
	)
	(segment
		(start 64.75095 -44.219368)
		(end 64.292734 -44.219368)
		(width 0.127)
		(layer "F.Cu")
		(net "PHY_SCC_A_TO_DRV_A_25_DN")
	)
	(segment
		(start 184.897522 -134.323074)
		(end 183.061864 -133.075172)
		(width 0.127)
		(layer "F.Cu")
		(net "PHY_SCC_A_TO_DRV_A_25_DN")
	)
	(segment
		(start 183.061864 -133.075172)
		(end 147.72005 -109.106462)
		(width 0.127)
		(layer "F.Cu")
		(net "PHY_SCC_A_TO_DRV_A_25_DN")
	)
	(segment
		(start 269.395956 -313.966352)
		(end 269.243556 -313.813952)
		(width 0.127)
		(layer "F.Cu")
		(net "PHY_SCC_A_TO_DRV_A_25_DN")
	)
	(arc
		(start 272.39595 -313.940952)
		(mid 272.358753 -313.851149)
		(end 272.26895 -313.813952)
		(width 0.127)
		(layer "F.Cu")
		(net "PHY_SCC_A_TO_DRV_A_25_DN")
	)
	(arc
		(start 272.26895 -314.505086)
		(mid 272.358753 -314.467889)
		(end 272.39595 -314.378086)
		(width 0.127)
		(layer "F.Cu")
		(net "PHY_SCC_A_TO_DRV_A_25_DN")
	)
	(segment
		(start 273.709384 -313.459114)
		(end 273.709638 -313.45886)
		(width 0.127)
		(layer "B.Cu")
		(net "PHY_SCC_A_TO_DRV_A_25_DN")
	)
	(segment
		(start 278.663654 -312.704988)
		(end 278.236934 -312.704988)
		(width 0.127)
		(layer "B.Cu")
		(net "PHY_SCC_A_TO_DRV_A_25_DN")
	)
	(segment
		(start 273.11223 -313.459114)
		(end 273.709384 -313.459114)
		(width 0.127)
		(layer "B.Cu")
		(net "PHY_SCC_A_TO_DRV_A_25_DN")
	)
	(segment
		(start 272.39595 -314.323984)
		(end 272.39595 -314.175394)
		(width 0.127)
		(layer "B.Cu")
		(net "PHY_SCC_A_TO_DRV_A_25_DN")
	)
	(segment
		(start 278.236934 -312.704988)
		(end 278.23668 -312.705242)
		(width 0.127)
		(layer "B.Cu")
		(net "PHY_SCC_A_TO_DRV_A_25_DN")
	)
	(segment
		(start 271.9705 -314.505086)
		(end 272.214848 -314.505086)
		(width 0.127)
		(layer "B.Cu")
		(net "PHY_SCC_A_TO_DRV_A_25_DN")
	)
	(segment
		(start 278.790654 -313.082432)
		(end 278.790654 -312.831988)
		(width 0.127)
		(layer "B.Cu")
		(net "PHY_SCC_A_TO_DRV_A_25_DN")
	)
	(segment
		(start 273.709638 -313.45886)
		(end 278.32939 -313.45886)
		(width 0.127)
		(layer "B.Cu")
		(net "PHY_SCC_A_TO_DRV_A_25_DN")
	)
	(arc
		(start 278.721312 -313.280044)
		(mid 278.772819 -313.187145)
		(end 278.790654 -313.082432)
		(width 0.127)
		(layer "B.Cu")
		(net "PHY_SCC_A_TO_DRV_A_25_DN")
	)
	(arc
		(start 272.39595 -314.175394)
		(mid 272.605744 -313.668908)
		(end 273.11223 -313.459114)
		(width 0.127)
		(layer "B.Cu")
		(net "PHY_SCC_A_TO_DRV_A_25_DN")
	)
	(arc
		(start 278.697944 -313.306206)
		(mid 278.709988 -313.293446)
		(end 278.721312 -313.280044)
		(width 0.127)
		(layer "B.Cu")
		(net "PHY_SCC_A_TO_DRV_A_25_DN")
	)
	(arc
		(start 278.790654 -312.831988)
		(mid 278.753457 -312.742185)
		(end 278.663654 -312.704988)
		(width 0.127)
		(layer "B.Cu")
		(net "PHY_SCC_A_TO_DRV_A_25_DN")
	)
	(arc
		(start 278.32939 -313.45886)
		(mid 278.528848 -313.419185)
		(end 278.697944 -313.306206)
		(width 0.127)
		(layer "B.Cu")
		(net "PHY_SCC_A_TO_DRV_A_25_DN")
	)
	(arc
		(start 272.214848 -314.505086)
		(mid 272.342906 -314.452042)
		(end 272.39595 -314.323984)
		(width 0.127)
		(layer "B.Cu")
		(net "PHY_SCC_A_TO_DRV_A_25_DN")
	)
	(segment
		(start 233.374692 -302.356774)
		(end 240.852706 -308.24932)
		(width 0.127)
		(layer "F.Cu")
		(net "PHY_SCC_A_TO_DRV_A_24_DP")
	)
	(segment
		(start 33.996884 -44.080176)
		(end 35.596576 -46.347888)
		(width 0.127)
		(layer "F.Cu")
		(net "PHY_SCC_A_TO_DRV_A_24_DP")
	)
	(segment
		(start 33.201102 -43.660568)
		(end 33.363408 -43.822874)
		(width 0.127)
		(layer "F.Cu")
		(net "PHY_SCC_A_TO_DRV_A_24_DP")
	)
	(segment
		(start 196.446648 -172.348906)
		(end 192.781174 -187.204858)
		(width 0.127)
		(layer "F.Cu")
		(net "PHY_SCC_A_TO_DRV_A_24_DP")
	)
	(segment
		(start 240.852706 -308.24932)
		(end 261.35457 -315.321696)
		(width 0.127)
		(layer "F.Cu")
		(net "PHY_SCC_A_TO_DRV_A_24_DP")
	)
	(segment
		(start 194.156584 -162.019234)
		(end 196.446648 -172.348906)
		(width 0.127)
		(layer "F.Cu")
		(net "PHY_SCC_A_TO_DRV_A_24_DP")
	)
	(segment
		(start 90.87104 -105.865676)
		(end 94.528132 -108.195872)
		(width 0.127)
		(layer "F.Cu")
		(net "PHY_SCC_A_TO_DRV_A_24_DP")
	)
	(segment
		(start 191.868552 -151.69769)
		(end 194.156584 -162.019234)
		(width 0.127)
		(layer "F.Cu")
		(net "PHY_SCC_A_TO_DRV_A_24_DP")
	)
	(segment
		(start 261.35457 -315.321696)
		(end 272.26895 -315.321696)
		(width 0.127)
		(layer "F.Cu")
		(net "PHY_SCC_A_TO_DRV_A_24_DP")
	)
	(segment
		(start 76.258166 -96.556322)
		(end 82.931 -100.807266)
		(width 0.127)
		(layer "F.Cu")
		(net "PHY_SCC_A_TO_DRV_A_24_DP")
	)
	(segment
		(start 182.986172 -139.4206)
		(end 191.868552 -151.69769)
		(width 0.127)
		(layer "F.Cu")
		(net "PHY_SCC_A_TO_DRV_A_24_DP")
	)
	(segment
		(start 35.596576 -46.347888)
		(end 41.89095 -63.410592)
		(width 0.127)
		(layer "F.Cu")
		(net "PHY_SCC_A_TO_DRV_A_24_DP")
	)
	(segment
		(start 32.742886 -43.660568)
		(end 33.201102 -43.660568)
		(width 0.127)
		(layer "F.Cu")
		(net "PHY_SCC_A_TO_DRV_A_24_DP")
	)
	(segment
		(start 167.299132 -126.265178)
		(end 182.986172 -139.4206)
		(width 0.127)
		(layer "F.Cu")
		(net "PHY_SCC_A_TO_DRV_A_24_DP")
	)
	(segment
		(start 67.684396 -91.094306)
		(end 76.258166 -96.556322)
		(width 0.127)
		(layer "F.Cu")
		(net "PHY_SCC_A_TO_DRV_A_24_DP")
	)
	(segment
		(start 41.89095 -63.410592)
		(end 59.111134 -85.632544)
		(width 0.127)
		(layer "F.Cu")
		(net "PHY_SCC_A_TO_DRV_A_24_DP")
	)
	(segment
		(start 33.363408 -43.822874)
		(end 33.59023 -43.822874)
		(width 0.127)
		(layer "F.Cu")
		(net "PHY_SCC_A_TO_DRV_A_24_DP")
	)
	(segment
		(start 272.68805 -315.740796)
		(end 272.68805 -316.17793)
		(width 0.127)
		(layer "F.Cu")
		(net "PHY_SCC_A_TO_DRV_A_24_DP")
	)
	(segment
		(start 33.59023 -43.822874)
		(end 33.996884 -44.080176)
		(width 0.127)
		(layer "F.Cu")
		(net "PHY_SCC_A_TO_DRV_A_24_DP")
	)
	(segment
		(start 208.778602 -263.48309)
		(end 233.374692 -302.356774)
		(width 0.127)
		(layer "F.Cu")
		(net "PHY_SCC_A_TO_DRV_A_24_DP")
	)
	(segment
		(start 82.931 -100.807266)
		(end 90.87104 -105.865676)
		(width 0.127)
		(layer "F.Cu")
		(net "PHY_SCC_A_TO_DRV_A_24_DP")
	)
	(segment
		(start 192.781174 -187.204858)
		(end 208.778602 -263.48309)
		(width 0.127)
		(layer "F.Cu")
		(net "PHY_SCC_A_TO_DRV_A_24_DP")
	)
	(segment
		(start 94.528132 -108.195872)
		(end 167.299132 -126.265178)
		(width 0.127)
		(layer "F.Cu")
		(net "PHY_SCC_A_TO_DRV_A_24_DP")
	)
	(segment
		(start 59.111134 -85.632544)
		(end 67.684396 -91.094306)
		(width 0.127)
		(layer "F.Cu")
		(net "PHY_SCC_A_TO_DRV_A_24_DP")
	)
	(segment
		(start 272.81505 -316.30493)
		(end 273.1135 -316.30493)
		(width 0.127)
		(layer "F.Cu")
		(net "PHY_SCC_A_TO_DRV_A_24_DP")
	)
	(arc
		(start 272.68805 -316.17793)
		(mid 272.725247 -316.267733)
		(end 272.81505 -316.30493)
		(width 0.127)
		(layer "F.Cu")
		(net "PHY_SCC_A_TO_DRV_A_24_DP")
	)
	(arc
		(start 272.26895 -315.321696)
		(mid 272.565298 -315.444448)
		(end 272.68805 -315.740796)
		(width 0.127)
		(layer "F.Cu")
		(net "PHY_SCC_A_TO_DRV_A_24_DP")
	)
	(segment
		(start 272.68805 -316.123828)
		(end 272.68805 -315.975238)
		(width 0.127)
		(layer "B.Cu")
		(net "PHY_SCC_A_TO_DRV_A_24_DP")
	)
	(segment
		(start 280.209752 -314.505086)
		(end 280.636726 -314.505086)
		(width 0.127)
		(layer "B.Cu")
		(net "PHY_SCC_A_TO_DRV_A_24_DP")
	)
	(segment
		(start 273.11223 -315.551058)
		(end 279.329134 -315.551058)
		(width 0.127)
		(layer "B.Cu")
		(net "PHY_SCC_A_TO_DRV_A_24_DP")
	)
	(segment
		(start 280.082752 -314.883038)
		(end 280.082752 -314.632086)
		(width 0.127)
		(layer "B.Cu")
		(net "PHY_SCC_A_TO_DRV_A_24_DP")
	)
	(segment
		(start 273.1135 -316.30493)
		(end 272.869152 -316.30493)
		(width 0.127)
		(layer "B.Cu")
		(net "PHY_SCC_A_TO_DRV_A_24_DP")
	)
	(arc
		(start 280.082752 -314.632086)
		(mid 280.119949 -314.542283)
		(end 280.209752 -314.505086)
		(width 0.127)
		(layer "B.Cu")
		(net "PHY_SCC_A_TO_DRV_A_24_DP")
	)
	(arc
		(start 272.68805 -315.975238)
		(mid 272.812289 -315.675297)
		(end 273.11223 -315.551058)
		(width 0.127)
		(layer "B.Cu")
		(net "PHY_SCC_A_TO_DRV_A_24_DP")
	)
	(arc
		(start 279.904698 -315.31306)
		(mid 279.92788 -315.288542)
		(end 279.949656 -315.262768)
		(width 0.127)
		(layer "B.Cu")
		(net "PHY_SCC_A_TO_DRV_A_24_DP")
	)
	(arc
		(start 279.949656 -315.262768)
		(mid 280.048501 -315.084225)
		(end 280.082752 -314.883038)
		(width 0.127)
		(layer "B.Cu")
		(net "PHY_SCC_A_TO_DRV_A_24_DP")
	)
	(arc
		(start 279.329134 -315.551058)
		(mid 279.640578 -315.489295)
		(end 279.904698 -315.31306)
		(width 0.127)
		(layer "B.Cu")
		(net "PHY_SCC_A_TO_DRV_A_24_DP")
	)
	(arc
		(start 272.869152 -316.30493)
		(mid 272.741094 -316.251886)
		(end 272.68805 -316.123828)
		(width 0.127)
		(layer "B.Cu")
		(net "PHY_SCC_A_TO_DRV_A_24_DP")
	)
	(segment
		(start 266.728956 -315.613796)
		(end 267.109956 -315.613796)
		(width 0.127)
		(layer "F.Cu")
		(net "PHY_SCC_A_TO_DRV_A_24_DN")
	)
	(segment
		(start 266.576556 -315.766196)
		(end 266.728956 -315.613796)
		(width 0.127)
		(layer "F.Cu")
		(net "PHY_SCC_A_TO_DRV_A_24_DN")
	)
	(segment
		(start 167.162988 -126.53264)
		(end 182.77078 -139.62126)
		(width 0.127)
		(layer "F.Cu")
		(net "PHY_SCC_A_TO_DRV_A_24_DN")
	)
	(segment
		(start 32.742886 -44.219368)
		(end 33.201102 -44.219368)
		(width 0.127)
		(layer "F.Cu")
		(net "PHY_SCC_A_TO_DRV_A_24_DN")
	)
	(segment
		(start 208.503266 -263.59485)
		(end 233.154474 -302.555402)
		(width 0.127)
		(layer "F.Cu")
		(net "PHY_SCC_A_TO_DRV_A_24_DN")
	)
	(segment
		(start 58.911236 -85.851746)
		(end 90.714068 -106.112056)
		(width 0.127)
		(layer "F.Cu")
		(net "PHY_SCC_A_TO_DRV_A_24_DN")
	)
	(segment
		(start 266.043156 -315.613796)
		(end 266.195556 -315.766196)
		(width 0.127)
		(layer "F.Cu")
		(net "PHY_SCC_A_TO_DRV_A_24_DN")
	)
	(segment
		(start 41.632378 -63.553848)
		(end 58.911236 -85.851746)
		(width 0.127)
		(layer "F.Cu")
		(net "PHY_SCC_A_TO_DRV_A_24_DN")
	)
	(segment
		(start 182.77078 -139.62126)
		(end 191.596264 -151.820118)
		(width 0.127)
		(layer "F.Cu")
		(net "PHY_SCC_A_TO_DRV_A_24_DN")
	)
	(segment
		(start 33.505394 -44.114974)
		(end 33.791652 -44.296076)
		(width 0.127)
		(layer "F.Cu")
		(net "PHY_SCC_A_TO_DRV_A_24_DN")
	)
	(segment
		(start 261.305548 -315.613796)
		(end 266.043156 -315.613796)
		(width 0.127)
		(layer "F.Cu")
		(net "PHY_SCC_A_TO_DRV_A_24_DN")
	)
	(segment
		(start 191.596264 -151.820118)
		(end 196.14642 -172.34535)
		(width 0.127)
		(layer "F.Cu")
		(net "PHY_SCC_A_TO_DRV_A_24_DN")
	)
	(segment
		(start 33.305496 -44.114974)
		(end 33.505394 -44.114974)
		(width 0.127)
		(layer "F.Cu")
		(net "PHY_SCC_A_TO_DRV_A_24_DN")
	)
	(segment
		(start 267.109956 -315.613796)
		(end 267.262356 -315.766196)
		(width 0.127)
		(layer "F.Cu")
		(net "PHY_SCC_A_TO_DRV_A_24_DN")
	)
	(segment
		(start 268.176756 -315.613796)
		(end 268.329156 -315.766196)
		(width 0.127)
		(layer "F.Cu")
		(net "PHY_SCC_A_TO_DRV_A_24_DN")
	)
	(segment
		(start 233.154474 -302.555402)
		(end 240.71072 -308.509416)
		(width 0.127)
		(layer "F.Cu")
		(net "PHY_SCC_A_TO_DRV_A_24_DN")
	)
	(segment
		(start 268.862556 -315.613796)
		(end 269.243556 -315.613796)
		(width 0.127)
		(layer "F.Cu")
		(net "PHY_SCC_A_TO_DRV_A_24_DN")
	)
	(segment
		(start 196.14642 -172.34535)
		(end 192.481454 -187.199524)
		(width 0.127)
		(layer "F.Cu")
		(net "PHY_SCC_A_TO_DRV_A_24_DN")
	)
	(segment
		(start 267.643356 -315.766196)
		(end 267.795756 -315.613796)
		(width 0.127)
		(layer "F.Cu")
		(net "PHY_SCC_A_TO_DRV_A_24_DN")
	)
	(segment
		(start 272.39595 -315.740796)
		(end 272.39595 -316.17793)
		(width 0.127)
		(layer "F.Cu")
		(net "PHY_SCC_A_TO_DRV_A_24_DN")
	)
	(segment
		(start 35.335718 -46.485048)
		(end 41.632378 -63.553848)
		(width 0.127)
		(layer "F.Cu")
		(net "PHY_SCC_A_TO_DRV_A_24_DN")
	)
	(segment
		(start 269.395956 -315.766196)
		(end 269.776956 -315.766196)
		(width 0.127)
		(layer "F.Cu")
		(net "PHY_SCC_A_TO_DRV_A_24_DN")
	)
	(segment
		(start 240.71072 -308.509416)
		(end 261.305548 -315.613796)
		(width 0.127)
		(layer "F.Cu")
		(net "PHY_SCC_A_TO_DRV_A_24_DN")
	)
	(segment
		(start 90.714068 -106.112056)
		(end 94.411292 -108.467906)
		(width 0.127)
		(layer "F.Cu")
		(net "PHY_SCC_A_TO_DRV_A_24_DN")
	)
	(segment
		(start 33.201102 -44.219368)
		(end 33.305496 -44.114974)
		(width 0.127)
		(layer "F.Cu")
		(net "PHY_SCC_A_TO_DRV_A_24_DN")
	)
	(segment
		(start 268.329156 -315.766196)
		(end 268.710156 -315.766196)
		(width 0.127)
		(layer "F.Cu")
		(net "PHY_SCC_A_TO_DRV_A_24_DN")
	)
	(segment
		(start 269.776956 -315.766196)
		(end 269.929356 -315.613796)
		(width 0.127)
		(layer "F.Cu")
		(net "PHY_SCC_A_TO_DRV_A_24_DN")
	)
	(segment
		(start 268.710156 -315.766196)
		(end 268.862556 -315.613796)
		(width 0.127)
		(layer "F.Cu")
		(net "PHY_SCC_A_TO_DRV_A_24_DN")
	)
	(segment
		(start 267.262356 -315.766196)
		(end 267.643356 -315.766196)
		(width 0.127)
		(layer "F.Cu")
		(net "PHY_SCC_A_TO_DRV_A_24_DN")
	)
	(segment
		(start 269.243556 -315.613796)
		(end 269.395956 -315.766196)
		(width 0.127)
		(layer "F.Cu")
		(net "PHY_SCC_A_TO_DRV_A_24_DN")
	)
	(segment
		(start 94.411292 -108.467906)
		(end 167.162988 -126.53264)
		(width 0.127)
		(layer "F.Cu")
		(net "PHY_SCC_A_TO_DRV_A_24_DN")
	)
	(segment
		(start 266.195556 -315.766196)
		(end 266.576556 -315.766196)
		(width 0.127)
		(layer "F.Cu")
		(net "PHY_SCC_A_TO_DRV_A_24_DN")
	)
	(segment
		(start 272.26895 -316.30493)
		(end 271.9705 -316.30493)
		(width 0.127)
		(layer "F.Cu")
		(net "PHY_SCC_A_TO_DRV_A_24_DN")
	)
	(segment
		(start 267.795756 -315.613796)
		(end 268.176756 -315.613796)
		(width 0.127)
		(layer "F.Cu")
		(net "PHY_SCC_A_TO_DRV_A_24_DN")
	)
	(segment
		(start 269.929356 -315.613796)
		(end 272.26895 -315.613796)
		(width 0.127)
		(layer "F.Cu")
		(net "PHY_SCC_A_TO_DRV_A_24_DN")
	)
	(segment
		(start 33.791652 -44.296076)
		(end 35.335718 -46.485048)
		(width 0.127)
		(layer "F.Cu")
		(net "PHY_SCC_A_TO_DRV_A_24_DN")
	)
	(segment
		(start 192.481454 -187.199524)
		(end 200.493884 -225.403918)
		(width 0.127)
		(layer "F.Cu")
		(net "PHY_SCC_A_TO_DRV_A_24_DN")
	)
	(segment
		(start 200.493884 -225.403918)
		(end 208.503266 -263.59485)
		(width 0.127)
		(layer "F.Cu")
		(net "PHY_SCC_A_TO_DRV_A_24_DN")
	)
	(arc
		(start 272.39595 -316.17793)
		(mid 272.358753 -316.267733)
		(end 272.26895 -316.30493)
		(width 0.127)
		(layer "F.Cu")
		(net "PHY_SCC_A_TO_DRV_A_24_DN")
	)
	(arc
		(start 272.26895 -315.613796)
		(mid 272.358753 -315.650993)
		(end 272.39595 -315.740796)
		(width 0.127)
		(layer "F.Cu")
		(net "PHY_SCC_A_TO_DRV_A_24_DN")
	)
	(segment
		(start 271.9705 -316.30493)
		(end 272.214848 -316.30493)
		(width 0.127)
		(layer "B.Cu")
		(net "PHY_SCC_A_TO_DRV_A_24_DN")
	)
	(segment
		(start 279.790652 -314.88253)
		(end 279.790652 -314.632086)
		(width 0.127)
		(layer "B.Cu")
		(net "PHY_SCC_A_TO_DRV_A_24_DN")
	)
	(segment
		(start 279.663652 -314.505086)
		(end 279.236678 -314.505086)
		(width 0.127)
		(layer "B.Cu")
		(net "PHY_SCC_A_TO_DRV_A_24_DN")
	)
	(segment
		(start 272.39595 -316.123828)
		(end 272.39595 -315.975238)
		(width 0.127)
		(layer "B.Cu")
		(net "PHY_SCC_A_TO_DRV_A_24_DN")
	)
	(segment
		(start 273.11223 -315.258958)
		(end 279.329388 -315.258958)
		(width 0.127)
		(layer "B.Cu")
		(net "PHY_SCC_A_TO_DRV_A_24_DN")
	)
	(arc
		(start 279.329388 -315.258958)
		(mid 279.528846 -315.219283)
		(end 279.697942 -315.106304)
		(width 0.127)
		(layer "B.Cu")
		(net "PHY_SCC_A_TO_DRV_A_24_DN")
	)
	(arc
		(start 279.790652 -314.632086)
		(mid 279.753455 -314.542283)
		(end 279.663652 -314.505086)
		(width 0.127)
		(layer "B.Cu")
		(net "PHY_SCC_A_TO_DRV_A_24_DN")
	)
	(arc
		(start 279.72131 -315.080142)
		(mid 279.772817 -314.987243)
		(end 279.790652 -314.88253)
		(width 0.127)
		(layer "B.Cu")
		(net "PHY_SCC_A_TO_DRV_A_24_DN")
	)
	(arc
		(start 272.214848 -316.30493)
		(mid 272.342906 -316.251886)
		(end 272.39595 -316.123828)
		(width 0.127)
		(layer "B.Cu")
		(net "PHY_SCC_A_TO_DRV_A_24_DN")
	)
	(arc
		(start 279.697942 -315.106304)
		(mid 279.709986 -315.093544)
		(end 279.72131 -315.080142)
		(width 0.127)
		(layer "B.Cu")
		(net "PHY_SCC_A_TO_DRV_A_24_DN")
	)
	(arc
		(start 272.39595 -315.975238)
		(mid 272.605744 -315.468752)
		(end 273.11223 -315.258958)
		(width 0.127)
		(layer "B.Cu")
		(net "PHY_SCC_A_TO_DRV_A_24_DN")
	)
	(segment
		(start 478.640648 -158.793942)
		(end 478.773998 -158.660592)
		(width 0.127)
		(layer "F.Cu")
		(net "PHY_SCC_A_TO_DRV_A_23_DP")
	)
	(segment
		(start 477.739202 -158.368492)
		(end 477.739202 -158.638748)
		(width 0.127)
		(layer "F.Cu")
		(net "PHY_SCC_A_TO_DRV_A_23_DP")
	)
	(segment
		(start 477.894396 -158.793942)
		(end 478.640648 -158.793942)
		(width 0.127)
		(layer "F.Cu")
		(net "PHY_SCC_A_TO_DRV_A_23_DP")
	)
	(segment
		(start 478.773998 -158.660592)
		(end 479.105214 -158.660592)
		(width 0.127)
		(layer "F.Cu")
		(net "PHY_SCC_A_TO_DRV_A_23_DP")
	)
	(segment
		(start 477.776286 -158.72841)
		(end 477.804734 -158.756858)
		(width 0.127)
		(layer "F.Cu")
		(net "PHY_SCC_A_TO_DRV_A_23_DP")
	)
	(arc
		(start 477.739202 -158.638748)
		(mid 477.748835 -158.687266)
		(end 477.776286 -158.72841)
		(width 0.127)
		(layer "F.Cu")
		(net "PHY_SCC_A_TO_DRV_A_23_DP")
	)
	(arc
		(start 477.804734 -158.756858)
		(mid 477.845885 -158.784291)
		(end 477.894396 -158.793942)
		(width 0.127)
		(layer "F.Cu")
		(net "PHY_SCC_A_TO_DRV_A_23_DP")
	)
	(segment
		(start 429.843692 -224.773998)
		(end 372.78564 -236.38002)
		(width 0.10795)
		(layer "In9.Cu")
		(net "PHY_SCC_A_TO_DRV_A_23_DP")
	)
	(segment
		(start 280.138886 -325.348346)
		(end 280.144982 -325.34225)
		(width 0.10795)
		(layer "In9.Cu")
		(net "PHY_SCC_A_TO_DRV_A_23_DP")
	)
	(segment
		(start 299.919136 -317.93942)
		(end 299.745146 -318.21247)
		(width 0.10795)
		(layer "In9.Cu")
		(net "PHY_SCC_A_TO_DRV_A_23_DP")
	)
	(segment
		(start 460.193644 -168.721024)
		(end 458.113638 -172.492416)
		(width 0.10795)
		(layer "In9.Cu")
		(net "PHY_SCC_A_TO_DRV_A_23_DP")
	)
	(segment
		(start 477.739202 -158.368492)
		(end 477.739202 -158.655258)
		(width 0.10795)
		(layer "In9.Cu")
		(net "PHY_SCC_A_TO_DRV_A_23_DP")
	)
	(segment
		(start 298.598844 -320.01206)
		(end 289.563556 -325.7677)
		(width 0.10795)
		(layer "In9.Cu")
		(net "PHY_SCC_A_TO_DRV_A_23_DP")
	)
	(segment
		(start 452.646288 -194.140328)
		(end 437.785764 -219.645484)
		(width 0.10795)
		(layer "In9.Cu")
		(net "PHY_SCC_A_TO_DRV_A_23_DP")
	)
	(segment
		(start 475.843854 -158.774892)
		(end 467.473538 -160.739582)
		(width 0.10795)
		(layer "In9.Cu")
		(net "PHY_SCC_A_TO_DRV_A_23_DP")
	)
	(segment
		(start 437.785764 -219.645484)
		(end 433.847748 -222.188532)
		(width 0.10795)
		(layer "In9.Cu")
		(net "PHY_SCC_A_TO_DRV_A_23_DP")
	)
	(segment
		(start 299.346112 -318.839088)
		(end 299.172122 -319.112392)
		(width 0.10795)
		(layer "In9.Cu")
		(net "PHY_SCC_A_TO_DRV_A_23_DP")
	)
	(segment
		(start 289.563556 -325.7677)
		(end 288.33953 -326.039988)
		(width 0.10795)
		(layer "In9.Cu")
		(net "PHY_SCC_A_TO_DRV_A_23_DP")
	)
	(segment
		(start 433.847748 -222.188532)
		(end 429.843692 -224.773998)
		(width 0.10795)
		(layer "In9.Cu")
		(net "PHY_SCC_A_TO_DRV_A_23_DP")
	)
	(segment
		(start 299.855128 -317.650114)
		(end 299.919136 -317.93942)
		(width 0.10795)
		(layer "In9.Cu")
		(net "PHY_SCC_A_TO_DRV_A_23_DP")
	)
	(segment
		(start 299.45584 -318.276732)
		(end 299.28185 -318.549782)
		(width 0.10795)
		(layer "In9.Cu")
		(net "PHY_SCC_A_TO_DRV_A_23_DP")
	)
	(segment
		(start 280.101802 -325.845932)
		(end 280.101802 -325.438008)
		(width 0.10795)
		(layer "In9.Cu")
		(net "PHY_SCC_A_TO_DRV_A_23_DP")
	)
	(segment
		(start 477.619568 -158.774892)
		(end 475.843854 -158.774892)
		(width 0.10795)
		(layer "In9.Cu")
		(net "PHY_SCC_A_TO_DRV_A_23_DP")
	)
	(segment
		(start 299.745146 -318.21247)
		(end 299.45584 -318.276732)
		(width 0.10795)
		(layer "In9.Cu")
		(net "PHY_SCC_A_TO_DRV_A_23_DP")
	)
	(segment
		(start 372.78564 -236.38002)
		(end 319.804034 -270.13408)
		(width 0.10795)
		(layer "In9.Cu")
		(net "PHY_SCC_A_TO_DRV_A_23_DP")
	)
	(segment
		(start 312.142378 -298.752514)
		(end 300.318424 -317.312802)
		(width 0.10795)
		(layer "In9.Cu")
		(net "PHY_SCC_A_TO_DRV_A_23_DP")
	)
	(segment
		(start 319.277492 -270.960596)
		(end 318.738758 -271.806162)
		(width 0.10795)
		(layer "In9.Cu")
		(net "PHY_SCC_A_TO_DRV_A_23_DP")
	)
	(segment
		(start 467.473538 -160.739582)
		(end 462.284318 -164.92982)
		(width 0.10795)
		(layer "In9.Cu")
		(net "PHY_SCC_A_TO_DRV_A_23_DP")
	)
	(segment
		(start 299.172122 -319.112392)
		(end 298.882816 -319.1764)
		(width 0.10795)
		(layer "In9.Cu")
		(net "PHY_SCC_A_TO_DRV_A_23_DP")
	)
	(segment
		(start 318.424306 -272.299176)
		(end 317.78448 -273.303492)
		(width 0.10795)
		(layer "In9.Cu")
		(net "PHY_SCC_A_TO_DRV_A_23_DP")
	)
	(segment
		(start 300.318424 -317.312802)
		(end 300.029118 -317.377064)
		(width 0.10795)
		(layer "In9.Cu")
		(net "PHY_SCC_A_TO_DRV_A_23_DP")
	)
	(segment
		(start 462.284318 -164.92982)
		(end 460.193644 -168.721024)
		(width 0.10795)
		(layer "In9.Cu")
		(net "PHY_SCC_A_TO_DRV_A_23_DP")
	)
	(segment
		(start 280.206196 -326.002904)
		(end 280.138886 -325.935594)
		(width 0.10795)
		(layer "In9.Cu")
		(net "PHY_SCC_A_TO_DRV_A_23_DP")
	)
	(segment
		(start 319.804034 -270.13408)
		(end 319.277492 -270.960596)
		(width 0.10795)
		(layer "In9.Cu")
		(net "PHY_SCC_A_TO_DRV_A_23_DP")
	)
	(segment
		(start 298.708572 -319.449704)
		(end 298.772834 -319.73901)
		(width 0.10795)
		(layer "In9.Cu")
		(net "PHY_SCC_A_TO_DRV_A_23_DP")
	)
	(segment
		(start 318.42456 -272.29943)
		(end 318.424306 -272.299176)
		(width 0.10795)
		(layer "In9.Cu")
		(net "PHY_SCC_A_TO_DRV_A_23_DP")
	)
	(segment
		(start 317.78448 -273.303492)
		(end 312.142378 -298.752514)
		(width 0.10795)
		(layer "In9.Cu")
		(net "PHY_SCC_A_TO_DRV_A_23_DP")
	)
	(segment
		(start 298.882816 -319.1764)
		(end 298.708572 -319.449704)
		(width 0.10795)
		(layer "In9.Cu")
		(net "PHY_SCC_A_TO_DRV_A_23_DP")
	)
	(segment
		(start 298.772834 -319.73901)
		(end 298.598844 -320.01206)
		(width 0.10795)
		(layer "In9.Cu")
		(net "PHY_SCC_A_TO_DRV_A_23_DP")
	)
	(segment
		(start 458.113638 -172.492416)
		(end 452.646288 -194.140328)
		(width 0.10795)
		(layer "In9.Cu")
		(net "PHY_SCC_A_TO_DRV_A_23_DP")
	)
	(segment
		(start 299.28185 -318.549782)
		(end 299.346112 -318.839088)
		(width 0.10795)
		(layer "In9.Cu")
		(net "PHY_SCC_A_TO_DRV_A_23_DP")
	)
	(segment
		(start 288.33953 -326.039988)
		(end 280.295858 -326.039988)
		(width 0.10795)
		(layer "In9.Cu")
		(net "PHY_SCC_A_TO_DRV_A_23_DP")
	)
	(segment
		(start 280.234644 -325.305166)
		(end 280.636726 -325.305166)
		(width 0.10795)
		(layer "In9.Cu")
		(net "PHY_SCC_A_TO_DRV_A_23_DP")
	)
	(segment
		(start 318.738758 -271.806162)
		(end 318.42456 -272.29943)
		(width 0.10795)
		(layer "In9.Cu")
		(net "PHY_SCC_A_TO_DRV_A_23_DP")
	)
	(segment
		(start 300.029118 -317.377064)
		(end 299.855128 -317.650114)
		(width 0.10795)
		(layer "In9.Cu")
		(net "PHY_SCC_A_TO_DRV_A_23_DP")
	)
	(arc
		(start 477.70415 -158.73984)
		(mid 477.665343 -158.76577)
		(end 477.619568 -158.774892)
		(width 0.10795)
		(layer "In9.Cu")
		(net "PHY_SCC_A_TO_DRV_A_23_DP")
	)
	(arc
		(start 280.138886 -325.935594)
		(mid 280.111453 -325.894443)
		(end 280.101802 -325.845932)
		(width 0.10795)
		(layer "In9.Cu")
		(net "PHY_SCC_A_TO_DRV_A_23_DP")
	)
	(arc
		(start 477.739202 -158.655258)
		(mid 477.730095 -158.70104)
		(end 477.70415 -158.73984)
		(width 0.10795)
		(layer "In9.Cu")
		(net "PHY_SCC_A_TO_DRV_A_23_DP")
	)
	(arc
		(start 280.144982 -325.34225)
		(mid 280.186133 -325.314817)
		(end 280.234644 -325.305166)
		(width 0.10795)
		(layer "In9.Cu")
		(net "PHY_SCC_A_TO_DRV_A_23_DP")
	)
	(arc
		(start 280.295858 -326.039988)
		(mid 280.24734 -326.030355)
		(end 280.206196 -326.002904)
		(width 0.10795)
		(layer "In9.Cu")
		(net "PHY_SCC_A_TO_DRV_A_23_DP")
	)
	(arc
		(start 280.101802 -325.438008)
		(mid 280.111435 -325.38949)
		(end 280.138886 -325.348346)
		(width 0.10795)
		(layer "In9.Cu")
		(net "PHY_SCC_A_TO_DRV_A_23_DP")
	)
	(segment
		(start 477.739202 -159.511492)
		(end 477.739202 -159.222948)
		(width 0.127)
		(layer "F.Cu")
		(net "PHY_SCC_A_TO_DRV_A_23_DN")
	)
	(segment
		(start 477.876108 -159.086042)
		(end 478.640648 -159.086042)
		(width 0.127)
		(layer "F.Cu")
		(net "PHY_SCC_A_TO_DRV_A_23_DN")
	)
	(segment
		(start 478.640648 -159.086042)
		(end 478.773998 -159.219392)
		(width 0.127)
		(layer "F.Cu")
		(net "PHY_SCC_A_TO_DRV_A_23_DN")
	)
	(segment
		(start 478.773998 -159.219392)
		(end 479.105214 -159.219392)
		(width 0.127)
		(layer "F.Cu")
		(net "PHY_SCC_A_TO_DRV_A_23_DN")
	)
	(segment
		(start 477.776286 -159.133286)
		(end 477.786446 -159.123126)
		(width 0.127)
		(layer "F.Cu")
		(net "PHY_SCC_A_TO_DRV_A_23_DN")
	)
	(arc
		(start 477.739202 -159.222948)
		(mid 477.748835 -159.17443)
		(end 477.776286 -159.133286)
		(width 0.127)
		(layer "F.Cu")
		(net "PHY_SCC_A_TO_DRV_A_23_DN")
	)
	(arc
		(start 477.786446 -159.123126)
		(mid 477.827597 -159.095693)
		(end 477.876108 -159.086042)
		(width 0.127)
		(layer "F.Cu")
		(net "PHY_SCC_A_TO_DRV_A_23_DN")
	)
	(segment
		(start 298.838112 -320.251328)
		(end 289.69208 -326.07758)
		(width 0.10795)
		(layer "In9.Cu")
		(net "PHY_SCC_A_TO_DRV_A_23_DN")
	)
	(segment
		(start 279.734518 -325.348346)
		(end 279.728422 -325.34225)
		(width 0.10795)
		(layer "In9.Cu")
		(net "PHY_SCC_A_TO_DRV_A_23_DN")
	)
	(segment
		(start 288.375852 -326.370188)
		(end 280.295858 -326.370188)
		(width 0.10795)
		(layer "In9.Cu")
		(net "PHY_SCC_A_TO_DRV_A_23_DN")
	)
	(segment
		(start 452.955152 -194.266312)
		(end 438.031382 -219.88018)
		(width 0.10795)
		(layer "In9.Cu")
		(net "PHY_SCC_A_TO_DRV_A_23_DN")
	)
	(segment
		(start 436.414926 -220.92412)
		(end 434.027072 -222.466154)
		(width 0.10795)
		(layer "In9.Cu")
		(net "PHY_SCC_A_TO_DRV_A_23_DN")
	)
	(segment
		(start 429.970692 -225.085402)
		(end 372.911624 -236.691678)
		(width 0.10795)
		(layer "In9.Cu")
		(net "PHY_SCC_A_TO_DRV_A_23_DN")
	)
	(segment
		(start 438.031382 -219.88018)
		(end 436.414926 -220.92412)
		(width 0.10795)
		(layer "In9.Cu")
		(net "PHY_SCC_A_TO_DRV_A_23_DN")
	)
	(segment
		(start 279.771602 -325.845932)
		(end 279.771602 -325.438008)
		(width 0.10795)
		(layer "In9.Cu")
		(net "PHY_SCC_A_TO_DRV_A_23_DN")
	)
	(segment
		(start 475.882208 -159.105092)
		(end 467.622382 -161.043874)
		(width 0.10795)
		(layer "In9.Cu")
		(net "PHY_SCC_A_TO_DRV_A_23_DN")
	)
	(segment
		(start 320.043302 -270.373348)
		(end 319.068958 -271.902428)
		(width 0.10795)
		(layer "In9.Cu")
		(net "PHY_SCC_A_TO_DRV_A_23_DN")
	)
	(segment
		(start 279.63876 -325.305166)
		(end 279.236678 -325.305166)
		(width 0.10795)
		(layer "In9.Cu")
		(net "PHY_SCC_A_TO_DRV_A_23_DN")
	)
	(segment
		(start 458.423518 -172.61459)
		(end 452.955152 -194.266312)
		(width 0.10795)
		(layer "In9.Cu")
		(net "PHY_SCC_A_TO_DRV_A_23_DN")
	)
	(segment
		(start 318.09436 -273.432016)
		(end 318.09436 -273.431762)
		(width 0.10795)
		(layer "In9.Cu")
		(net "PHY_SCC_A_TO_DRV_A_23_DN")
	)
	(segment
		(start 312.452258 -298.880784)
		(end 298.838112 -320.251328)
		(width 0.10795)
		(layer "In9.Cu")
		(net "PHY_SCC_A_TO_DRV_A_23_DN")
	)
	(segment
		(start 318.09436 -273.431762)
		(end 318.094106 -273.433032)
		(width 0.10795)
		(layer "In9.Cu")
		(net "PHY_SCC_A_TO_DRV_A_23_DN")
	)
	(segment
		(start 289.69208 -326.07758)
		(end 288.375852 -326.370188)
		(width 0.10795)
		(layer "In9.Cu")
		(net "PHY_SCC_A_TO_DRV_A_23_DN")
	)
	(segment
		(start 318.094106 -273.433032)
		(end 312.452258 -298.880784)
		(width 0.10795)
		(layer "In9.Cu")
		(net "PHY_SCC_A_TO_DRV_A_23_DN")
	)
	(segment
		(start 467.622382 -161.043874)
		(end 462.542382 -165.146228)
		(width 0.10795)
		(layer "In9.Cu")
		(net "PHY_SCC_A_TO_DRV_A_23_DN")
	)
	(segment
		(start 279.97277 -326.236584)
		(end 279.905206 -326.16902)
		(width 0.10795)
		(layer "In9.Cu")
		(net "PHY_SCC_A_TO_DRV_A_23_DN")
	)
	(segment
		(start 346.477082 -253.53264)
		(end 320.043302 -270.373348)
		(width 0.10795)
		(layer "In9.Cu")
		(net "PHY_SCC_A_TO_DRV_A_23_DN")
	)
	(segment
		(start 477.739202 -159.511492)
		(end 477.739202 -159.224726)
		(width 0.10795)
		(layer "In9.Cu")
		(net "PHY_SCC_A_TO_DRV_A_23_DN")
	)
	(segment
		(start 319.068958 -271.902428)
		(end 319.068958 -271.902682)
		(width 0.10795)
		(layer "In9.Cu")
		(net "PHY_SCC_A_TO_DRV_A_23_DN")
	)
	(segment
		(start 372.911624 -236.691678)
		(end 346.477082 -253.53264)
		(width 0.10795)
		(layer "In9.Cu")
		(net "PHY_SCC_A_TO_DRV_A_23_DN")
	)
	(segment
		(start 319.068958 -271.902682)
		(end 318.09436 -273.432016)
		(width 0.10795)
		(layer "In9.Cu")
		(net "PHY_SCC_A_TO_DRV_A_23_DN")
	)
	(segment
		(start 462.542382 -165.146228)
		(end 458.423518 -172.61459)
		(width 0.10795)
		(layer "In9.Cu")
		(net "PHY_SCC_A_TO_DRV_A_23_DN")
	)
	(segment
		(start 477.619568 -159.105092)
		(end 475.882208 -159.105092)
		(width 0.10795)
		(layer "In9.Cu")
		(net "PHY_SCC_A_TO_DRV_A_23_DN")
	)
	(segment
		(start 434.027072 -222.466154)
		(end 429.970692 -225.085402)
		(width 0.10795)
		(layer "In9.Cu")
		(net "PHY_SCC_A_TO_DRV_A_23_DN")
	)
	(arc
		(start 477.70415 -159.140144)
		(mid 477.665343 -159.114214)
		(end 477.619568 -159.105092)
		(width 0.10795)
		(layer "In9.Cu")
		(net "PHY_SCC_A_TO_DRV_A_23_DN")
	)
	(arc
		(start 279.728422 -325.34225)
		(mid 279.687271 -325.314817)
		(end 279.63876 -325.305166)
		(width 0.10795)
		(layer "In9.Cu")
		(net "PHY_SCC_A_TO_DRV_A_23_DN")
	)
	(arc
		(start 279.905206 -326.16902)
		(mid 279.80632 -326.020743)
		(end 279.771602 -325.845932)
		(width 0.10795)
		(layer "In9.Cu")
		(net "PHY_SCC_A_TO_DRV_A_23_DN")
	)
	(arc
		(start 279.771602 -325.438008)
		(mid 279.761969 -325.38949)
		(end 279.734518 -325.348346)
		(width 0.10795)
		(layer "In9.Cu")
		(net "PHY_SCC_A_TO_DRV_A_23_DN")
	)
	(arc
		(start 280.295858 -326.370188)
		(mid 280.121047 -326.335469)
		(end 279.97277 -326.236584)
		(width 0.10795)
		(layer "In9.Cu")
		(net "PHY_SCC_A_TO_DRV_A_23_DN")
	)
	(arc
		(start 477.739202 -159.224726)
		(mid 477.730095 -159.178944)
		(end 477.70415 -159.140144)
		(width 0.10795)
		(layer "In9.Cu")
		(net "PHY_SCC_A_TO_DRV_A_23_DN")
	)
	(segment
		(start 440.873896 -158.660592)
		(end 440.740546 -158.793942)
		(width 0.127)
		(layer "F.Cu")
		(net "PHY_SCC_A_TO_DRV_A_22_DP")
	)
	(segment
		(start 441.205112 -158.660592)
		(end 440.873896 -158.660592)
		(width 0.127)
		(layer "F.Cu")
		(net "PHY_SCC_A_TO_DRV_A_22_DP")
	)
	(segment
		(start 440.740546 -158.793942)
		(end 439.979816 -158.793942)
		(width 0.127)
		(layer "F.Cu")
		(net "PHY_SCC_A_TO_DRV_A_22_DP")
	)
	(segment
		(start 439.890154 -158.756858)
		(end 439.876184 -158.742888)
		(width 0.127)
		(layer "F.Cu")
		(net "PHY_SCC_A_TO_DRV_A_22_DP")
	)
	(segment
		(start 439.8391 -158.653226)
		(end 439.8391 -158.368492)
		(width 0.127)
		(layer "F.Cu")
		(net "PHY_SCC_A_TO_DRV_A_22_DP")
	)
	(arc
		(start 439.876184 -158.742888)
		(mid 439.848751 -158.701737)
		(end 439.8391 -158.653226)
		(width 0.127)
		(layer "F.Cu")
		(net "PHY_SCC_A_TO_DRV_A_22_DP")
	)
	(arc
		(start 439.979816 -158.793942)
		(mid 439.931298 -158.784309)
		(end 439.890154 -158.756858)
		(width 0.127)
		(layer "F.Cu")
		(net "PHY_SCC_A_TO_DRV_A_22_DP")
	)
	(segment
		(start 297.689016 -317.504572)
		(end 297.753024 -317.793878)
		(width 0.10795)
		(layer "In9.Cu")
		(net "PHY_SCC_A_TO_DRV_A_22_DP")
	)
	(segment
		(start 393.694412 -185.843926)
		(end 355.456236 -210.20405)
		(width 0.10795)
		(layer "In9.Cu")
		(net "PHY_SCC_A_TO_DRV_A_22_DP")
	)
	(segment
		(start 309.924704 -298.685966)
		(end 298.725336 -316.267592)
		(width 0.10795)
		(layer "In9.Cu")
		(net "PHY_SCC_A_TO_DRV_A_22_DP")
	)
	(segment
		(start 335.576418 -241.409728)
		(end 315.704474 -272.602706)
		(width 0.10795)
		(layer "In9.Cu")
		(net "PHY_SCC_A_TO_DRV_A_22_DP")
	)
	(segment
		(start 297.863006 -317.231522)
		(end 297.689016 -317.504572)
		(width 0.10795)
		(layer "In9.Cu")
		(net "PHY_SCC_A_TO_DRV_A_22_DP")
	)
	(segment
		(start 298.326302 -316.89421)
		(end 298.152312 -317.16726)
		(width 0.10795)
		(layer "In9.Cu")
		(net "PHY_SCC_A_TO_DRV_A_22_DP")
	)
	(segment
		(start 297.579034 -318.067182)
		(end 297.289728 -318.13119)
		(width 0.10795)
		(layer "In9.Cu")
		(net "PHY_SCC_A_TO_DRV_A_22_DP")
	)
	(segment
		(start 279.101804 -324.075552)
		(end 279.101804 -323.642228)
		(width 0.10795)
		(layer "In9.Cu")
		(net "PHY_SCC_A_TO_DRV_A_22_DP")
	)
	(segment
		(start 288.645346 -324.177152)
		(end 288.363914 -324.239636)
		(width 0.10795)
		(layer "In9.Cu")
		(net "PHY_SCC_A_TO_DRV_A_22_DP")
	)
	(segment
		(start 403.163024 -179.811934)
		(end 393.694412 -185.843926)
		(width 0.10795)
		(layer "In9.Cu")
		(net "PHY_SCC_A_TO_DRV_A_22_DP")
	)
	(segment
		(start 298.152312 -317.16726)
		(end 297.863006 -317.231522)
		(width 0.10795)
		(layer "In9.Cu")
		(net "PHY_SCC_A_TO_DRV_A_22_DP")
	)
	(segment
		(start 315.704474 -272.602706)
		(end 309.924704 -298.685966)
		(width 0.10795)
		(layer "In9.Cu")
		(net "PHY_SCC_A_TO_DRV_A_22_DP")
	)
	(segment
		(start 297.00601 -318.96685)
		(end 288.926778 -324.114922)
		(width 0.10795)
		(layer "In9.Cu")
		(net "PHY_SCC_A_TO_DRV_A_22_DP")
	)
	(segment
		(start 403.163278 -179.811934)
		(end 403.163024 -179.811934)
		(width 0.10795)
		(layer "In9.Cu")
		(net "PHY_SCC_A_TO_DRV_A_22_DP")
	)
	(segment
		(start 279.238964 -323.505068)
		(end 279.636728 -323.505068)
		(width 0.10795)
		(layer "In9.Cu")
		(net "PHY_SCC_A_TO_DRV_A_22_DP")
	)
	(segment
		(start 297.289728 -318.13119)
		(end 297.115738 -318.404494)
		(width 0.10795)
		(layer "In9.Cu")
		(net "PHY_SCC_A_TO_DRV_A_22_DP")
	)
	(segment
		(start 279.138888 -323.552566)
		(end 279.149302 -323.542152)
		(width 0.10795)
		(layer "In9.Cu")
		(net "PHY_SCC_A_TO_DRV_A_22_DP")
	)
	(segment
		(start 297.753024 -317.793878)
		(end 297.579034 -318.067182)
		(width 0.10795)
		(layer "In9.Cu")
		(net "PHY_SCC_A_TO_DRV_A_22_DP")
	)
	(segment
		(start 297.18 -318.6938)
		(end 297.00601 -318.96685)
		(width 0.10795)
		(layer "In9.Cu")
		(net "PHY_SCC_A_TO_DRV_A_22_DP")
	)
	(segment
		(start 431.616866 -161.68497)
		(end 403.163278 -179.811934)
		(width 0.10795)
		(layer "In9.Cu")
		(net "PHY_SCC_A_TO_DRV_A_22_DP")
	)
	(segment
		(start 297.115738 -318.404494)
		(end 297.18 -318.6938)
		(width 0.10795)
		(layer "In9.Cu")
		(net "PHY_SCC_A_TO_DRV_A_22_DP")
	)
	(segment
		(start 438.348882 -158.774892)
		(end 431.616866 -161.68497)
		(width 0.10795)
		(layer "In9.Cu")
		(net "PHY_SCC_A_TO_DRV_A_22_DP")
	)
	(segment
		(start 439.719466 -158.774892)
		(end 438.348882 -158.774892)
		(width 0.10795)
		(layer "In9.Cu")
		(net "PHY_SCC_A_TO_DRV_A_22_DP")
	)
	(segment
		(start 439.8391 -158.368492)
		(end 439.8391 -158.655258)
		(width 0.10795)
		(layer "In9.Cu")
		(net "PHY_SCC_A_TO_DRV_A_22_DP")
	)
	(segment
		(start 298.26204 -316.604904)
		(end 298.326302 -316.89421)
		(width 0.10795)
		(layer "In9.Cu")
		(net "PHY_SCC_A_TO_DRV_A_22_DP")
	)
	(segment
		(start 298.43603 -316.3316)
		(end 298.26204 -316.604904)
		(width 0.10795)
		(layer "In9.Cu")
		(net "PHY_SCC_A_TO_DRV_A_22_DP")
	)
	(segment
		(start 279.17648 -324.202806)
		(end 279.138888 -324.165214)
		(width 0.10795)
		(layer "In9.Cu")
		(net "PHY_SCC_A_TO_DRV_A_22_DP")
	)
	(segment
		(start 355.456236 -210.20405)
		(end 335.576418 -241.409728)
		(width 0.10795)
		(layer "In9.Cu")
		(net "PHY_SCC_A_TO_DRV_A_22_DP")
	)
	(segment
		(start 288.926778 -324.114922)
		(end 288.645346 -324.177152)
		(width 0.10795)
		(layer "In9.Cu")
		(net "PHY_SCC_A_TO_DRV_A_22_DP")
	)
	(segment
		(start 288.363914 -324.239636)
		(end 288.363914 -324.23989)
		(width 0.10795)
		(layer "In9.Cu")
		(net "PHY_SCC_A_TO_DRV_A_22_DP")
	)
	(segment
		(start 298.725336 -316.267592)
		(end 298.43603 -316.3316)
		(width 0.10795)
		(layer "In9.Cu")
		(net "PHY_SCC_A_TO_DRV_A_22_DP")
	)
	(segment
		(start 288.363914 -324.23989)
		(end 279.266142 -324.23989)
		(width 0.10795)
		(layer "In9.Cu")
		(net "PHY_SCC_A_TO_DRV_A_22_DP")
	)
	(arc
		(start 439.8391 -158.655258)
		(mid 439.829993 -158.70104)
		(end 439.804048 -158.73984)
		(width 0.10795)
		(layer "In9.Cu")
		(net "PHY_SCC_A_TO_DRV_A_22_DP")
	)
	(arc
		(start 279.101804 -323.642228)
		(mid 279.111437 -323.59371)
		(end 279.138888 -323.552566)
		(width 0.10795)
		(layer "In9.Cu")
		(net "PHY_SCC_A_TO_DRV_A_22_DP")
	)
	(arc
		(start 279.266142 -324.23989)
		(mid 279.217624 -324.230257)
		(end 279.17648 -324.202806)
		(width 0.10795)
		(layer "In9.Cu")
		(net "PHY_SCC_A_TO_DRV_A_22_DP")
	)
	(arc
		(start 279.149302 -323.542152)
		(mid 279.190453 -323.514719)
		(end 279.238964 -323.505068)
		(width 0.10795)
		(layer "In9.Cu")
		(net "PHY_SCC_A_TO_DRV_A_22_DP")
	)
	(arc
		(start 279.138888 -324.165214)
		(mid 279.111455 -324.124063)
		(end 279.101804 -324.075552)
		(width 0.10795)
		(layer "In9.Cu")
		(net "PHY_SCC_A_TO_DRV_A_22_DP")
	)
	(arc
		(start 439.804048 -158.73984)
		(mid 439.765241 -158.76577)
		(end 439.719466 -158.774892)
		(width 0.10795)
		(layer "In9.Cu")
		(net "PHY_SCC_A_TO_DRV_A_22_DP")
	)
	(segment
		(start 441.205112 -159.219392)
		(end 440.873896 -159.219392)
		(width 0.127)
		(layer "F.Cu")
		(net "PHY_SCC_A_TO_DRV_A_22_DN")
	)
	(segment
		(start 439.8391 -159.236918)
		(end 439.8391 -159.511492)
		(width 0.127)
		(layer "F.Cu")
		(net "PHY_SCC_A_TO_DRV_A_22_DN")
	)
	(segment
		(start 439.900314 -159.123126)
		(end 439.876184 -159.147256)
		(width 0.127)
		(layer "F.Cu")
		(net "PHY_SCC_A_TO_DRV_A_22_DN")
	)
	(segment
		(start 440.740546 -159.086042)
		(end 439.989976 -159.086042)
		(width 0.127)
		(layer "F.Cu")
		(net "PHY_SCC_A_TO_DRV_A_22_DN")
	)
	(segment
		(start 440.873896 -159.219392)
		(end 440.740546 -159.086042)
		(width 0.127)
		(layer "F.Cu")
		(net "PHY_SCC_A_TO_DRV_A_22_DN")
	)
	(arc
		(start 439.989976 -159.086042)
		(mid 439.941458 -159.095675)
		(end 439.900314 -159.123126)
		(width 0.127)
		(layer "F.Cu")
		(net "PHY_SCC_A_TO_DRV_A_22_DN")
	)
	(arc
		(start 439.876184 -159.147256)
		(mid 439.848751 -159.188407)
		(end 439.8391 -159.236918)
		(width 0.127)
		(layer "F.Cu")
		(net "PHY_SCC_A_TO_DRV_A_22_DN")
	)
	(segment
		(start 439.719466 -159.105092)
		(end 438.417208 -159.105092)
		(width 0.10795)
		(layer "In9.Cu")
		(net "PHY_SCC_A_TO_DRV_A_22_DN")
	)
	(segment
		(start 278.771604 -324.075552)
		(end 278.771604 -323.642228)
		(width 0.10795)
		(layer "In9.Cu")
		(net "PHY_SCC_A_TO_DRV_A_22_DN")
	)
	(segment
		(start 278.943054 -324.436486)
		(end 278.905208 -324.39864)
		(width 0.10795)
		(layer "In9.Cu")
		(net "PHY_SCC_A_TO_DRV_A_22_DN")
	)
	(segment
		(start 288.400236 -324.57009)
		(end 279.266142 -324.57009)
		(width 0.10795)
		(layer "In9.Cu")
		(net "PHY_SCC_A_TO_DRV_A_22_DN")
	)
	(segment
		(start 431.772314 -161.977832)
		(end 355.695504 -210.443318)
		(width 0.10795)
		(layer "In9.Cu")
		(net "PHY_SCC_A_TO_DRV_A_22_DN")
	)
	(segment
		(start 278.634444 -323.505068)
		(end 278.23668 -323.505068)
		(width 0.10795)
		(layer "In9.Cu")
		(net "PHY_SCC_A_TO_DRV_A_22_DN")
	)
	(segment
		(start 438.417208 -159.105092)
		(end 431.772314 -161.977832)
		(width 0.10795)
		(layer "In9.Cu")
		(net "PHY_SCC_A_TO_DRV_A_22_DN")
	)
	(segment
		(start 355.695504 -210.443318)
		(end 316.014354 -272.730976)
		(width 0.10795)
		(layer "In9.Cu")
		(net "PHY_SCC_A_TO_DRV_A_22_DN")
	)
	(segment
		(start 310.234584 -298.814236)
		(end 297.245278 -319.206118)
		(width 0.10795)
		(layer "In9.Cu")
		(net "PHY_SCC_A_TO_DRV_A_22_DN")
	)
	(segment
		(start 439.8391 -159.511492)
		(end 439.8391 -159.224726)
		(width 0.10795)
		(layer "In9.Cu")
		(net "PHY_SCC_A_TO_DRV_A_22_DN")
	)
	(segment
		(start 278.73452 -323.552566)
		(end 278.724106 -323.542152)
		(width 0.10795)
		(layer "In9.Cu")
		(net "PHY_SCC_A_TO_DRV_A_22_DN")
	)
	(segment
		(start 316.014354 -272.730976)
		(end 310.234584 -298.814236)
		(width 0.10795)
		(layer "In9.Cu")
		(net "PHY_SCC_A_TO_DRV_A_22_DN")
	)
	(segment
		(start 289.055048 -324.424802)
		(end 288.400236 -324.57009)
		(width 0.10795)
		(layer "In9.Cu")
		(net "PHY_SCC_A_TO_DRV_A_22_DN")
	)
	(segment
		(start 297.245278 -319.206118)
		(end 289.055048 -324.424802)
		(width 0.10795)
		(layer "In9.Cu")
		(net "PHY_SCC_A_TO_DRV_A_22_DN")
	)
	(arc
		(start 278.724106 -323.542152)
		(mid 278.682955 -323.514719)
		(end 278.634444 -323.505068)
		(width 0.10795)
		(layer "In9.Cu")
		(net "PHY_SCC_A_TO_DRV_A_22_DN")
	)
	(arc
		(start 278.905208 -324.39864)
		(mid 278.806322 -324.250363)
		(end 278.771604 -324.075552)
		(width 0.10795)
		(layer "In9.Cu")
		(net "PHY_SCC_A_TO_DRV_A_22_DN")
	)
	(arc
		(start 439.8391 -159.224726)
		(mid 439.829993 -159.178944)
		(end 439.804048 -159.140144)
		(width 0.10795)
		(layer "In9.Cu")
		(net "PHY_SCC_A_TO_DRV_A_22_DN")
	)
	(arc
		(start 439.804048 -159.140144)
		(mid 439.765241 -159.114214)
		(end 439.719466 -159.105092)
		(width 0.10795)
		(layer "In9.Cu")
		(net "PHY_SCC_A_TO_DRV_A_22_DN")
	)
	(arc
		(start 279.266142 -324.57009)
		(mid 279.091331 -324.535371)
		(end 278.943054 -324.436486)
		(width 0.10795)
		(layer "In9.Cu")
		(net "PHY_SCC_A_TO_DRV_A_22_DN")
	)
	(arc
		(start 278.771604 -323.642228)
		(mid 278.761971 -323.59371)
		(end 278.73452 -323.552566)
		(width 0.10795)
		(layer "In9.Cu")
		(net "PHY_SCC_A_TO_DRV_A_22_DN")
	)
	(segment
		(start 414.774634 -158.793942)
		(end 415.540698 -158.793942)
		(width 0.127)
		(layer "F.Cu")
		(net "PHY_SCC_A_TO_DRV_A_21_DP")
	)
	(segment
		(start 415.674048 -158.660592)
		(end 416.005264 -158.660592)
		(width 0.127)
		(layer "F.Cu")
		(net "PHY_SCC_A_TO_DRV_A_21_DP")
	)
	(segment
		(start 414.639252 -158.368492)
		(end 414.639252 -158.65856)
		(width 0.127)
		(layer "F.Cu")
		(net "PHY_SCC_A_TO_DRV_A_21_DP")
	)
	(segment
		(start 415.540698 -158.793942)
		(end 415.674048 -158.660592)
		(width 0.127)
		(layer "F.Cu")
		(net "PHY_SCC_A_TO_DRV_A_21_DP")
	)
	(segment
		(start 414.676336 -158.748222)
		(end 414.684972 -158.756858)
		(width 0.127)
		(layer "F.Cu")
		(net "PHY_SCC_A_TO_DRV_A_21_DP")
	)
	(arc
		(start 414.684972 -158.756858)
		(mid 414.726123 -158.784291)
		(end 414.774634 -158.793942)
		(width 0.127)
		(layer "F.Cu")
		(net "PHY_SCC_A_TO_DRV_A_21_DP")
	)
	(arc
		(start 414.639252 -158.65856)
		(mid 414.648885 -158.707078)
		(end 414.676336 -158.748222)
		(width 0.127)
		(layer "F.Cu")
		(net "PHY_SCC_A_TO_DRV_A_21_DP")
	)
	(segment
		(start 295.59504 -318.146684)
		(end 295.76903 -317.873634)
		(width 0.10795)
		(layer "In9.Cu")
		(net "PHY_SCC_A_TO_DRV_A_21_DP")
	)
	(segment
		(start 371.93601 -181.582314)
		(end 405.418798 -160.25114)
		(width 0.10795)
		(layer "In9.Cu")
		(net "PHY_SCC_A_TO_DRV_A_21_DP")
	)
	(segment
		(start 296.452036 -316.411356)
		(end 296.741342 -316.347348)
		(width 0.10795)
		(layer "In9.Cu")
		(net "PHY_SCC_A_TO_DRV_A_21_DP")
	)
	(segment
		(start 296.741342 -316.347348)
		(end 296.915586 -316.074044)
		(width 0.10795)
		(layer "In9.Cu")
		(net "PHY_SCC_A_TO_DRV_A_21_DP")
	)
	(segment
		(start 295.76903 -317.873634)
		(end 295.705022 -317.584328)
		(width 0.10795)
		(layer "In9.Cu")
		(net "PHY_SCC_A_TO_DRV_A_21_DP")
	)
	(segment
		(start 280.144982 -321.742308)
		(end 280.138886 -321.748404)
		(width 0.10795)
		(layer "In9.Cu")
		(net "PHY_SCC_A_TO_DRV_A_21_DP")
	)
	(segment
		(start 280.636726 -321.705224)
		(end 280.234644 -321.705224)
		(width 0.10795)
		(layer "In9.Cu")
		(net "PHY_SCC_A_TO_DRV_A_21_DP")
	)
	(segment
		(start 295.705022 -317.584328)
		(end 295.879012 -317.311024)
		(width 0.10795)
		(layer "In9.Cu")
		(net "PHY_SCC_A_TO_DRV_A_21_DP")
	)
	(segment
		(start 313.826398 -274.774152)
		(end 314.523374 -271.631664)
		(width 0.10795)
		(layer "In9.Cu")
		(net "PHY_SCC_A_TO_DRV_A_21_DP")
	)
	(segment
		(start 280.138886 -322.335652)
		(end 280.206196 -322.402962)
		(width 0.10795)
		(layer "In9.Cu")
		(net "PHY_SCC_A_TO_DRV_A_21_DP")
	)
	(segment
		(start 412.076392 -158.774892)
		(end 414.519618 -158.774892)
		(width 0.10795)
		(layer "In9.Cu")
		(net "PHY_SCC_A_TO_DRV_A_21_DP")
	)
	(segment
		(start 280.101802 -321.838066)
		(end 280.101802 -322.24599)
		(width 0.10795)
		(layer "In9.Cu")
		(net "PHY_SCC_A_TO_DRV_A_21_DP")
	)
	(segment
		(start 296.851324 -315.784738)
		(end 297.025314 -315.511688)
		(width 0.10795)
		(layer "In9.Cu")
		(net "PHY_SCC_A_TO_DRV_A_21_DP")
	)
	(segment
		(start 414.639252 -158.655258)
		(end 414.639252 -158.368492)
		(width 0.10795)
		(layer "In9.Cu")
		(net "PHY_SCC_A_TO_DRV_A_21_DP")
	)
	(segment
		(start 314.523374 -271.631664)
		(end 371.93601 -181.582314)
		(width 0.10795)
		(layer "In9.Cu")
		(net "PHY_SCC_A_TO_DRV_A_21_DP")
	)
	(segment
		(start 296.168318 -317.247016)
		(end 296.342308 -316.973712)
		(width 0.10795)
		(layer "In9.Cu")
		(net "PHY_SCC_A_TO_DRV_A_21_DP")
	)
	(segment
		(start 405.418798 -160.25114)
		(end 412.076392 -158.774892)
		(width 0.10795)
		(layer "In9.Cu")
		(net "PHY_SCC_A_TO_DRV_A_21_DP")
	)
	(segment
		(start 295.879012 -317.311024)
		(end 296.168318 -317.247016)
		(width 0.10795)
		(layer "In9.Cu")
		(net "PHY_SCC_A_TO_DRV_A_21_DP")
	)
	(segment
		(start 289.185604 -322.230242)
		(end 295.59504 -318.146684)
		(width 0.10795)
		(layer "In9.Cu")
		(net "PHY_SCC_A_TO_DRV_A_21_DP")
	)
	(segment
		(start 297.31462 -315.447426)
		(end 308.808374 -297.407076)
		(width 0.10795)
		(layer "In9.Cu")
		(net "PHY_SCC_A_TO_DRV_A_21_DP")
	)
	(segment
		(start 308.808374 -297.407076)
		(end 313.826398 -274.774152)
		(width 0.10795)
		(layer "In9.Cu")
		(net "PHY_SCC_A_TO_DRV_A_21_DP")
	)
	(segment
		(start 296.342308 -316.973712)
		(end 296.278046 -316.684406)
		(width 0.10795)
		(layer "In9.Cu")
		(net "PHY_SCC_A_TO_DRV_A_21_DP")
	)
	(segment
		(start 296.915586 -316.074044)
		(end 296.851324 -315.784738)
		(width 0.10795)
		(layer "In9.Cu")
		(net "PHY_SCC_A_TO_DRV_A_21_DP")
	)
	(segment
		(start 288.238946 -322.440046)
		(end 289.185604 -322.230242)
		(width 0.10795)
		(layer "In9.Cu")
		(net "PHY_SCC_A_TO_DRV_A_21_DP")
	)
	(segment
		(start 296.278046 -316.684406)
		(end 296.452036 -316.411356)
		(width 0.10795)
		(layer "In9.Cu")
		(net "PHY_SCC_A_TO_DRV_A_21_DP")
	)
	(segment
		(start 280.295858 -322.440046)
		(end 288.238946 -322.440046)
		(width 0.10795)
		(layer "In9.Cu")
		(net "PHY_SCC_A_TO_DRV_A_21_DP")
	)
	(segment
		(start 297.025314 -315.511688)
		(end 297.31462 -315.447426)
		(width 0.10795)
		(layer "In9.Cu")
		(net "PHY_SCC_A_TO_DRV_A_21_DP")
	)
	(arc
		(start 280.101802 -322.24599)
		(mid 280.111435 -322.294508)
		(end 280.138886 -322.335652)
		(width 0.10795)
		(layer "In9.Cu")
		(net "PHY_SCC_A_TO_DRV_A_21_DP")
	)
	(arc
		(start 414.6042 -158.73984)
		(mid 414.63013 -158.701033)
		(end 414.639252 -158.655258)
		(width 0.10795)
		(layer "In9.Cu")
		(net "PHY_SCC_A_TO_DRV_A_21_DP")
	)
	(arc
		(start 280.138886 -321.748404)
		(mid 280.111453 -321.789555)
		(end 280.101802 -321.838066)
		(width 0.10795)
		(layer "In9.Cu")
		(net "PHY_SCC_A_TO_DRV_A_21_DP")
	)
	(arc
		(start 280.206196 -322.402962)
		(mid 280.247347 -322.430395)
		(end 280.295858 -322.440046)
		(width 0.10795)
		(layer "In9.Cu")
		(net "PHY_SCC_A_TO_DRV_A_21_DP")
	)
	(arc
		(start 280.234644 -321.705224)
		(mid 280.186126 -321.714857)
		(end 280.144982 -321.742308)
		(width 0.10795)
		(layer "In9.Cu")
		(net "PHY_SCC_A_TO_DRV_A_21_DP")
	)
	(arc
		(start 414.519618 -158.774892)
		(mid 414.5654 -158.765785)
		(end 414.6042 -158.73984)
		(width 0.10795)
		(layer "In9.Cu")
		(net "PHY_SCC_A_TO_DRV_A_21_DP")
	)
	(segment
		(start 414.792414 -159.086042)
		(end 415.540698 -159.086042)
		(width 0.127)
		(layer "F.Cu")
		(net "PHY_SCC_A_TO_DRV_A_21_DN")
	)
	(segment
		(start 414.639252 -159.511492)
		(end 414.639252 -159.239204)
		(width 0.127)
		(layer "F.Cu")
		(net "PHY_SCC_A_TO_DRV_A_21_DN")
	)
	(segment
		(start 415.674048 -159.219392)
		(end 416.005264 -159.219392)
		(width 0.127)
		(layer "F.Cu")
		(net "PHY_SCC_A_TO_DRV_A_21_DN")
	)
	(segment
		(start 415.540698 -159.086042)
		(end 415.674048 -159.219392)
		(width 0.127)
		(layer "F.Cu")
		(net "PHY_SCC_A_TO_DRV_A_21_DN")
	)
	(segment
		(start 414.676336 -159.149542)
		(end 414.702752 -159.123126)
		(width 0.127)
		(layer "F.Cu")
		(net "PHY_SCC_A_TO_DRV_A_21_DN")
	)
	(arc
		(start 414.639252 -159.239204)
		(mid 414.648885 -159.190686)
		(end 414.676336 -159.149542)
		(width 0.127)
		(layer "F.Cu")
		(net "PHY_SCC_A_TO_DRV_A_21_DN")
	)
	(arc
		(start 414.702752 -159.123126)
		(mid 414.743903 -159.095693)
		(end 414.792414 -159.086042)
		(width 0.127)
		(layer "F.Cu")
		(net "PHY_SCC_A_TO_DRV_A_21_DN")
	)
	(segment
		(start 279.236678 -321.705224)
		(end 279.63876 -321.705224)
		(width 0.10795)
		(layer "In9.Cu")
		(net "PHY_SCC_A_TO_DRV_A_21_DN")
	)
	(segment
		(start 279.728422 -321.742308)
		(end 279.734518 -321.748404)
		(width 0.10795)
		(layer "In9.Cu")
		(net "PHY_SCC_A_TO_DRV_A_21_DN")
	)
	(segment
		(start 314.148978 -274.846034)
		(end 314.254134 -274.371816)
		(width 0.10795)
		(layer "In9.Cu")
		(net "PHY_SCC_A_TO_DRV_A_21_DN")
	)
	(segment
		(start 279.905206 -322.569078)
		(end 279.97277 -322.636642)
		(width 0.10795)
		(layer "In9.Cu")
		(net "PHY_SCC_A_TO_DRV_A_21_DN")
	)
	(segment
		(start 314.254134 -274.371816)
		(end 314.49137 -273.302984)
		(width 0.10795)
		(layer "In9.Cu")
		(net "PHY_SCC_A_TO_DRV_A_21_DN")
	)
	(segment
		(start 309.118254 -297.535346)
		(end 314.148978 -274.846034)
		(width 0.10795)
		(layer "In9.Cu")
		(net "PHY_SCC_A_TO_DRV_A_21_DN")
	)
	(segment
		(start 314.833254 -271.759934)
		(end 372.175278 -181.821582)
		(width 0.10795)
		(layer "In9.Cu")
		(net "PHY_SCC_A_TO_DRV_A_21_DN")
	)
	(segment
		(start 405.547068 -160.56102)
		(end 412.112714 -159.105092)
		(width 0.10795)
		(layer "In9.Cu")
		(net "PHY_SCC_A_TO_DRV_A_21_DN")
	)
	(segment
		(start 288.275268 -322.770246)
		(end 289.313874 -322.540122)
		(width 0.10795)
		(layer "In9.Cu")
		(net "PHY_SCC_A_TO_DRV_A_21_DN")
	)
	(segment
		(start 295.834308 -318.385952)
		(end 309.118254 -297.535346)
		(width 0.10795)
		(layer "In9.Cu")
		(net "PHY_SCC_A_TO_DRV_A_21_DN")
	)
	(segment
		(start 280.295858 -322.770246)
		(end 288.275268 -322.770246)
		(width 0.10795)
		(layer "In9.Cu")
		(net "PHY_SCC_A_TO_DRV_A_21_DN")
	)
	(segment
		(start 279.771602 -321.838066)
		(end 279.771602 -322.24599)
		(width 0.10795)
		(layer "In9.Cu")
		(net "PHY_SCC_A_TO_DRV_A_21_DN")
	)
	(segment
		(start 414.639252 -159.224726)
		(end 414.639252 -159.511492)
		(width 0.10795)
		(layer "In9.Cu")
		(net "PHY_SCC_A_TO_DRV_A_21_DN")
	)
	(segment
		(start 372.175278 -181.821582)
		(end 405.547068 -160.56102)
		(width 0.10795)
		(layer "In9.Cu")
		(net "PHY_SCC_A_TO_DRV_A_21_DN")
	)
	(segment
		(start 289.313874 -322.540122)
		(end 295.834308 -318.385952)
		(width 0.10795)
		(layer "In9.Cu")
		(net "PHY_SCC_A_TO_DRV_A_21_DN")
	)
	(segment
		(start 412.112714 -159.105092)
		(end 414.519618 -159.105092)
		(width 0.10795)
		(layer "In9.Cu")
		(net "PHY_SCC_A_TO_DRV_A_21_DN")
	)
	(segment
		(start 314.49137 -273.302984)
		(end 314.833254 -271.759934)
		(width 0.10795)
		(layer "In9.Cu")
		(net "PHY_SCC_A_TO_DRV_A_21_DN")
	)
	(arc
		(start 279.771602 -322.24599)
		(mid 279.806321 -322.420801)
		(end 279.905206 -322.569078)
		(width 0.10795)
		(layer "In9.Cu")
		(net "PHY_SCC_A_TO_DRV_A_21_DN")
	)
	(arc
		(start 279.734518 -321.748404)
		(mid 279.761951 -321.789555)
		(end 279.771602 -321.838066)
		(width 0.10795)
		(layer "In9.Cu")
		(net "PHY_SCC_A_TO_DRV_A_21_DN")
	)
	(arc
		(start 414.519618 -159.105092)
		(mid 414.5654 -159.114199)
		(end 414.6042 -159.140144)
		(width 0.10795)
		(layer "In9.Cu")
		(net "PHY_SCC_A_TO_DRV_A_21_DN")
	)
	(arc
		(start 279.97277 -322.636642)
		(mid 280.121047 -322.735528)
		(end 280.295858 -322.770246)
		(width 0.10795)
		(layer "In9.Cu")
		(net "PHY_SCC_A_TO_DRV_A_21_DN")
	)
	(arc
		(start 414.6042 -159.140144)
		(mid 414.63013 -159.178951)
		(end 414.639252 -159.224726)
		(width 0.10795)
		(layer "In9.Cu")
		(net "PHY_SCC_A_TO_DRV_A_21_DN")
	)
	(arc
		(start 279.63876 -321.705224)
		(mid 279.687278 -321.714857)
		(end 279.728422 -321.742308)
		(width 0.10795)
		(layer "In9.Cu")
		(net "PHY_SCC_A_TO_DRV_A_21_DN")
	)
	(segment
		(start 383.08915 -158.368492)
		(end 383.08915 -158.650432)
		(width 0.127)
		(layer "F.Cu")
		(net "PHY_SCC_A_TO_DRV_A_20_DP")
	)
	(segment
		(start 384.123946 -158.660592)
		(end 384.455162 -158.660592)
		(width 0.127)
		(layer "F.Cu")
		(net "PHY_SCC_A_TO_DRV_A_20_DP")
	)
	(segment
		(start 383.126234 -158.740094)
		(end 383.142998 -158.756858)
		(width 0.127)
		(layer "F.Cu")
		(net "PHY_SCC_A_TO_DRV_A_20_DP")
	)
	(segment
		(start 383.990596 -158.793942)
		(end 384.123946 -158.660592)
		(width 0.127)
		(layer "F.Cu")
		(net "PHY_SCC_A_TO_DRV_A_20_DP")
	)
	(segment
		(start 383.23266 -158.793942)
		(end 383.990596 -158.793942)
		(width 0.127)
		(layer "F.Cu")
		(net "PHY_SCC_A_TO_DRV_A_20_DP")
	)
	(arc
		(start 383.08915 -158.650432)
		(mid 383.098783 -158.69895)
		(end 383.126234 -158.740094)
		(width 0.127)
		(layer "F.Cu")
		(net "PHY_SCC_A_TO_DRV_A_20_DP")
	)
	(arc
		(start 383.142998 -158.756858)
		(mid 383.184149 -158.784291)
		(end 383.23266 -158.793942)
		(width 0.127)
		(layer "F.Cu")
		(net "PHY_SCC_A_TO_DRV_A_20_DP")
	)
	(segment
		(start 294.739822 -315.97981)
		(end 294.565832 -316.253114)
		(width 0.10795)
		(layer "In9.Cu")
		(net "PHY_SCC_A_TO_DRV_A_20_DP")
	)
	(segment
		(start 295.602406 -315.016134)
		(end 295.3131 -315.080142)
		(width 0.10795)
		(layer "In9.Cu")
		(net "PHY_SCC_A_TO_DRV_A_20_DP")
	)
	(segment
		(start 294.390826 -316.917578)
		(end 288.996628 -320.354706)
		(width 0.10795)
		(layer "In9.Cu")
		(net "PHY_SCC_A_TO_DRV_A_20_DP")
	)
	(segment
		(start 313.64936 -268.468602)
		(end 307.455824 -296.413682)
		(width 0.10795)
		(layer "In9.Cu")
		(net "PHY_SCC_A_TO_DRV_A_20_DP")
	)
	(segment
		(start 294.62984 -316.54242)
		(end 294.390826 -316.917578)
		(width 0.10795)
		(layer "In9.Cu")
		(net "PHY_SCC_A_TO_DRV_A_20_DP")
	)
	(segment
		(start 331.19314 -240.392458)
		(end 328.37755 -244.898164)
		(width 0.10795)
		(layer "In9.Cu")
		(net "PHY_SCC_A_TO_DRV_A_20_DP")
	)
	(segment
		(start 296.175684 -314.116466)
		(end 295.886378 -314.180474)
		(width 0.10795)
		(layer "In9.Cu")
		(net "PHY_SCC_A_TO_DRV_A_20_DP")
	)
	(segment
		(start 382.4097 -158.774892)
		(end 382.053846 -158.998158)
		(width 0.10795)
		(layer "In9.Cu")
		(net "PHY_SCC_A_TO_DRV_A_20_DP")
	)
	(segment
		(start 328.37755 -244.898164)
		(end 313.64936 -268.468602)
		(width 0.10795)
		(layer "In9.Cu")
		(net "PHY_SCC_A_TO_DRV_A_20_DP")
	)
	(segment
		(start 279.101804 -320.47561)
		(end 279.101804 -320.042286)
		(width 0.10795)
		(layer "In9.Cu")
		(net "PHY_SCC_A_TO_DRV_A_20_DP")
	)
	(segment
		(start 335.886552 -232.881424)
		(end 335.260442 -233.8832)
		(width 0.10795)
		(layer "In9.Cu")
		(net "PHY_SCC_A_TO_DRV_A_20_DP")
	)
	(segment
		(start 343.3953 -220.86443)
		(end 343.395554 -220.86443)
		(width 0.10795)
		(layer "In9.Cu")
		(net "PHY_SCC_A_TO_DRV_A_20_DP")
	)
	(segment
		(start 294.565832 -316.253114)
		(end 294.62984 -316.54242)
		(width 0.10795)
		(layer "In9.Cu")
		(net "PHY_SCC_A_TO_DRV_A_20_DP")
	)
	(segment
		(start 279.238964 -319.905126)
		(end 279.636728 -319.905126)
		(width 0.10795)
		(layer "In9.Cu")
		(net "PHY_SCC_A_TO_DRV_A_20_DP")
	)
	(segment
		(start 343.395554 -220.86443)
		(end 335.886552 -232.881424)
		(width 0.10795)
		(layer "In9.Cu")
		(net "PHY_SCC_A_TO_DRV_A_20_DP")
	)
	(segment
		(start 295.776396 -314.743084)
		(end 295.602406 -315.016134)
		(width 0.10795)
		(layer "In9.Cu")
		(net "PHY_SCC_A_TO_DRV_A_20_DP")
	)
	(segment
		(start 383.08915 -158.368492)
		(end 383.08915 -158.655258)
		(width 0.10795)
		(layer "In9.Cu")
		(net "PHY_SCC_A_TO_DRV_A_20_DP")
	)
	(segment
		(start 332.13167 -238.890048)
		(end 331.19314 -240.392458)
		(width 0.10795)
		(layer "In9.Cu")
		(net "PHY_SCC_A_TO_DRV_A_20_DP")
	)
	(segment
		(start 279.138888 -319.952624)
		(end 279.149302 -319.94221)
		(width 0.10795)
		(layer "In9.Cu")
		(net "PHY_SCC_A_TO_DRV_A_20_DP")
	)
	(segment
		(start 335.260442 -233.8832)
		(end 332.131924 -238.890048)
		(width 0.10795)
		(layer "In9.Cu")
		(net "PHY_SCC_A_TO_DRV_A_20_DP")
	)
	(segment
		(start 279.17648 -320.602864)
		(end 279.138888 -320.565272)
		(width 0.10795)
		(layer "In9.Cu")
		(net "PHY_SCC_A_TO_DRV_A_20_DP")
	)
	(segment
		(start 287.710372 -320.639948)
		(end 279.266142 -320.639948)
		(width 0.10795)
		(layer "In9.Cu")
		(net "PHY_SCC_A_TO_DRV_A_20_DP")
	)
	(segment
		(start 332.131924 -238.890048)
		(end 332.13167 -238.890048)
		(width 0.10795)
		(layer "In9.Cu")
		(net "PHY_SCC_A_TO_DRV_A_20_DP")
	)
	(segment
		(start 295.712388 -314.453778)
		(end 295.776396 -314.743084)
		(width 0.10795)
		(layer "In9.Cu")
		(net "PHY_SCC_A_TO_DRV_A_20_DP")
	)
	(segment
		(start 288.996628 -320.354706)
		(end 288.031936 -320.568574)
		(width 0.10795)
		(layer "In9.Cu")
		(net "PHY_SCC_A_TO_DRV_A_20_DP")
	)
	(segment
		(start 373.431816 -172.796454)
		(end 343.3953 -220.86443)
		(width 0.10795)
		(layer "In9.Cu")
		(net "PHY_SCC_A_TO_DRV_A_20_DP")
	)
	(segment
		(start 295.886378 -314.180474)
		(end 295.712388 -314.453778)
		(width 0.10795)
		(layer "In9.Cu")
		(net "PHY_SCC_A_TO_DRV_A_20_DP")
	)
	(segment
		(start 288.031936 -320.568574)
		(end 287.710372 -320.639948)
		(width 0.10795)
		(layer "In9.Cu")
		(net "PHY_SCC_A_TO_DRV_A_20_DP")
	)
	(segment
		(start 295.3131 -315.080142)
		(end 295.13911 -315.353446)
		(width 0.10795)
		(layer "In9.Cu")
		(net "PHY_SCC_A_TO_DRV_A_20_DP")
	)
	(segment
		(start 295.13911 -315.353446)
		(end 295.203118 -315.642752)
		(width 0.10795)
		(layer "In9.Cu")
		(net "PHY_SCC_A_TO_DRV_A_20_DP")
	)
	(segment
		(start 295.203118 -315.642752)
		(end 295.029128 -315.915802)
		(width 0.10795)
		(layer "In9.Cu")
		(net "PHY_SCC_A_TO_DRV_A_20_DP")
	)
	(segment
		(start 382.053846 -158.998158)
		(end 373.431816 -172.796454)
		(width 0.10795)
		(layer "In9.Cu")
		(net "PHY_SCC_A_TO_DRV_A_20_DP")
	)
	(segment
		(start 307.455824 -296.413682)
		(end 296.175684 -314.116466)
		(width 0.10795)
		(layer "In9.Cu")
		(net "PHY_SCC_A_TO_DRV_A_20_DP")
	)
	(segment
		(start 382.969516 -158.774892)
		(end 382.4097 -158.774892)
		(width 0.10795)
		(layer "In9.Cu")
		(net "PHY_SCC_A_TO_DRV_A_20_DP")
	)
	(segment
		(start 295.029128 -315.915802)
		(end 294.739822 -315.97981)
		(width 0.10795)
		(layer "In9.Cu")
		(net "PHY_SCC_A_TO_DRV_A_20_DP")
	)
	(arc
		(start 383.054098 -158.73984)
		(mid 383.015291 -158.76577)
		(end 382.969516 -158.774892)
		(width 0.10795)
		(layer "In9.Cu")
		(net "PHY_SCC_A_TO_DRV_A_20_DP")
	)
	(arc
		(start 279.149302 -319.94221)
		(mid 279.190453 -319.914777)
		(end 279.238964 -319.905126)
		(width 0.10795)
		(layer "In9.Cu")
		(net "PHY_SCC_A_TO_DRV_A_20_DP")
	)
	(arc
		(start 383.08915 -158.655258)
		(mid 383.080043 -158.70104)
		(end 383.054098 -158.73984)
		(width 0.10795)
		(layer "In9.Cu")
		(net "PHY_SCC_A_TO_DRV_A_20_DP")
	)
	(arc
		(start 279.266142 -320.639948)
		(mid 279.217624 -320.630315)
		(end 279.17648 -320.602864)
		(width 0.10795)
		(layer "In9.Cu")
		(net "PHY_SCC_A_TO_DRV_A_20_DP")
	)
	(arc
		(start 279.138888 -320.565272)
		(mid 279.111455 -320.524121)
		(end 279.101804 -320.47561)
		(width 0.10795)
		(layer "In9.Cu")
		(net "PHY_SCC_A_TO_DRV_A_20_DP")
	)
	(arc
		(start 279.101804 -320.042286)
		(mid 279.111437 -319.993768)
		(end 279.138888 -319.952624)
		(width 0.10795)
		(layer "In9.Cu")
		(net "PHY_SCC_A_TO_DRV_A_20_DP")
	)
	(segment
		(start 383.990596 -159.086042)
		(end 384.123946 -159.219392)
		(width 0.127)
		(layer "F.Cu")
		(net "PHY_SCC_A_TO_DRV_A_20_DN")
	)
	(segment
		(start 383.08915 -159.511492)
		(end 383.08915 -159.229298)
		(width 0.127)
		(layer "F.Cu")
		(net "PHY_SCC_A_TO_DRV_A_20_DN")
	)
	(segment
		(start 383.126234 -159.139636)
		(end 383.142744 -159.123126)
		(width 0.127)
		(layer "F.Cu")
		(net "PHY_SCC_A_TO_DRV_A_20_DN")
	)
	(segment
		(start 383.232406 -159.086042)
		(end 383.990596 -159.086042)
		(width 0.127)
		(layer "F.Cu")
		(net "PHY_SCC_A_TO_DRV_A_20_DN")
	)
	(segment
		(start 384.123946 -159.219392)
		(end 384.455162 -159.219392)
		(width 0.127)
		(layer "F.Cu")
		(net "PHY_SCC_A_TO_DRV_A_20_DN")
	)
	(arc
		(start 383.142744 -159.123126)
		(mid 383.183895 -159.095693)
		(end 383.232406 -159.086042)
		(width 0.127)
		(layer "F.Cu")
		(net "PHY_SCC_A_TO_DRV_A_20_DN")
	)
	(arc
		(start 383.08915 -159.229298)
		(mid 383.098783 -159.18078)
		(end 383.126234 -159.139636)
		(width 0.127)
		(layer "F.Cu")
		(net "PHY_SCC_A_TO_DRV_A_20_DN")
	)
	(segment
		(start 278.943054 -320.836544)
		(end 278.905208 -320.798698)
		(width 0.10795)
		(layer "In9.Cu")
		(net "PHY_SCC_A_TO_DRV_A_20_DN")
	)
	(segment
		(start 330.534772 -242.069366)
		(end 328.657712 -245.07317)
		(width 0.10795)
		(layer "In9.Cu")
		(net "PHY_SCC_A_TO_DRV_A_20_DN")
	)
	(segment
		(start 328.657712 -245.07317)
		(end 313.959748 -268.595602)
		(width 0.10795)
		(layer "In9.Cu")
		(net "PHY_SCC_A_TO_DRV_A_20_DN")
	)
	(segment
		(start 382.50495 -159.105092)
		(end 382.293876 -159.23768)
		(width 0.10795)
		(layer "In9.Cu")
		(net "PHY_SCC_A_TO_DRV_A_20_DN")
	)
	(segment
		(start 382.293876 -159.23768)
		(end 373.711978 -172.971714)
		(width 0.10795)
		(layer "In9.Cu")
		(net "PHY_SCC_A_TO_DRV_A_20_DN")
	)
	(segment
		(start 294.630094 -317.156846)
		(end 289.124898 -320.664586)
		(width 0.10795)
		(layer "In9.Cu")
		(net "PHY_SCC_A_TO_DRV_A_20_DN")
	)
	(segment
		(start 278.73452 -319.952624)
		(end 278.724106 -319.94221)
		(width 0.10795)
		(layer "In9.Cu")
		(net "PHY_SCC_A_TO_DRV_A_20_DN")
	)
	(segment
		(start 382.969516 -159.105092)
		(end 382.50495 -159.105092)
		(width 0.10795)
		(layer "In9.Cu")
		(net "PHY_SCC_A_TO_DRV_A_20_DN")
	)
	(segment
		(start 343.675716 -221.039436)
		(end 330.534772 -242.069366)
		(width 0.10795)
		(layer "In9.Cu")
		(net "PHY_SCC_A_TO_DRV_A_20_DN")
	)
	(segment
		(start 313.959748 -268.595602)
		(end 307.765704 -296.541952)
		(width 0.10795)
		(layer "In9.Cu")
		(net "PHY_SCC_A_TO_DRV_A_20_DN")
	)
	(segment
		(start 278.771604 -320.47561)
		(end 278.771604 -320.042286)
		(width 0.10795)
		(layer "In9.Cu")
		(net "PHY_SCC_A_TO_DRV_A_20_DN")
	)
	(segment
		(start 373.711978 -172.97146)
		(end 343.675716 -221.039436)
		(width 0.10795)
		(layer "In9.Cu")
		(net "PHY_SCC_A_TO_DRV_A_20_DN")
	)
	(segment
		(start 373.711978 -172.971714)
		(end 373.711978 -172.97146)
		(width 0.10795)
		(layer "In9.Cu")
		(net "PHY_SCC_A_TO_DRV_A_20_DN")
	)
	(segment
		(start 307.765704 -296.541952)
		(end 294.630094 -317.156846)
		(width 0.10795)
		(layer "In9.Cu")
		(net "PHY_SCC_A_TO_DRV_A_20_DN")
	)
	(segment
		(start 289.124898 -320.664586)
		(end 288.103564 -320.891154)
		(width 0.10795)
		(layer "In9.Cu")
		(net "PHY_SCC_A_TO_DRV_A_20_DN")
	)
	(segment
		(start 278.634444 -319.905126)
		(end 278.23668 -319.905126)
		(width 0.10795)
		(layer "In9.Cu")
		(net "PHY_SCC_A_TO_DRV_A_20_DN")
	)
	(segment
		(start 383.08915 -159.511492)
		(end 383.08915 -159.224726)
		(width 0.10795)
		(layer "In9.Cu")
		(net "PHY_SCC_A_TO_DRV_A_20_DN")
	)
	(segment
		(start 287.942782 -320.926714)
		(end 287.746694 -320.970148)
		(width 0.10795)
		(layer "In9.Cu")
		(net "PHY_SCC_A_TO_DRV_A_20_DN")
	)
	(segment
		(start 287.746694 -320.970148)
		(end 279.266142 -320.970148)
		(width 0.10795)
		(layer "In9.Cu")
		(net "PHY_SCC_A_TO_DRV_A_20_DN")
	)
	(segment
		(start 288.103564 -320.891154)
		(end 287.942782 -320.926714)
		(width 0.10795)
		(layer "In9.Cu")
		(net "PHY_SCC_A_TO_DRV_A_20_DN")
	)
	(arc
		(start 383.08915 -159.224726)
		(mid 383.080043 -159.178944)
		(end 383.054098 -159.140144)
		(width 0.10795)
		(layer "In9.Cu")
		(net "PHY_SCC_A_TO_DRV_A_20_DN")
	)
	(arc
		(start 278.905208 -320.798698)
		(mid 278.806322 -320.650421)
		(end 278.771604 -320.47561)
		(width 0.10795)
		(layer "In9.Cu")
		(net "PHY_SCC_A_TO_DRV_A_20_DN")
	)
	(arc
		(start 383.054098 -159.140144)
		(mid 383.015291 -159.114214)
		(end 382.969516 -159.105092)
		(width 0.10795)
		(layer "In9.Cu")
		(net "PHY_SCC_A_TO_DRV_A_20_DN")
	)
	(arc
		(start 278.724106 -319.94221)
		(mid 278.682955 -319.914777)
		(end 278.634444 -319.905126)
		(width 0.10795)
		(layer "In9.Cu")
		(net "PHY_SCC_A_TO_DRV_A_20_DN")
	)
	(arc
		(start 278.771604 -320.042286)
		(mid 278.761971 -319.993768)
		(end 278.73452 -319.952624)
		(width 0.10795)
		(layer "In9.Cu")
		(net "PHY_SCC_A_TO_DRV_A_20_DN")
	)
	(arc
		(start 279.266142 -320.970148)
		(mid 279.091331 -320.935429)
		(end 278.943054 -320.836544)
		(width 0.10795)
		(layer "In9.Cu")
		(net "PHY_SCC_A_TO_DRV_A_20_DN")
	)
	(segment
		(start 237.757462 -337.23453)
		(end 270.863568 -354.92182)
		(width 0.127)
		(layer "F.Cu")
		(net "PHY_SCC_A_TO_DRV_A_2_DP")
	)
	(segment
		(start 272.68805 -355.34092)
		(end 272.68805 -355.778054)
		(width 0.127)
		(layer "F.Cu")
		(net "PHY_SCC_A_TO_DRV_A_2_DP")
	)
	(segment
		(start 270.863568 -354.92182)
		(end 272.26895 -354.92182)
		(width 0.127)
		(layer "F.Cu")
		(net "PHY_SCC_A_TO_DRV_A_2_DP")
	)
	(segment
		(start 272.81505 -355.905054)
		(end 273.1135 -355.905054)
		(width 0.127)
		(layer "F.Cu")
		(net "PHY_SCC_A_TO_DRV_A_2_DP")
	)
	(segment
		(start 203.62799 -330.401168)
		(end 237.757462 -337.23453)
		(width 0.127)
		(layer "F.Cu")
		(net "PHY_SCC_A_TO_DRV_A_2_DP")
	)
	(segment
		(start 151.284686 -337.905852)
		(end 158.965392 -339.44306)
		(width 0.127)
		(layer "F.Cu")
		(net "PHY_SCC_A_TO_DRV_A_2_DP")
	)
	(segment
		(start 97.323656 -274.12188)
		(end 101.68509 -285.945072)
		(width 0.127)
		(layer "F.Cu")
		(net "PHY_SCC_A_TO_DRV_A_2_DP")
	)
	(segment
		(start 106.353102 -302.951388)
		(end 151.284686 -337.905852)
		(width 0.127)
		(layer "F.Cu")
		(net "PHY_SCC_A_TO_DRV_A_2_DP")
	)
	(segment
		(start 96.502474 -273.836638)
		(end 96.87433 -273.836638)
		(width 0.127)
		(layer "F.Cu")
		(net "PHY_SCC_A_TO_DRV_A_2_DP")
	)
	(segment
		(start 96.326452 -273.660616)
		(end 96.502474 -273.836638)
		(width 0.127)
		(layer "F.Cu")
		(net "PHY_SCC_A_TO_DRV_A_2_DP")
	)
	(segment
		(start 101.68509 -285.945072)
		(end 101.241098 -288.128202)
		(width 0.127)
		(layer "F.Cu")
		(net "PHY_SCC_A_TO_DRV_A_2_DP")
	)
	(segment
		(start 101.241098 -288.128456)
		(end 100.796852 -290.312094)
		(width 0.127)
		(layer "F.Cu")
		(net "PHY_SCC_A_TO_DRV_A_2_DP")
	)
	(segment
		(start 106.09326 -302.360076)
		(end 106.353102 -302.951388)
		(width 0.127)
		(layer "F.Cu")
		(net "PHY_SCC_A_TO_DRV_A_2_DP")
	)
	(segment
		(start 158.965392 -339.44306)
		(end 203.62799 -330.401168)
		(width 0.127)
		(layer "F.Cu")
		(net "PHY_SCC_A_TO_DRV_A_2_DP")
	)
	(segment
		(start 101.241098 -288.128202)
		(end 101.241098 -288.128456)
		(width 0.127)
		(layer "F.Cu")
		(net "PHY_SCC_A_TO_DRV_A_2_DP")
	)
	(segment
		(start 95.842836 -273.660616)
		(end 96.326452 -273.660616)
		(width 0.127)
		(layer "F.Cu")
		(net "PHY_SCC_A_TO_DRV_A_2_DP")
	)
	(segment
		(start 100.796852 -290.312094)
		(end 106.09326 -302.360076)
		(width 0.127)
		(layer "F.Cu")
		(net "PHY_SCC_A_TO_DRV_A_2_DP")
	)
	(segment
		(start 96.87433 -273.836638)
		(end 97.323656 -274.12188)
		(width 0.127)
		(layer "F.Cu")
		(net "PHY_SCC_A_TO_DRV_A_2_DP")
	)
	(arc
		(start 272.68805 -355.778054)
		(mid 272.725247 -355.867857)
		(end 272.81505 -355.905054)
		(width 0.127)
		(layer "F.Cu")
		(net "PHY_SCC_A_TO_DRV_A_2_DP")
	)
	(arc
		(start 272.26895 -354.92182)
		(mid 272.565298 -355.044572)
		(end 272.68805 -355.34092)
		(width 0.127)
		(layer "F.Cu")
		(net "PHY_SCC_A_TO_DRV_A_2_DP")
	)
	(segment
		(start 280.082752 -354.483162)
		(end 280.082752 -354.23221)
		(width 0.127)
		(layer "B.Cu")
		(net "PHY_SCC_A_TO_DRV_A_2_DP")
	)
	(segment
		(start 273.11223 -355.151182)
		(end 279.329134 -355.151182)
		(width 0.127)
		(layer "B.Cu")
		(net "PHY_SCC_A_TO_DRV_A_2_DP")
	)
	(segment
		(start 272.68805 -355.723952)
		(end 272.68805 -355.575362)
		(width 0.127)
		(layer "B.Cu")
		(net "PHY_SCC_A_TO_DRV_A_2_DP")
	)
	(segment
		(start 280.209752 -354.10521)
		(end 280.636726 -354.10521)
		(width 0.127)
		(layer "B.Cu")
		(net "PHY_SCC_A_TO_DRV_A_2_DP")
	)
	(segment
		(start 273.1135 -355.905054)
		(end 272.869152 -355.905054)
		(width 0.127)
		(layer "B.Cu")
		(net "PHY_SCC_A_TO_DRV_A_2_DP")
	)
	(arc
		(start 279.329134 -355.151182)
		(mid 279.640578 -355.089419)
		(end 279.904698 -354.913184)
		(width 0.127)
		(layer "B.Cu")
		(net "PHY_SCC_A_TO_DRV_A_2_DP")
	)
	(arc
		(start 279.904698 -354.913184)
		(mid 279.92788 -354.888666)
		(end 279.949656 -354.862892)
		(width 0.127)
		(layer "B.Cu")
		(net "PHY_SCC_A_TO_DRV_A_2_DP")
	)
	(arc
		(start 279.949656 -354.862892)
		(mid 280.048501 -354.684349)
		(end 280.082752 -354.483162)
		(width 0.127)
		(layer "B.Cu")
		(net "PHY_SCC_A_TO_DRV_A_2_DP")
	)
	(arc
		(start 272.68805 -355.575362)
		(mid 272.812289 -355.275421)
		(end 273.11223 -355.151182)
		(width 0.127)
		(layer "B.Cu")
		(net "PHY_SCC_A_TO_DRV_A_2_DP")
	)
	(arc
		(start 272.869152 -355.905054)
		(mid 272.741094 -355.85201)
		(end 272.68805 -355.723952)
		(width 0.127)
		(layer "B.Cu")
		(net "PHY_SCC_A_TO_DRV_A_2_DP")
	)
	(arc
		(start 280.082752 -354.23221)
		(mid 280.119949 -354.142407)
		(end 280.209752 -354.10521)
		(width 0.127)
		(layer "B.Cu")
		(net "PHY_SCC_A_TO_DRV_A_2_DP")
	)
	(segment
		(start 272.26895 -355.905054)
		(end 271.9705 -355.905054)
		(width 0.127)
		(layer "F.Cu")
		(net "PHY_SCC_A_TO_DRV_A_2_DN")
	)
	(segment
		(start 106.115358 -303.136554)
		(end 151.159718 -338.178902)
		(width 0.127)
		(layer "F.Cu")
		(net "PHY_SCC_A_TO_DRV_A_2_DN")
	)
	(segment
		(start 207.270858 -331.5843)
		(end 207.450182 -331.464666)
		(width 0.127)
		(layer "F.Cu")
		(net "PHY_SCC_A_TO_DRV_A_2_DN")
	)
	(segment
		(start 207.823816 -331.539596)
		(end 207.943196 -331.71892)
		(width 0.127)
		(layer "F.Cu")
		(net "PHY_SCC_A_TO_DRV_A_2_DN")
	)
	(segment
		(start 208.31683 -331.793596)
		(end 208.496154 -331.674216)
		(width 0.127)
		(layer "F.Cu")
		(net "PHY_SCC_A_TO_DRV_A_2_DN")
	)
	(segment
		(start 207.450182 -331.464666)
		(end 207.823816 -331.539596)
		(width 0.127)
		(layer "F.Cu")
		(net "PHY_SCC_A_TO_DRV_A_2_DN")
	)
	(segment
		(start 204.685646 -330.9112)
		(end 204.805026 -331.090524)
		(width 0.127)
		(layer "F.Cu")
		(net "PHY_SCC_A_TO_DRV_A_2_DN")
	)
	(segment
		(start 96.78924 -274.128738)
		(end 97.083626 -274.315682)
		(width 0.127)
		(layer "F.Cu")
		(net "PHY_SCC_A_TO_DRV_A_2_DN")
	)
	(segment
		(start 206.897224 -331.50937)
		(end 207.270858 -331.5843)
		(width 0.127)
		(layer "F.Cu")
		(net "PHY_SCC_A_TO_DRV_A_2_DN")
	)
	(segment
		(start 206.224632 -331.37475)
		(end 206.403956 -331.25537)
		(width 0.127)
		(layer "F.Cu")
		(net "PHY_SCC_A_TO_DRV_A_2_DN")
	)
	(segment
		(start 96.326452 -274.219416)
		(end 96.41713 -274.128738)
		(width 0.127)
		(layer "F.Cu")
		(net "PHY_SCC_A_TO_DRV_A_2_DN")
	)
	(segment
		(start 95.842836 -274.219416)
		(end 96.326452 -274.219416)
		(width 0.127)
		(layer "F.Cu")
		(net "PHY_SCC_A_TO_DRV_A_2_DN")
	)
	(segment
		(start 101.382068 -285.968186)
		(end 100.492052 -290.34486)
		(width 0.127)
		(layer "F.Cu")
		(net "PHY_SCC_A_TO_DRV_A_2_DN")
	)
	(segment
		(start 97.083626 -274.315682)
		(end 101.382068 -285.968186)
		(width 0.127)
		(layer "F.Cu")
		(net "PHY_SCC_A_TO_DRV_A_2_DN")
	)
	(segment
		(start 204.805026 -331.090524)
		(end 205.17866 -331.165454)
		(width 0.127)
		(layer "F.Cu")
		(net "PHY_SCC_A_TO_DRV_A_2_DN")
	)
	(segment
		(start 205.17866 -331.165454)
		(end 205.357984 -331.04582)
		(width 0.127)
		(layer "F.Cu")
		(net "PHY_SCC_A_TO_DRV_A_2_DN")
	)
	(segment
		(start 105.825798 -302.477678)
		(end 106.115358 -303.136554)
		(width 0.127)
		(layer "F.Cu")
		(net "PHY_SCC_A_TO_DRV_A_2_DN")
	)
	(segment
		(start 207.943196 -331.71892)
		(end 208.31683 -331.793596)
		(width 0.127)
		(layer "F.Cu")
		(net "PHY_SCC_A_TO_DRV_A_2_DN")
	)
	(segment
		(start 158.965646 -339.741256)
		(end 203.628244 -330.699364)
		(width 0.127)
		(layer "F.Cu")
		(net "PHY_SCC_A_TO_DRV_A_2_DN")
	)
	(segment
		(start 206.77759 -331.330046)
		(end 206.897224 -331.50937)
		(width 0.127)
		(layer "F.Cu")
		(net "PHY_SCC_A_TO_DRV_A_2_DN")
	)
	(segment
		(start 96.41713 -274.128738)
		(end 96.78924 -274.128738)
		(width 0.127)
		(layer "F.Cu")
		(net "PHY_SCC_A_TO_DRV_A_2_DN")
	)
	(segment
		(start 100.492052 -290.34486)
		(end 105.825798 -302.477678)
		(width 0.127)
		(layer "F.Cu")
		(net "PHY_SCC_A_TO_DRV_A_2_DN")
	)
	(segment
		(start 272.39595 -355.34092)
		(end 272.39595 -355.778054)
		(width 0.127)
		(layer "F.Cu")
		(net "PHY_SCC_A_TO_DRV_A_2_DN")
	)
	(segment
		(start 237.65764 -337.51266)
		(end 270.790416 -355.21392)
		(width 0.127)
		(layer "F.Cu")
		(net "PHY_SCC_A_TO_DRV_A_2_DN")
	)
	(segment
		(start 203.628244 -330.699364)
		(end 204.685646 -330.9112)
		(width 0.127)
		(layer "F.Cu")
		(net "PHY_SCC_A_TO_DRV_A_2_DN")
	)
	(segment
		(start 205.851252 -331.300074)
		(end 206.224632 -331.37475)
		(width 0.127)
		(layer "F.Cu")
		(net "PHY_SCC_A_TO_DRV_A_2_DN")
	)
	(segment
		(start 206.403956 -331.25537)
		(end 206.77759 -331.330046)
		(width 0.127)
		(layer "F.Cu")
		(net "PHY_SCC_A_TO_DRV_A_2_DN")
	)
	(segment
		(start 205.357984 -331.04582)
		(end 205.731618 -331.12075)
		(width 0.127)
		(layer "F.Cu")
		(net "PHY_SCC_A_TO_DRV_A_2_DN")
	)
	(segment
		(start 205.731618 -331.12075)
		(end 205.851252 -331.300074)
		(width 0.127)
		(layer "F.Cu")
		(net "PHY_SCC_A_TO_DRV_A_2_DN")
	)
	(segment
		(start 208.496154 -331.674216)
		(end 237.65764 -337.51266)
		(width 0.127)
		(layer "F.Cu")
		(net "PHY_SCC_A_TO_DRV_A_2_DN")
	)
	(segment
		(start 151.159718 -338.178902)
		(end 158.965646 -339.741256)
		(width 0.127)
		(layer "F.Cu")
		(net "PHY_SCC_A_TO_DRV_A_2_DN")
	)
	(segment
		(start 270.790416 -355.21392)
		(end 272.26895 -355.21392)
		(width 0.127)
		(layer "F.Cu")
		(net "PHY_SCC_A_TO_DRV_A_2_DN")
	)
	(arc
		(start 272.39595 -355.778054)
		(mid 272.358753 -355.867857)
		(end 272.26895 -355.905054)
		(width 0.127)
		(layer "F.Cu")
		(net "PHY_SCC_A_TO_DRV_A_2_DN")
	)
	(arc
		(start 272.26895 -355.21392)
		(mid 272.358753 -355.251117)
		(end 272.39595 -355.34092)
		(width 0.127)
		(layer "F.Cu")
		(net "PHY_SCC_A_TO_DRV_A_2_DN")
	)
	(segment
		(start 271.9705 -355.905054)
		(end 272.214848 -355.905054)
		(width 0.127)
		(layer "B.Cu")
		(net "PHY_SCC_A_TO_DRV_A_2_DN")
	)
	(segment
		(start 279.663652 -354.10521)
		(end 279.236678 -354.10521)
		(width 0.127)
		(layer "B.Cu")
		(net "PHY_SCC_A_TO_DRV_A_2_DN")
	)
	(segment
		(start 272.39595 -355.723952)
		(end 272.39595 -355.575362)
		(width 0.127)
		(layer "B.Cu")
		(net "PHY_SCC_A_TO_DRV_A_2_DN")
	)
	(segment
		(start 279.790652 -354.482654)
		(end 279.790652 -354.23221)
		(width 0.127)
		(layer "B.Cu")
		(net "PHY_SCC_A_TO_DRV_A_2_DN")
	)
	(segment
		(start 273.11223 -354.859082)
		(end 279.329388 -354.859082)
		(width 0.127)
		(layer "B.Cu")
		(net "PHY_SCC_A_TO_DRV_A_2_DN")
	)
	(arc
		(start 279.790652 -354.23221)
		(mid 279.753455 -354.142407)
		(end 279.663652 -354.10521)
		(width 0.127)
		(layer "B.Cu")
		(net "PHY_SCC_A_TO_DRV_A_2_DN")
	)
	(arc
		(start 279.329388 -354.859082)
		(mid 279.528846 -354.819407)
		(end 279.697942 -354.706428)
		(width 0.127)
		(layer "B.Cu")
		(net "PHY_SCC_A_TO_DRV_A_2_DN")
	)
	(arc
		(start 279.697942 -354.706428)
		(mid 279.709986 -354.693668)
		(end 279.72131 -354.680266)
		(width 0.127)
		(layer "B.Cu")
		(net "PHY_SCC_A_TO_DRV_A_2_DN")
	)
	(arc
		(start 272.214848 -355.905054)
		(mid 272.342906 -355.85201)
		(end 272.39595 -355.723952)
		(width 0.127)
		(layer "B.Cu")
		(net "PHY_SCC_A_TO_DRV_A_2_DN")
	)
	(arc
		(start 272.39595 -355.575362)
		(mid 272.605744 -355.068876)
		(end 273.11223 -354.859082)
		(width 0.127)
		(layer "B.Cu")
		(net "PHY_SCC_A_TO_DRV_A_2_DN")
	)
	(arc
		(start 279.72131 -354.680266)
		(mid 279.772817 -354.587367)
		(end 279.790652 -354.482654)
		(width 0.127)
		(layer "B.Cu")
		(net "PHY_SCC_A_TO_DRV_A_2_DN")
	)
	(segment
		(start 351.539302 -158.368492)
		(end 351.539302 -158.653734)
		(width 0.127)
		(layer "F.Cu")
		(net "PHY_SCC_A_TO_DRV_A_19_DP")
	)
	(segment
		(start 352.574098 -158.660592)
		(end 352.905314 -158.660592)
		(width 0.127)
		(layer "F.Cu")
		(net "PHY_SCC_A_TO_DRV_A_19_DP")
	)
	(segment
		(start 352.440748 -158.793942)
		(end 352.574098 -158.660592)
		(width 0.127)
		(layer "F.Cu")
		(net "PHY_SCC_A_TO_DRV_A_19_DP")
	)
	(segment
		(start 351.67951 -158.793942)
		(end 352.440748 -158.793942)
		(width 0.127)
		(layer "F.Cu")
		(net "PHY_SCC_A_TO_DRV_A_19_DP")
	)
	(segment
		(start 351.576386 -158.743396)
		(end 351.589848 -158.756858)
		(width 0.127)
		(layer "F.Cu")
		(net "PHY_SCC_A_TO_DRV_A_19_DP")
	)
	(arc
		(start 351.589848 -158.756858)
		(mid 351.630999 -158.784291)
		(end 351.67951 -158.793942)
		(width 0.127)
		(layer "F.Cu")
		(net "PHY_SCC_A_TO_DRV_A_19_DP")
	)
	(arc
		(start 351.539302 -158.653734)
		(mid 351.548935 -158.702252)
		(end 351.576386 -158.743396)
		(width 0.127)
		(layer "F.Cu")
		(net "PHY_SCC_A_TO_DRV_A_19_DP")
	)
	(segment
		(start 292.87343 -316.10808)
		(end 292.809422 -315.818774)
		(width 0.10795)
		(layer "In9.Cu")
		(net "PHY_SCC_A_TO_DRV_A_19_DP")
	)
	(segment
		(start 312.437272 -267.221716)
		(end 314.51677 -257.843528)
		(width 0.10795)
		(layer "In9.Cu")
		(net "PHY_SCC_A_TO_DRV_A_19_DP")
	)
	(segment
		(start 280.295858 -318.83985)
		(end 288.205164 -318.83985)
		(width 0.10795)
		(layer "In9.Cu")
		(net "PHY_SCC_A_TO_DRV_A_19_DP")
	)
	(segment
		(start 280.636726 -318.105028)
		(end 280.234644 -318.105028)
		(width 0.10795)
		(layer "In9.Cu")
		(net "PHY_SCC_A_TO_DRV_A_19_DP")
	)
	(segment
		(start 294.419274 -313.682126)
		(end 306.254404 -295.10736)
		(width 0.10795)
		(layer "In9.Cu")
		(net "PHY_SCC_A_TO_DRV_A_19_DP")
	)
	(segment
		(start 280.138886 -318.735456)
		(end 280.206196 -318.802766)
		(width 0.10795)
		(layer "In9.Cu")
		(net "PHY_SCC_A_TO_DRV_A_19_DP")
	)
	(segment
		(start 345.790012 -185.799476)
		(end 344.607896 -180.23586)
		(width 0.10795)
		(layer "In9.Cu")
		(net "PHY_SCC_A_TO_DRV_A_19_DP")
	)
	(segment
		(start 343.486994 -160.998662)
		(end 346.06992 -159.320738)
		(width 0.10795)
		(layer "In9.Cu")
		(net "PHY_SCC_A_TO_DRV_A_19_DP")
	)
	(segment
		(start 293.3827 -314.919106)
		(end 293.55669 -314.645802)
		(width 0.10795)
		(layer "In9.Cu")
		(net "PHY_SCC_A_TO_DRV_A_19_DP")
	)
	(segment
		(start 334.16875 -226.995228)
		(end 337.511644 -221.747334)
		(width 0.10795)
		(layer "In9.Cu")
		(net "PHY_SCC_A_TO_DRV_A_19_DP")
	)
	(segment
		(start 341.699596 -166.549324)
		(end 342.584024 -162.385756)
		(width 0.10795)
		(layer "In9.Cu")
		(net "PHY_SCC_A_TO_DRV_A_19_DP")
	)
	(segment
		(start 347.917262 -158.927546)
		(end 349.772732 -158.532576)
		(width 0.10795)
		(layer "In9.Cu")
		(net "PHY_SCC_A_TO_DRV_A_19_DP")
	)
	(segment
		(start 292.809422 -315.818774)
		(end 292.983412 -315.54547)
		(width 0.10795)
		(layer "In9.Cu")
		(net "PHY_SCC_A_TO_DRV_A_19_DP")
	)
	(segment
		(start 294.019986 -314.308744)
		(end 293.955724 -314.019184)
		(width 0.10795)
		(layer "In9.Cu")
		(net "PHY_SCC_A_TO_DRV_A_19_DP")
	)
	(segment
		(start 343.42578 -174.672244)
		(end 341.699596 -166.549324)
		(width 0.10795)
		(layer "In9.Cu")
		(net "PHY_SCC_A_TO_DRV_A_19_DP")
	)
	(segment
		(start 350.911922 -158.774892)
		(end 351.419668 -158.774892)
		(width 0.10795)
		(layer "In9.Cu")
		(net "PHY_SCC_A_TO_DRV_A_19_DP")
	)
	(segment
		(start 292.983412 -315.54547)
		(end 293.272718 -315.481462)
		(width 0.10795)
		(layer "In9.Cu")
		(net "PHY_SCC_A_TO_DRV_A_19_DP")
	)
	(segment
		(start 342.584024 -162.385756)
		(end 343.486994 -160.998662)
		(width 0.10795)
		(layer "In9.Cu")
		(net "PHY_SCC_A_TO_DRV_A_19_DP")
	)
	(segment
		(start 293.272718 -315.481462)
		(end 293.446708 -315.208412)
		(width 0.10795)
		(layer "In9.Cu")
		(net "PHY_SCC_A_TO_DRV_A_19_DP")
	)
	(segment
		(start 344.607896 -180.235606)
		(end 344.016838 -177.453798)
		(width 0.10795)
		(layer "In9.Cu")
		(net "PHY_SCC_A_TO_DRV_A_19_DP")
	)
	(segment
		(start 343.755218 -176.222406)
		(end 343.42578 -174.672244)
		(width 0.10795)
		(layer "In9.Cu")
		(net "PHY_SCC_A_TO_DRV_A_19_DP")
	)
	(segment
		(start 346.06992 -159.320738)
		(end 347.917262 -158.927546)
		(width 0.10795)
		(layer "In9.Cu")
		(net "PHY_SCC_A_TO_DRV_A_19_DP")
	)
	(segment
		(start 351.539302 -158.655258)
		(end 351.539302 -158.368492)
		(width 0.10795)
		(layer "In9.Cu")
		(net "PHY_SCC_A_TO_DRV_A_19_DP")
	)
	(segment
		(start 344.607896 -180.23586)
		(end 344.607896 -180.235606)
		(width 0.10795)
		(layer "In9.Cu")
		(net "PHY_SCC_A_TO_DRV_A_19_DP")
	)
	(segment
		(start 337.511644 -221.747334)
		(end 341.651082 -203.773024)
		(width 0.10795)
		(layer "In9.Cu")
		(net "PHY_SCC_A_TO_DRV_A_19_DP")
	)
	(segment
		(start 344.763852 -190.256668)
		(end 345.790012 -185.799476)
		(width 0.10795)
		(layer "In9.Cu")
		(net "PHY_SCC_A_TO_DRV_A_19_DP")
	)
	(segment
		(start 294.129968 -313.746134)
		(end 294.419274 -313.682126)
		(width 0.10795)
		(layer "In9.Cu")
		(net "PHY_SCC_A_TO_DRV_A_19_DP")
	)
	(segment
		(start 349.772732 -158.532576)
		(end 350.911922 -158.774892)
		(width 0.10795)
		(layer "In9.Cu")
		(net "PHY_SCC_A_TO_DRV_A_19_DP")
	)
	(segment
		(start 314.51677 -257.843528)
		(end 330.825602 -232.243376)
		(width 0.10795)
		(layer "In9.Cu")
		(net "PHY_SCC_A_TO_DRV_A_19_DP")
	)
	(segment
		(start 344.016838 -177.453798)
		(end 343.86139 -176.723294)
		(width 0.10795)
		(layer "In9.Cu")
		(net "PHY_SCC_A_TO_DRV_A_19_DP")
	)
	(segment
		(start 289.177476 -318.624458)
		(end 292.69944 -316.38113)
		(width 0.10795)
		(layer "In9.Cu")
		(net "PHY_SCC_A_TO_DRV_A_19_DP")
	)
	(segment
		(start 293.845996 -314.581794)
		(end 294.019986 -314.308744)
		(width 0.10795)
		(layer "In9.Cu")
		(net "PHY_SCC_A_TO_DRV_A_19_DP")
	)
	(segment
		(start 343.86139 -176.723294)
		(end 343.755218 -176.222406)
		(width 0.10795)
		(layer "In9.Cu")
		(net "PHY_SCC_A_TO_DRV_A_19_DP")
	)
	(segment
		(start 292.69944 -316.38113)
		(end 292.87343 -316.10808)
		(width 0.10795)
		(layer "In9.Cu")
		(net "PHY_SCC_A_TO_DRV_A_19_DP")
	)
	(segment
		(start 280.144982 -318.142112)
		(end 280.138886 -318.148208)
		(width 0.10795)
		(layer "In9.Cu")
		(net "PHY_SCC_A_TO_DRV_A_19_DP")
	)
	(segment
		(start 293.955724 -314.019184)
		(end 294.129968 -313.746134)
		(width 0.10795)
		(layer "In9.Cu")
		(net "PHY_SCC_A_TO_DRV_A_19_DP")
	)
	(segment
		(start 288.205164 -318.83985)
		(end 289.177476 -318.624458)
		(width 0.10795)
		(layer "In9.Cu")
		(net "PHY_SCC_A_TO_DRV_A_19_DP")
	)
	(segment
		(start 330.825602 -232.243376)
		(end 334.16875 -226.995228)
		(width 0.10795)
		(layer "In9.Cu")
		(net "PHY_SCC_A_TO_DRV_A_19_DP")
	)
	(segment
		(start 280.101802 -318.23787)
		(end 280.101802 -318.645794)
		(width 0.10795)
		(layer "In9.Cu")
		(net "PHY_SCC_A_TO_DRV_A_19_DP")
	)
	(segment
		(start 306.254404 -295.10736)
		(end 310.37276 -276.53234)
		(width 0.10795)
		(layer "In9.Cu")
		(net "PHY_SCC_A_TO_DRV_A_19_DP")
	)
	(segment
		(start 293.55669 -314.645802)
		(end 293.845996 -314.581794)
		(width 0.10795)
		(layer "In9.Cu")
		(net "PHY_SCC_A_TO_DRV_A_19_DP")
	)
	(segment
		(start 341.651082 -203.773024)
		(end 344.763852 -190.256668)
		(width 0.10795)
		(layer "In9.Cu")
		(net "PHY_SCC_A_TO_DRV_A_19_DP")
	)
	(segment
		(start 293.446708 -315.208412)
		(end 293.3827 -314.919106)
		(width 0.10795)
		(layer "In9.Cu")
		(net "PHY_SCC_A_TO_DRV_A_19_DP")
	)
	(segment
		(start 310.37276 -276.53234)
		(end 312.437272 -267.221716)
		(width 0.10795)
		(layer "In9.Cu")
		(net "PHY_SCC_A_TO_DRV_A_19_DP")
	)
	(arc
		(start 351.419668 -158.774892)
		(mid 351.46545 -158.765785)
		(end 351.50425 -158.73984)
		(width 0.10795)
		(layer "In9.Cu")
		(net "PHY_SCC_A_TO_DRV_A_19_DP")
	)
	(arc
		(start 280.234644 -318.105028)
		(mid 280.186126 -318.114661)
		(end 280.144982 -318.142112)
		(width 0.10795)
		(layer "In9.Cu")
		(net "PHY_SCC_A_TO_DRV_A_19_DP")
	)
	(arc
		(start 351.50425 -158.73984)
		(mid 351.53018 -158.701033)
		(end 351.539302 -158.655258)
		(width 0.10795)
		(layer "In9.Cu")
		(net "PHY_SCC_A_TO_DRV_A_19_DP")
	)
	(arc
		(start 280.206196 -318.802766)
		(mid 280.247347 -318.830199)
		(end 280.295858 -318.83985)
		(width 0.10795)
		(layer "In9.Cu")
		(net "PHY_SCC_A_TO_DRV_A_19_DP")
	)
	(arc
		(start 280.138886 -318.148208)
		(mid 280.111453 -318.189359)
		(end 280.101802 -318.23787)
		(width 0.10795)
		(layer "In9.Cu")
		(net "PHY_SCC_A_TO_DRV_A_19_DP")
	)
	(arc
		(start 280.101802 -318.645794)
		(mid 280.111435 -318.694312)
		(end 280.138886 -318.735456)
		(width 0.10795)
		(layer "In9.Cu")
		(net "PHY_SCC_A_TO_DRV_A_19_DP")
	)
	(segment
		(start 352.440748 -159.086042)
		(end 352.574098 -159.219392)
		(width 0.127)
		(layer "F.Cu")
		(net "PHY_SCC_A_TO_DRV_A_19_DN")
	)
	(segment
		(start 351.576386 -159.133794)
		(end 351.587054 -159.123126)
		(width 0.127)
		(layer "F.Cu")
		(net "PHY_SCC_A_TO_DRV_A_19_DN")
	)
	(segment
		(start 351.676716 -159.086042)
		(end 352.440748 -159.086042)
		(width 0.127)
		(layer "F.Cu")
		(net "PHY_SCC_A_TO_DRV_A_19_DN")
	)
	(segment
		(start 352.574098 -159.219392)
		(end 352.905314 -159.219392)
		(width 0.127)
		(layer "F.Cu")
		(net "PHY_SCC_A_TO_DRV_A_19_DN")
	)
	(segment
		(start 351.539302 -159.511492)
		(end 351.539302 -159.223456)
		(width 0.127)
		(layer "F.Cu")
		(net "PHY_SCC_A_TO_DRV_A_19_DN")
	)
	(arc
		(start 351.587054 -159.123126)
		(mid 351.628205 -159.095693)
		(end 351.676716 -159.086042)
		(width 0.127)
		(layer "F.Cu")
		(net "PHY_SCC_A_TO_DRV_A_19_DN")
	)
	(arc
		(start 351.539302 -159.223456)
		(mid 351.548935 -159.174938)
		(end 351.576386 -159.133794)
		(width 0.127)
		(layer "F.Cu")
		(net "PHY_SCC_A_TO_DRV_A_19_DN")
	)
	(segment
		(start 279.771602 -318.23787)
		(end 279.771602 -318.645794)
		(width 0.10795)
		(layer "In9.Cu")
		(net "PHY_SCC_A_TO_DRV_A_19_DN")
	)
	(segment
		(start 343.725754 -161.237676)
		(end 346.198698 -159.631126)
		(width 0.10795)
		(layer "In9.Cu")
		(net "PHY_SCC_A_TO_DRV_A_19_DN")
	)
	(segment
		(start 314.82665 -257.971798)
		(end 331.10424 -232.420922)
		(width 0.10795)
		(layer "In9.Cu")
		(net "PHY_SCC_A_TO_DRV_A_19_DN")
	)
	(segment
		(start 331.10424 -232.420922)
		(end 334.447388 -227.172774)
		(width 0.10795)
		(layer "In9.Cu")
		(net "PHY_SCC_A_TO_DRV_A_19_DN")
	)
	(segment
		(start 350.877124 -159.105092)
		(end 351.419668 -159.105092)
		(width 0.10795)
		(layer "In9.Cu")
		(net "PHY_SCC_A_TO_DRV_A_19_DN")
	)
	(segment
		(start 344.042746 -194.860164)
		(end 346.12834 -185.80227)
		(width 0.10795)
		(layer "In9.Cu")
		(net "PHY_SCC_A_TO_DRV_A_19_DN")
	)
	(segment
		(start 346.12834 -185.80227)
		(end 343.748868 -174.603664)
		(width 0.10795)
		(layer "In9.Cu")
		(net "PHY_SCC_A_TO_DRV_A_19_DN")
	)
	(segment
		(start 337.820762 -221.876874)
		(end 344.042746 -194.860164)
		(width 0.10795)
		(layer "In9.Cu")
		(net "PHY_SCC_A_TO_DRV_A_19_DN")
	)
	(segment
		(start 334.447388 -227.172774)
		(end 337.820762 -221.876874)
		(width 0.10795)
		(layer "In9.Cu")
		(net "PHY_SCC_A_TO_DRV_A_19_DN")
	)
	(segment
		(start 289.305746 -318.934338)
		(end 292.938708 -316.620398)
		(width 0.10795)
		(layer "In9.Cu")
		(net "PHY_SCC_A_TO_DRV_A_19_DN")
	)
	(segment
		(start 343.748868 -174.603664)
		(end 342.037416 -166.549324)
		(width 0.10795)
		(layer "In9.Cu")
		(net "PHY_SCC_A_TO_DRV_A_19_DN")
	)
	(segment
		(start 279.236678 -318.105028)
		(end 279.63876 -318.105028)
		(width 0.10795)
		(layer "In9.Cu")
		(net "PHY_SCC_A_TO_DRV_A_19_DN")
	)
	(segment
		(start 351.539302 -159.224726)
		(end 351.539302 -159.511492)
		(width 0.10795)
		(layer "In9.Cu")
		(net "PHY_SCC_A_TO_DRV_A_19_DN")
	)
	(segment
		(start 349.772732 -158.870396)
		(end 350.877124 -159.105092)
		(width 0.10795)
		(layer "In9.Cu")
		(net "PHY_SCC_A_TO_DRV_A_19_DN")
	)
	(segment
		(start 279.728422 -318.142112)
		(end 279.734518 -318.148208)
		(width 0.10795)
		(layer "In9.Cu")
		(net "PHY_SCC_A_TO_DRV_A_19_DN")
	)
	(segment
		(start 346.198698 -159.631126)
		(end 349.772732 -158.870396)
		(width 0.10795)
		(layer "In9.Cu")
		(net "PHY_SCC_A_TO_DRV_A_19_DN")
	)
	(segment
		(start 280.295858 -319.17005)
		(end 288.241486 -319.17005)
		(width 0.10795)
		(layer "In9.Cu")
		(net "PHY_SCC_A_TO_DRV_A_19_DN")
	)
	(segment
		(start 342.894412 -162.514534)
		(end 343.725754 -161.237676)
		(width 0.10795)
		(layer "In9.Cu")
		(net "PHY_SCC_A_TO_DRV_A_19_DN")
	)
	(segment
		(start 288.241486 -319.17005)
		(end 289.305746 -318.934338)
		(width 0.10795)
		(layer "In9.Cu")
		(net "PHY_SCC_A_TO_DRV_A_19_DN")
	)
	(segment
		(start 292.938708 -316.620398)
		(end 306.564284 -295.23563)
		(width 0.10795)
		(layer "In9.Cu")
		(net "PHY_SCC_A_TO_DRV_A_19_DN")
	)
	(segment
		(start 342.037416 -166.549324)
		(end 342.894412 -162.514534)
		(width 0.10795)
		(layer "In9.Cu")
		(net "PHY_SCC_A_TO_DRV_A_19_DN")
	)
	(segment
		(start 306.564284 -295.23563)
		(end 314.82665 -257.971798)
		(width 0.10795)
		(layer "In9.Cu")
		(net "PHY_SCC_A_TO_DRV_A_19_DN")
	)
	(segment
		(start 279.905206 -318.968882)
		(end 279.97277 -319.036446)
		(width 0.10795)
		(layer "In9.Cu")
		(net "PHY_SCC_A_TO_DRV_A_19_DN")
	)
	(arc
		(start 279.771602 -318.645794)
		(mid 279.806321 -318.820605)
		(end 279.905206 -318.968882)
		(width 0.10795)
		(layer "In9.Cu")
		(net "PHY_SCC_A_TO_DRV_A_19_DN")
	)
	(arc
		(start 279.63876 -318.105028)
		(mid 279.687278 -318.114661)
		(end 279.728422 -318.142112)
		(width 0.10795)
		(layer "In9.Cu")
		(net "PHY_SCC_A_TO_DRV_A_19_DN")
	)
	(arc
		(start 279.734518 -318.148208)
		(mid 279.761951 -318.189359)
		(end 279.771602 -318.23787)
		(width 0.10795)
		(layer "In9.Cu")
		(net "PHY_SCC_A_TO_DRV_A_19_DN")
	)
	(arc
		(start 279.97277 -319.036446)
		(mid 280.121047 -319.135332)
		(end 280.295858 -319.17005)
		(width 0.10795)
		(layer "In9.Cu")
		(net "PHY_SCC_A_TO_DRV_A_19_DN")
	)
	(arc
		(start 351.419668 -159.105092)
		(mid 351.46545 -159.114199)
		(end 351.50425 -159.140144)
		(width 0.10795)
		(layer "In9.Cu")
		(net "PHY_SCC_A_TO_DRV_A_19_DN")
	)
	(arc
		(start 351.50425 -159.140144)
		(mid 351.53018 -159.178951)
		(end 351.539302 -159.224726)
		(width 0.10795)
		(layer "In9.Cu")
		(net "PHY_SCC_A_TO_DRV_A_19_DN")
	)
	(segment
		(start 321.023996 -158.660592)
		(end 321.355212 -158.660592)
		(width 0.127)
		(layer "F.Cu")
		(net "PHY_SCC_A_TO_DRV_A_18_DP")
	)
	(segment
		(start 320.890646 -158.793942)
		(end 321.023996 -158.660592)
		(width 0.127)
		(layer "F.Cu")
		(net "PHY_SCC_A_TO_DRV_A_18_DP")
	)
	(segment
		(start 319.9892 -158.368492)
		(end 319.9892 -158.666688)
		(width 0.127)
		(layer "F.Cu")
		(net "PHY_SCC_A_TO_DRV_A_18_DP")
	)
	(segment
		(start 319.9892 -158.666688)
		(end 320.116454 -158.793942)
		(width 0.127)
		(layer "F.Cu")
		(net "PHY_SCC_A_TO_DRV_A_18_DP")
	)
	(segment
		(start 320.116454 -158.793942)
		(end 320.890646 -158.793942)
		(width 0.127)
		(layer "F.Cu")
		(net "PHY_SCC_A_TO_DRV_A_18_DP")
	)
	(segment
		(start 293.379652 -311.900062)
		(end 293.205662 -312.173366)
		(width 0.10795)
		(layer "In9.Cu")
		(net "PHY_SCC_A_TO_DRV_A_18_DP")
	)
	(segment
		(start 287.465008 -317.040006)
		(end 279.266142 -317.040006)
		(width 0.10795)
		(layer "In9.Cu")
		(net "PHY_SCC_A_TO_DRV_A_18_DP")
	)
	(segment
		(start 317.974472 -160.216596)
		(end 309.180484 -199.880728)
		(width 0.10795)
		(layer "In9.Cu")
		(net "PHY_SCC_A_TO_DRV_A_18_DP")
	)
	(segment
		(start 293.668958 -311.8358)
		(end 293.379652 -311.900062)
		(width 0.10795)
		(layer "In9.Cu")
		(net "PHY_SCC_A_TO_DRV_A_18_DP")
	)
	(segment
		(start 293.842694 -311.562496)
		(end 293.668958 -311.8358)
		(width 0.10795)
		(layer "In9.Cu")
		(net "PHY_SCC_A_TO_DRV_A_18_DP")
	)
	(segment
		(start 279.17648 -317.002922)
		(end 279.138888 -316.96533)
		(width 0.10795)
		(layer "In9.Cu")
		(net "PHY_SCC_A_TO_DRV_A_18_DP")
	)
	(segment
		(start 305.191414 -293.725346)
		(end 294.814244 -310.035702)
		(width 0.10795)
		(layer "In9.Cu")
		(net "PHY_SCC_A_TO_DRV_A_18_DP")
	)
	(segment
		(start 309.180738 -199.880728)
		(end 307.91023 -205.610714)
		(width 0.10795)
		(layer "In9.Cu")
		(net "PHY_SCC_A_TO_DRV_A_18_DP")
	)
	(segment
		(start 309.180484 -199.880728)
		(end 309.180738 -199.880728)
		(width 0.10795)
		(layer "In9.Cu")
		(net "PHY_SCC_A_TO_DRV_A_18_DP")
	)
	(segment
		(start 293.270178 -312.462672)
		(end 291.924994 -314.576714)
		(width 0.10795)
		(layer "In9.Cu")
		(net "PHY_SCC_A_TO_DRV_A_18_DP")
	)
	(segment
		(start 294.814244 -310.035702)
		(end 294.524938 -310.099964)
		(width 0.10795)
		(layer "In9.Cu")
		(net "PHY_SCC_A_TO_DRV_A_18_DP")
	)
	(segment
		(start 312.135012 -224.665286)
		(end 316.328044 -243.57711)
		(width 0.10795)
		(layer "In9.Cu")
		(net "PHY_SCC_A_TO_DRV_A_18_DP")
	)
	(segment
		(start 318.59093 -159.241744)
		(end 317.974472 -160.216596)
		(width 0.10795)
		(layer "In9.Cu")
		(net "PHY_SCC_A_TO_DRV_A_18_DP")
	)
	(segment
		(start 294.415464 -310.66232)
		(end 294.241474 -310.935624)
		(width 0.10795)
		(layer "In9.Cu")
		(net "PHY_SCC_A_TO_DRV_A_18_DP")
	)
	(segment
		(start 293.205662 -312.173366)
		(end 293.270178 -312.462672)
		(width 0.10795)
		(layer "In9.Cu")
		(net "PHY_SCC_A_TO_DRV_A_18_DP")
	)
	(segment
		(start 319.058036 -158.774892)
		(end 318.59093 -159.241744)
		(width 0.10795)
		(layer "In9.Cu")
		(net "PHY_SCC_A_TO_DRV_A_18_DP")
	)
	(segment
		(start 293.778432 -311.27319)
		(end 293.842694 -311.562496)
		(width 0.10795)
		(layer "In9.Cu")
		(net "PHY_SCC_A_TO_DRV_A_18_DP")
	)
	(segment
		(start 294.241474 -310.935624)
		(end 293.952168 -310.999886)
		(width 0.10795)
		(layer "In9.Cu")
		(net "PHY_SCC_A_TO_DRV_A_18_DP")
	)
	(segment
		(start 294.524938 -310.099964)
		(end 294.351202 -310.373268)
		(width 0.10795)
		(layer "In9.Cu")
		(net "PHY_SCC_A_TO_DRV_A_18_DP")
	)
	(segment
		(start 319.820798 -158.774892)
		(end 319.058036 -158.774892)
		(width 0.10795)
		(layer "In9.Cu")
		(net "PHY_SCC_A_TO_DRV_A_18_DP")
	)
	(segment
		(start 279.238964 -316.305184)
		(end 279.636728 -316.305184)
		(width 0.10795)
		(layer "In9.Cu")
		(net "PHY_SCC_A_TO_DRV_A_18_DP")
	)
	(segment
		(start 279.138888 -316.352682)
		(end 279.149302 -316.342268)
		(width 0.10795)
		(layer "In9.Cu")
		(net "PHY_SCC_A_TO_DRV_A_18_DP")
	)
	(segment
		(start 291.924994 -314.576714)
		(end 288.374582 -316.83833)
		(width 0.10795)
		(layer "In9.Cu")
		(net "PHY_SCC_A_TO_DRV_A_18_DP")
	)
	(segment
		(start 293.952168 -310.999886)
		(end 293.778432 -311.27319)
		(width 0.10795)
		(layer "In9.Cu")
		(net "PHY_SCC_A_TO_DRV_A_18_DP")
	)
	(segment
		(start 307.91023 -205.610714)
		(end 312.135012 -224.665286)
		(width 0.10795)
		(layer "In9.Cu")
		(net "PHY_SCC_A_TO_DRV_A_18_DP")
	)
	(segment
		(start 316.328044 -243.57711)
		(end 305.191414 -293.725346)
		(width 0.10795)
		(layer "In9.Cu")
		(net "PHY_SCC_A_TO_DRV_A_18_DP")
	)
	(segment
		(start 294.351202 -310.373268)
		(end 294.415464 -310.66232)
		(width 0.10795)
		(layer "In9.Cu")
		(net "PHY_SCC_A_TO_DRV_A_18_DP")
	)
	(segment
		(start 279.101804 -316.875668)
		(end 279.101804 -316.442344)
		(width 0.10795)
		(layer "In9.Cu")
		(net "PHY_SCC_A_TO_DRV_A_18_DP")
	)
	(segment
		(start 319.9892 -158.368492)
		(end 319.9892 -158.60649)
		(width 0.10795)
		(layer "In9.Cu")
		(net "PHY_SCC_A_TO_DRV_A_18_DP")
	)
	(segment
		(start 288.374582 -316.83833)
		(end 287.465008 -317.040006)
		(width 0.10795)
		(layer "In9.Cu")
		(net "PHY_SCC_A_TO_DRV_A_18_DP")
	)
	(arc
		(start 279.266142 -317.040006)
		(mid 279.217624 -317.030373)
		(end 279.17648 -317.002922)
		(width 0.10795)
		(layer "In9.Cu")
		(net "PHY_SCC_A_TO_DRV_A_18_DP")
	)
	(arc
		(start 279.149302 -316.342268)
		(mid 279.190453 -316.314835)
		(end 279.238964 -316.305184)
		(width 0.10795)
		(layer "In9.Cu")
		(net "PHY_SCC_A_TO_DRV_A_18_DP")
	)
	(arc
		(start 279.101804 -316.442344)
		(mid 279.111437 -316.393826)
		(end 279.138888 -316.352682)
		(width 0.10795)
		(layer "In9.Cu")
		(net "PHY_SCC_A_TO_DRV_A_18_DP")
	)
	(arc
		(start 319.9892 -158.60649)
		(mid 319.939876 -158.725568)
		(end 319.820798 -158.774892)
		(width 0.10795)
		(layer "In9.Cu")
		(net "PHY_SCC_A_TO_DRV_A_18_DP")
	)
	(arc
		(start 279.138888 -316.96533)
		(mid 279.111455 -316.924179)
		(end 279.101804 -316.875668)
		(width 0.10795)
		(layer "In9.Cu")
		(net "PHY_SCC_A_TO_DRV_A_18_DP")
	)
	(segment
		(start 319.9892 -159.213296)
		(end 320.116454 -159.086042)
		(width 0.127)
		(layer "F.Cu")
		(net "PHY_SCC_A_TO_DRV_A_18_DN")
	)
	(segment
		(start 319.9892 -159.511492)
		(end 319.9892 -159.213296)
		(width 0.127)
		(layer "F.Cu")
		(net "PHY_SCC_A_TO_DRV_A_18_DN")
	)
	(segment
		(start 321.023996 -159.219392)
		(end 321.355212 -159.219392)
		(width 0.127)
		(layer "F.Cu")
		(net "PHY_SCC_A_TO_DRV_A_18_DN")
	)
	(segment
		(start 320.116454 -159.086042)
		(end 320.890646 -159.086042)
		(width 0.127)
		(layer "F.Cu")
		(net "PHY_SCC_A_TO_DRV_A_18_DN")
	)
	(segment
		(start 320.890646 -159.086042)
		(end 321.023996 -159.219392)
		(width 0.127)
		(layer "F.Cu")
		(net "PHY_SCC_A_TO_DRV_A_18_DN")
	)
	(segment
		(start 288.502852 -317.14821)
		(end 292.164516 -314.815982)
		(width 0.10795)
		(layer "In9.Cu")
		(net "PHY_SCC_A_TO_DRV_A_18_DN")
	)
	(segment
		(start 278.23668 -316.305184)
		(end 278.634444 -316.305184)
		(width 0.10795)
		(layer "In9.Cu")
		(net "PHY_SCC_A_TO_DRV_A_18_DN")
	)
	(segment
		(start 292.164516 -314.815982)
		(end 305.501294 -293.853616)
		(width 0.10795)
		(layer "In9.Cu")
		(net "PHY_SCC_A_TO_DRV_A_18_DN")
	)
	(segment
		(start 278.771604 -316.442344)
		(end 278.771604 -316.875668)
		(width 0.10795)
		(layer "In9.Cu")
		(net "PHY_SCC_A_TO_DRV_A_18_DN")
	)
	(segment
		(start 305.501294 -293.853616)
		(end 316.666372 -243.57711)
		(width 0.10795)
		(layer "In9.Cu")
		(net "PHY_SCC_A_TO_DRV_A_18_DN")
	)
	(segment
		(start 287.50133 -317.370206)
		(end 288.502852 -317.14821)
		(width 0.10795)
		(layer "In9.Cu")
		(net "PHY_SCC_A_TO_DRV_A_18_DN")
	)
	(segment
		(start 316.666372 -243.57711)
		(end 308.248558 -205.610714)
		(width 0.10795)
		(layer "In9.Cu")
		(net "PHY_SCC_A_TO_DRV_A_18_DN")
	)
	(segment
		(start 308.248558 -205.610714)
		(end 318.284606 -160.344358)
		(width 0.10795)
		(layer "In9.Cu")
		(net "PHY_SCC_A_TO_DRV_A_18_DN")
	)
	(segment
		(start 319.9892 -159.273494)
		(end 319.9892 -159.511492)
		(width 0.10795)
		(layer "In9.Cu")
		(net "PHY_SCC_A_TO_DRV_A_18_DN")
	)
	(segment
		(start 318.850518 -159.449516)
		(end 319.194942 -159.105092)
		(width 0.10795)
		(layer "In9.Cu")
		(net "PHY_SCC_A_TO_DRV_A_18_DN")
	)
	(segment
		(start 319.194942 -159.105092)
		(end 319.820798 -159.105092)
		(width 0.10795)
		(layer "In9.Cu")
		(net "PHY_SCC_A_TO_DRV_A_18_DN")
	)
	(segment
		(start 278.905208 -317.198756)
		(end 278.943054 -317.236602)
		(width 0.10795)
		(layer "In9.Cu")
		(net "PHY_SCC_A_TO_DRV_A_18_DN")
	)
	(segment
		(start 279.266142 -317.370206)
		(end 287.50133 -317.370206)
		(width 0.10795)
		(layer "In9.Cu")
		(net "PHY_SCC_A_TO_DRV_A_18_DN")
	)
	(segment
		(start 278.724106 -316.342268)
		(end 278.73452 -316.352682)
		(width 0.10795)
		(layer "In9.Cu")
		(net "PHY_SCC_A_TO_DRV_A_18_DN")
	)
	(segment
		(start 318.284606 -160.344358)
		(end 318.850518 -159.449516)
		(width 0.10795)
		(layer "In9.Cu")
		(net "PHY_SCC_A_TO_DRV_A_18_DN")
	)
	(arc
		(start 278.634444 -316.305184)
		(mid 278.682962 -316.314817)
		(end 278.724106 -316.342268)
		(width 0.10795)
		(layer "In9.Cu")
		(net "PHY_SCC_A_TO_DRV_A_18_DN")
	)
	(arc
		(start 278.943054 -317.236602)
		(mid 279.091331 -317.335488)
		(end 279.266142 -317.370206)
		(width 0.10795)
		(layer "In9.Cu")
		(net "PHY_SCC_A_TO_DRV_A_18_DN")
	)
	(arc
		(start 319.820798 -159.105092)
		(mid 319.939876 -159.154416)
		(end 319.9892 -159.273494)
		(width 0.10795)
		(layer "In9.Cu")
		(net "PHY_SCC_A_TO_DRV_A_18_DN")
	)
	(arc
		(start 278.771604 -316.875668)
		(mid 278.806323 -317.050479)
		(end 278.905208 -317.198756)
		(width 0.10795)
		(layer "In9.Cu")
		(net "PHY_SCC_A_TO_DRV_A_18_DN")
	)
	(arc
		(start 278.73452 -316.352682)
		(mid 278.761953 -316.393833)
		(end 278.771604 -316.442344)
		(width 0.10795)
		(layer "In9.Cu")
		(net "PHY_SCC_A_TO_DRV_A_18_DN")
	)
	(segment
		(start 192.715642 -180.383434)
		(end 190.743586 -188.372496)
		(width 0.127)
		(layer "F.Cu")
		(net "PHY_SCC_A_TO_DRV_A_17_DP")
	)
	(segment
		(start 272.81505 -328.905108)
		(end 273.1135 -328.905108)
		(width 0.127)
		(layer "F.Cu")
		(net "PHY_SCC_A_TO_DRV_A_17_DP")
	)
	(segment
		(start 191.521842 -158.828232)
		(end 191.887602 -159.059626)
		(width 0.127)
		(layer "F.Cu")
		(net "PHY_SCC_A_TO_DRV_A_17_DP")
	)
	(segment
		(start 192.715642 -180.38318)
		(end 192.715642 -180.383434)
		(width 0.127)
		(layer "F.Cu")
		(net "PHY_SCC_A_TO_DRV_A_17_DP")
	)
	(segment
		(start 272.68805 -328.34326)
		(end 272.68805 -328.778108)
		(width 0.127)
		(layer "F.Cu")
		(net "PHY_SCC_A_TO_DRV_A_17_DP")
	)
	(segment
		(start 190.492888 -158.660592)
		(end 190.976504 -158.660592)
		(width 0.127)
		(layer "F.Cu")
		(net "PHY_SCC_A_TO_DRV_A_17_DP")
	)
	(segment
		(start 271.616678 -327.92416)
		(end 272.26895 -327.92416)
		(width 0.127)
		(layer "F.Cu")
		(net "PHY_SCC_A_TO_DRV_A_17_DP")
	)
	(segment
		(start 240.705894 -317.262002)
		(end 271.616678 -327.92416)
		(width 0.127)
		(layer "F.Cu")
		(net "PHY_SCC_A_TO_DRV_A_17_DP")
	)
	(segment
		(start 191.887602 -159.059626)
		(end 194.687698 -172.394372)
		(width 0.127)
		(layer "F.Cu")
		(net "PHY_SCC_A_TO_DRV_A_17_DP")
	)
	(segment
		(start 190.976504 -158.660592)
		(end 191.144144 -158.828232)
		(width 0.127)
		(layer "F.Cu")
		(net "PHY_SCC_A_TO_DRV_A_17_DP")
	)
	(segment
		(start 190.743586 -188.372496)
		(end 207.456024 -264.710926)
		(width 0.127)
		(layer "F.Cu")
		(net "PHY_SCC_A_TO_DRV_A_17_DP")
	)
	(segment
		(start 207.456024 -264.710926)
		(end 240.705894 -317.262002)
		(width 0.127)
		(layer "F.Cu")
		(net "PHY_SCC_A_TO_DRV_A_17_DP")
	)
	(segment
		(start 194.687698 -172.394372)
		(end 192.715642 -180.38318)
		(width 0.127)
		(layer "F.Cu")
		(net "PHY_SCC_A_TO_DRV_A_17_DP")
	)
	(segment
		(start 191.144144 -158.828232)
		(end 191.521842 -158.828232)
		(width 0.127)
		(layer "F.Cu")
		(net "PHY_SCC_A_TO_DRV_A_17_DP")
	)
	(arc
		(start 272.26895 -327.92416)
		(mid 272.565298 -328.046912)
		(end 272.68805 -328.34326)
		(width 0.127)
		(layer "F.Cu")
		(net "PHY_SCC_A_TO_DRV_A_17_DP")
	)
	(arc
		(start 272.68805 -328.778108)
		(mid 272.725247 -328.867911)
		(end 272.81505 -328.905108)
		(width 0.127)
		(layer "F.Cu")
		(net "PHY_SCC_A_TO_DRV_A_17_DP")
	)
	(segment
		(start 272.68805 -328.575416)
		(end 272.68805 -328.724006)
		(width 0.127)
		(layer "B.Cu")
		(net "PHY_SCC_A_TO_DRV_A_17_DP")
	)
	(segment
		(start 279.082754 -327.232264)
		(end 279.082754 -327.483216)
		(width 0.127)
		(layer "B.Cu")
		(net "PHY_SCC_A_TO_DRV_A_17_DP")
	)
	(segment
		(start 272.869152 -328.905108)
		(end 273.1135 -328.905108)
		(width 0.127)
		(layer "B.Cu")
		(net "PHY_SCC_A_TO_DRV_A_17_DP")
	)
	(segment
		(start 278.329136 -328.151236)
		(end 273.11223 -328.151236)
		(width 0.127)
		(layer "B.Cu")
		(net "PHY_SCC_A_TO_DRV_A_17_DP")
	)
	(segment
		(start 279.636728 -327.105264)
		(end 279.209754 -327.105264)
		(width 0.127)
		(layer "B.Cu")
		(net "PHY_SCC_A_TO_DRV_A_17_DP")
	)
	(arc
		(start 279.209754 -327.105264)
		(mid 279.119951 -327.142461)
		(end 279.082754 -327.232264)
		(width 0.127)
		(layer "B.Cu")
		(net "PHY_SCC_A_TO_DRV_A_17_DP")
	)
	(arc
		(start 272.68805 -328.724006)
		(mid 272.741094 -328.852064)
		(end 272.869152 -328.905108)
		(width 0.127)
		(layer "B.Cu")
		(net "PHY_SCC_A_TO_DRV_A_17_DP")
	)
	(arc
		(start 279.082754 -327.483216)
		(mid 279.04852 -327.684409)
		(end 278.949658 -327.862946)
		(width 0.127)
		(layer "B.Cu")
		(net "PHY_SCC_A_TO_DRV_A_17_DP")
	)
	(arc
		(start 278.949658 -327.862946)
		(mid 278.927871 -327.888711)
		(end 278.9047 -327.913238)
		(width 0.127)
		(layer "B.Cu")
		(net "PHY_SCC_A_TO_DRV_A_17_DP")
	)
	(arc
		(start 278.9047 -327.913238)
		(mid 278.640599 -328.089519)
		(end 278.329136 -328.151236)
		(width 0.127)
		(layer "B.Cu")
		(net "PHY_SCC_A_TO_DRV_A_17_DP")
	)
	(arc
		(start 273.11223 -328.151236)
		(mid 272.812289 -328.275475)
		(end 272.68805 -328.575416)
		(width 0.127)
		(layer "B.Cu")
		(net "PHY_SCC_A_TO_DRV_A_17_DP")
	)
	(segment
		(start 240.513362 -317.504826)
		(end 240.873534 -317.629032)
		(width 0.127)
		(layer "F.Cu")
		(net "PHY_SCC_A_TO_DRV_A_17_DN")
	)
	(segment
		(start 242.336574 -318.29502)
		(end 242.530376 -318.200532)
		(width 0.127)
		(layer "F.Cu")
		(net "PHY_SCC_A_TO_DRV_A_17_DN")
	)
	(segment
		(start 240.873534 -317.629032)
		(end 240.968022 -317.822834)
		(width 0.127)
		(layer "F.Cu")
		(net "PHY_SCC_A_TO_DRV_A_17_DN")
	)
	(segment
		(start 243.898928 -318.672718)
		(end 243.993416 -318.86652)
		(width 0.127)
		(layer "F.Cu")
		(net "PHY_SCC_A_TO_DRV_A_17_DN")
	)
	(segment
		(start 190.492888 -159.219392)
		(end 190.976504 -159.219392)
		(width 0.127)
		(layer "F.Cu")
		(net "PHY_SCC_A_TO_DRV_A_17_DN")
	)
	(segment
		(start 242.890548 -318.324738)
		(end 242.984782 -318.51854)
		(width 0.127)
		(layer "F.Cu")
		(net "PHY_SCC_A_TO_DRV_A_17_DN")
	)
	(segment
		(start 243.993416 -318.86652)
		(end 244.353588 -318.990726)
		(width 0.127)
		(layer "F.Cu")
		(net "PHY_SCC_A_TO_DRV_A_17_DN")
	)
	(segment
		(start 244.54739 -318.896238)
		(end 271.567656 -328.21626)
		(width 0.127)
		(layer "F.Cu")
		(net "PHY_SCC_A_TO_DRV_A_17_DN")
	)
	(segment
		(start 190.976504 -159.219392)
		(end 191.075564 -159.120332)
		(width 0.127)
		(layer "F.Cu")
		(net "PHY_SCC_A_TO_DRV_A_17_DN")
	)
	(segment
		(start 242.984782 -318.51854)
		(end 243.344954 -318.642746)
		(width 0.127)
		(layer "F.Cu")
		(net "PHY_SCC_A_TO_DRV_A_17_DN")
	)
	(segment
		(start 191.075564 -159.120332)
		(end 191.437006 -159.120332)
		(width 0.127)
		(layer "F.Cu")
		(net "PHY_SCC_A_TO_DRV_A_17_DN")
	)
	(segment
		(start 190.443612 -188.368432)
		(end 207.18145 -264.823702)
		(width 0.127)
		(layer "F.Cu")
		(net "PHY_SCC_A_TO_DRV_A_17_DN")
	)
	(segment
		(start 241.976402 -318.170814)
		(end 242.336574 -318.29502)
		(width 0.127)
		(layer "F.Cu")
		(net "PHY_SCC_A_TO_DRV_A_17_DN")
	)
	(segment
		(start 241.881914 -317.977012)
		(end 241.976402 -318.170814)
		(width 0.127)
		(layer "F.Cu")
		(net "PHY_SCC_A_TO_DRV_A_17_DN")
	)
	(segment
		(start 240.968022 -317.822834)
		(end 241.328194 -317.94704)
		(width 0.127)
		(layer "F.Cu")
		(net "PHY_SCC_A_TO_DRV_A_17_DN")
	)
	(segment
		(start 191.626998 -159.240474)
		(end 194.387978 -172.389038)
		(width 0.127)
		(layer "F.Cu")
		(net "PHY_SCC_A_TO_DRV_A_17_DN")
	)
	(segment
		(start 244.353588 -318.990726)
		(end 244.54739 -318.896238)
		(width 0.127)
		(layer "F.Cu")
		(net "PHY_SCC_A_TO_DRV_A_17_DN")
	)
	(segment
		(start 207.18145 -264.823702)
		(end 240.513362 -317.504826)
		(width 0.127)
		(layer "F.Cu")
		(net "PHY_SCC_A_TO_DRV_A_17_DN")
	)
	(segment
		(start 243.344954 -318.642746)
		(end 243.538756 -318.548512)
		(width 0.127)
		(layer "F.Cu")
		(net "PHY_SCC_A_TO_DRV_A_17_DN")
	)
	(segment
		(start 241.328194 -317.94704)
		(end 241.521742 -317.852806)
		(width 0.127)
		(layer "F.Cu")
		(net "PHY_SCC_A_TO_DRV_A_17_DN")
	)
	(segment
		(start 272.39595 -328.34326)
		(end 272.39595 -328.778108)
		(width 0.127)
		(layer "F.Cu")
		(net "PHY_SCC_A_TO_DRV_A_17_DN")
	)
	(segment
		(start 191.437006 -159.120332)
		(end 191.626998 -159.240474)
		(width 0.127)
		(layer "F.Cu")
		(net "PHY_SCC_A_TO_DRV_A_17_DN")
	)
	(segment
		(start 243.538756 -318.548512)
		(end 243.898928 -318.672718)
		(width 0.127)
		(layer "F.Cu")
		(net "PHY_SCC_A_TO_DRV_A_17_DN")
	)
	(segment
		(start 241.521742 -317.852806)
		(end 241.881914 -317.977012)
		(width 0.127)
		(layer "F.Cu")
		(net "PHY_SCC_A_TO_DRV_A_17_DN")
	)
	(segment
		(start 272.26895 -328.905108)
		(end 271.9705 -328.905108)
		(width 0.127)
		(layer "F.Cu")
		(net "PHY_SCC_A_TO_DRV_A_17_DN")
	)
	(segment
		(start 194.387978 -172.389038)
		(end 190.443612 -188.368432)
		(width 0.127)
		(layer "F.Cu")
		(net "PHY_SCC_A_TO_DRV_A_17_DN")
	)
	(segment
		(start 271.567656 -328.21626)
		(end 272.26895 -328.21626)
		(width 0.127)
		(layer "F.Cu")
		(net "PHY_SCC_A_TO_DRV_A_17_DN")
	)
	(segment
		(start 242.530376 -318.200532)
		(end 242.890548 -318.324738)
		(width 0.127)
		(layer "F.Cu")
		(net "PHY_SCC_A_TO_DRV_A_17_DN")
	)
	(arc
		(start 272.26895 -328.21626)
		(mid 272.358753 -328.253457)
		(end 272.39595 -328.34326)
		(width 0.127)
		(layer "F.Cu")
		(net "PHY_SCC_A_TO_DRV_A_17_DN")
	)
	(arc
		(start 272.39595 -328.778108)
		(mid 272.358753 -328.867911)
		(end 272.26895 -328.905108)
		(width 0.127)
		(layer "F.Cu")
		(net "PHY_SCC_A_TO_DRV_A_17_DN")
	)
	(segment
		(start 272.39595 -328.724006)
		(end 272.39595 -328.575416)
		(width 0.127)
		(layer "B.Cu")
		(net "PHY_SCC_A_TO_DRV_A_17_DN")
	)
	(segment
		(start 273.11223 -327.859136)
		(end 278.32939 -327.859136)
		(width 0.127)
		(layer "B.Cu")
		(net "PHY_SCC_A_TO_DRV_A_17_DN")
	)
	(segment
		(start 271.9705 -328.905108)
		(end 272.214848 -328.905108)
		(width 0.127)
		(layer "B.Cu")
		(net "PHY_SCC_A_TO_DRV_A_17_DN")
	)
	(segment
		(start 278.663654 -327.105264)
		(end 278.23668 -327.105264)
		(width 0.127)
		(layer "B.Cu")
		(net "PHY_SCC_A_TO_DRV_A_17_DN")
	)
	(segment
		(start 278.790654 -327.482708)
		(end 278.790654 -327.232264)
		(width 0.127)
		(layer "B.Cu")
		(net "PHY_SCC_A_TO_DRV_A_17_DN")
	)
	(arc
		(start 272.39595 -328.575416)
		(mid 272.605744 -328.06893)
		(end 273.11223 -327.859136)
		(width 0.127)
		(layer "B.Cu")
		(net "PHY_SCC_A_TO_DRV_A_17_DN")
	)
	(arc
		(start 278.790654 -327.232264)
		(mid 278.753457 -327.142461)
		(end 278.663654 -327.105264)
		(width 0.127)
		(layer "B.Cu")
		(net "PHY_SCC_A_TO_DRV_A_17_DN")
	)
	(arc
		(start 278.697944 -327.706482)
		(mid 278.709988 -327.693722)
		(end 278.721312 -327.68032)
		(width 0.127)
		(layer "B.Cu")
		(net "PHY_SCC_A_TO_DRV_A_17_DN")
	)
	(arc
		(start 278.721312 -327.68032)
		(mid 278.772819 -327.587421)
		(end 278.790654 -327.482708)
		(width 0.127)
		(layer "B.Cu")
		(net "PHY_SCC_A_TO_DRV_A_17_DN")
	)
	(arc
		(start 278.32939 -327.859136)
		(mid 278.528848 -327.819461)
		(end 278.697944 -327.706482)
		(width 0.127)
		(layer "B.Cu")
		(net "PHY_SCC_A_TO_DRV_A_17_DN")
	)
	(arc
		(start 272.214848 -328.905108)
		(mid 272.342906 -328.852064)
		(end 272.39595 -328.724006)
		(width 0.127)
		(layer "B.Cu")
		(net "PHY_SCC_A_TO_DRV_A_17_DN")
	)
	(segment
		(start 159.620966 -158.829756)
		(end 160.03905 -158.829756)
		(width 0.127)
		(layer "F.Cu")
		(net "PHY_SCC_A_TO_DRV_A_16_DP")
	)
	(segment
		(start 206.233268 -266.491212)
		(end 239.3061 -318.75349)
		(width 0.127)
		(layer "F.Cu")
		(net "PHY_SCC_A_TO_DRV_A_16_DP")
	)
	(segment
		(start 163.195762 -161.779458)
		(end 166.646352 -177.34407)
		(width 0.127)
		(layer "F.Cu")
		(net "PHY_SCC_A_TO_DRV_A_16_DP")
	)
	(segment
		(start 270.768064 -329.613768)
		(end 272.26895 -329.613768)
		(width 0.127)
		(layer "F.Cu")
		(net "PHY_SCC_A_TO_DRV_A_16_DP")
	)
	(segment
		(start 158.942786 -158.660592)
		(end 159.451802 -158.660592)
		(width 0.127)
		(layer "F.Cu")
		(net "PHY_SCC_A_TO_DRV_A_16_DP")
	)
	(segment
		(start 160.554162 -158.944056)
		(end 161.959798 -159.83966)
		(width 0.127)
		(layer "F.Cu")
		(net "PHY_SCC_A_TO_DRV_A_16_DP")
	)
	(segment
		(start 272.68805 -330.032868)
		(end 272.68805 -330.577952)
		(width 0.127)
		(layer "F.Cu")
		(net "PHY_SCC_A_TO_DRV_A_16_DP")
	)
	(segment
		(start 161.959798 -159.83966)
		(end 163.195762 -161.779458)
		(width 0.127)
		(layer "F.Cu")
		(net "PHY_SCC_A_TO_DRV_A_16_DP")
	)
	(segment
		(start 166.646352 -177.34407)
		(end 195.316602 -216.79662)
		(width 0.127)
		(layer "F.Cu")
		(net "PHY_SCC_A_TO_DRV_A_16_DP")
	)
	(segment
		(start 159.451802 -158.660592)
		(end 159.620966 -158.829756)
		(width 0.127)
		(layer "F.Cu")
		(net "PHY_SCC_A_TO_DRV_A_16_DP")
	)
	(segment
		(start 160.03905 -158.829756)
		(end 160.554162 -158.944056)
		(width 0.127)
		(layer "F.Cu")
		(net "PHY_SCC_A_TO_DRV_A_16_DP")
	)
	(segment
		(start 195.316602 -216.79662)
		(end 206.233268 -266.491212)
		(width 0.127)
		(layer "F.Cu")
		(net "PHY_SCC_A_TO_DRV_A_16_DP")
	)
	(segment
		(start 239.3061 -318.75349)
		(end 270.768064 -329.613768)
		(width 0.127)
		(layer "F.Cu")
		(net "PHY_SCC_A_TO_DRV_A_16_DP")
	)
	(segment
		(start 272.81505 -330.704952)
		(end 273.1135 -330.704952)
		(width 0.127)
		(layer "F.Cu")
		(net "PHY_SCC_A_TO_DRV_A_16_DP")
	)
	(arc
		(start 272.68805 -330.577952)
		(mid 272.725247 -330.667755)
		(end 272.81505 -330.704952)
		(width 0.127)
		(layer "F.Cu")
		(net "PHY_SCC_A_TO_DRV_A_16_DP")
	)
	(arc
		(start 272.26895 -329.613768)
		(mid 272.565298 -329.73652)
		(end 272.68805 -330.032868)
		(width 0.127)
		(layer "F.Cu")
		(net "PHY_SCC_A_TO_DRV_A_16_DP")
	)
	(segment
		(start 280.082752 -329.28306)
		(end 280.082752 -329.032108)
		(width 0.127)
		(layer "B.Cu")
		(net "PHY_SCC_A_TO_DRV_A_16_DP")
	)
	(segment
		(start 280.209752 -328.905108)
		(end 280.636726 -328.905108)
		(width 0.127)
		(layer "B.Cu")
		(net "PHY_SCC_A_TO_DRV_A_16_DP")
	)
	(segment
		(start 273.1135 -330.704952)
		(end 272.869152 -330.704952)
		(width 0.127)
		(layer "B.Cu")
		(net "PHY_SCC_A_TO_DRV_A_16_DP")
	)
	(segment
		(start 272.68805 -330.52385)
		(end 272.68805 -330.37526)
		(width 0.127)
		(layer "B.Cu")
		(net "PHY_SCC_A_TO_DRV_A_16_DP")
	)
	(segment
		(start 273.11223 -329.95108)
		(end 279.329134 -329.95108)
		(width 0.127)
		(layer "B.Cu")
		(net "PHY_SCC_A_TO_DRV_A_16_DP")
	)
	(arc
		(start 279.904698 -329.713082)
		(mid 279.92788 -329.688564)
		(end 279.949656 -329.66279)
		(width 0.127)
		(layer "B.Cu")
		(net "PHY_SCC_A_TO_DRV_A_16_DP")
	)
	(arc
		(start 279.329134 -329.95108)
		(mid 279.640578 -329.889317)
		(end 279.904698 -329.713082)
		(width 0.127)
		(layer "B.Cu")
		(net "PHY_SCC_A_TO_DRV_A_16_DP")
	)
	(arc
		(start 272.869152 -330.704952)
		(mid 272.741094 -330.651908)
		(end 272.68805 -330.52385)
		(width 0.127)
		(layer "B.Cu")
		(net "PHY_SCC_A_TO_DRV_A_16_DP")
	)
	(arc
		(start 279.949656 -329.66279)
		(mid 280.048501 -329.484247)
		(end 280.082752 -329.28306)
		(width 0.127)
		(layer "B.Cu")
		(net "PHY_SCC_A_TO_DRV_A_16_DP")
	)
	(arc
		(start 280.082752 -329.032108)
		(mid 280.119949 -328.942305)
		(end 280.209752 -328.905108)
		(width 0.127)
		(layer "B.Cu")
		(net "PHY_SCC_A_TO_DRV_A_16_DP")
	)
	(arc
		(start 272.68805 -330.37526)
		(mid 272.812289 -330.075319)
		(end 273.11223 -329.95108)
		(width 0.127)
		(layer "B.Cu")
		(net "PHY_SCC_A_TO_DRV_A_16_DP")
	)
	(segment
		(start 239.114076 -318.996314)
		(end 270.719042 -329.905868)
		(width 0.127)
		(layer "F.Cu")
		(net "PHY_SCC_A_TO_DRV_A_16_DN")
	)
	(segment
		(start 166.374572 -177.467006)
		(end 195.044314 -216.919048)
		(width 0.127)
		(layer "F.Cu")
		(net "PHY_SCC_A_TO_DRV_A_16_DN")
	)
	(segment
		(start 270.719042 -329.905868)
		(end 272.26895 -329.905868)
		(width 0.127)
		(layer "F.Cu")
		(net "PHY_SCC_A_TO_DRV_A_16_DN")
	)
	(segment
		(start 159.549338 -159.121856)
		(end 160.006792 -159.121856)
		(width 0.127)
		(layer "F.Cu")
		(net "PHY_SCC_A_TO_DRV_A_16_DN")
	)
	(segment
		(start 158.942786 -159.219392)
		(end 159.451802 -159.219392)
		(width 0.127)
		(layer "F.Cu")
		(net "PHY_SCC_A_TO_DRV_A_16_DN")
	)
	(segment
		(start 165.09873 -172.417486)
		(end 165.280594 -172.53331)
		(width 0.127)
		(layer "F.Cu")
		(net "PHY_SCC_A_TO_DRV_A_16_DN")
	)
	(segment
		(start 165.478206 -174.128684)
		(end 165.560502 -174.50054)
		(width 0.127)
		(layer "F.Cu")
		(net "PHY_SCC_A_TO_DRV_A_16_DN")
	)
	(segment
		(start 162.921696 -161.892996)
		(end 165.132004 -171.863766)
		(width 0.127)
		(layer "F.Cu")
		(net "PHY_SCC_A_TO_DRV_A_16_DN")
	)
	(segment
		(start 165.132004 -171.863766)
		(end 165.016434 -172.04563)
		(width 0.127)
		(layer "F.Cu")
		(net "PHY_SCC_A_TO_DRV_A_16_DN")
	)
	(segment
		(start 166.374318 -177.467006)
		(end 166.374572 -177.467006)
		(width 0.127)
		(layer "F.Cu")
		(net "PHY_SCC_A_TO_DRV_A_16_DN")
	)
	(segment
		(start 165.24732 -173.08703)
		(end 165.329616 -173.45914)
		(width 0.127)
		(layer "F.Cu")
		(net "PHY_SCC_A_TO_DRV_A_16_DN")
	)
	(segment
		(start 272.26895 -330.704952)
		(end 271.9705 -330.704952)
		(width 0.127)
		(layer "F.Cu")
		(net "PHY_SCC_A_TO_DRV_A_16_DN")
	)
	(segment
		(start 159.451802 -159.219392)
		(end 159.549338 -159.121856)
		(width 0.127)
		(layer "F.Cu")
		(net "PHY_SCC_A_TO_DRV_A_16_DN")
	)
	(segment
		(start 205.958948 -266.603988)
		(end 239.114076 -318.996314)
		(width 0.127)
		(layer "F.Cu")
		(net "PHY_SCC_A_TO_DRV_A_16_DN")
	)
	(segment
		(start 165.709092 -175.170084)
		(end 165.791388 -175.542194)
		(width 0.127)
		(layer "F.Cu")
		(net "PHY_SCC_A_TO_DRV_A_16_DN")
	)
	(segment
		(start 272.39595 -330.032868)
		(end 272.39595 -330.577952)
		(width 0.127)
		(layer "F.Cu")
		(net "PHY_SCC_A_TO_DRV_A_16_DN")
	)
	(segment
		(start 161.748216 -160.051242)
		(end 162.921696 -161.892996)
		(width 0.127)
		(layer "F.Cu")
		(net "PHY_SCC_A_TO_DRV_A_16_DN")
	)
	(segment
		(start 165.791388 -175.542194)
		(end 165.973252 -175.658018)
		(width 0.127)
		(layer "F.Cu")
		(net "PHY_SCC_A_TO_DRV_A_16_DN")
	)
	(segment
		(start 165.824916 -174.988474)
		(end 165.709092 -175.170084)
		(width 0.127)
		(layer "F.Cu")
		(net "PHY_SCC_A_TO_DRV_A_16_DN")
	)
	(segment
		(start 165.973252 -175.658018)
		(end 166.374318 -177.467006)
		(width 0.127)
		(layer "F.Cu")
		(net "PHY_SCC_A_TO_DRV_A_16_DN")
	)
	(segment
		(start 165.363144 -172.90542)
		(end 165.24732 -173.08703)
		(width 0.127)
		(layer "F.Cu")
		(net "PHY_SCC_A_TO_DRV_A_16_DN")
	)
	(segment
		(start 165.742366 -174.616364)
		(end 165.824916 -174.988474)
		(width 0.127)
		(layer "F.Cu")
		(net "PHY_SCC_A_TO_DRV_A_16_DN")
	)
	(segment
		(start 165.016434 -172.04563)
		(end 165.09873 -172.417486)
		(width 0.127)
		(layer "F.Cu")
		(net "PHY_SCC_A_TO_DRV_A_16_DN")
	)
	(segment
		(start 165.51148 -173.574964)
		(end 165.59403 -173.94682)
		(width 0.127)
		(layer "F.Cu")
		(net "PHY_SCC_A_TO_DRV_A_16_DN")
	)
	(segment
		(start 165.560502 -174.50054)
		(end 165.742366 -174.616364)
		(width 0.127)
		(layer "F.Cu")
		(net "PHY_SCC_A_TO_DRV_A_16_DN")
	)
	(segment
		(start 195.044314 -216.919048)
		(end 205.958948 -266.603988)
		(width 0.127)
		(layer "F.Cu")
		(net "PHY_SCC_A_TO_DRV_A_16_DN")
	)
	(segment
		(start 165.329616 -173.45914)
		(end 165.51148 -173.574964)
		(width 0.127)
		(layer "F.Cu")
		(net "PHY_SCC_A_TO_DRV_A_16_DN")
	)
	(segment
		(start 165.59403 -173.94682)
		(end 165.478206 -174.128684)
		(width 0.127)
		(layer "F.Cu")
		(net "PHY_SCC_A_TO_DRV_A_16_DN")
	)
	(segment
		(start 165.280594 -172.53331)
		(end 165.363144 -172.90542)
		(width 0.127)
		(layer "F.Cu")
		(net "PHY_SCC_A_TO_DRV_A_16_DN")
	)
	(segment
		(start 160.006792 -159.121856)
		(end 160.440624 -159.218122)
		(width 0.127)
		(layer "F.Cu")
		(net "PHY_SCC_A_TO_DRV_A_16_DN")
	)
	(segment
		(start 160.440624 -159.218122)
		(end 161.748216 -160.051242)
		(width 0.127)
		(layer "F.Cu")
		(net "PHY_SCC_A_TO_DRV_A_16_DN")
	)
	(arc
		(start 272.26895 -329.905868)
		(mid 272.358753 -329.943065)
		(end 272.39595 -330.032868)
		(width 0.127)
		(layer "F.Cu")
		(net "PHY_SCC_A_TO_DRV_A_16_DN")
	)
	(arc
		(start 272.39595 -330.577952)
		(mid 272.358753 -330.667755)
		(end 272.26895 -330.704952)
		(width 0.127)
		(layer "F.Cu")
		(net "PHY_SCC_A_TO_DRV_A_16_DN")
	)
	(segment
		(start 279.663652 -328.905108)
		(end 279.236678 -328.905108)
		(width 0.127)
		(layer "B.Cu")
		(net "PHY_SCC_A_TO_DRV_A_16_DN")
	)
	(segment
		(start 273.11223 -329.65898)
		(end 279.329388 -329.65898)
		(width 0.127)
		(layer "B.Cu")
		(net "PHY_SCC_A_TO_DRV_A_16_DN")
	)
	(segment
		(start 271.9705 -330.704952)
		(end 272.214848 -330.704952)
		(width 0.127)
		(layer "B.Cu")
		(net "PHY_SCC_A_TO_DRV_A_16_DN")
	)
	(segment
		(start 272.39595 -330.52385)
		(end 272.39595 -330.37526)
		(width 0.127)
		(layer "B.Cu")
		(net "PHY_SCC_A_TO_DRV_A_16_DN")
	)
	(segment
		(start 279.790652 -329.282552)
		(end 279.790652 -329.032108)
		(width 0.127)
		(layer "B.Cu")
		(net "PHY_SCC_A_TO_DRV_A_16_DN")
	)
	(arc
		(start 279.790652 -329.032108)
		(mid 279.753455 -328.942305)
		(end 279.663652 -328.905108)
		(width 0.127)
		(layer "B.Cu")
		(net "PHY_SCC_A_TO_DRV_A_16_DN")
	)
	(arc
		(start 272.214848 -330.704952)
		(mid 272.342906 -330.651908)
		(end 272.39595 -330.52385)
		(width 0.127)
		(layer "B.Cu")
		(net "PHY_SCC_A_TO_DRV_A_16_DN")
	)
	(arc
		(start 279.329388 -329.65898)
		(mid 279.528846 -329.619305)
		(end 279.697942 -329.506326)
		(width 0.127)
		(layer "B.Cu")
		(net "PHY_SCC_A_TO_DRV_A_16_DN")
	)
	(arc
		(start 272.39595 -330.37526)
		(mid 272.605744 -329.868774)
		(end 273.11223 -329.65898)
		(width 0.127)
		(layer "B.Cu")
		(net "PHY_SCC_A_TO_DRV_A_16_DN")
	)
	(arc
		(start 279.72131 -329.480164)
		(mid 279.772817 -329.387265)
		(end 279.790652 -329.282552)
		(width 0.127)
		(layer "B.Cu")
		(net "PHY_SCC_A_TO_DRV_A_16_DN")
	)
	(arc
		(start 279.697942 -329.506326)
		(mid 279.709986 -329.493566)
		(end 279.72131 -329.480164)
		(width 0.127)
		(layer "B.Cu")
		(net "PHY_SCC_A_TO_DRV_A_16_DN")
	)
	(segment
		(start 270.973296 -331.521816)
		(end 272.26895 -331.521816)
		(width 0.127)
		(layer "F.Cu")
		(net "PHY_SCC_A_TO_DRV_A_15_DP")
	)
	(segment
		(start 129.96926 -159.641794)
		(end 132.091938 -162.973766)
		(width 0.127)
		(layer "F.Cu")
		(net "PHY_SCC_A_TO_DRV_A_15_DP")
	)
	(segment
		(start 196.380354 -258.854702)
		(end 234.362244 -318.893698)
		(width 0.127)
		(layer "F.Cu")
		(net "PHY_SCC_A_TO_DRV_A_15_DP")
	)
	(segment
		(start 127.901446 -158.834582)
		(end 128.352296 -158.834582)
		(width 0.127)
		(layer "F.Cu")
		(net "PHY_SCC_A_TO_DRV_A_15_DP")
	)
	(segment
		(start 188.103256 -254.194056)
		(end 196.380354 -258.854702)
		(width 0.127)
		(layer "F.Cu")
		(net "PHY_SCC_A_TO_DRV_A_15_DP")
	)
	(segment
		(start 127.392684 -158.660592)
		(end 127.727456 -158.660592)
		(width 0.127)
		(layer "F.Cu")
		(net "PHY_SCC_A_TO_DRV_A_15_DP")
	)
	(segment
		(start 127.727456 -158.660592)
		(end 127.901446 -158.834582)
		(width 0.127)
		(layer "F.Cu")
		(net "PHY_SCC_A_TO_DRV_A_15_DP")
	)
	(segment
		(start 128.352296 -158.834582)
		(end 128.890014 -158.953962)
		(width 0.127)
		(layer "F.Cu")
		(net "PHY_SCC_A_TO_DRV_A_15_DP")
	)
	(segment
		(start 272.81505 -332.50505)
		(end 273.1135 -332.50505)
		(width 0.127)
		(layer "F.Cu")
		(net "PHY_SCC_A_TO_DRV_A_15_DP")
	)
	(segment
		(start 132.091938 -162.973766)
		(end 139.838938 -197.918578)
		(width 0.127)
		(layer "F.Cu")
		(net "PHY_SCC_A_TO_DRV_A_15_DP")
	)
	(segment
		(start 272.68805 -331.940916)
		(end 272.68805 -332.37805)
		(width 0.127)
		(layer "F.Cu")
		(net "PHY_SCC_A_TO_DRV_A_15_DP")
	)
	(segment
		(start 234.362244 -318.893698)
		(end 270.973296 -331.521816)
		(width 0.127)
		(layer "F.Cu")
		(net "PHY_SCC_A_TO_DRV_A_15_DP")
	)
	(segment
		(start 139.838938 -197.918578)
		(end 168.744646 -243.293646)
		(width 0.127)
		(layer "F.Cu")
		(net "PHY_SCC_A_TO_DRV_A_15_DP")
	)
	(segment
		(start 128.890014 -158.953962)
		(end 129.96926 -159.641794)
		(width 0.127)
		(layer "F.Cu")
		(net "PHY_SCC_A_TO_DRV_A_15_DP")
	)
	(segment
		(start 168.744646 -243.293646)
		(end 188.103256 -254.194056)
		(width 0.127)
		(layer "F.Cu")
		(net "PHY_SCC_A_TO_DRV_A_15_DP")
	)
	(arc
		(start 272.26895 -331.521816)
		(mid 272.565298 -331.644568)
		(end 272.68805 -331.940916)
		(width 0.127)
		(layer "F.Cu")
		(net "PHY_SCC_A_TO_DRV_A_15_DP")
	)
	(arc
		(start 272.68805 -332.37805)
		(mid 272.725247 -332.467853)
		(end 272.81505 -332.50505)
		(width 0.127)
		(layer "F.Cu")
		(net "PHY_SCC_A_TO_DRV_A_15_DP")
	)
	(segment
		(start 272.68805 -332.175358)
		(end 272.68805 -332.323948)
		(width 0.127)
		(layer "B.Cu")
		(net "PHY_SCC_A_TO_DRV_A_15_DP")
	)
	(segment
		(start 279.636728 -330.705206)
		(end 279.209754 -330.705206)
		(width 0.127)
		(layer "B.Cu")
		(net "PHY_SCC_A_TO_DRV_A_15_DP")
	)
	(segment
		(start 272.869152 -332.50505)
		(end 273.1135 -332.50505)
		(width 0.127)
		(layer "B.Cu")
		(net "PHY_SCC_A_TO_DRV_A_15_DP")
	)
	(segment
		(start 278.329136 -331.751178)
		(end 273.11223 -331.751178)
		(width 0.127)
		(layer "B.Cu")
		(net "PHY_SCC_A_TO_DRV_A_15_DP")
	)
	(segment
		(start 279.082754 -330.832206)
		(end 279.082754 -331.083158)
		(width 0.127)
		(layer "B.Cu")
		(net "PHY_SCC_A_TO_DRV_A_15_DP")
	)
	(arc
		(start 279.209754 -330.705206)
		(mid 279.119951 -330.742403)
		(end 279.082754 -330.832206)
		(width 0.127)
		(layer "B.Cu")
		(net "PHY_SCC_A_TO_DRV_A_15_DP")
	)
	(arc
		(start 272.68805 -332.323948)
		(mid 272.741094 -332.452006)
		(end 272.869152 -332.50505)
		(width 0.127)
		(layer "B.Cu")
		(net "PHY_SCC_A_TO_DRV_A_15_DP")
	)
	(arc
		(start 279.082754 -331.083158)
		(mid 279.04852 -331.284351)
		(end 278.949658 -331.462888)
		(width 0.127)
		(layer "B.Cu")
		(net "PHY_SCC_A_TO_DRV_A_15_DP")
	)
	(arc
		(start 278.949658 -331.462888)
		(mid 278.927871 -331.488653)
		(end 278.9047 -331.51318)
		(width 0.127)
		(layer "B.Cu")
		(net "PHY_SCC_A_TO_DRV_A_15_DP")
	)
	(arc
		(start 278.9047 -331.51318)
		(mid 278.640599 -331.689461)
		(end 278.329136 -331.751178)
		(width 0.127)
		(layer "B.Cu")
		(net "PHY_SCC_A_TO_DRV_A_15_DP")
	)
	(arc
		(start 273.11223 -331.751178)
		(mid 272.812289 -331.875417)
		(end 272.68805 -332.175358)
		(width 0.127)
		(layer "B.Cu")
		(net "PHY_SCC_A_TO_DRV_A_15_DP")
	)
	(segment
		(start 230.293418 -313.008772)
		(end 230.497126 -313.33059)
		(width 0.127)
		(layer "F.Cu")
		(net "PHY_SCC_A_TO_DRV_A_15_DN")
	)
	(segment
		(start 231.433878 -314.811664)
		(end 234.169966 -319.136522)
		(width 0.127)
		(layer "F.Cu")
		(net "PHY_SCC_A_TO_DRV_A_15_DN")
	)
	(segment
		(start 229.309168 -311.737756)
		(end 229.512876 -312.059828)
		(width 0.127)
		(layer "F.Cu")
		(net "PHY_SCC_A_TO_DRV_A_15_DN")
	)
	(segment
		(start 168.537382 -243.51234)
		(end 175.239172 -247.286018)
		(width 0.127)
		(layer "F.Cu")
		(net "PHY_SCC_A_TO_DRV_A_15_DN")
	)
	(segment
		(start 270.924274 -331.813916)
		(end 272.26895 -331.813916)
		(width 0.127)
		(layer "F.Cu")
		(net "PHY_SCC_A_TO_DRV_A_15_DN")
	)
	(segment
		(start 127.761492 -159.219392)
		(end 127.854202 -159.126682)
		(width 0.127)
		(layer "F.Cu")
		(net "PHY_SCC_A_TO_DRV_A_15_DN")
	)
	(segment
		(start 230.497126 -313.33059)
		(end 230.449882 -313.540902)
		(width 0.127)
		(layer "F.Cu")
		(net "PHY_SCC_A_TO_DRV_A_15_DN")
	)
	(segment
		(start 230.863648 -313.910218)
		(end 231.067356 -314.23229)
		(width 0.127)
		(layer "F.Cu")
		(net "PHY_SCC_A_TO_DRV_A_15_DN")
	)
	(segment
		(start 127.854202 -159.126682)
		(end 128.320038 -159.126682)
		(width 0.127)
		(layer "F.Cu")
		(net "PHY_SCC_A_TO_DRV_A_15_DN")
	)
	(segment
		(start 230.083106 -312.961274)
		(end 230.293418 -313.008772)
		(width 0.127)
		(layer "F.Cu")
		(net "PHY_SCC_A_TO_DRV_A_15_DN")
	)
	(segment
		(start 229.512876 -312.059828)
		(end 229.722934 -312.107072)
		(width 0.127)
		(layer "F.Cu")
		(net "PHY_SCC_A_TO_DRV_A_15_DN")
	)
	(segment
		(start 234.169966 -319.136522)
		(end 270.924274 -331.813916)
		(width 0.127)
		(layer "F.Cu")
		(net "PHY_SCC_A_TO_DRV_A_15_DN")
	)
	(segment
		(start 230.653336 -313.862974)
		(end 230.863648 -313.910218)
		(width 0.127)
		(layer "F.Cu")
		(net "PHY_SCC_A_TO_DRV_A_15_DN")
	)
	(segment
		(start 127.392684 -159.219392)
		(end 127.761492 -159.219392)
		(width 0.127)
		(layer "F.Cu")
		(net "PHY_SCC_A_TO_DRV_A_15_DN")
	)
	(segment
		(start 229.356412 -311.527444)
		(end 229.309168 -311.737756)
		(width 0.127)
		(layer "F.Cu")
		(net "PHY_SCC_A_TO_DRV_A_15_DN")
	)
	(segment
		(start 272.39595 -331.940916)
		(end 272.39595 -332.37805)
		(width 0.127)
		(layer "F.Cu")
		(net "PHY_SCC_A_TO_DRV_A_15_DN")
	)
	(segment
		(start 139.564872 -198.032116)
		(end 168.537382 -243.51234)
		(width 0.127)
		(layer "F.Cu")
		(net "PHY_SCC_A_TO_DRV_A_15_DN")
	)
	(segment
		(start 229.722934 -312.107072)
		(end 229.926642 -312.429144)
		(width 0.127)
		(layer "F.Cu")
		(net "PHY_SCC_A_TO_DRV_A_15_DN")
	)
	(segment
		(start 131.817872 -163.087304)
		(end 139.564872 -198.032116)
		(width 0.127)
		(layer "F.Cu")
		(net "PHY_SCC_A_TO_DRV_A_15_DN")
	)
	(segment
		(start 231.22382 -314.76442)
		(end 231.433878 -314.811664)
		(width 0.127)
		(layer "F.Cu")
		(net "PHY_SCC_A_TO_DRV_A_15_DN")
	)
	(segment
		(start 196.172836 -259.073142)
		(end 229.356412 -311.527444)
		(width 0.127)
		(layer "F.Cu")
		(net "PHY_SCC_A_TO_DRV_A_15_DN")
	)
	(segment
		(start 229.879398 -312.639456)
		(end 230.083106 -312.961274)
		(width 0.127)
		(layer "F.Cu")
		(net "PHY_SCC_A_TO_DRV_A_15_DN")
	)
	(segment
		(start 272.26895 -332.50505)
		(end 271.9705 -332.50505)
		(width 0.127)
		(layer "F.Cu")
		(net "PHY_SCC_A_TO_DRV_A_15_DN")
	)
	(segment
		(start 187.959746 -254.448818)
		(end 196.172836 -259.073142)
		(width 0.127)
		(layer "F.Cu")
		(net "PHY_SCC_A_TO_DRV_A_15_DN")
	)
	(segment
		(start 231.020112 -314.442348)
		(end 231.22382 -314.76442)
		(width 0.127)
		(layer "F.Cu")
		(net "PHY_SCC_A_TO_DRV_A_15_DN")
	)
	(segment
		(start 128.320038 -159.126682)
		(end 128.776476 -159.228028)
		(width 0.127)
		(layer "F.Cu")
		(net "PHY_SCC_A_TO_DRV_A_15_DN")
	)
	(segment
		(start 128.776476 -159.228028)
		(end 129.757678 -159.853376)
		(width 0.127)
		(layer "F.Cu")
		(net "PHY_SCC_A_TO_DRV_A_15_DN")
	)
	(segment
		(start 231.067356 -314.23229)
		(end 231.020112 -314.442348)
		(width 0.127)
		(layer "F.Cu")
		(net "PHY_SCC_A_TO_DRV_A_15_DN")
	)
	(segment
		(start 230.449882 -313.540902)
		(end 230.653336 -313.862974)
		(width 0.127)
		(layer "F.Cu")
		(net "PHY_SCC_A_TO_DRV_A_15_DN")
	)
	(segment
		(start 129.757678 -159.853376)
		(end 131.817872 -163.087304)
		(width 0.127)
		(layer "F.Cu")
		(net "PHY_SCC_A_TO_DRV_A_15_DN")
	)
	(segment
		(start 175.239172 -247.286018)
		(end 187.959746 -254.448818)
		(width 0.127)
		(layer "F.Cu")
		(net "PHY_SCC_A_TO_DRV_A_15_DN")
	)
	(segment
		(start 229.926642 -312.429144)
		(end 229.879398 -312.639456)
		(width 0.127)
		(layer "F.Cu")
		(net "PHY_SCC_A_TO_DRV_A_15_DN")
	)
	(arc
		(start 272.39595 -332.37805)
		(mid 272.358753 -332.467853)
		(end 272.26895 -332.50505)
		(width 0.127)
		(layer "F.Cu")
		(net "PHY_SCC_A_TO_DRV_A_15_DN")
	)
	(arc
		(start 272.26895 -331.813916)
		(mid 272.358753 -331.851113)
		(end 272.39595 -331.940916)
		(width 0.127)
		(layer "F.Cu")
		(net "PHY_SCC_A_TO_DRV_A_15_DN")
	)
	(segment
		(start 271.9705 -332.50505)
		(end 272.214848 -332.50505)
		(width 0.127)
		(layer "B.Cu")
		(net "PHY_SCC_A_TO_DRV_A_15_DN")
	)
	(segment
		(start 278.663654 -330.705206)
		(end 278.23668 -330.705206)
		(width 0.127)
		(layer "B.Cu")
		(net "PHY_SCC_A_TO_DRV_A_15_DN")
	)
	(segment
		(start 278.790654 -331.08265)
		(end 278.790654 -330.832206)
		(width 0.127)
		(layer "B.Cu")
		(net "PHY_SCC_A_TO_DRV_A_15_DN")
	)
	(segment
		(start 272.39595 -332.323948)
		(end 272.39595 -332.175358)
		(width 0.127)
		(layer "B.Cu")
		(net "PHY_SCC_A_TO_DRV_A_15_DN")
	)
	(segment
		(start 273.11223 -331.459078)
		(end 278.32939 -331.459078)
		(width 0.127)
		(layer "B.Cu")
		(net "PHY_SCC_A_TO_DRV_A_15_DN")
	)
	(arc
		(start 278.697944 -331.306424)
		(mid 278.709988 -331.293664)
		(end 278.721312 -331.280262)
		(width 0.127)
		(layer "B.Cu")
		(net "PHY_SCC_A_TO_DRV_A_15_DN")
	)
	(arc
		(start 272.214848 -332.50505)
		(mid 272.342906 -332.452006)
		(end 272.39595 -332.323948)
		(width 0.127)
		(layer "B.Cu")
		(net "PHY_SCC_A_TO_DRV_A_15_DN")
	)
	(arc
		(start 278.790654 -330.832206)
		(mid 278.753457 -330.742403)
		(end 278.663654 -330.705206)
		(width 0.127)
		(layer "B.Cu")
		(net "PHY_SCC_A_TO_DRV_A_15_DN")
	)
	(arc
		(start 278.32939 -331.459078)
		(mid 278.528848 -331.419403)
		(end 278.697944 -331.306424)
		(width 0.127)
		(layer "B.Cu")
		(net "PHY_SCC_A_TO_DRV_A_15_DN")
	)
	(arc
		(start 272.39595 -332.175358)
		(mid 272.605744 -331.668872)
		(end 273.11223 -331.459078)
		(width 0.127)
		(layer "B.Cu")
		(net "PHY_SCC_A_TO_DRV_A_15_DN")
	)
	(arc
		(start 278.721312 -331.280262)
		(mid 278.772819 -331.187363)
		(end 278.790654 -331.08265)
		(width 0.127)
		(layer "B.Cu")
		(net "PHY_SCC_A_TO_DRV_A_15_DN")
	)
	(segment
		(start 271.413224 -333.32166)
		(end 250.779534 -326.204326)
		(width 0.127)
		(layer "F.Cu")
		(net "PHY_SCC_A_TO_DRV_A_14_DP")
	)
	(segment
		(start 137.713466 -230.189532)
		(end 124.143516 -227.294694)
		(width 0.127)
		(layer "F.Cu")
		(net "PHY_SCC_A_TO_DRV_A_14_DP")
	)
	(segment
		(start 108.216192 -200.649078)
		(end 102.296468 -173.922436)
		(width 0.127)
		(layer "F.Cu")
		(net "PHY_SCC_A_TO_DRV_A_14_DP")
	)
	(segment
		(start 191.263016 -257.931666)
		(end 145.047716 -231.925368)
		(width 0.127)
		(layer "F.Cu")
		(net "PHY_SCC_A_TO_DRV_A_14_DP")
	)
	(segment
		(start 272.177256 -333.32166)
		(end 271.413224 -333.32166)
		(width 0.127)
		(layer "F.Cu")
		(net "PHY_SCC_A_TO_DRV_A_14_DP")
	)
	(segment
		(start 111.147606 -213.881716)
		(end 108.216192 -200.649078)
		(width 0.127)
		(layer "F.Cu")
		(net "PHY_SCC_A_TO_DRV_A_14_DP")
	)
	(segment
		(start 97.643442 -158.977838)
		(end 97.442528 -158.933134)
		(width 0.127)
		(layer "F.Cu")
		(net "PHY_SCC_A_TO_DRV_A_14_DP")
	)
	(segment
		(start 124.143516 -227.294694)
		(end 123.600972 -227.17887)
		(width 0.127)
		(layer "F.Cu")
		(net "PHY_SCC_A_TO_DRV_A_14_DP")
	)
	(segment
		(start 97.442528 -158.933134)
		(end 96.959674 -158.825946)
		(width 0.127)
		(layer "F.Cu")
		(net "PHY_SCC_A_TO_DRV_A_14_DP")
	)
	(segment
		(start 102.296468 -173.922436)
		(end 102.296214 -173.922436)
		(width 0.127)
		(layer "F.Cu")
		(net "PHY_SCC_A_TO_DRV_A_14_DP")
	)
	(segment
		(start 98.65487 -159.621728)
		(end 97.643442 -158.977838)
		(width 0.127)
		(layer "F.Cu")
		(net "PHY_SCC_A_TO_DRV_A_14_DP")
	)
	(segment
		(start 96.215708 -158.660592)
		(end 95.842836 -158.660592)
		(width 0.127)
		(layer "F.Cu")
		(net "PHY_SCC_A_TO_DRV_A_14_DP")
	)
	(segment
		(start 144.562068 -231.65181)
		(end 137.713466 -230.189532)
		(width 0.127)
		(layer "F.Cu")
		(net "PHY_SCC_A_TO_DRV_A_14_DP")
	)
	(segment
		(start 120.343676 -226.483926)
		(end 115.742974 -223.229932)
		(width 0.127)
		(layer "F.Cu")
		(net "PHY_SCC_A_TO_DRV_A_14_DP")
	)
	(segment
		(start 145.048224 -231.92486)
		(end 144.562068 -231.65181)
		(width 0.127)
		(layer "F.Cu")
		(net "PHY_SCC_A_TO_DRV_A_14_DP")
	)
	(segment
		(start 233.098086 -320.105024)
		(end 195.136008 -260.11124)
		(width 0.127)
		(layer "F.Cu")
		(net "PHY_SCC_A_TO_DRV_A_14_DP")
	)
	(segment
		(start 250.779534 -326.203818)
		(end 233.098086 -320.105024)
		(width 0.127)
		(layer "F.Cu")
		(net "PHY_SCC_A_TO_DRV_A_14_DP")
	)
	(segment
		(start 250.779534 -326.204326)
		(end 250.779534 -326.203818)
		(width 0.127)
		(layer "F.Cu")
		(net "PHY_SCC_A_TO_DRV_A_14_DP")
	)
	(segment
		(start 123.600972 -227.17887)
		(end 120.343676 -226.483926)
		(width 0.127)
		(layer "F.Cu")
		(net "PHY_SCC_A_TO_DRV_A_14_DP")
	)
	(segment
		(start 96.959674 -158.825946)
		(end 96.381062 -158.825946)
		(width 0.127)
		(layer "F.Cu")
		(net "PHY_SCC_A_TO_DRV_A_14_DP")
	)
	(segment
		(start 99.380802 -160.759648)
		(end 98.65487 -159.621728)
		(width 0.127)
		(layer "F.Cu")
		(net "PHY_SCC_A_TO_DRV_A_14_DP")
	)
	(segment
		(start 195.136008 -260.11124)
		(end 191.263016 -257.931666)
		(width 0.127)
		(layer "F.Cu")
		(net "PHY_SCC_A_TO_DRV_A_14_DP")
	)
	(segment
		(start 273.1135 -334.304894)
		(end 272.81505 -334.304894)
		(width 0.127)
		(layer "F.Cu")
		(net "PHY_SCC_A_TO_DRV_A_14_DP")
	)
	(segment
		(start 115.742974 -223.229932)
		(end 111.147606 -213.881716)
		(width 0.127)
		(layer "F.Cu")
		(net "PHY_SCC_A_TO_DRV_A_14_DP")
	)
	(segment
		(start 96.381062 -158.825946)
		(end 96.215708 -158.660592)
		(width 0.127)
		(layer "F.Cu")
		(net "PHY_SCC_A_TO_DRV_A_14_DP")
	)
	(segment
		(start 272.68805 -334.177894)
		(end 272.68805 -333.832454)
		(width 0.127)
		(layer "F.Cu")
		(net "PHY_SCC_A_TO_DRV_A_14_DP")
	)
	(segment
		(start 145.047716 -231.925368)
		(end 145.048224 -231.92486)
		(width 0.127)
		(layer "F.Cu")
		(net "PHY_SCC_A_TO_DRV_A_14_DP")
	)
	(segment
		(start 102.296214 -173.922436)
		(end 99.380802 -160.759648)
		(width 0.127)
		(layer "F.Cu")
		(net "PHY_SCC_A_TO_DRV_A_14_DP")
	)
	(arc
		(start 272.81505 -334.304894)
		(mid 272.725247 -334.267697)
		(end 272.68805 -334.177894)
		(width 0.127)
		(layer "F.Cu")
		(net "PHY_SCC_A_TO_DRV_A_14_DP")
	)
	(arc
		(start 272.68805 -333.832454)
		(mid 272.538442 -333.471268)
		(end 272.177256 -333.32166)
		(width 0.127)
		(layer "F.Cu")
		(net "PHY_SCC_A_TO_DRV_A_14_DP")
	)
	(segment
		(start 280.209752 -332.50505)
		(end 280.636726 -332.50505)
		(width 0.127)
		(layer "B.Cu")
		(net "PHY_SCC_A_TO_DRV_A_14_DP")
	)
	(segment
		(start 280.082752 -332.883002)
		(end 280.082752 -332.63205)
		(width 0.127)
		(layer "B.Cu")
		(net "PHY_SCC_A_TO_DRV_A_14_DP")
	)
	(segment
		(start 272.68805 -334.123792)
		(end 272.68805 -333.975202)
		(width 0.127)
		(layer "B.Cu")
		(net "PHY_SCC_A_TO_DRV_A_14_DP")
	)
	(segment
		(start 273.1135 -334.304894)
		(end 272.869152 -334.304894)
		(width 0.127)
		(layer "B.Cu")
		(net "PHY_SCC_A_TO_DRV_A_14_DP")
	)
	(segment
		(start 273.11223 -333.551022)
		(end 279.329134 -333.551022)
		(width 0.127)
		(layer "B.Cu")
		(net "PHY_SCC_A_TO_DRV_A_14_DP")
	)
	(arc
		(start 279.329134 -333.551022)
		(mid 279.640578 -333.489259)
		(end 279.904698 -333.313024)
		(width 0.127)
		(layer "B.Cu")
		(net "PHY_SCC_A_TO_DRV_A_14_DP")
	)
	(arc
		(start 280.082752 -332.63205)
		(mid 280.119949 -332.542247)
		(end 280.209752 -332.50505)
		(width 0.127)
		(layer "B.Cu")
		(net "PHY_SCC_A_TO_DRV_A_14_DP")
	)
	(arc
		(start 272.68805 -333.975202)
		(mid 272.812289 -333.675261)
		(end 273.11223 -333.551022)
		(width 0.127)
		(layer "B.Cu")
		(net "PHY_SCC_A_TO_DRV_A_14_DP")
	)
	(arc
		(start 279.949656 -333.262732)
		(mid 280.048501 -333.084189)
		(end 280.082752 -332.883002)
		(width 0.127)
		(layer "B.Cu")
		(net "PHY_SCC_A_TO_DRV_A_14_DP")
	)
	(arc
		(start 279.904698 -333.313024)
		(mid 279.92788 -333.288506)
		(end 279.949656 -333.262732)
		(width 0.127)
		(layer "B.Cu")
		(net "PHY_SCC_A_TO_DRV_A_14_DP")
	)
	(arc
		(start 272.869152 -334.304894)
		(mid 272.741094 -334.25185)
		(end 272.68805 -334.123792)
		(width 0.127)
		(layer "B.Cu")
		(net "PHY_SCC_A_TO_DRV_A_14_DP")
	)
	(segment
		(start 250.130818 -326.450706)
		(end 250.03633 -326.256904)
		(width 0.127)
		(layer "F.Cu")
		(net "PHY_SCC_A_TO_DRV_A_14_DN")
	)
	(segment
		(start 271.9705 -334.304894)
		(end 272.26895 -334.304894)
		(width 0.127)
		(layer "F.Cu")
		(net "PHY_SCC_A_TO_DRV_A_14_DN")
	)
	(segment
		(start 247.659144 -325.436992)
		(end 247.465342 -325.531226)
		(width 0.127)
		(layer "F.Cu")
		(net "PHY_SCC_A_TO_DRV_A_14_DN")
	)
	(segment
		(start 97.529904 -159.251904)
		(end 97.033842 -159.141922)
		(width 0.127)
		(layer "F.Cu")
		(net "PHY_SCC_A_TO_DRV_A_14_DN")
	)
	(segment
		(start 249.122184 -326.10298)
		(end 249.02795 -325.909178)
		(width 0.127)
		(layer "F.Cu")
		(net "PHY_SCC_A_TO_DRV_A_14_DN")
	)
	(segment
		(start 247.010936 -325.213218)
		(end 240.006632 -322.797424)
		(width 0.127)
		(layer "F.Cu")
		(net "PHY_SCC_A_TO_DRV_A_14_DN")
	)
	(segment
		(start 121.91111 -227.117148)
		(end 120.223788 -226.75723)
		(width 0.127)
		(layer "F.Cu")
		(net "PHY_SCC_A_TO_DRV_A_14_DN")
	)
	(segment
		(start 249.482356 -326.227186)
		(end 249.122184 -326.10298)
		(width 0.127)
		(layer "F.Cu")
		(net "PHY_SCC_A_TO_DRV_A_14_DN")
	)
	(segment
		(start 98.443288 -159.833564)
		(end 97.529904 -159.251904)
		(width 0.127)
		(layer "F.Cu")
		(net "PHY_SCC_A_TO_DRV_A_14_DN")
	)
	(segment
		(start 271.364202 -333.61376)
		(end 250.684538 -326.480678)
		(width 0.127)
		(layer "F.Cu")
		(net "PHY_SCC_A_TO_DRV_A_14_DN")
	)
	(segment
		(start 96.927416 -159.118046)
		(end 96.376998 -159.118046)
		(width 0.127)
		(layer "F.Cu")
		(net "PHY_SCC_A_TO_DRV_A_14_DN")
	)
	(segment
		(start 144.457674 -231.928416)
		(end 137.652506 -230.475282)
		(width 0.127)
		(layer "F.Cu")
		(net "PHY_SCC_A_TO_DRV_A_14_DN")
	)
	(segment
		(start 272.39595 -334.177894)
		(end 272.39595 -333.832454)
		(width 0.127)
		(layer "F.Cu")
		(net "PHY_SCC_A_TO_DRV_A_14_DN")
	)
	(segment
		(start 247.10517 -325.40702)
		(end 247.010936 -325.213218)
		(width 0.127)
		(layer "F.Cu")
		(net "PHY_SCC_A_TO_DRV_A_14_DN")
	)
	(segment
		(start 110.86973 -213.979252)
		(end 107.93095 -200.712324)
		(width 0.127)
		(layer "F.Cu")
		(net "PHY_SCC_A_TO_DRV_A_14_DN")
	)
	(segment
		(start 248.667778 -325.784972)
		(end 248.473976 -325.879206)
		(width 0.127)
		(layer "F.Cu")
		(net "PHY_SCC_A_TO_DRV_A_14_DN")
	)
	(segment
		(start 124.082556 -227.580444)
		(end 123.540012 -227.46462)
		(width 0.127)
		(layer "F.Cu")
		(net "PHY_SCC_A_TO_DRV_A_14_DN")
	)
	(segment
		(start 272.177256 -333.61376)
		(end 271.364202 -333.61376)
		(width 0.127)
		(layer "F.Cu")
		(net "PHY_SCC_A_TO_DRV_A_14_DN")
	)
	(segment
		(start 99.106736 -160.873186)
		(end 98.443288 -159.833564)
		(width 0.127)
		(layer "F.Cu")
		(net "PHY_SCC_A_TO_DRV_A_14_DN")
	)
	(segment
		(start 232.906062 -320.347848)
		(end 194.92849 -260.32968)
		(width 0.127)
		(layer "F.Cu")
		(net "PHY_SCC_A_TO_DRV_A_14_DN")
	)
	(segment
		(start 248.473976 -325.879206)
		(end 248.113804 -325.755)
		(width 0.127)
		(layer "F.Cu")
		(net "PHY_SCC_A_TO_DRV_A_14_DN")
	)
	(segment
		(start 247.465342 -325.531226)
		(end 247.10517 -325.40702)
		(width 0.127)
		(layer "F.Cu")
		(net "PHY_SCC_A_TO_DRV_A_14_DN")
	)
	(segment
		(start 102.061518 -174.214536)
		(end 99.106736 -160.873186)
		(width 0.127)
		(layer "F.Cu")
		(net "PHY_SCC_A_TO_DRV_A_14_DN")
	)
	(segment
		(start 249.676158 -326.132698)
		(end 249.482356 -326.227186)
		(width 0.127)
		(layer "F.Cu")
		(net "PHY_SCC_A_TO_DRV_A_14_DN")
	)
	(segment
		(start 144.568672 -231.991154)
		(end 144.568926 -231.9909)
		(width 0.127)
		(layer "F.Cu")
		(net "PHY_SCC_A_TO_DRV_A_14_DN")
	)
	(segment
		(start 248.019316 -325.561198)
		(end 247.659144 -325.436992)
		(width 0.127)
		(layer "F.Cu")
		(net "PHY_SCC_A_TO_DRV_A_14_DN")
	)
	(segment
		(start 123.540012 -227.46462)
		(end 121.91111 -227.117148)
		(width 0.127)
		(layer "F.Cu")
		(net "PHY_SCC_A_TO_DRV_A_14_DN")
	)
	(segment
		(start 115.513612 -223.425512)
		(end 110.86973 -213.979252)
		(width 0.127)
		(layer "F.Cu")
		(net "PHY_SCC_A_TO_DRV_A_14_DN")
	)
	(segment
		(start 102.061772 -174.214536)
		(end 102.061518 -174.214536)
		(width 0.127)
		(layer "F.Cu")
		(net "PHY_SCC_A_TO_DRV_A_14_DN")
	)
	(segment
		(start 120.223788 -226.75723)
		(end 115.513612 -223.425512)
		(width 0.127)
		(layer "F.Cu")
		(net "PHY_SCC_A_TO_DRV_A_14_DN")
	)
	(segment
		(start 194.92849 -260.32968)
		(end 144.568672 -231.991154)
		(width 0.127)
		(layer "F.Cu")
		(net "PHY_SCC_A_TO_DRV_A_14_DN")
	)
	(segment
		(start 96.275652 -159.219392)
		(end 95.842836 -159.219392)
		(width 0.127)
		(layer "F.Cu")
		(net "PHY_SCC_A_TO_DRV_A_14_DN")
	)
	(segment
		(start 107.93095 -200.712324)
		(end 102.061772 -174.214536)
		(width 0.127)
		(layer "F.Cu")
		(net "PHY_SCC_A_TO_DRV_A_14_DN")
	)
	(segment
		(start 250.684538 -326.480678)
		(end 250.49099 -326.574912)
		(width 0.127)
		(layer "F.Cu")
		(net "PHY_SCC_A_TO_DRV_A_14_DN")
	)
	(segment
		(start 249.02795 -325.909178)
		(end 248.667778 -325.784972)
		(width 0.127)
		(layer "F.Cu")
		(net "PHY_SCC_A_TO_DRV_A_14_DN")
	)
	(segment
		(start 137.652506 -230.475282)
		(end 124.625354 -227.696268)
		(width 0.127)
		(layer "F.Cu")
		(net "PHY_SCC_A_TO_DRV_A_14_DN")
	)
	(segment
		(start 250.03633 -326.256904)
		(end 249.676158 -326.132698)
		(width 0.127)
		(layer "F.Cu")
		(net "PHY_SCC_A_TO_DRV_A_14_DN")
	)
	(segment
		(start 248.113804 -325.755)
		(end 248.019316 -325.561198)
		(width 0.127)
		(layer "F.Cu")
		(net "PHY_SCC_A_TO_DRV_A_14_DN")
	)
	(segment
		(start 250.49099 -326.574912)
		(end 250.130818 -326.450706)
		(width 0.127)
		(layer "F.Cu")
		(net "PHY_SCC_A_TO_DRV_A_14_DN")
	)
	(segment
		(start 144.568926 -231.9909)
		(end 144.457674 -231.928416)
		(width 0.127)
		(layer "F.Cu")
		(net "PHY_SCC_A_TO_DRV_A_14_DN")
	)
	(segment
		(start 97.033842 -159.141922)
		(end 96.927416 -159.118046)
		(width 0.127)
		(layer "F.Cu")
		(net "PHY_SCC_A_TO_DRV_A_14_DN")
	)
	(segment
		(start 240.006632 -322.797424)
		(end 232.906062 -320.347848)
		(width 0.127)
		(layer "F.Cu")
		(net "PHY_SCC_A_TO_DRV_A_14_DN")
	)
	(segment
		(start 124.625354 -227.696268)
		(end 124.082556 -227.580444)
		(width 0.127)
		(layer "F.Cu")
		(net "PHY_SCC_A_TO_DRV_A_14_DN")
	)
	(segment
		(start 96.376998 -159.118046)
		(end 96.275652 -159.219392)
		(width 0.127)
		(layer "F.Cu")
		(net "PHY_SCC_A_TO_DRV_A_14_DN")
	)
	(arc
		(start 272.39595 -333.832454)
		(mid 272.331896 -333.677814)
		(end 272.177256 -333.61376)
		(width 0.127)
		(layer "F.Cu")
		(net "PHY_SCC_A_TO_DRV_A_14_DN")
	)
	(arc
		(start 272.26895 -334.304894)
		(mid 272.358753 -334.267697)
		(end 272.39595 -334.177894)
		(width 0.127)
		(layer "F.Cu")
		(net "PHY_SCC_A_TO_DRV_A_14_DN")
	)
	(segment
		(start 273.11223 -333.258922)
		(end 279.329388 -333.258922)
		(width 0.127)
		(layer "B.Cu")
		(net "PHY_SCC_A_TO_DRV_A_14_DN")
	)
	(segment
		(start 279.790652 -332.882494)
		(end 279.790652 -332.63205)
		(width 0.127)
		(layer "B.Cu")
		(net "PHY_SCC_A_TO_DRV_A_14_DN")
	)
	(segment
		(start 279.663652 -332.50505)
		(end 279.236678 -332.50505)
		(width 0.127)
		(layer "B.Cu")
		(net "PHY_SCC_A_TO_DRV_A_14_DN")
	)
	(segment
		(start 272.39595 -334.123792)
		(end 272.39595 -333.975202)
		(width 0.127)
		(layer "B.Cu")
		(net "PHY_SCC_A_TO_DRV_A_14_DN")
	)
	(segment
		(start 271.9705 -334.304894)
		(end 272.214848 -334.304894)
		(width 0.127)
		(layer "B.Cu")
		(net "PHY_SCC_A_TO_DRV_A_14_DN")
	)
	(arc
		(start 279.72131 -333.080106)
		(mid 279.772817 -332.987207)
		(end 279.790652 -332.882494)
		(width 0.127)
		(layer "B.Cu")
		(net "PHY_SCC_A_TO_DRV_A_14_DN")
	)
	(arc
		(start 279.329388 -333.258922)
		(mid 279.528846 -333.219247)
		(end 279.697942 -333.106268)
		(width 0.127)
		(layer "B.Cu")
		(net "PHY_SCC_A_TO_DRV_A_14_DN")
	)
	(arc
		(start 279.697942 -333.106268)
		(mid 279.709986 -333.093508)
		(end 279.72131 -333.080106)
		(width 0.127)
		(layer "B.Cu")
		(net "PHY_SCC_A_TO_DRV_A_14_DN")
	)
	(arc
		(start 272.39595 -333.975202)
		(mid 272.605744 -333.468716)
		(end 273.11223 -333.258922)
		(width 0.127)
		(layer "B.Cu")
		(net "PHY_SCC_A_TO_DRV_A_14_DN")
	)
	(arc
		(start 279.790652 -332.63205)
		(mid 279.753455 -332.542247)
		(end 279.663652 -332.50505)
		(width 0.127)
		(layer "B.Cu")
		(net "PHY_SCC_A_TO_DRV_A_14_DN")
	)
	(arc
		(start 272.214848 -334.304894)
		(mid 272.342906 -334.25185)
		(end 272.39595 -334.123792)
		(width 0.127)
		(layer "B.Cu")
		(net "PHY_SCC_A_TO_DRV_A_14_DN")
	)
	(segment
		(start 232.274618 -321.791076)
		(end 251.578618 -328.450194)
		(width 0.127)
		(layer "F.Cu")
		(net "PHY_SCC_A_TO_DRV_A_13_DP")
	)
	(segment
		(start 194.648836 -262.293608)
		(end 232.274618 -321.791076)
		(width 0.127)
		(layer "F.Cu")
		(net "PHY_SCC_A_TO_DRV_A_13_DP")
	)
	(segment
		(start 64.292734 -158.660592)
		(end 64.90335 -158.660592)
		(width 0.127)
		(layer "F.Cu")
		(net "PHY_SCC_A_TO_DRV_A_13_DP")
	)
	(segment
		(start 68.30441 -161.707576)
		(end 72.434704 -180.343048)
		(width 0.127)
		(layer "F.Cu")
		(net "PHY_SCC_A_TO_DRV_A_13_DP")
	)
	(segment
		(start 270.919194 -335.121758)
		(end 272.26895 -335.121758)
		(width 0.127)
		(layer "F.Cu")
		(net "PHY_SCC_A_TO_DRV_A_13_DP")
	)
	(segment
		(start 251.579888 -328.450702)
		(end 251.596906 -328.456544)
		(width 0.127)
		(layer "F.Cu")
		(net "PHY_SCC_A_TO_DRV_A_13_DP")
	)
	(segment
		(start 272.68805 -335.540858)
		(end 272.68805 -335.977992)
		(width 0.127)
		(layer "F.Cu")
		(net "PHY_SCC_A_TO_DRV_A_13_DP")
	)
	(segment
		(start 142.271242 -232.815384)
		(end 194.648836 -262.293608)
		(width 0.127)
		(layer "F.Cu")
		(net "PHY_SCC_A_TO_DRV_A_13_DP")
	)
	(segment
		(start 72.435974 -180.345842)
		(end 72.43572 -180.345842)
		(width 0.127)
		(layer "F.Cu")
		(net "PHY_SCC_A_TO_DRV_A_13_DP")
	)
	(segment
		(start 251.596906 -328.456544)
		(end 251.597414 -328.456798)
		(width 0.127)
		(layer "F.Cu")
		(net "PHY_SCC_A_TO_DRV_A_13_DP")
	)
	(segment
		(start 142.271242 -232.815892)
		(end 142.271242 -232.815384)
		(width 0.127)
		(layer "F.Cu")
		(net "PHY_SCC_A_TO_DRV_A_13_DP")
	)
	(segment
		(start 87.003382 -216.075768)
		(end 89.255092 -219.60967)
		(width 0.127)
		(layer "F.Cu")
		(net "PHY_SCC_A_TO_DRV_A_13_DP")
	)
	(segment
		(start 66.97091 -159.615378)
		(end 68.30441 -161.707576)
		(width 0.127)
		(layer "F.Cu")
		(net "PHY_SCC_A_TO_DRV_A_13_DP")
	)
	(segment
		(start 65.077848 -158.83509)
		(end 65.577974 -158.83509)
		(width 0.127)
		(layer "F.Cu")
		(net "PHY_SCC_A_TO_DRV_A_13_DP")
	)
	(segment
		(start 64.90335 -158.660592)
		(end 65.077848 -158.83509)
		(width 0.127)
		(layer "F.Cu")
		(net "PHY_SCC_A_TO_DRV_A_13_DP")
	)
	(segment
		(start 65.577974 -158.83509)
		(end 65.836038 -158.89224)
		(width 0.127)
		(layer "F.Cu")
		(net "PHY_SCC_A_TO_DRV_A_13_DP")
	)
	(segment
		(start 251.597414 -328.456798)
		(end 270.919194 -335.121758)
		(width 0.127)
		(layer "F.Cu")
		(net "PHY_SCC_A_TO_DRV_A_13_DP")
	)
	(segment
		(start 95.544894 -223.462342)
		(end 142.271242 -232.815892)
		(width 0.127)
		(layer "F.Cu")
		(net "PHY_SCC_A_TO_DRV_A_13_DP")
	)
	(segment
		(start 72.43572 -180.345842)
		(end 87.003382 -216.075768)
		(width 0.127)
		(layer "F.Cu")
		(net "PHY_SCC_A_TO_DRV_A_13_DP")
	)
	(segment
		(start 65.836038 -158.89224)
		(end 66.97091 -159.615378)
		(width 0.127)
		(layer "F.Cu")
		(net "PHY_SCC_A_TO_DRV_A_13_DP")
	)
	(segment
		(start 72.434704 -180.343048)
		(end 72.435974 -180.345842)
		(width 0.127)
		(layer "F.Cu")
		(net "PHY_SCC_A_TO_DRV_A_13_DP")
	)
	(segment
		(start 89.255092 -219.60967)
		(end 95.544894 -223.462342)
		(width 0.127)
		(layer "F.Cu")
		(net "PHY_SCC_A_TO_DRV_A_13_DP")
	)
	(segment
		(start 251.578618 -328.450194)
		(end 251.579888 -328.450702)
		(width 0.127)
		(layer "F.Cu")
		(net "PHY_SCC_A_TO_DRV_A_13_DP")
	)
	(segment
		(start 272.81505 -336.104992)
		(end 273.1135 -336.104992)
		(width 0.127)
		(layer "F.Cu")
		(net "PHY_SCC_A_TO_DRV_A_13_DP")
	)
	(arc
		(start 272.26895 -335.121758)
		(mid 272.565298 -335.24451)
		(end 272.68805 -335.540858)
		(width 0.127)
		(layer "F.Cu")
		(net "PHY_SCC_A_TO_DRV_A_13_DP")
	)
	(arc
		(start 272.68805 -335.977992)
		(mid 272.725247 -336.067795)
		(end 272.81505 -336.104992)
		(width 0.127)
		(layer "F.Cu")
		(net "PHY_SCC_A_TO_DRV_A_13_DP")
	)
	(segment
		(start 278.329136 -335.35112)
		(end 273.11223 -335.35112)
		(width 0.127)
		(layer "B.Cu")
		(net "PHY_SCC_A_TO_DRV_A_13_DP")
	)
	(segment
		(start 272.68805 -335.7753)
		(end 272.68805 -335.92389)
		(width 0.127)
		(layer "B.Cu")
		(net "PHY_SCC_A_TO_DRV_A_13_DP")
	)
	(segment
		(start 279.082754 -334.432148)
		(end 279.082754 -334.6831)
		(width 0.127)
		(layer "B.Cu")
		(net "PHY_SCC_A_TO_DRV_A_13_DP")
	)
	(segment
		(start 279.636728 -334.305148)
		(end 279.209754 -334.305148)
		(width 0.127)
		(layer "B.Cu")
		(net "PHY_SCC_A_TO_DRV_A_13_DP")
	)
	(segment
		(start 272.869152 -336.104992)
		(end 273.1135 -336.104992)
		(width 0.127)
		(layer "B.Cu")
		(net "PHY_SCC_A_TO_DRV_A_13_DP")
	)
	(arc
		(start 279.082754 -334.6831)
		(mid 279.04852 -334.884293)
		(end 278.949658 -335.06283)
		(width 0.127)
		(layer "B.Cu")
		(net "PHY_SCC_A_TO_DRV_A_13_DP")
	)
	(arc
		(start 279.209754 -334.305148)
		(mid 279.119951 -334.342345)
		(end 279.082754 -334.432148)
		(width 0.127)
		(layer "B.Cu")
		(net "PHY_SCC_A_TO_DRV_A_13_DP")
	)
	(arc
		(start 273.11223 -335.35112)
		(mid 272.812289 -335.475359)
		(end 272.68805 -335.7753)
		(width 0.127)
		(layer "B.Cu")
		(net "PHY_SCC_A_TO_DRV_A_13_DP")
	)
	(arc
		(start 278.949658 -335.06283)
		(mid 278.927871 -335.088595)
		(end 278.9047 -335.113122)
		(width 0.127)
		(layer "B.Cu")
		(net "PHY_SCC_A_TO_DRV_A_13_DP")
	)
	(arc
		(start 272.68805 -335.92389)
		(mid 272.741094 -336.051948)
		(end 272.869152 -336.104992)
		(width 0.127)
		(layer "B.Cu")
		(net "PHY_SCC_A_TO_DRV_A_13_DP")
	)
	(arc
		(start 278.9047 -335.113122)
		(mid 278.640599 -335.289403)
		(end 278.329136 -335.35112)
		(width 0.127)
		(layer "B.Cu")
		(net "PHY_SCC_A_TO_DRV_A_13_DP")
	)
	(segment
		(start 65.7225 -159.166306)
		(end 66.759328 -159.82696)
		(width 0.127)
		(layer "F.Cu")
		(net "PHY_SCC_A_TO_DRV_A_13_DN")
	)
	(segment
		(start 228.81336 -317.149734)
		(end 229.017068 -317.471806)
		(width 0.127)
		(layer "F.Cu")
		(net "PHY_SCC_A_TO_DRV_A_13_DN")
	)
	(segment
		(start 72.155304 -180.433218)
		(end 72.155812 -180.433218)
		(width 0.127)
		(layer "F.Cu")
		(net "PHY_SCC_A_TO_DRV_A_13_DN")
	)
	(segment
		(start 272.26895 -336.104992)
		(end 271.9705 -336.104992)
		(width 0.127)
		(layer "F.Cu")
		(net "PHY_SCC_A_TO_DRV_A_13_DN")
	)
	(segment
		(start 272.39595 -335.540858)
		(end 272.39595 -335.977992)
		(width 0.127)
		(layer "F.Cu")
		(net "PHY_SCC_A_TO_DRV_A_13_DN")
	)
	(segment
		(start 229.79761 -318.42075)
		(end 230.001064 -318.742822)
		(width 0.127)
		(layer "F.Cu")
		(net "PHY_SCC_A_TO_DRV_A_13_DN")
	)
	(segment
		(start 80.85328 -201.765408)
		(end 86.742778 -216.210388)
		(width 0.127)
		(layer "F.Cu")
		(net "PHY_SCC_A_TO_DRV_A_13_DN")
	)
	(segment
		(start 229.430834 -317.841122)
		(end 229.38359 -318.051434)
		(width 0.127)
		(layer "F.Cu")
		(net "PHY_SCC_A_TO_DRV_A_13_DN")
	)
	(segment
		(start 79.115666 -197.503796)
		(end 80.85328 -201.765408)
		(width 0.127)
		(layer "F.Cu")
		(net "PHY_SCC_A_TO_DRV_A_13_DN")
	)
	(segment
		(start 89.04478 -219.823792)
		(end 95.436436 -223.738694)
		(width 0.127)
		(layer "F.Cu")
		(net "PHY_SCC_A_TO_DRV_A_13_DN")
	)
	(segment
		(start 64.995552 -159.12719)
		(end 65.54597 -159.12719)
		(width 0.127)
		(layer "F.Cu")
		(net "PHY_SCC_A_TO_DRV_A_13_DN")
	)
	(segment
		(start 72.155812 -180.433218)
		(end 79.115666 -197.503796)
		(width 0.127)
		(layer "F.Cu")
		(net "PHY_SCC_A_TO_DRV_A_13_DN")
	)
	(segment
		(start 95.436436 -223.738694)
		(end 142.168626 -233.093514)
		(width 0.127)
		(layer "F.Cu")
		(net "PHY_SCC_A_TO_DRV_A_13_DN")
	)
	(segment
		(start 251.483876 -328.7268)
		(end 251.485146 -328.727308)
		(width 0.127)
		(layer "F.Cu")
		(net "PHY_SCC_A_TO_DRV_A_13_DN")
	)
	(segment
		(start 270.870172 -335.413858)
		(end 272.26895 -335.413858)
		(width 0.127)
		(layer "F.Cu")
		(net "PHY_SCC_A_TO_DRV_A_13_DN")
	)
	(segment
		(start 229.95382 -318.95288)
		(end 230.157528 -319.274952)
		(width 0.127)
		(layer "F.Cu")
		(net "PHY_SCC_A_TO_DRV_A_13_DN")
	)
	(segment
		(start 64.90335 -159.219392)
		(end 64.995552 -159.12719)
		(width 0.127)
		(layer "F.Cu")
		(net "PHY_SCC_A_TO_DRV_A_13_DN")
	)
	(segment
		(start 68.030344 -161.821114)
		(end 72.155304 -180.433218)
		(width 0.127)
		(layer "F.Cu")
		(net "PHY_SCC_A_TO_DRV_A_13_DN")
	)
	(segment
		(start 230.52405 -319.85458)
		(end 230.727504 -320.176652)
		(width 0.127)
		(layer "F.Cu")
		(net "PHY_SCC_A_TO_DRV_A_13_DN")
	)
	(segment
		(start 232.08234 -322.0339)
		(end 251.483368 -328.726546)
		(width 0.127)
		(layer "F.Cu")
		(net "PHY_SCC_A_TO_DRV_A_13_DN")
	)
	(segment
		(start 64.292734 -159.219392)
		(end 64.90335 -159.219392)
		(width 0.127)
		(layer "F.Cu")
		(net "PHY_SCC_A_TO_DRV_A_13_DN")
	)
	(segment
		(start 230.937816 -320.223896)
		(end 232.08234 -322.0339)
		(width 0.127)
		(layer "F.Cu")
		(net "PHY_SCC_A_TO_DRV_A_13_DN")
	)
	(segment
		(start 86.742778 -216.210388)
		(end 89.04478 -219.823792)
		(width 0.127)
		(layer "F.Cu")
		(net "PHY_SCC_A_TO_DRV_A_13_DN")
	)
	(segment
		(start 251.485146 -328.727308)
		(end 270.870172 -335.413858)
		(width 0.127)
		(layer "F.Cu")
		(net "PHY_SCC_A_TO_DRV_A_13_DN")
	)
	(segment
		(start 230.157528 -319.274952)
		(end 230.367586 -319.32245)
		(width 0.127)
		(layer "F.Cu")
		(net "PHY_SCC_A_TO_DRV_A_13_DN")
	)
	(segment
		(start 230.001064 -318.742822)
		(end 229.95382 -318.95288)
		(width 0.127)
		(layer "F.Cu")
		(net "PHY_SCC_A_TO_DRV_A_13_DN")
	)
	(segment
		(start 228.860858 -316.939422)
		(end 228.81336 -317.149734)
		(width 0.127)
		(layer "F.Cu")
		(net "PHY_SCC_A_TO_DRV_A_13_DN")
	)
	(segment
		(start 230.367586 -319.32245)
		(end 230.571294 -319.644268)
		(width 0.127)
		(layer "F.Cu")
		(net "PHY_SCC_A_TO_DRV_A_13_DN")
	)
	(segment
		(start 229.38359 -318.051434)
		(end 229.587298 -318.373252)
		(width 0.127)
		(layer "F.Cu")
		(net "PHY_SCC_A_TO_DRV_A_13_DN")
	)
	(segment
		(start 142.168626 -233.093006)
		(end 194.441318 -262.512048)
		(width 0.127)
		(layer "F.Cu")
		(net "PHY_SCC_A_TO_DRV_A_13_DN")
	)
	(segment
		(start 229.587298 -318.373252)
		(end 229.79761 -318.42075)
		(width 0.127)
		(layer "F.Cu")
		(net "PHY_SCC_A_TO_DRV_A_13_DN")
	)
	(segment
		(start 194.441318 -262.512048)
		(end 228.860858 -316.939422)
		(width 0.127)
		(layer "F.Cu")
		(net "PHY_SCC_A_TO_DRV_A_13_DN")
	)
	(segment
		(start 229.22738 -317.51905)
		(end 229.430834 -317.841122)
		(width 0.127)
		(layer "F.Cu")
		(net "PHY_SCC_A_TO_DRV_A_13_DN")
	)
	(segment
		(start 229.017068 -317.471806)
		(end 229.22738 -317.51905)
		(width 0.127)
		(layer "F.Cu")
		(net "PHY_SCC_A_TO_DRV_A_13_DN")
	)
	(segment
		(start 251.483368 -328.726546)
		(end 251.483876 -328.7268)
		(width 0.127)
		(layer "F.Cu")
		(net "PHY_SCC_A_TO_DRV_A_13_DN")
	)
	(segment
		(start 230.571294 -319.644268)
		(end 230.52405 -319.85458)
		(width 0.127)
		(layer "F.Cu")
		(net "PHY_SCC_A_TO_DRV_A_13_DN")
	)
	(segment
		(start 66.759328 -159.82696)
		(end 68.030344 -161.821114)
		(width 0.127)
		(layer "F.Cu")
		(net "PHY_SCC_A_TO_DRV_A_13_DN")
	)
	(segment
		(start 142.168626 -233.093514)
		(end 142.168626 -233.093006)
		(width 0.127)
		(layer "F.Cu")
		(net "PHY_SCC_A_TO_DRV_A_13_DN")
	)
	(segment
		(start 230.727504 -320.176652)
		(end 230.937816 -320.223896)
		(width 0.127)
		(layer "F.Cu")
		(net "PHY_SCC_A_TO_DRV_A_13_DN")
	)
	(segment
		(start 65.54597 -159.12719)
		(end 65.7225 -159.166306)
		(width 0.127)
		(layer "F.Cu")
		(net "PHY_SCC_A_TO_DRV_A_13_DN")
	)
	(arc
		(start 272.39595 -335.977992)
		(mid 272.358753 -336.067795)
		(end 272.26895 -336.104992)
		(width 0.127)
		(layer "F.Cu")
		(net "PHY_SCC_A_TO_DRV_A_13_DN")
	)
	(arc
		(start 272.26895 -335.413858)
		(mid 272.358753 -335.451055)
		(end 272.39595 -335.540858)
		(width 0.127)
		(layer "F.Cu")
		(net "PHY_SCC_A_TO_DRV_A_13_DN")
	)
	(segment
		(start 278.663654 -334.305148)
		(end 278.23668 -334.305148)
		(width 0.127)
		(layer "B.Cu")
		(net "PHY_SCC_A_TO_DRV_A_13_DN")
	)
	(segment
		(start 273.11223 -335.05902)
		(end 278.32939 -335.05902)
		(width 0.127)
		(layer "B.Cu")
		(net "PHY_SCC_A_TO_DRV_A_13_DN")
	)
	(segment
		(start 272.39595 -335.92389)
		(end 272.39595 -335.7753)
		(width 0.127)
		(layer "B.Cu")
		(net "PHY_SCC_A_TO_DRV_A_13_DN")
	)
	(segment
		(start 271.9705 -336.104992)
		(end 272.214848 -336.104992)
		(width 0.127)
		(layer "B.Cu")
		(net "PHY_SCC_A_TO_DRV_A_13_DN")
	)
	(segment
		(start 278.790654 -334.682592)
		(end 278.790654 -334.432148)
		(width 0.127)
		(layer "B.Cu")
		(net "PHY_SCC_A_TO_DRV_A_13_DN")
	)
	(arc
		(start 278.790654 -334.432148)
		(mid 278.753457 -334.342345)
		(end 278.663654 -334.305148)
		(width 0.127)
		(layer "B.Cu")
		(net "PHY_SCC_A_TO_DRV_A_13_DN")
	)
	(arc
		(start 272.39595 -335.7753)
		(mid 272.605744 -335.268814)
		(end 273.11223 -335.05902)
		(width 0.127)
		(layer "B.Cu")
		(net "PHY_SCC_A_TO_DRV_A_13_DN")
	)
	(arc
		(start 278.697944 -334.906366)
		(mid 278.709988 -334.893606)
		(end 278.721312 -334.880204)
		(width 0.127)
		(layer "B.Cu")
		(net "PHY_SCC_A_TO_DRV_A_13_DN")
	)
	(arc
		(start 278.32939 -335.05902)
		(mid 278.528848 -335.019345)
		(end 278.697944 -334.906366)
		(width 0.127)
		(layer "B.Cu")
		(net "PHY_SCC_A_TO_DRV_A_13_DN")
	)
	(arc
		(start 272.214848 -336.104992)
		(mid 272.342906 -336.051948)
		(end 272.39595 -335.92389)
		(width 0.127)
		(layer "B.Cu")
		(net "PHY_SCC_A_TO_DRV_A_13_DN")
	)
	(arc
		(start 278.721312 -334.880204)
		(mid 278.772819 -334.787305)
		(end 278.790654 -334.682592)
		(width 0.127)
		(layer "B.Cu")
		(net "PHY_SCC_A_TO_DRV_A_13_DN")
	)
	(segment
		(start 33.43148 -158.84017)
		(end 33.902904 -158.84017)
		(width 0.127)
		(layer "F.Cu")
		(net "PHY_SCC_A_TO_DRV_A_12_DP")
	)
	(segment
		(start 148.167598 -238.498888)
		(end 154.414474 -242.004596)
		(width 0.127)
		(layer "F.Cu")
		(net "PHY_SCC_A_TO_DRV_A_12_DP")
	)
	(segment
		(start 154.414474 -242.004596)
		(end 166.907718 -249.015758)
		(width 0.127)
		(layer "F.Cu")
		(net "PHY_SCC_A_TO_DRV_A_12_DP")
	)
	(segment
		(start 54.464966 -199.798686)
		(end 94.857316 -225.55962)
		(width 0.127)
		(layer "F.Cu")
		(net "PHY_SCC_A_TO_DRV_A_12_DP")
	)
	(segment
		(start 33.902904 -158.84017)
		(end 34.344102 -158.93796)
		(width 0.127)
		(layer "F.Cu")
		(net "PHY_SCC_A_TO_DRV_A_12_DP")
	)
	(segment
		(start 271.263872 -336.921856)
		(end 272.26895 -336.921856)
		(width 0.127)
		(layer "F.Cu")
		(net "PHY_SCC_A_TO_DRV_A_12_DP")
	)
	(segment
		(start 33.251902 -158.660592)
		(end 33.43148 -158.84017)
		(width 0.127)
		(layer "F.Cu")
		(net "PHY_SCC_A_TO_DRV_A_12_DP")
	)
	(segment
		(start 272.68805 -337.340956)
		(end 272.68805 -337.77809)
		(width 0.127)
		(layer "F.Cu")
		(net "PHY_SCC_A_TO_DRV_A_12_DP")
	)
	(segment
		(start 166.907718 -249.015758)
		(end 193.68516 -264.043414)
		(width 0.127)
		(layer "F.Cu")
		(net "PHY_SCC_A_TO_DRV_A_12_DP")
	)
	(segment
		(start 272.81505 -337.90509)
		(end 273.1135 -337.90509)
		(width 0.127)
		(layer "F.Cu")
		(net "PHY_SCC_A_TO_DRV_A_12_DP")
	)
	(segment
		(start 37.301424 -162.923982)
		(end 40.6781 -178.155854)
		(width 0.127)
		(layer "F.Cu")
		(net "PHY_SCC_A_TO_DRV_A_12_DP")
	)
	(segment
		(start 32.742886 -158.660592)
		(end 33.251902 -158.660592)
		(width 0.127)
		(layer "F.Cu")
		(net "PHY_SCC_A_TO_DRV_A_12_DP")
	)
	(segment
		(start 40.6781 -178.155854)
		(end 40.678354 -178.155854)
		(width 0.127)
		(layer "F.Cu")
		(net "PHY_SCC_A_TO_DRV_A_12_DP")
	)
	(segment
		(start 231.030526 -323.069458)
		(end 271.263872 -336.921856)
		(width 0.127)
		(layer "F.Cu")
		(net "PHY_SCC_A_TO_DRV_A_12_DP")
	)
	(segment
		(start 40.678354 -178.155854)
		(end 54.464966 -199.798686)
		(width 0.127)
		(layer "F.Cu")
		(net "PHY_SCC_A_TO_DRV_A_12_DP")
	)
	(segment
		(start 34.344102 -158.93796)
		(end 35.047428 -159.386016)
		(width 0.127)
		(layer "F.Cu")
		(net "PHY_SCC_A_TO_DRV_A_12_DP")
	)
	(segment
		(start 193.68516 -264.043414)
		(end 231.030526 -323.069458)
		(width 0.127)
		(layer "F.Cu")
		(net "PHY_SCC_A_TO_DRV_A_12_DP")
	)
	(segment
		(start 94.857316 -225.55962)
		(end 141.880844 -234.971082)
		(width 0.127)
		(layer "F.Cu")
		(net "PHY_SCC_A_TO_DRV_A_12_DP")
	)
	(segment
		(start 141.880844 -234.971082)
		(end 148.167598 -238.498888)
		(width 0.127)
		(layer "F.Cu")
		(net "PHY_SCC_A_TO_DRV_A_12_DP")
	)
	(segment
		(start 35.047428 -159.386016)
		(end 37.301424 -162.923982)
		(width 0.127)
		(layer "F.Cu")
		(net "PHY_SCC_A_TO_DRV_A_12_DP")
	)
	(arc
		(start 272.26895 -336.921856)
		(mid 272.565298 -337.044608)
		(end 272.68805 -337.340956)
		(width 0.127)
		(layer "F.Cu")
		(net "PHY_SCC_A_TO_DRV_A_12_DP")
	)
	(arc
		(start 272.68805 -337.77809)
		(mid 272.725247 -337.867893)
		(end 272.81505 -337.90509)
		(width 0.127)
		(layer "F.Cu")
		(net "PHY_SCC_A_TO_DRV_A_12_DP")
	)
	(segment
		(start 280.209752 -336.105246)
		(end 280.636726 -336.105246)
		(width 0.127)
		(layer "B.Cu")
		(net "PHY_SCC_A_TO_DRV_A_12_DP")
	)
	(segment
		(start 273.11223 -337.151218)
		(end 279.329134 -337.151218)
		(width 0.127)
		(layer "B.Cu")
		(net "PHY_SCC_A_TO_DRV_A_12_DP")
	)
	(segment
		(start 273.1135 -337.90509)
		(end 272.869152 -337.90509)
		(width 0.127)
		(layer "B.Cu")
		(net "PHY_SCC_A_TO_DRV_A_12_DP")
	)
	(segment
		(start 272.68805 -337.723988)
		(end 272.68805 -337.575398)
		(width 0.127)
		(layer "B.Cu")
		(net "PHY_SCC_A_TO_DRV_A_12_DP")
	)
	(segment
		(start 280.082752 -336.483198)
		(end 280.082752 -336.232246)
		(width 0.127)
		(layer "B.Cu")
		(net "PHY_SCC_A_TO_DRV_A_12_DP")
	)
	(arc
		(start 272.869152 -337.90509)
		(mid 272.741094 -337.852046)
		(end 272.68805 -337.723988)
		(width 0.127)
		(layer "B.Cu")
		(net "PHY_SCC_A_TO_DRV_A_12_DP")
	)
	(arc
		(start 280.082752 -336.232246)
		(mid 280.119949 -336.142443)
		(end 280.209752 -336.105246)
		(width 0.127)
		(layer "B.Cu")
		(net "PHY_SCC_A_TO_DRV_A_12_DP")
	)
	(arc
		(start 279.329134 -337.151218)
		(mid 279.640578 -337.089455)
		(end 279.904698 -336.91322)
		(width 0.127)
		(layer "B.Cu")
		(net "PHY_SCC_A_TO_DRV_A_12_DP")
	)
	(arc
		(start 279.904698 -336.91322)
		(mid 279.92788 -336.888702)
		(end 279.949656 -336.862928)
		(width 0.127)
		(layer "B.Cu")
		(net "PHY_SCC_A_TO_DRV_A_12_DP")
	)
	(arc
		(start 272.68805 -337.575398)
		(mid 272.812289 -337.275457)
		(end 273.11223 -337.151218)
		(width 0.127)
		(layer "B.Cu")
		(net "PHY_SCC_A_TO_DRV_A_12_DP")
	)
	(arc
		(start 279.949656 -336.862928)
		(mid 280.048501 -336.684385)
		(end 280.082752 -336.483198)
		(width 0.127)
		(layer "B.Cu")
		(net "PHY_SCC_A_TO_DRV_A_12_DP")
	)
	(segment
		(start 154.271472 -242.259358)
		(end 166.764716 -249.27052)
		(width 0.127)
		(layer "F.Cu")
		(net "PHY_SCC_A_TO_DRV_A_12_DN")
	)
	(segment
		(start 166.764716 -249.27052)
		(end 193.477642 -264.262108)
		(width 0.127)
		(layer "F.Cu")
		(net "PHY_SCC_A_TO_DRV_A_12_DN")
	)
	(segment
		(start 266.820142 -335.861914)
		(end 267.180314 -335.98612)
		(width 0.127)
		(layer "F.Cu")
		(net "PHY_SCC_A_TO_DRV_A_12_DN")
	)
	(segment
		(start 267.734288 -336.015584)
		(end 267.828776 -336.209386)
		(width 0.127)
		(layer "F.Cu")
		(net "PHY_SCC_A_TO_DRV_A_12_DN")
	)
	(segment
		(start 268.38275 -336.23885)
		(end 268.742922 -336.362802)
		(width 0.127)
		(layer "F.Cu")
		(net "PHY_SCC_A_TO_DRV_A_12_DN")
	)
	(segment
		(start 141.778228 -235.24845)
		(end 148.024596 -238.75365)
		(width 0.127)
		(layer "F.Cu")
		(net "PHY_SCC_A_TO_DRV_A_12_DN")
	)
	(segment
		(start 230.838502 -323.312282)
		(end 266.725654 -335.668366)
		(width 0.127)
		(layer "F.Cu")
		(net "PHY_SCC_A_TO_DRV_A_12_DN")
	)
	(segment
		(start 269.846044 -336.903822)
		(end 270.20647 -337.028028)
		(width 0.127)
		(layer "F.Cu")
		(net "PHY_SCC_A_TO_DRV_A_12_DN")
	)
	(segment
		(start 270.400272 -336.93354)
		(end 271.21485 -337.213956)
		(width 0.127)
		(layer "F.Cu")
		(net "PHY_SCC_A_TO_DRV_A_12_DN")
	)
	(segment
		(start 272.39595 -337.340956)
		(end 272.39595 -337.77809)
		(width 0.127)
		(layer "F.Cu")
		(net "PHY_SCC_A_TO_DRV_A_12_DN")
	)
	(segment
		(start 267.180314 -335.98612)
		(end 267.374116 -335.891632)
		(width 0.127)
		(layer "F.Cu")
		(net "PHY_SCC_A_TO_DRV_A_12_DN")
	)
	(segment
		(start 193.477642 -264.262108)
		(end 230.838502 -323.312282)
		(width 0.127)
		(layer "F.Cu")
		(net "PHY_SCC_A_TO_DRV_A_12_DN")
	)
	(segment
		(start 74.504296 -212.92566)
		(end 94.746318 -225.835464)
		(width 0.127)
		(layer "F.Cu")
		(net "PHY_SCC_A_TO_DRV_A_12_DN")
	)
	(segment
		(start 268.742922 -336.362802)
		(end 268.83741 -336.556604)
		(width 0.127)
		(layer "F.Cu")
		(net "PHY_SCC_A_TO_DRV_A_12_DN")
	)
	(segment
		(start 40.466264 -178.367182)
		(end 54.253384 -200.010268)
		(width 0.127)
		(layer "F.Cu")
		(net "PHY_SCC_A_TO_DRV_A_12_DN")
	)
	(segment
		(start 33.8709 -159.13227)
		(end 34.230564 -159.212026)
		(width 0.127)
		(layer "F.Cu")
		(net "PHY_SCC_A_TO_DRV_A_12_DN")
	)
	(segment
		(start 268.83741 -336.556604)
		(end 269.197582 -336.680556)
		(width 0.127)
		(layer "F.Cu")
		(net "PHY_SCC_A_TO_DRV_A_12_DN")
	)
	(segment
		(start 34.835846 -159.597598)
		(end 37.027358 -163.03752)
		(width 0.127)
		(layer "F.Cu")
		(net "PHY_SCC_A_TO_DRV_A_12_DN")
	)
	(segment
		(start 33.251902 -159.219392)
		(end 33.339024 -159.13227)
		(width 0.127)
		(layer "F.Cu")
		(net "PHY_SCC_A_TO_DRV_A_12_DN")
	)
	(segment
		(start 54.253384 -200.010268)
		(end 74.504296 -212.92566)
		(width 0.127)
		(layer "F.Cu")
		(net "PHY_SCC_A_TO_DRV_A_12_DN")
	)
	(segment
		(start 34.230564 -159.212026)
		(end 34.835846 -159.597598)
		(width 0.127)
		(layer "F.Cu")
		(net "PHY_SCC_A_TO_DRV_A_12_DN")
	)
	(segment
		(start 266.725654 -335.668366)
		(end 266.820142 -335.861914)
		(width 0.127)
		(layer "F.Cu")
		(net "PHY_SCC_A_TO_DRV_A_12_DN")
	)
	(segment
		(start 268.188948 -336.333338)
		(end 268.38275 -336.23885)
		(width 0.127)
		(layer "F.Cu")
		(net "PHY_SCC_A_TO_DRV_A_12_DN")
	)
	(segment
		(start 94.746318 -225.835464)
		(end 141.778228 -235.24845)
		(width 0.127)
		(layer "F.Cu")
		(net "PHY_SCC_A_TO_DRV_A_12_DN")
	)
	(segment
		(start 33.339024 -159.13227)
		(end 33.8709 -159.13227)
		(width 0.127)
		(layer "F.Cu")
		(net "PHY_SCC_A_TO_DRV_A_12_DN")
	)
	(segment
		(start 267.374116 -335.891632)
		(end 267.734288 -336.015584)
		(width 0.127)
		(layer "F.Cu")
		(net "PHY_SCC_A_TO_DRV_A_12_DN")
	)
	(segment
		(start 40.418766 -178.336702)
		(end 40.466264 -178.367182)
		(width 0.127)
		(layer "F.Cu")
		(net "PHY_SCC_A_TO_DRV_A_12_DN")
	)
	(segment
		(start 37.027358 -163.03752)
		(end 40.418766 -178.336702)
		(width 0.127)
		(layer "F.Cu")
		(net "PHY_SCC_A_TO_DRV_A_12_DN")
	)
	(segment
		(start 269.197582 -336.680556)
		(end 269.391384 -336.586068)
		(width 0.127)
		(layer "F.Cu")
		(net "PHY_SCC_A_TO_DRV_A_12_DN")
	)
	(segment
		(start 269.751556 -336.710274)
		(end 269.846044 -336.903822)
		(width 0.127)
		(layer "F.Cu")
		(net "PHY_SCC_A_TO_DRV_A_12_DN")
	)
	(segment
		(start 267.828776 -336.209386)
		(end 268.188948 -336.333338)
		(width 0.127)
		(layer "F.Cu")
		(net "PHY_SCC_A_TO_DRV_A_12_DN")
	)
	(segment
		(start 148.024596 -238.75365)
		(end 154.271472 -242.259358)
		(width 0.127)
		(layer "F.Cu")
		(net "PHY_SCC_A_TO_DRV_A_12_DN")
	)
	(segment
		(start 271.21485 -337.213956)
		(end 272.26895 -337.213956)
		(width 0.127)
		(layer "F.Cu")
		(net "PHY_SCC_A_TO_DRV_A_12_DN")
	)
	(segment
		(start 270.20647 -337.028028)
		(end 270.400018 -336.93354)
		(width 0.127)
		(layer "F.Cu")
		(net "PHY_SCC_A_TO_DRV_A_12_DN")
	)
	(segment
		(start 269.391384 -336.586068)
		(end 269.751556 -336.710274)
		(width 0.127)
		(layer "F.Cu")
		(net "PHY_SCC_A_TO_DRV_A_12_DN")
	)
	(segment
		(start 270.400018 -336.93354)
		(end 270.400272 -336.93354)
		(width 0.127)
		(layer "F.Cu")
		(net "PHY_SCC_A_TO_DRV_A_12_DN")
	)
	(segment
		(start 32.742886 -159.219392)
		(end 33.251902 -159.219392)
		(width 0.127)
		(layer "F.Cu")
		(net "PHY_SCC_A_TO_DRV_A_12_DN")
	)
	(segment
		(start 272.26895 -337.90509)
		(end 271.9705 -337.90509)
		(width 0.127)
		(layer "F.Cu")
		(net "PHY_SCC_A_TO_DRV_A_12_DN")
	)
	(arc
		(start 272.39595 -337.77809)
		(mid 272.358753 -337.867893)
		(end 272.26895 -337.90509)
		(width 0.127)
		(layer "F.Cu")
		(net "PHY_SCC_A_TO_DRV_A_12_DN")
	)
	(arc
		(start 272.26895 -337.213956)
		(mid 272.358753 -337.251153)
		(end 272.39595 -337.340956)
		(width 0.127)
		(layer "F.Cu")
		(net "PHY_SCC_A_TO_DRV_A_12_DN")
	)
	(segment
		(start 279.790652 -336.48269)
		(end 279.790652 -336.232246)
		(width 0.127)
		(layer "B.Cu")
		(net "PHY_SCC_A_TO_DRV_A_12_DN")
	)
	(segment
		(start 272.39595 -337.723988)
		(end 272.39595 -337.575398)
		(width 0.127)
		(layer "B.Cu")
		(net "PHY_SCC_A_TO_DRV_A_12_DN")
	)
	(segment
		(start 271.9705 -337.90509)
		(end 272.214848 -337.90509)
		(width 0.127)
		(layer "B.Cu")
		(net "PHY_SCC_A_TO_DRV_A_12_DN")
	)
	(segment
		(start 273.11223 -336.859118)
		(end 279.329388 -336.859118)
		(width 0.127)
		(layer "B.Cu")
		(net "PHY_SCC_A_TO_DRV_A_12_DN")
	)
	(segment
		(start 279.663652 -336.105246)
		(end 279.236678 -336.105246)
		(width 0.127)
		(layer "B.Cu")
		(net "PHY_SCC_A_TO_DRV_A_12_DN")
	)
	(arc
		(start 279.697942 -336.706464)
		(mid 279.709986 -336.693704)
		(end 279.72131 -336.680302)
		(width 0.127)
		(layer "B.Cu")
		(net "PHY_SCC_A_TO_DRV_A_12_DN")
	)
	(arc
		(start 279.329388 -336.859118)
		(mid 279.528846 -336.819443)
		(end 279.697942 -336.706464)
		(width 0.127)
		(layer "B.Cu")
		(net "PHY_SCC_A_TO_DRV_A_12_DN")
	)
	(arc
		(start 272.214848 -337.90509)
		(mid 272.342906 -337.852046)
		(end 272.39595 -337.723988)
		(width 0.127)
		(layer "B.Cu")
		(net "PHY_SCC_A_TO_DRV_A_12_DN")
	)
	(arc
		(start 279.790652 -336.232246)
		(mid 279.753455 -336.142443)
		(end 279.663652 -336.105246)
		(width 0.127)
		(layer "B.Cu")
		(net "PHY_SCC_A_TO_DRV_A_12_DN")
	)
	(arc
		(start 272.39595 -337.575398)
		(mid 272.605744 -337.068912)
		(end 273.11223 -336.859118)
		(width 0.127)
		(layer "B.Cu")
		(net "PHY_SCC_A_TO_DRV_A_12_DN")
	)
	(arc
		(start 279.72131 -336.680302)
		(mid 279.772817 -336.587403)
		(end 279.790652 -336.48269)
		(width 0.127)
		(layer "B.Cu")
		(net "PHY_SCC_A_TO_DRV_A_12_DN")
	)
	(segment
		(start 478.773998 -273.660616)
		(end 479.105214 -273.660616)
		(width 0.127)
		(layer "F.Cu")
		(net "PHY_SCC_A_TO_DRV_A_11_DP")
	)
	(segment
		(start 478.640648 -273.793966)
		(end 478.773998 -273.660616)
		(width 0.127)
		(layer "F.Cu")
		(net "PHY_SCC_A_TO_DRV_A_11_DP")
	)
	(segment
		(start 477.776286 -273.744436)
		(end 477.788732 -273.756882)
		(width 0.127)
		(layer "F.Cu")
		(net "PHY_SCC_A_TO_DRV_A_11_DP")
	)
	(segment
		(start 477.878394 -273.793966)
		(end 478.640648 -273.793966)
		(width 0.127)
		(layer "F.Cu")
		(net "PHY_SCC_A_TO_DRV_A_11_DP")
	)
	(segment
		(start 477.739202 -273.368516)
		(end 477.739202 -273.654774)
		(width 0.127)
		(layer "F.Cu")
		(net "PHY_SCC_A_TO_DRV_A_11_DP")
	)
	(arc
		(start 477.739202 -273.654774)
		(mid 477.748835 -273.703292)
		(end 477.776286 -273.744436)
		(width 0.127)
		(layer "F.Cu")
		(net "PHY_SCC_A_TO_DRV_A_11_DP")
	)
	(arc
		(start 477.788732 -273.756882)
		(mid 477.829883 -273.784315)
		(end 477.878394 -273.793966)
		(width 0.127)
		(layer "F.Cu")
		(net "PHY_SCC_A_TO_DRV_A_11_DP")
	)
	(segment
		(start 477.619568 -273.774916)
		(end 475.87789 -273.774916)
		(width 0.10795)
		(layer "In9.Cu")
		(net "PHY_SCC_A_TO_DRV_A_11_DP")
	)
	(segment
		(start 280.101802 -347.445838)
		(end 280.101802 -347.037914)
		(width 0.10795)
		(layer "In9.Cu")
		(net "PHY_SCC_A_TO_DRV_A_11_DP")
	)
	(segment
		(start 357.230934 -332.357222)
		(end 356.914704 -332.427326)
		(width 0.10795)
		(layer "In9.Cu")
		(net "PHY_SCC_A_TO_DRV_A_11_DP")
	)
	(segment
		(start 357.956358 -332.19644)
		(end 357.706422 -332.037182)
		(width 0.10795)
		(layer "In9.Cu")
		(net "PHY_SCC_A_TO_DRV_A_11_DP")
	)
	(segment
		(start 357.706422 -332.037182)
		(end 357.390192 -332.107286)
		(width 0.10795)
		(layer "In9.Cu")
		(net "PHY_SCC_A_TO_DRV_A_11_DP")
	)
	(segment
		(start 355.14788 -332.818994)
		(end 288.290762 -347.639894)
		(width 0.10795)
		(layer "In9.Cu")
		(net "PHY_SCC_A_TO_DRV_A_11_DP")
	)
	(segment
		(start 356.18928 -332.588108)
		(end 355.873304 -332.658212)
		(width 0.10795)
		(layer "In9.Cu")
		(net "PHY_SCC_A_TO_DRV_A_11_DP")
	)
	(segment
		(start 475.87789 -273.774916)
		(end 458.376782 -277.654766)
		(width 0.10795)
		(layer "In9.Cu")
		(net "PHY_SCC_A_TO_DRV_A_11_DP")
	)
	(segment
		(start 357.390192 -332.107286)
		(end 357.230934 -332.357222)
		(width 0.10795)
		(layer "In9.Cu")
		(net "PHY_SCC_A_TO_DRV_A_11_DP")
	)
	(segment
		(start 355.873304 -332.658212)
		(end 355.623368 -332.498954)
		(width 0.10795)
		(layer "In9.Cu")
		(net "PHY_SCC_A_TO_DRV_A_11_DP")
	)
	(segment
		(start 356.348538 -332.338172)
		(end 356.18928 -332.588108)
		(width 0.10795)
		(layer "In9.Cu")
		(net "PHY_SCC_A_TO_DRV_A_11_DP")
	)
	(segment
		(start 280.206196 -347.60281)
		(end 280.138886 -347.5355)
		(width 0.10795)
		(layer "In9.Cu")
		(net "PHY_SCC_A_TO_DRV_A_11_DP")
	)
	(segment
		(start 356.914704 -332.427326)
		(end 356.664768 -332.268068)
		(width 0.10795)
		(layer "In9.Cu")
		(net "PHY_SCC_A_TO_DRV_A_11_DP")
	)
	(segment
		(start 288.290762 -347.639894)
		(end 280.295858 -347.639894)
		(width 0.10795)
		(layer "In9.Cu")
		(net "PHY_SCC_A_TO_DRV_A_11_DP")
	)
	(segment
		(start 458.376782 -277.654766)
		(end 359.664762 -331.817726)
		(width 0.10795)
		(layer "In9.Cu")
		(net "PHY_SCC_A_TO_DRV_A_11_DP")
	)
	(segment
		(start 280.234644 -346.905072)
		(end 280.636726 -346.905072)
		(width 0.10795)
		(layer "In9.Cu")
		(net "PHY_SCC_A_TO_DRV_A_11_DP")
	)
	(segment
		(start 355.623368 -332.498954)
		(end 355.307138 -332.569058)
		(width 0.10795)
		(layer "In9.Cu")
		(net "PHY_SCC_A_TO_DRV_A_11_DP")
	)
	(segment
		(start 356.664768 -332.268068)
		(end 356.348538 -332.338172)
		(width 0.10795)
		(layer "In9.Cu")
		(net "PHY_SCC_A_TO_DRV_A_11_DP")
	)
	(segment
		(start 355.307138 -332.569058)
		(end 355.14788 -332.818994)
		(width 0.10795)
		(layer "In9.Cu")
		(net "PHY_SCC_A_TO_DRV_A_11_DP")
	)
	(segment
		(start 359.664762 -331.817726)
		(end 357.956358 -332.19644)
		(width 0.10795)
		(layer "In9.Cu")
		(net "PHY_SCC_A_TO_DRV_A_11_DP")
	)
	(segment
		(start 280.138886 -346.948252)
		(end 280.144982 -346.942156)
		(width 0.10795)
		(layer "In9.Cu")
		(net "PHY_SCC_A_TO_DRV_A_11_DP")
	)
	(segment
		(start 477.739202 -273.368516)
		(end 477.739202 -273.655282)
		(width 0.10795)
		(layer "In9.Cu")
		(net "PHY_SCC_A_TO_DRV_A_11_DP")
	)
	(arc
		(start 477.739202 -273.655282)
		(mid 477.730095 -273.701064)
		(end 477.70415 -273.739864)
		(width 0.10795)
		(layer "In9.Cu")
		(net "PHY_SCC_A_TO_DRV_A_11_DP")
	)
	(arc
		(start 280.295858 -347.639894)
		(mid 280.24734 -347.630261)
		(end 280.206196 -347.60281)
		(width 0.10795)
		(layer "In9.Cu")
		(net "PHY_SCC_A_TO_DRV_A_11_DP")
	)
	(arc
		(start 477.70415 -273.739864)
		(mid 477.665343 -273.765794)
		(end 477.619568 -273.774916)
		(width 0.10795)
		(layer "In9.Cu")
		(net "PHY_SCC_A_TO_DRV_A_11_DP")
	)
	(arc
		(start 280.101802 -347.037914)
		(mid 280.111435 -346.989396)
		(end 280.138886 -346.948252)
		(width 0.10795)
		(layer "In9.Cu")
		(net "PHY_SCC_A_TO_DRV_A_11_DP")
	)
	(arc
		(start 280.144982 -346.942156)
		(mid 280.186133 -346.914723)
		(end 280.234644 -346.905072)
		(width 0.10795)
		(layer "In9.Cu")
		(net "PHY_SCC_A_TO_DRV_A_11_DP")
	)
	(arc
		(start 280.138886 -347.5355)
		(mid 280.111453 -347.494349)
		(end 280.101802 -347.445838)
		(width 0.10795)
		(layer "In9.Cu")
		(net "PHY_SCC_A_TO_DRV_A_11_DP")
	)
	(segment
		(start 477.887792 -274.086066)
		(end 478.640648 -274.086066)
		(width 0.127)
		(layer "F.Cu")
		(net "PHY_SCC_A_TO_DRV_A_11_DN")
	)
	(segment
		(start 477.776286 -274.144994)
		(end 477.79813 -274.12315)
		(width 0.127)
		(layer "F.Cu")
		(net "PHY_SCC_A_TO_DRV_A_11_DN")
	)
	(segment
		(start 478.773998 -274.219416)
		(end 479.105214 -274.219416)
		(width 0.127)
		(layer "F.Cu")
		(net "PHY_SCC_A_TO_DRV_A_11_DN")
	)
	(segment
		(start 477.739202 -274.511516)
		(end 477.739202 -274.234656)
		(width 0.127)
		(layer "F.Cu")
		(net "PHY_SCC_A_TO_DRV_A_11_DN")
	)
	(segment
		(start 478.640648 -274.086066)
		(end 478.773998 -274.219416)
		(width 0.127)
		(layer "F.Cu")
		(net "PHY_SCC_A_TO_DRV_A_11_DN")
	)
	(arc
		(start 477.79813 -274.12315)
		(mid 477.839281 -274.095717)
		(end 477.887792 -274.086066)
		(width 0.127)
		(layer "F.Cu")
		(net "PHY_SCC_A_TO_DRV_A_11_DN")
	)
	(arc
		(start 477.739202 -274.234656)
		(mid 477.748835 -274.186138)
		(end 477.776286 -274.144994)
		(width 0.127)
		(layer "F.Cu")
		(net "PHY_SCC_A_TO_DRV_A_11_DN")
	)
	(segment
		(start 359.782364 -332.129892)
		(end 355.219254 -333.141574)
		(width 0.10795)
		(layer "In9.Cu")
		(net "PHY_SCC_A_TO_DRV_A_11_DN")
	)
	(segment
		(start 279.771602 -347.445838)
		(end 279.771602 -347.037914)
		(width 0.10795)
		(layer "In9.Cu")
		(net "PHY_SCC_A_TO_DRV_A_11_DN")
	)
	(segment
		(start 477.739202 -274.511516)
		(end 477.739202 -274.22475)
		(width 0.10795)
		(layer "In9.Cu")
		(net "PHY_SCC_A_TO_DRV_A_11_DN")
	)
	(segment
		(start 477.619568 -274.105116)
		(end 475.914212 -274.105116)
		(width 0.10795)
		(layer "In9.Cu")
		(net "PHY_SCC_A_TO_DRV_A_11_DN")
	)
	(segment
		(start 279.97277 -347.83649)
		(end 279.905206 -347.768926)
		(width 0.10795)
		(layer "In9.Cu")
		(net "PHY_SCC_A_TO_DRV_A_11_DN")
	)
	(segment
		(start 346.862146 -334.994504)
		(end 288.338514 -347.967554)
		(width 0.10795)
		(layer "In9.Cu")
		(net "PHY_SCC_A_TO_DRV_A_11_DN")
	)
	(segment
		(start 288.315146 -347.970094)
		(end 280.295858 -347.970094)
		(width 0.10795)
		(layer "In9.Cu")
		(net "PHY_SCC_A_TO_DRV_A_11_DN")
	)
	(segment
		(start 475.914212 -274.105116)
		(end 458.494384 -277.966932)
		(width 0.10795)
		(layer "In9.Cu")
		(net "PHY_SCC_A_TO_DRV_A_11_DN")
	)
	(segment
		(start 279.63876 -346.905072)
		(end 279.236678 -346.905072)
		(width 0.10795)
		(layer "In9.Cu")
		(net "PHY_SCC_A_TO_DRV_A_11_DN")
	)
	(segment
		(start 458.494384 -277.966932)
		(end 359.782364 -332.129892)
		(width 0.10795)
		(layer "In9.Cu")
		(net "PHY_SCC_A_TO_DRV_A_11_DN")
	)
	(segment
		(start 355.219254 -333.141574)
		(end 346.862146 -334.994504)
		(width 0.10795)
		(layer "In9.Cu")
		(net "PHY_SCC_A_TO_DRV_A_11_DN")
	)
	(segment
		(start 279.734518 -346.948252)
		(end 279.728422 -346.942156)
		(width 0.10795)
		(layer "In9.Cu")
		(net "PHY_SCC_A_TO_DRV_A_11_DN")
	)
	(arc
		(start 477.739202 -274.22475)
		(mid 477.730095 -274.178968)
		(end 477.70415 -274.140168)
		(width 0.10795)
		(layer "In9.Cu")
		(net "PHY_SCC_A_TO_DRV_A_11_DN")
	)
	(arc
		(start 477.70415 -274.140168)
		(mid 477.665343 -274.114238)
		(end 477.619568 -274.105116)
		(width 0.10795)
		(layer "In9.Cu")
		(net "PHY_SCC_A_TO_DRV_A_11_DN")
	)
	(arc
		(start 288.338514 -347.967554)
		(mid 288.3269 -347.969471)
		(end 288.315146 -347.970094)
		(width 0.10795)
		(layer "In9.Cu")
		(net "PHY_SCC_A_TO_DRV_A_11_DN")
	)
	(arc
		(start 280.295858 -347.970094)
		(mid 280.121047 -347.935375)
		(end 279.97277 -347.83649)
		(width 0.10795)
		(layer "In9.Cu")
		(net "PHY_SCC_A_TO_DRV_A_11_DN")
	)
	(arc
		(start 279.771602 -347.037914)
		(mid 279.761969 -346.989396)
		(end 279.734518 -346.948252)
		(width 0.10795)
		(layer "In9.Cu")
		(net "PHY_SCC_A_TO_DRV_A_11_DN")
	)
	(arc
		(start 279.905206 -347.768926)
		(mid 279.80632 -347.620649)
		(end 279.771602 -347.445838)
		(width 0.10795)
		(layer "In9.Cu")
		(net "PHY_SCC_A_TO_DRV_A_11_DN")
	)
	(arc
		(start 279.728422 -346.942156)
		(mid 279.687271 -346.914723)
		(end 279.63876 -346.905072)
		(width 0.10795)
		(layer "In9.Cu")
		(net "PHY_SCC_A_TO_DRV_A_11_DN")
	)
	(segment
		(start 447.223896 -273.660616)
		(end 447.555112 -273.660616)
		(width 0.127)
		(layer "F.Cu")
		(net "PHY_SCC_A_TO_DRV_A_10_DP")
	)
	(segment
		(start 446.1891 -273.368516)
		(end 446.1891 -273.628104)
		(width 0.127)
		(layer "F.Cu")
		(net "PHY_SCC_A_TO_DRV_A_10_DP")
	)
	(segment
		(start 447.090546 -273.793966)
		(end 447.223896 -273.660616)
		(width 0.127)
		(layer "F.Cu")
		(net "PHY_SCC_A_TO_DRV_A_10_DP")
	)
	(segment
		(start 446.226184 -273.717766)
		(end 446.2653 -273.756882)
		(width 0.127)
		(layer "F.Cu")
		(net "PHY_SCC_A_TO_DRV_A_10_DP")
	)
	(segment
		(start 446.354962 -273.793966)
		(end 447.090546 -273.793966)
		(width 0.127)
		(layer "F.Cu")
		(net "PHY_SCC_A_TO_DRV_A_10_DP")
	)
	(arc
		(start 446.1891 -273.628104)
		(mid 446.198733 -273.676622)
		(end 446.226184 -273.717766)
		(width 0.127)
		(layer "F.Cu")
		(net "PHY_SCC_A_TO_DRV_A_10_DP")
	)
	(arc
		(start 446.2653 -273.756882)
		(mid 446.306451 -273.784315)
		(end 446.354962 -273.793966)
		(width 0.127)
		(layer "F.Cu")
		(net "PHY_SCC_A_TO_DRV_A_10_DP")
	)
	(segment
		(start 279.17648 -345.802966)
		(end 279.138888 -345.765374)
		(width 0.10795)
		(layer "In9.Cu")
		(net "PHY_SCC_A_TO_DRV_A_10_DP")
	)
	(segment
		(start 279.238964 -345.105228)
		(end 279.636728 -345.105228)
		(width 0.10795)
		(layer "In9.Cu")
		(net "PHY_SCC_A_TO_DRV_A_10_DP")
	)
	(segment
		(start 357.33482 -330.581)
		(end 357.01859 -330.651104)
		(width 0.10795)
		(layer "In9.Cu")
		(net "PHY_SCC_A_TO_DRV_A_10_DP")
	)
	(segment
		(start 356.293166 -330.811886)
		(end 355.976936 -330.88199)
		(width 0.10795)
		(layer "In9.Cu")
		(net "PHY_SCC_A_TO_DRV_A_10_DP")
	)
	(segment
		(start 357.01859 -330.651104)
		(end 356.859332 -330.90104)
		(width 0.10795)
		(layer "In9.Cu")
		(net "PHY_SCC_A_TO_DRV_A_10_DP")
	)
	(segment
		(start 358.37622 -330.350114)
		(end 358.05999 -330.420218)
		(width 0.10795)
		(layer "In9.Cu")
		(net "PHY_SCC_A_TO_DRV_A_10_DP")
	)
	(segment
		(start 446.1891 -273.368516)
		(end 446.1891 -273.655282)
		(width 0.10795)
		(layer "In9.Cu")
		(net "PHY_SCC_A_TO_DRV_A_10_DP")
	)
	(segment
		(start 357.584756 -330.740258)
		(end 357.33482 -330.581)
		(width 0.10795)
		(layer "In9.Cu")
		(net "PHY_SCC_A_TO_DRV_A_10_DP")
	)
	(segment
		(start 289.478974 -345.84005)
		(end 279.266142 -345.84005)
		(width 0.10795)
		(layer "In9.Cu")
		(net "PHY_SCC_A_TO_DRV_A_10_DP")
	)
	(segment
		(start 429.181768 -280.594308)
		(end 360.539284 -330.085192)
		(width 0.10795)
		(layer "In9.Cu")
		(net "PHY_SCC_A_TO_DRV_A_10_DP")
	)
	(segment
		(start 357.900732 -330.670154)
		(end 357.584756 -330.740258)
		(width 0.10795)
		(layer "In9.Cu")
		(net "PHY_SCC_A_TO_DRV_A_10_DP")
	)
	(segment
		(start 360.539284 -330.085192)
		(end 358.626156 -330.509372)
		(width 0.10795)
		(layer "In9.Cu")
		(net "PHY_SCC_A_TO_DRV_A_10_DP")
	)
	(segment
		(start 279.101804 -345.675712)
		(end 279.101804 -345.242388)
		(width 0.10795)
		(layer "In9.Cu")
		(net "PHY_SCC_A_TO_DRV_A_10_DP")
	)
	(segment
		(start 358.05999 -330.420218)
		(end 357.900732 -330.670154)
		(width 0.10795)
		(layer "In9.Cu")
		(net "PHY_SCC_A_TO_DRV_A_10_DP")
	)
	(segment
		(start 444.532766 -273.774916)
		(end 429.181768 -280.594308)
		(width 0.10795)
		(layer "In9.Cu")
		(net "PHY_SCC_A_TO_DRV_A_10_DP")
	)
	(segment
		(start 355.817932 -331.131926)
		(end 289.478974 -345.84005)
		(width 0.10795)
		(layer "In9.Cu")
		(net "PHY_SCC_A_TO_DRV_A_10_DP")
	)
	(segment
		(start 356.543102 -330.971144)
		(end 356.293166 -330.811886)
		(width 0.10795)
		(layer "In9.Cu")
		(net "PHY_SCC_A_TO_DRV_A_10_DP")
	)
	(segment
		(start 358.626156 -330.509372)
		(end 358.37622 -330.350114)
		(width 0.10795)
		(layer "In9.Cu")
		(net "PHY_SCC_A_TO_DRV_A_10_DP")
	)
	(segment
		(start 356.859332 -330.90104)
		(end 356.543102 -330.971144)
		(width 0.10795)
		(layer "In9.Cu")
		(net "PHY_SCC_A_TO_DRV_A_10_DP")
	)
	(segment
		(start 355.976936 -330.88199)
		(end 355.817932 -331.131926)
		(width 0.10795)
		(layer "In9.Cu")
		(net "PHY_SCC_A_TO_DRV_A_10_DP")
	)
	(segment
		(start 279.138888 -345.152726)
		(end 279.149302 -345.142312)
		(width 0.10795)
		(layer "In9.Cu")
		(net "PHY_SCC_A_TO_DRV_A_10_DP")
	)
	(segment
		(start 446.069466 -273.774916)
		(end 444.532766 -273.774916)
		(width 0.10795)
		(layer "In9.Cu")
		(net "PHY_SCC_A_TO_DRV_A_10_DP")
	)
	(arc
		(start 446.154048 -273.739864)
		(mid 446.115241 -273.765794)
		(end 446.069466 -273.774916)
		(width 0.10795)
		(layer "In9.Cu")
		(net "PHY_SCC_A_TO_DRV_A_10_DP")
	)
	(arc
		(start 279.149302 -345.142312)
		(mid 279.190453 -345.114879)
		(end 279.238964 -345.105228)
		(width 0.10795)
		(layer "In9.Cu")
		(net "PHY_SCC_A_TO_DRV_A_10_DP")
	)
	(arc
		(start 279.266142 -345.84005)
		(mid 279.217624 -345.830417)
		(end 279.17648 -345.802966)
		(width 0.10795)
		(layer "In9.Cu")
		(net "PHY_SCC_A_TO_DRV_A_10_DP")
	)
	(arc
		(start 279.101804 -345.242388)
		(mid 279.111437 -345.19387)
		(end 279.138888 -345.152726)
		(width 0.10795)
		(layer "In9.Cu")
		(net "PHY_SCC_A_TO_DRV_A_10_DP")
	)
	(arc
		(start 279.138888 -345.765374)
		(mid 279.111455 -345.724223)
		(end 279.101804 -345.675712)
		(width 0.10795)
		(layer "In9.Cu")
		(net "PHY_SCC_A_TO_DRV_A_10_DP")
	)
	(arc
		(start 446.1891 -273.655282)
		(mid 446.179993 -273.701064)
		(end 446.154048 -273.739864)
		(width 0.10795)
		(layer "In9.Cu")
		(net "PHY_SCC_A_TO_DRV_A_10_DP")
	)
	(segment
		(start 446.340992 -274.086066)
		(end 447.090546 -274.086066)
		(width 0.127)
		(layer "F.Cu")
		(net "PHY_SCC_A_TO_DRV_A_10_DN")
	)
	(segment
		(start 446.1891 -274.511516)
		(end 446.1891 -274.237958)
		(width 0.127)
		(layer "F.Cu")
		(net "PHY_SCC_A_TO_DRV_A_10_DN")
	)
	(segment
		(start 447.223896 -274.219416)
		(end 447.555112 -274.219416)
		(width 0.127)
		(layer "F.Cu")
		(net "PHY_SCC_A_TO_DRV_A_10_DN")
	)
	(segment
		(start 447.090546 -274.086066)
		(end 447.223896 -274.219416)
		(width 0.127)
		(layer "F.Cu")
		(net "PHY_SCC_A_TO_DRV_A_10_DN")
	)
	(segment
		(start 446.226184 -274.148296)
		(end 446.25133 -274.12315)
		(width 0.127)
		(layer "F.Cu")
		(net "PHY_SCC_A_TO_DRV_A_10_DN")
	)
	(arc
		(start 446.25133 -274.12315)
		(mid 446.292481 -274.095717)
		(end 446.340992 -274.086066)
		(width 0.127)
		(layer "F.Cu")
		(net "PHY_SCC_A_TO_DRV_A_10_DN")
	)
	(arc
		(start 446.1891 -274.237958)
		(mid 446.198733 -274.18944)
		(end 446.226184 -274.148296)
		(width 0.127)
		(layer "F.Cu")
		(net "PHY_SCC_A_TO_DRV_A_10_DN")
	)
	(segment
		(start 278.634444 -345.105228)
		(end 278.23668 -345.105228)
		(width 0.10795)
		(layer "In9.Cu")
		(net "PHY_SCC_A_TO_DRV_A_10_DN")
	)
	(segment
		(start 444.60287 -274.105116)
		(end 429.347122 -280.882344)
		(width 0.10795)
		(layer "In9.Cu")
		(net "PHY_SCC_A_TO_DRV_A_10_DN")
	)
	(segment
		(start 278.73452 -345.152726)
		(end 278.724106 -345.142312)
		(width 0.10795)
		(layer "In9.Cu")
		(net "PHY_SCC_A_TO_DRV_A_10_DN")
	)
	(segment
		(start 278.943054 -346.036646)
		(end 278.905208 -345.9988)
		(width 0.10795)
		(layer "In9.Cu")
		(net "PHY_SCC_A_TO_DRV_A_10_DN")
	)
	(segment
		(start 360.677206 -330.39304)
		(end 289.515296 -346.17025)
		(width 0.10795)
		(layer "In9.Cu")
		(net "PHY_SCC_A_TO_DRV_A_10_DN")
	)
	(segment
		(start 429.347122 -280.882344)
		(end 360.677206 -330.39304)
		(width 0.10795)
		(layer "In9.Cu")
		(net "PHY_SCC_A_TO_DRV_A_10_DN")
	)
	(segment
		(start 278.771604 -345.675712)
		(end 278.771604 -345.242388)
		(width 0.10795)
		(layer "In9.Cu")
		(net "PHY_SCC_A_TO_DRV_A_10_DN")
	)
	(segment
		(start 446.1891 -274.511516)
		(end 446.1891 -274.22475)
		(width 0.10795)
		(layer "In9.Cu")
		(net "PHY_SCC_A_TO_DRV_A_10_DN")
	)
	(segment
		(start 446.069466 -274.105116)
		(end 444.60287 -274.105116)
		(width 0.10795)
		(layer "In9.Cu")
		(net "PHY_SCC_A_TO_DRV_A_10_DN")
	)
	(segment
		(start 289.515296 -346.17025)
		(end 279.266142 -346.17025)
		(width 0.10795)
		(layer "In9.Cu")
		(net "PHY_SCC_A_TO_DRV_A_10_DN")
	)
	(arc
		(start 278.905208 -345.9988)
		(mid 278.806322 -345.850523)
		(end 278.771604 -345.675712)
		(width 0.10795)
		(layer "In9.Cu")
		(net "PHY_SCC_A_TO_DRV_A_10_DN")
	)
	(arc
		(start 279.266142 -346.17025)
		(mid 279.091331 -346.135531)
		(end 278.943054 -346.036646)
		(width 0.10795)
		(layer "In9.Cu")
		(net "PHY_SCC_A_TO_DRV_A_10_DN")
	)
	(arc
		(start 446.1891 -274.22475)
		(mid 446.179993 -274.178968)
		(end 446.154048 -274.140168)
		(width 0.10795)
		(layer "In9.Cu")
		(net "PHY_SCC_A_TO_DRV_A_10_DN")
	)
	(arc
		(start 278.771604 -345.242388)
		(mid 278.761971 -345.19387)
		(end 278.73452 -345.152726)
		(width 0.10795)
		(layer "In9.Cu")
		(net "PHY_SCC_A_TO_DRV_A_10_DN")
	)
	(arc
		(start 446.154048 -274.140168)
		(mid 446.115241 -274.114238)
		(end 446.069466 -274.105116)
		(width 0.10795)
		(layer "In9.Cu")
		(net "PHY_SCC_A_TO_DRV_A_10_DN")
	)
	(arc
		(start 278.724106 -345.142312)
		(mid 278.682955 -345.114879)
		(end 278.634444 -345.105228)
		(width 0.10795)
		(layer "In9.Cu")
		(net "PHY_SCC_A_TO_DRV_A_10_DN")
	)
	(segment
		(start 270.951198 -356.71887)
		(end 272.26895 -356.71887)
		(width 0.127)
		(layer "F.Cu")
		(net "PHY_SCC_A_TO_DRV_A_1_DP")
	)
	(segment
		(start 272.68805 -357.13797)
		(end 272.68805 -357.577898)
		(width 0.127)
		(layer "F.Cu")
		(net "PHY_SCC_A_TO_DRV_A_1_DP")
	)
	(segment
		(start 204.33919 -332.294484)
		(end 207.9117 -333.009494)
		(width 0.127)
		(layer "F.Cu")
		(net "PHY_SCC_A_TO_DRV_A_1_DP")
	)
	(segment
		(start 203.200254 -332.066392)
		(end 204.338936 -332.29423)
		(width 0.127)
		(layer "F.Cu")
		(net "PHY_SCC_A_TO_DRV_A_1_DP")
	)
	(segment
		(start 65.481708 -273.827494)
		(end 66.651632 -274.568412)
		(width 0.127)
		(layer "F.Cu")
		(net "PHY_SCC_A_TO_DRV_A_1_DP")
	)
	(segment
		(start 207.9117 -333.009494)
		(end 237.754668 -338.983066)
		(width 0.127)
		(layer "F.Cu")
		(net "PHY_SCC_A_TO_DRV_A_1_DP")
	)
	(segment
		(start 94.021402 -338.07781)
		(end 112.48771 -341.774018)
		(width 0.127)
		(layer "F.Cu")
		(net "PHY_SCC_A_TO_DRV_A_1_DP")
	)
	(segment
		(start 158.574232 -341.099902)
		(end 203.200254 -332.066392)
		(width 0.127)
		(layer "F.Cu")
		(net "PHY_SCC_A_TO_DRV_A_1_DP")
	)
	(segment
		(start 112.48771 -341.774018)
		(end 137.231882 -336.825082)
		(width 0.127)
		(layer "F.Cu")
		(net "PHY_SCC_A_TO_DRV_A_1_DP")
	)
	(segment
		(start 65.019428 -273.827494)
		(end 65.481708 -273.827494)
		(width 0.127)
		(layer "F.Cu")
		(net "PHY_SCC_A_TO_DRV_A_1_DP")
	)
	(segment
		(start 137.231882 -336.825082)
		(end 158.574232 -341.099902)
		(width 0.127)
		(layer "F.Cu")
		(net "PHY_SCC_A_TO_DRV_A_1_DP")
	)
	(segment
		(start 204.338936 -332.29423)
		(end 204.33919 -332.294484)
		(width 0.127)
		(layer "F.Cu")
		(net "PHY_SCC_A_TO_DRV_A_1_DP")
	)
	(segment
		(start 237.754668 -338.983066)
		(end 270.951198 -356.71887)
		(width 0.127)
		(layer "F.Cu")
		(net "PHY_SCC_A_TO_DRV_A_1_DP")
	)
	(segment
		(start 64.292734 -273.660616)
		(end 64.85255 -273.660616)
		(width 0.127)
		(layer "F.Cu")
		(net "PHY_SCC_A_TO_DRV_A_1_DP")
	)
	(segment
		(start 88.869012 -334.818228)
		(end 94.021402 -338.07781)
		(width 0.127)
		(layer "F.Cu")
		(net "PHY_SCC_A_TO_DRV_A_1_DP")
	)
	(segment
		(start 272.81505 -357.704898)
		(end 273.1135 -357.704898)
		(width 0.127)
		(layer "F.Cu")
		(net "PHY_SCC_A_TO_DRV_A_1_DP")
	)
	(segment
		(start 66.651632 -274.568412)
		(end 88.869012 -334.818228)
		(width 0.127)
		(layer "F.Cu")
		(net "PHY_SCC_A_TO_DRV_A_1_DP")
	)
	(segment
		(start 64.85255 -273.660616)
		(end 65.019428 -273.827494)
		(width 0.127)
		(layer "F.Cu")
		(net "PHY_SCC_A_TO_DRV_A_1_DP")
	)
	(arc
		(start 272.68805 -357.577898)
		(mid 272.725247 -357.667701)
		(end 272.81505 -357.704898)
		(width 0.127)
		(layer "F.Cu")
		(net "PHY_SCC_A_TO_DRV_A_1_DP")
	)
	(arc
		(start 272.26895 -356.71887)
		(mid 272.565298 -356.841622)
		(end 272.68805 -357.13797)
		(width 0.127)
		(layer "F.Cu")
		(net "PHY_SCC_A_TO_DRV_A_1_DP")
	)
	(segment
		(start 279.082754 -356.032054)
		(end 279.082754 -356.283006)
		(width 0.127)
		(layer "B.Cu")
		(net "PHY_SCC_A_TO_DRV_A_1_DP")
	)
	(segment
		(start 272.869152 -357.704898)
		(end 273.1135 -357.704898)
		(width 0.127)
		(layer "B.Cu")
		(net "PHY_SCC_A_TO_DRV_A_1_DP")
	)
	(segment
		(start 279.636728 -355.905054)
		(end 279.209754 -355.905054)
		(width 0.127)
		(layer "B.Cu")
		(net "PHY_SCC_A_TO_DRV_A_1_DP")
	)
	(segment
		(start 278.329136 -356.951026)
		(end 273.11223 -356.951026)
		(width 0.127)
		(layer "B.Cu")
		(net "PHY_SCC_A_TO_DRV_A_1_DP")
	)
	(segment
		(start 272.68805 -357.375206)
		(end 272.68805 -357.523796)
		(width 0.127)
		(layer "B.Cu")
		(net "PHY_SCC_A_TO_DRV_A_1_DP")
	)
	(arc
		(start 272.68805 -357.523796)
		(mid 272.741094 -357.651854)
		(end 272.869152 -357.704898)
		(width 0.127)
		(layer "B.Cu")
		(net "PHY_SCC_A_TO_DRV_A_1_DP")
	)
	(arc
		(start 278.949658 -356.662736)
		(mid 278.927871 -356.688501)
		(end 278.9047 -356.713028)
		(width 0.127)
		(layer "B.Cu")
		(net "PHY_SCC_A_TO_DRV_A_1_DP")
	)
	(arc
		(start 278.9047 -356.713028)
		(mid 278.640599 -356.889309)
		(end 278.329136 -356.951026)
		(width 0.127)
		(layer "B.Cu")
		(net "PHY_SCC_A_TO_DRV_A_1_DP")
	)
	(arc
		(start 279.209754 -355.905054)
		(mid 279.119951 -355.942251)
		(end 279.082754 -356.032054)
		(width 0.127)
		(layer "B.Cu")
		(net "PHY_SCC_A_TO_DRV_A_1_DP")
	)
	(arc
		(start 273.11223 -356.951026)
		(mid 272.812289 -357.075265)
		(end 272.68805 -357.375206)
		(width 0.127)
		(layer "B.Cu")
		(net "PHY_SCC_A_TO_DRV_A_1_DP")
	)
	(arc
		(start 279.082754 -356.283006)
		(mid 279.04852 -356.484199)
		(end 278.949658 -356.662736)
		(width 0.127)
		(layer "B.Cu")
		(net "PHY_SCC_A_TO_DRV_A_1_DP")
	)
	(segment
		(start 88.629236 -335.012284)
		(end 93.910912 -338.353654)
		(width 0.127)
		(layer "F.Cu")
		(net "PHY_SCC_A_TO_DRV_A_1_DN")
	)
	(segment
		(start 204.16266 -332.55712)
		(end 204.28204 -332.736444)
		(width 0.127)
		(layer "F.Cu")
		(net "PHY_SCC_A_TO_DRV_A_1_DN")
	)
	(segment
		(start 204.834998 -332.69174)
		(end 205.208632 -332.766416)
		(width 0.127)
		(layer "F.Cu")
		(net "PHY_SCC_A_TO_DRV_A_1_DN")
	)
	(segment
		(start 207.30083 -333.185262)
		(end 207.42021 -333.364586)
		(width 0.127)
		(layer "F.Cu")
		(net "PHY_SCC_A_TO_DRV_A_1_DN")
	)
	(segment
		(start 206.254604 -332.975966)
		(end 206.374238 -333.15529)
		(width 0.127)
		(layer "F.Cu")
		(net "PHY_SCC_A_TO_DRV_A_1_DN")
	)
	(segment
		(start 205.208632 -332.766416)
		(end 205.328266 -332.945994)
		(width 0.127)
		(layer "F.Cu")
		(net "PHY_SCC_A_TO_DRV_A_1_DN")
	)
	(segment
		(start 272.26895 -357.704898)
		(end 271.9705 -357.704898)
		(width 0.127)
		(layer "F.Cu")
		(net "PHY_SCC_A_TO_DRV_A_1_DN")
	)
	(segment
		(start 204.655674 -332.811374)
		(end 204.834998 -332.69174)
		(width 0.127)
		(layer "F.Cu")
		(net "PHY_SCC_A_TO_DRV_A_1_DN")
	)
	(segment
		(start 204.28204 -332.736444)
		(end 204.655674 -332.811374)
		(width 0.127)
		(layer "F.Cu")
		(net "PHY_SCC_A_TO_DRV_A_1_DN")
	)
	(segment
		(start 205.328266 -332.945994)
		(end 205.701646 -333.02067)
		(width 0.127)
		(layer "F.Cu")
		(net "PHY_SCC_A_TO_DRV_A_1_DN")
	)
	(segment
		(start 64.85255 -274.219416)
		(end 64.952372 -274.119594)
		(width 0.127)
		(layer "F.Cu")
		(net "PHY_SCC_A_TO_DRV_A_1_DN")
	)
	(segment
		(start 158.574486 -341.398098)
		(end 203.200508 -332.364588)
		(width 0.127)
		(layer "F.Cu")
		(net "PHY_SCC_A_TO_DRV_A_1_DN")
	)
	(segment
		(start 207.793844 -333.439516)
		(end 207.973168 -333.319882)
		(width 0.127)
		(layer "F.Cu")
		(net "PHY_SCC_A_TO_DRV_A_1_DN")
	)
	(segment
		(start 270.878046 -357.01097)
		(end 272.26895 -357.01097)
		(width 0.127)
		(layer "F.Cu")
		(net "PHY_SCC_A_TO_DRV_A_1_DN")
	)
	(segment
		(start 64.952372 -274.119594)
		(end 65.396872 -274.119594)
		(width 0.127)
		(layer "F.Cu")
		(net "PHY_SCC_A_TO_DRV_A_1_DN")
	)
	(segment
		(start 93.910912 -338.353654)
		(end 112.48771 -342.07196)
		(width 0.127)
		(layer "F.Cu")
		(net "PHY_SCC_A_TO_DRV_A_1_DN")
	)
	(segment
		(start 66.411602 -274.762468)
		(end 71.950834 -289.783266)
		(width 0.127)
		(layer "F.Cu")
		(net "PHY_SCC_A_TO_DRV_A_1_DN")
	)
	(segment
		(start 272.39595 -357.13797)
		(end 272.39595 -357.577898)
		(width 0.127)
		(layer "F.Cu")
		(net "PHY_SCC_A_TO_DRV_A_1_DN")
	)
	(segment
		(start 65.396872 -274.119594)
		(end 66.411602 -274.762468)
		(width 0.127)
		(layer "F.Cu")
		(net "PHY_SCC_A_TO_DRV_A_1_DN")
	)
	(segment
		(start 203.200508 -332.364588)
		(end 204.16266 -332.55712)
		(width 0.127)
		(layer "F.Cu")
		(net "PHY_SCC_A_TO_DRV_A_1_DN")
	)
	(segment
		(start 112.48771 -342.07196)
		(end 137.231882 -337.123024)
		(width 0.127)
		(layer "F.Cu")
		(net "PHY_SCC_A_TO_DRV_A_1_DN")
	)
	(segment
		(start 205.701646 -333.02067)
		(end 205.88097 -332.901036)
		(width 0.127)
		(layer "F.Cu")
		(net "PHY_SCC_A_TO_DRV_A_1_DN")
	)
	(segment
		(start 205.88097 -332.901036)
		(end 206.254604 -332.975966)
		(width 0.127)
		(layer "F.Cu")
		(net "PHY_SCC_A_TO_DRV_A_1_DN")
	)
	(segment
		(start 64.292734 -274.219416)
		(end 64.85255 -274.219416)
		(width 0.127)
		(layer "F.Cu")
		(net "PHY_SCC_A_TO_DRV_A_1_DN")
	)
	(segment
		(start 207.42021 -333.364586)
		(end 207.793844 -333.439516)
		(width 0.127)
		(layer "F.Cu")
		(net "PHY_SCC_A_TO_DRV_A_1_DN")
	)
	(segment
		(start 237.654846 -339.261196)
		(end 270.878046 -357.01097)
		(width 0.127)
		(layer "F.Cu")
		(net "PHY_SCC_A_TO_DRV_A_1_DN")
	)
	(segment
		(start 71.950834 -289.783266)
		(end 88.629236 -335.012284)
		(width 0.127)
		(layer "F.Cu")
		(net "PHY_SCC_A_TO_DRV_A_1_DN")
	)
	(segment
		(start 206.927196 -333.110586)
		(end 207.30083 -333.185262)
		(width 0.127)
		(layer "F.Cu")
		(net "PHY_SCC_A_TO_DRV_A_1_DN")
	)
	(segment
		(start 206.747872 -333.229966)
		(end 206.927196 -333.110586)
		(width 0.127)
		(layer "F.Cu")
		(net "PHY_SCC_A_TO_DRV_A_1_DN")
	)
	(segment
		(start 137.231882 -337.123024)
		(end 158.574486 -341.398098)
		(width 0.127)
		(layer "F.Cu")
		(net "PHY_SCC_A_TO_DRV_A_1_DN")
	)
	(segment
		(start 206.374238 -333.15529)
		(end 206.747872 -333.229966)
		(width 0.127)
		(layer "F.Cu")
		(net "PHY_SCC_A_TO_DRV_A_1_DN")
	)
	(segment
		(start 207.973168 -333.319882)
		(end 237.654846 -339.261196)
		(width 0.127)
		(layer "F.Cu")
		(net "PHY_SCC_A_TO_DRV_A_1_DN")
	)
	(arc
		(start 272.26895 -357.01097)
		(mid 272.358753 -357.048167)
		(end 272.39595 -357.13797)
		(width 0.127)
		(layer "F.Cu")
		(net "PHY_SCC_A_TO_DRV_A_1_DN")
	)
	(arc
		(start 272.39595 -357.577898)
		(mid 272.358753 -357.667701)
		(end 272.26895 -357.704898)
		(width 0.127)
		(layer "F.Cu")
		(net "PHY_SCC_A_TO_DRV_A_1_DN")
	)
	(segment
		(start 273.11223 -356.658926)
		(end 278.32939 -356.658926)
		(width 0.127)
		(layer "B.Cu")
		(net "PHY_SCC_A_TO_DRV_A_1_DN")
	)
	(segment
		(start 278.663654 -355.905054)
		(end 278.23668 -355.905054)
		(width 0.127)
		(layer "B.Cu")
		(net "PHY_SCC_A_TO_DRV_A_1_DN")
	)
	(segment
		(start 271.9705 -357.704898)
		(end 272.214848 -357.704898)
		(width 0.127)
		(layer "B.Cu")
		(net "PHY_SCC_A_TO_DRV_A_1_DN")
	)
	(segment
		(start 272.39595 -357.523796)
		(end 272.39595 -357.375206)
		(width 0.127)
		(layer "B.Cu")
		(net "PHY_SCC_A_TO_DRV_A_1_DN")
	)
	(segment
		(start 278.790654 -356.282498)
		(end 278.790654 -356.032054)
		(width 0.127)
		(layer "B.Cu")
		(net "PHY_SCC_A_TO_DRV_A_1_DN")
	)
	(arc
		(start 278.721312 -356.48011)
		(mid 278.772819 -356.387211)
		(end 278.790654 -356.282498)
		(width 0.127)
		(layer "B.Cu")
		(net "PHY_SCC_A_TO_DRV_A_1_DN")
	)
	(arc
		(start 272.214848 -357.704898)
		(mid 272.342906 -357.651854)
		(end 272.39595 -357.523796)
		(width 0.127)
		(layer "B.Cu")
		(net "PHY_SCC_A_TO_DRV_A_1_DN")
	)
	(arc
		(start 278.697944 -356.506272)
		(mid 278.709988 -356.493512)
		(end 278.721312 -356.48011)
		(width 0.127)
		(layer "B.Cu")
		(net "PHY_SCC_A_TO_DRV_A_1_DN")
	)
	(arc
		(start 278.32939 -356.658926)
		(mid 278.528848 -356.619251)
		(end 278.697944 -356.506272)
		(width 0.127)
		(layer "B.Cu")
		(net "PHY_SCC_A_TO_DRV_A_1_DN")
	)
	(arc
		(start 278.790654 -356.032054)
		(mid 278.753457 -355.942251)
		(end 278.663654 -355.905054)
		(width 0.127)
		(layer "B.Cu")
		(net "PHY_SCC_A_TO_DRV_A_1_DN")
	)
	(arc
		(start 272.39595 -357.375206)
		(mid 272.605744 -356.86872)
		(end 273.11223 -356.658926)
		(width 0.127)
		(layer "B.Cu")
		(net "PHY_SCC_A_TO_DRV_A_1_DN")
	)
	(segment
		(start 32.742886 -273.660616)
		(end 33.150302 -273.660616)
		(width 0.127)
		(layer "F.Cu")
		(net "PHY_SCC_A_TO_DRV_A_0_DP")
	)
	(segment
		(start 208.857088 -335.027524)
		(end 208.857088 -335.028032)
		(width 0.127)
		(layer "F.Cu")
		(net "PHY_SCC_A_TO_DRV_A_0_DP")
	)
	(segment
		(start 237.456726 -340.753446)
		(end 270.439896 -358.370632)
		(width 0.127)
		(layer "F.Cu")
		(net "PHY_SCC_A_TO_DRV_A_0_DP")
	)
	(segment
		(start 35.234372 -274.598892)
		(end 43.286172 -296.43324)
		(width 0.127)
		(layer "F.Cu")
		(net "PHY_SCC_A_TO_DRV_A_0_DP")
	)
	(segment
		(start 43.905424 -297.386756)
		(end 50.059844 -306.86375)
		(width 0.127)
		(layer "F.Cu")
		(net "PHY_SCC_A_TO_DRV_A_0_DP")
	)
	(segment
		(start 272.81505 -359.504996)
		(end 273.1135 -359.504996)
		(width 0.127)
		(layer "F.Cu")
		(net "PHY_SCC_A_TO_DRV_A_0_DP")
	)
	(segment
		(start 270.439896 -358.370632)
		(end 272.26895 -358.370632)
		(width 0.127)
		(layer "F.Cu")
		(net "PHY_SCC_A_TO_DRV_A_0_DP")
	)
	(segment
		(start 272.68805 -358.789732)
		(end 272.68805 -359.377996)
		(width 0.127)
		(layer "F.Cu")
		(net "PHY_SCC_A_TO_DRV_A_0_DP")
	)
	(segment
		(start 136.937496 -338.482178)
		(end 158.386526 -342.775286)
		(width 0.127)
		(layer "F.Cu")
		(net "PHY_SCC_A_TO_DRV_A_0_DP")
	)
	(segment
		(start 50.059844 -306.86375)
		(end 56.83377 -317.294514)
		(width 0.127)
		(layer "F.Cu")
		(net "PHY_SCC_A_TO_DRV_A_0_DP")
	)
	(segment
		(start 93.565218 -339.653372)
		(end 112.48136 -343.43975)
		(width 0.127)
		(layer "F.Cu")
		(net "PHY_SCC_A_TO_DRV_A_0_DP")
	)
	(segment
		(start 56.834278 -317.295022)
		(end 93.565218 -339.653372)
		(width 0.127)
		(layer "F.Cu")
		(net "PHY_SCC_A_TO_DRV_A_0_DP")
	)
	(segment
		(start 56.83377 -317.294514)
		(end 56.834278 -317.295022)
		(width 0.127)
		(layer "F.Cu")
		(net "PHY_SCC_A_TO_DRV_A_0_DP")
	)
	(segment
		(start 43.286172 -296.43324)
		(end 43.905424 -297.386756)
		(width 0.127)
		(layer "F.Cu")
		(net "PHY_SCC_A_TO_DRV_A_0_DP")
	)
	(segment
		(start 34.012378 -273.825208)
		(end 35.234372 -274.598892)
		(width 0.127)
		(layer "F.Cu")
		(net "PHY_SCC_A_TO_DRV_A_0_DP")
	)
	(segment
		(start 158.386526 -342.775286)
		(end 202.72502 -333.800196)
		(width 0.127)
		(layer "F.Cu")
		(net "PHY_SCC_A_TO_DRV_A_0_DP")
	)
	(segment
		(start 33.314894 -273.825208)
		(end 34.012378 -273.825208)
		(width 0.127)
		(layer "F.Cu")
		(net "PHY_SCC_A_TO_DRV_A_0_DP")
	)
	(segment
		(start 112.48136 -343.43975)
		(end 136.937496 -338.482178)
		(width 0.127)
		(layer "F.Cu")
		(net "PHY_SCC_A_TO_DRV_A_0_DP")
	)
	(segment
		(start 202.72502 -333.800196)
		(end 208.857088 -335.027524)
		(width 0.127)
		(layer "F.Cu")
		(net "PHY_SCC_A_TO_DRV_A_0_DP")
	)
	(segment
		(start 33.150302 -273.660616)
		(end 33.314894 -273.825208)
		(width 0.127)
		(layer "F.Cu")
		(net "PHY_SCC_A_TO_DRV_A_0_DP")
	)
	(segment
		(start 208.857088 -335.028032)
		(end 237.456726 -340.753446)
		(width 0.127)
		(layer "F.Cu")
		(net "PHY_SCC_A_TO_DRV_A_0_DP")
	)
	(arc
		(start 272.26895 -358.370632)
		(mid 272.565298 -358.493384)
		(end 272.68805 -358.789732)
		(width 0.127)
		(layer "F.Cu")
		(net "PHY_SCC_A_TO_DRV_A_0_DP")
	)
	(arc
		(start 272.68805 -359.377996)
		(mid 272.725247 -359.467799)
		(end 272.81505 -359.504996)
		(width 0.127)
		(layer "F.Cu")
		(net "PHY_SCC_A_TO_DRV_A_0_DP")
	)
	(segment
		(start 272.68805 -359.323894)
		(end 272.68805 -359.175304)
		(width 0.127)
		(layer "B.Cu")
		(net "PHY_SCC_A_TO_DRV_A_0_DP")
	)
	(segment
		(start 280.209752 -357.705152)
		(end 280.636726 -357.705152)
		(width 0.127)
		(layer "B.Cu")
		(net "PHY_SCC_A_TO_DRV_A_0_DP")
	)
	(segment
		(start 273.11223 -358.751124)
		(end 279.329134 -358.751124)
		(width 0.127)
		(layer "B.Cu")
		(net "PHY_SCC_A_TO_DRV_A_0_DP")
	)
	(segment
		(start 280.082752 -358.083104)
		(end 280.082752 -357.832152)
		(width 0.127)
		(layer "B.Cu")
		(net "PHY_SCC_A_TO_DRV_A_0_DP")
	)
	(segment
		(start 273.1135 -359.504996)
		(end 272.869152 -359.504996)
		(width 0.127)
		(layer "B.Cu")
		(net "PHY_SCC_A_TO_DRV_A_0_DP")
	)
	(arc
		(start 279.904698 -358.513126)
		(mid 279.92788 -358.488608)
		(end 279.949656 -358.462834)
		(width 0.127)
		(layer "B.Cu")
		(net "PHY_SCC_A_TO_DRV_A_0_DP")
	)
	(arc
		(start 279.949656 -358.462834)
		(mid 280.048501 -358.284291)
		(end 280.082752 -358.083104)
		(width 0.127)
		(layer "B.Cu")
		(net "PHY_SCC_A_TO_DRV_A_0_DP")
	)
	(arc
		(start 280.082752 -357.832152)
		(mid 280.119949 -357.742349)
		(end 280.209752 -357.705152)
		(width 0.127)
		(layer "B.Cu")
		(net "PHY_SCC_A_TO_DRV_A_0_DP")
	)
	(arc
		(start 279.329134 -358.751124)
		(mid 279.640578 -358.689361)
		(end 279.904698 -358.513126)
		(width 0.127)
		(layer "B.Cu")
		(net "PHY_SCC_A_TO_DRV_A_0_DP")
	)
	(arc
		(start 272.869152 -359.504996)
		(mid 272.741094 -359.451952)
		(end 272.68805 -359.323894)
		(width 0.127)
		(layer "B.Cu")
		(net "PHY_SCC_A_TO_DRV_A_0_DP")
	)
	(arc
		(start 272.68805 -359.175304)
		(mid 272.812289 -358.875363)
		(end 273.11223 -358.751124)
		(width 0.127)
		(layer "B.Cu")
		(net "PHY_SCC_A_TO_DRV_A_0_DP")
	)
	(segment
		(start 112.481614 -343.737946)
		(end 136.93775 -338.780374)
		(width 0.127)
		(layer "F.Cu")
		(net "PHY_SCC_A_TO_DRV_A_0_DN")
	)
	(segment
		(start 207.753966 -335.104994)
		(end 208.1276 -335.179924)
		(width 0.127)
		(layer "F.Cu")
		(net "PHY_SCC_A_TO_DRV_A_0_DN")
	)
	(segment
		(start 208.799938 -335.314544)
		(end 237.357158 -341.031576)
		(width 0.127)
		(layer "F.Cu")
		(net "PHY_SCC_A_TO_DRV_A_0_DN")
	)
	(segment
		(start 204.98943 -334.551782)
		(end 205.109064 -334.731106)
		(width 0.127)
		(layer "F.Cu")
		(net "PHY_SCC_A_TO_DRV_A_0_DN")
	)
	(segment
		(start 49.814734 -307.023008)
		(end 56.624982 -317.509906)
		(width 0.127)
		(layer "F.Cu")
		(net "PHY_SCC_A_TO_DRV_A_0_DN")
	)
	(segment
		(start 56.624982 -317.509906)
		(end 56.652414 -317.52667)
		(width 0.127)
		(layer "F.Cu")
		(net "PHY_SCC_A_TO_DRV_A_0_DN")
	)
	(segment
		(start 206.155036 -334.940402)
		(end 206.52867 -335.015078)
		(width 0.127)
		(layer "F.Cu")
		(net "PHY_SCC_A_TO_DRV_A_0_DN")
	)
	(segment
		(start 272.26895 -359.504996)
		(end 271.9705 -359.504996)
		(width 0.127)
		(layer "F.Cu")
		(net "PHY_SCC_A_TO_DRV_A_0_DN")
	)
	(segment
		(start 270.366744 -358.662732)
		(end 272.26895 -358.662732)
		(width 0.127)
		(layer "F.Cu")
		(net "PHY_SCC_A_TO_DRV_A_0_DN")
	)
	(segment
		(start 56.652414 -317.52667)
		(end 56.652414 -317.526416)
		(width 0.127)
		(layer "F.Cu")
		(net "PHY_SCC_A_TO_DRV_A_0_DN")
	)
	(segment
		(start 272.39595 -358.789732)
		(end 272.39595 -359.377996)
		(width 0.127)
		(layer "F.Cu")
		(net "PHY_SCC_A_TO_DRV_A_0_DN")
	)
	(segment
		(start 205.109064 -334.731106)
		(end 205.482444 -334.805782)
		(width 0.127)
		(layer "F.Cu")
		(net "PHY_SCC_A_TO_DRV_A_0_DN")
	)
	(segment
		(start 205.482444 -334.805782)
		(end 205.662022 -334.686148)
		(width 0.127)
		(layer "F.Cu")
		(net "PHY_SCC_A_TO_DRV_A_0_DN")
	)
	(segment
		(start 206.52867 -335.015078)
		(end 206.707994 -334.895698)
		(width 0.127)
		(layer "F.Cu")
		(net "PHY_SCC_A_TO_DRV_A_0_DN")
	)
	(segment
		(start 43.660314 -297.546014)
		(end 49.814734 -307.023008)
		(width 0.127)
		(layer "F.Cu")
		(net "PHY_SCC_A_TO_DRV_A_0_DN")
	)
	(segment
		(start 34.994342 -274.792948)
		(end 43.023282 -296.565066)
		(width 0.127)
		(layer "F.Cu")
		(net "PHY_SCC_A_TO_DRV_A_0_DN")
	)
	(segment
		(start 93.457268 -339.929724)
		(end 112.481614 -343.737946)
		(width 0.127)
		(layer "F.Cu")
		(net "PHY_SCC_A_TO_DRV_A_0_DN")
	)
	(segment
		(start 237.357158 -341.031576)
		(end 270.366744 -358.662732)
		(width 0.127)
		(layer "F.Cu")
		(net "PHY_SCC_A_TO_DRV_A_0_DN")
	)
	(segment
		(start 136.93775 -338.780374)
		(end 158.38678 -343.073482)
		(width 0.127)
		(layer "F.Cu")
		(net "PHY_SCC_A_TO_DRV_A_0_DN")
	)
	(segment
		(start 208.24698 -335.359248)
		(end 208.620614 -335.433924)
		(width 0.127)
		(layer "F.Cu")
		(net "PHY_SCC_A_TO_DRV_A_0_DN")
	)
	(segment
		(start 33.25241 -274.117308)
		(end 33.927542 -274.117308)
		(width 0.127)
		(layer "F.Cu")
		(net "PHY_SCC_A_TO_DRV_A_0_DN")
	)
	(segment
		(start 202.725274 -334.098392)
		(end 204.98943 -334.551782)
		(width 0.127)
		(layer "F.Cu")
		(net "PHY_SCC_A_TO_DRV_A_0_DN")
	)
	(segment
		(start 208.1276 -335.179924)
		(end 208.24698 -335.359248)
		(width 0.127)
		(layer "F.Cu")
		(net "PHY_SCC_A_TO_DRV_A_0_DN")
	)
	(segment
		(start 207.201008 -335.149952)
		(end 207.574642 -335.224628)
		(width 0.127)
		(layer "F.Cu")
		(net "PHY_SCC_A_TO_DRV_A_0_DN")
	)
	(segment
		(start 56.652414 -317.526416)
		(end 93.457268 -339.929724)
		(width 0.127)
		(layer "F.Cu")
		(net "PHY_SCC_A_TO_DRV_A_0_DN")
	)
	(segment
		(start 206.035402 -334.761078)
		(end 206.155036 -334.940402)
		(width 0.127)
		(layer "F.Cu")
		(net "PHY_SCC_A_TO_DRV_A_0_DN")
	)
	(segment
		(start 33.150302 -274.219416)
		(end 33.25241 -274.117308)
		(width 0.127)
		(layer "F.Cu")
		(net "PHY_SCC_A_TO_DRV_A_0_DN")
	)
	(segment
		(start 207.574642 -335.224628)
		(end 207.753966 -335.104994)
		(width 0.127)
		(layer "F.Cu")
		(net "PHY_SCC_A_TO_DRV_A_0_DN")
	)
	(segment
		(start 32.742886 -274.219416)
		(end 33.150302 -274.219416)
		(width 0.127)
		(layer "F.Cu")
		(net "PHY_SCC_A_TO_DRV_A_0_DN")
	)
	(segment
		(start 43.023282 -296.565066)
		(end 43.660314 -297.546014)
		(width 0.127)
		(layer "F.Cu")
		(net "PHY_SCC_A_TO_DRV_A_0_DN")
	)
	(segment
		(start 33.927542 -274.117308)
		(end 34.994342 -274.792948)
		(width 0.127)
		(layer "F.Cu")
		(net "PHY_SCC_A_TO_DRV_A_0_DN")
	)
	(segment
		(start 207.081628 -334.970374)
		(end 207.201008 -335.149952)
		(width 0.127)
		(layer "F.Cu")
		(net "PHY_SCC_A_TO_DRV_A_0_DN")
	)
	(segment
		(start 205.662022 -334.686148)
		(end 206.035402 -334.761078)
		(width 0.127)
		(layer "F.Cu")
		(net "PHY_SCC_A_TO_DRV_A_0_DN")
	)
	(segment
		(start 158.38678 -343.073482)
		(end 202.725274 -334.098392)
		(width 0.127)
		(layer "F.Cu")
		(net "PHY_SCC_A_TO_DRV_A_0_DN")
	)
	(segment
		(start 208.620614 -335.433924)
		(end 208.799938 -335.314544)
		(width 0.127)
		(layer "F.Cu")
		(net "PHY_SCC_A_TO_DRV_A_0_DN")
	)
	(segment
		(start 206.707994 -334.895698)
		(end 207.081628 -334.970374)
		(width 0.127)
		(layer "F.Cu")
		(net "PHY_SCC_A_TO_DRV_A_0_DN")
	)
	(arc
		(start 272.26895 -358.662732)
		(mid 272.358753 -358.699929)
		(end 272.39595 -358.789732)
		(width 0.127)
		(layer "F.Cu")
		(net "PHY_SCC_A_TO_DRV_A_0_DN")
	)
	(arc
		(start 272.39595 -359.377996)
		(mid 272.358753 -359.467799)
		(end 272.26895 -359.504996)
		(width 0.127)
		(layer "F.Cu")
		(net "PHY_SCC_A_TO_DRV_A_0_DN")
	)
	(segment
		(start 279.790652 -358.082596)
		(end 279.790652 -357.832152)
		(width 0.127)
		(layer "B.Cu")
		(net "PHY_SCC_A_TO_DRV_A_0_DN")
	)
	(segment
		(start 273.11223 -358.459024)
		(end 279.329388 -358.459024)
		(width 0.127)
		(layer "B.Cu")
		(net "PHY_SCC_A_TO_DRV_A_0_DN")
	)
	(segment
		(start 272.39595 -359.323894)
		(end 272.39595 -359.175304)
		(width 0.127)
		(layer "B.Cu")
		(net "PHY_SCC_A_TO_DRV_A_0_DN")
	)
	(segment
		(start 279.663652 -357.705152)
		(end 279.236678 -357.705152)
		(width 0.127)
		(layer "B.Cu")
		(net "PHY_SCC_A_TO_DRV_A_0_DN")
	)
	(segment
		(start 271.9705 -359.504996)
		(end 272.214848 -359.504996)
		(width 0.127)
		(layer "B.Cu")
		(net "PHY_SCC_A_TO_DRV_A_0_DN")
	)
	(arc
		(start 279.329388 -358.459024)
		(mid 279.528846 -358.419349)
		(end 279.697942 -358.30637)
		(width 0.127)
		(layer "B.Cu")
		(net "PHY_SCC_A_TO_DRV_A_0_DN")
	)
	(arc
		(start 279.697942 -358.30637)
		(mid 279.709986 -358.29361)
		(end 279.72131 -358.280208)
		(width 0.127)
		(layer "B.Cu")
		(net "PHY_SCC_A_TO_DRV_A_0_DN")
	)
	(arc
		(start 272.39595 -359.175304)
		(mid 272.605744 -358.668818)
		(end 273.11223 -358.459024)
		(width 0.127)
		(layer "B.Cu")
		(net "PHY_SCC_A_TO_DRV_A_0_DN")
	)
	(arc
		(start 279.72131 -358.280208)
		(mid 279.772817 -358.187309)
		(end 279.790652 -358.082596)
		(width 0.127)
		(layer "B.Cu")
		(net "PHY_SCC_A_TO_DRV_A_0_DN")
	)
	(arc
		(start 272.214848 -359.504996)
		(mid 272.342906 -359.451952)
		(end 272.39595 -359.323894)
		(width 0.127)
		(layer "B.Cu")
		(net "PHY_SCC_A_TO_DRV_A_0_DN")
	)
	(arc
		(start 279.790652 -357.832152)
		(mid 279.753455 -357.742349)
		(end 279.663652 -357.705152)
		(width 0.127)
		(layer "B.Cu")
		(net "PHY_SCC_A_TO_DRV_A_0_DN")
	)
	(segment
		(start 420.563548 -278.186896)
		(end 420.761668 -278.385016)
		(width 0.127)
		(layer "F.Cu")
		(net "PHY_DRV_A_TO_SCC_A_9_DP")
	)
	(segment
		(start 420.563548 -278.056086)
		(end 420.563548 -278.186896)
		(width 0.127)
		(layer "F.Cu")
		(net "PHY_DRV_A_TO_SCC_A_9_DP")
	)
	(segment
		(start 419.516306 -277.896066)
		(end 420.403528 -277.896066)
		(width 0.127)
		(layer "F.Cu")
		(net "PHY_DRV_A_TO_SCC_A_9_DP")
	)
	(segment
		(start 420.761668 -278.385016)
		(end 422.025064 -278.385016)
		(width 0.127)
		(layer "F.Cu")
		(net "PHY_DRV_A_TO_SCC_A_9_DP")
	)
	(segment
		(start 420.403528 -277.896066)
		(end 420.563548 -278.056086)
		(width 0.127)
		(layer "F.Cu")
		(net "PHY_DRV_A_TO_SCC_A_9_DP")
	)
	(segment
		(start 419.389052 -278.321516)
		(end 419.389052 -278.02332)
		(width 0.127)
		(layer "F.Cu")
		(net "PHY_DRV_A_TO_SCC_A_9_DP")
	)
	(arc
		(start 419.389052 -278.02332)
		(mid 419.426324 -277.933338)
		(end 419.516306 -277.896066)
		(width 0.127)
		(layer "F.Cu")
		(net "PHY_DRV_A_TO_SCC_A_9_DP")
	)
	(segment
		(start 418.4142 -277.896066)
		(end 370.315236 -298.233846)
		(width 0.127)
		(layer "B.Cu")
		(net "PHY_DRV_A_TO_SCC_A_9_DP")
	)
	(segment
		(start 345.241118 -303.792636)
		(end 307.405532 -328.837036)
		(width 0.127)
		(layer "B.Cu")
		(net "PHY_DRV_A_TO_SCC_A_9_DP")
	)
	(segment
		(start 286.863536 -343.30513)
		(end 286.436562 -343.30513)
		(width 0.127)
		(layer "B.Cu")
		(net "PHY_DRV_A_TO_SCC_A_9_DP")
	)
	(segment
		(start 307.405532 -328.837036)
		(end 302.218852 -336.981292)
		(width 0.127)
		(layer "B.Cu")
		(net "PHY_DRV_A_TO_SCC_A_9_DP")
	)
	(segment
		(start 419.212268 -277.896066)
		(end 418.4142 -277.896066)
		(width 0.127)
		(layer "B.Cu")
		(net "PHY_DRV_A_TO_SCC_A_9_DP")
	)
	(segment
		(start 419.389052 -278.321516)
		(end 419.389052 -278.07285)
		(width 0.127)
		(layer "B.Cu")
		(net "PHY_DRV_A_TO_SCC_A_9_DP")
	)
	(segment
		(start 291.610288 -343.739724)
		(end 288.851594 -344.351102)
		(width 0.127)
		(layer "B.Cu")
		(net "PHY_DRV_A_TO_SCC_A_9_DP")
	)
	(segment
		(start 286.990536 -343.682574)
		(end 286.990536 -343.43213)
		(width 0.127)
		(layer "B.Cu")
		(net "PHY_DRV_A_TO_SCC_A_9_DP")
	)
	(segment
		(start 288.851594 -344.351102)
		(end 287.7439 -344.351102)
		(width 0.127)
		(layer "B.Cu")
		(net "PHY_DRV_A_TO_SCC_A_9_DP")
	)
	(segment
		(start 302.218852 -336.981292)
		(end 291.610288 -343.739724)
		(width 0.127)
		(layer "B.Cu")
		(net "PHY_DRV_A_TO_SCC_A_9_DP")
	)
	(segment
		(start 370.315236 -298.233846)
		(end 345.241118 -303.792636)
		(width 0.127)
		(layer "B.Cu")
		(net "PHY_DRV_A_TO_SCC_A_9_DP")
	)
	(arc
		(start 287.16859 -344.11285)
		(mid 287.03682 -343.915408)
		(end 286.990536 -343.682574)
		(width 0.127)
		(layer "B.Cu")
		(net "PHY_DRV_A_TO_SCC_A_9_DP")
	)
	(arc
		(start 287.7439 -344.351102)
		(mid 287.432563 -344.289173)
		(end 287.16859 -344.11285)
		(width 0.127)
		(layer "B.Cu")
		(net "PHY_DRV_A_TO_SCC_A_9_DP")
	)
	(arc
		(start 419.389052 -278.07285)
		(mid 419.337273 -277.947845)
		(end 419.212268 -277.896066)
		(width 0.127)
		(layer "B.Cu")
		(net "PHY_DRV_A_TO_SCC_A_9_DP")
	)
	(arc
		(start 286.990536 -343.43213)
		(mid 286.953339 -343.342327)
		(end 286.863536 -343.30513)
		(width 0.127)
		(layer "B.Cu")
		(net "PHY_DRV_A_TO_SCC_A_9_DP")
	)
	(segment
		(start 419.389052 -277.178516)
		(end 419.389052 -277.476712)
		(width 0.127)
		(layer "F.Cu")
		(net "PHY_DRV_A_TO_SCC_A_9_DN")
	)
	(segment
		(start 420.563548 -277.476966)
		(end 420.563548 -277.242016)
		(width 0.127)
		(layer "F.Cu")
		(net "PHY_DRV_A_TO_SCC_A_9_DN")
	)
	(segment
		(start 419.516306 -277.603966)
		(end 420.436548 -277.603966)
		(width 0.127)
		(layer "F.Cu")
		(net "PHY_DRV_A_TO_SCC_A_9_DN")
	)
	(segment
		(start 420.690548 -277.115016)
		(end 422.025064 -277.115016)
		(width 0.127)
		(layer "F.Cu")
		(net "PHY_DRV_A_TO_SCC_A_9_DN")
	)
	(segment
		(start 420.436548 -277.603966)
		(end 420.563548 -277.476966)
		(width 0.127)
		(layer "F.Cu")
		(net "PHY_DRV_A_TO_SCC_A_9_DN")
	)
	(segment
		(start 420.563548 -277.242016)
		(end 420.690548 -277.115016)
		(width 0.127)
		(layer "F.Cu")
		(net "PHY_DRV_A_TO_SCC_A_9_DN")
	)
	(arc
		(start 419.389052 -277.476712)
		(mid 419.426324 -277.566694)
		(end 419.516306 -277.603966)
		(width 0.127)
		(layer "F.Cu")
		(net "PHY_DRV_A_TO_SCC_A_9_DN")
	)
	(segment
		(start 291.49675 -343.465658)
		(end 288.81959 -344.059002)
		(width 0.127)
		(layer "B.Cu")
		(net "PHY_DRV_A_TO_SCC_A_9_DN")
	)
	(segment
		(start 347.778578 -302.774604)
		(end 347.406722 -302.857154)
		(width 0.127)
		(layer "B.Cu")
		(net "PHY_DRV_A_TO_SCC_A_9_DN")
	)
	(segment
		(start 418.354764 -277.603966)
		(end 370.225828 -297.954192)
		(width 0.127)
		(layer "B.Cu")
		(net "PHY_DRV_A_TO_SCC_A_9_DN")
	)
	(segment
		(start 348.820232 -302.543718)
		(end 348.448122 -302.626268)
		(width 0.127)
		(layer "B.Cu")
		(net "PHY_DRV_A_TO_SCC_A_9_DN")
	)
	(segment
		(start 348.332298 -302.808132)
		(end 347.960442 -302.890428)
		(width 0.127)
		(layer "B.Cu")
		(net "PHY_DRV_A_TO_SCC_A_9_DN")
	)
	(segment
		(start 349.489776 -302.395382)
		(end 349.373952 -302.577246)
		(width 0.127)
		(layer "B.Cu")
		(net "PHY_DRV_A_TO_SCC_A_9_DN")
	)
	(segment
		(start 347.290898 -303.039018)
		(end 345.12504 -303.519078)
		(width 0.127)
		(layer "B.Cu")
		(net "PHY_DRV_A_TO_SCC_A_9_DN")
	)
	(segment
		(start 287.282636 -343.682574)
		(end 287.282636 -343.43213)
		(width 0.127)
		(layer "B.Cu")
		(net "PHY_DRV_A_TO_SCC_A_9_DN")
	)
	(segment
		(start 347.960442 -302.890428)
		(end 347.778578 -302.774604)
		(width 0.127)
		(layer "B.Cu")
		(net "PHY_DRV_A_TO_SCC_A_9_DN")
	)
	(segment
		(start 349.373952 -302.577246)
		(end 349.001842 -302.659542)
		(width 0.127)
		(layer "B.Cu")
		(net "PHY_DRV_A_TO_SCC_A_9_DN")
	)
	(segment
		(start 307.192426 -328.62774)
		(end 302.00727 -336.76971)
		(width 0.127)
		(layer "B.Cu")
		(net "PHY_DRV_A_TO_SCC_A_9_DN")
	)
	(segment
		(start 288.81959 -344.059002)
		(end 287.7439 -344.059002)
		(width 0.127)
		(layer "B.Cu")
		(net "PHY_DRV_A_TO_SCC_A_9_DN")
	)
	(segment
		(start 419.212268 -277.603966)
		(end 418.354764 -277.603966)
		(width 0.127)
		(layer "B.Cu")
		(net "PHY_DRV_A_TO_SCC_A_9_DN")
	)
	(segment
		(start 287.409636 -343.30513)
		(end 287.83661 -343.30513)
		(width 0.127)
		(layer "B.Cu")
		(net "PHY_DRV_A_TO_SCC_A_9_DN")
	)
	(segment
		(start 345.12504 -303.519078)
		(end 307.192426 -328.62774)
		(width 0.127)
		(layer "B.Cu")
		(net "PHY_DRV_A_TO_SCC_A_9_DN")
	)
	(segment
		(start 370.225828 -297.954192)
		(end 350.043496 -302.428656)
		(width 0.127)
		(layer "B.Cu")
		(net "PHY_DRV_A_TO_SCC_A_9_DN")
	)
	(segment
		(start 419.389052 -277.178516)
		(end 419.389052 -277.427182)
		(width 0.127)
		(layer "B.Cu")
		(net "PHY_DRV_A_TO_SCC_A_9_DN")
	)
	(segment
		(start 349.001842 -302.659542)
		(end 348.820232 -302.543718)
		(width 0.127)
		(layer "B.Cu")
		(net "PHY_DRV_A_TO_SCC_A_9_DN")
	)
	(segment
		(start 347.406722 -302.857154)
		(end 347.290898 -303.039018)
		(width 0.127)
		(layer "B.Cu")
		(net "PHY_DRV_A_TO_SCC_A_9_DN")
	)
	(segment
		(start 349.861632 -302.312832)
		(end 349.489776 -302.395382)
		(width 0.127)
		(layer "B.Cu")
		(net "PHY_DRV_A_TO_SCC_A_9_DN")
	)
	(segment
		(start 302.00727 -336.76971)
		(end 291.49675 -343.465658)
		(width 0.127)
		(layer "B.Cu")
		(net "PHY_DRV_A_TO_SCC_A_9_DN")
	)
	(segment
		(start 350.043496 -302.428656)
		(end 349.861632 -302.312832)
		(width 0.127)
		(layer "B.Cu")
		(net "PHY_DRV_A_TO_SCC_A_9_DN")
	)
	(segment
		(start 348.448122 -302.626268)
		(end 348.332298 -302.808132)
		(width 0.127)
		(layer "B.Cu")
		(net "PHY_DRV_A_TO_SCC_A_9_DN")
	)
	(arc
		(start 419.389052 -277.427182)
		(mid 419.337273 -277.552187)
		(end 419.212268 -277.603966)
		(width 0.127)
		(layer "B.Cu")
		(net "PHY_DRV_A_TO_SCC_A_9_DN")
	)
	(arc
		(start 287.7439 -344.059002)
		(mid 287.544442 -344.019327)
		(end 287.375346 -343.906348)
		(width 0.127)
		(layer "B.Cu")
		(net "PHY_DRV_A_TO_SCC_A_9_DN")
	)
	(arc
		(start 287.375346 -343.906348)
		(mid 287.306745 -343.80368)
		(end 287.282636 -343.682574)
		(width 0.127)
		(layer "B.Cu")
		(net "PHY_DRV_A_TO_SCC_A_9_DN")
	)
	(arc
		(start 287.282636 -343.43213)
		(mid 287.319833 -343.342327)
		(end 287.409636 -343.30513)
		(width 0.127)
		(layer "B.Cu")
		(net "PHY_DRV_A_TO_SCC_A_9_DN")
	)
	(segment
		(start 388.871714 -277.896066)
		(end 389.013446 -278.037798)
		(width 0.127)
		(layer "F.Cu")
		(net "PHY_DRV_A_TO_SCC_A_8_DP")
	)
	(segment
		(start 387.966204 -277.896066)
		(end 388.871714 -277.896066)
		(width 0.127)
		(layer "F.Cu")
		(net "PHY_DRV_A_TO_SCC_A_8_DP")
	)
	(segment
		(start 389.013446 -278.037798)
		(end 389.013446 -278.209756)
		(width 0.127)
		(layer "F.Cu")
		(net "PHY_DRV_A_TO_SCC_A_8_DP")
	)
	(segment
		(start 387.83895 -278.321516)
		(end 387.83895 -278.02332)
		(width 0.127)
		(layer "F.Cu")
		(net "PHY_DRV_A_TO_SCC_A_8_DP")
	)
	(segment
		(start 389.013446 -278.209756)
		(end 389.188706 -278.385016)
		(width 0.127)
		(layer "F.Cu")
		(net "PHY_DRV_A_TO_SCC_A_8_DP")
	)
	(segment
		(start 389.188706 -278.385016)
		(end 390.474962 -278.385016)
		(width 0.127)
		(layer "F.Cu")
		(net "PHY_DRV_A_TO_SCC_A_8_DP")
	)
	(arc
		(start 387.83895 -278.02332)
		(mid 387.876222 -277.933338)
		(end 387.966204 -277.896066)
		(width 0.127)
		(layer "F.Cu")
		(net "PHY_DRV_A_TO_SCC_A_8_DP")
	)
	(segment
		(start 387.83895 -278.321516)
		(end 387.83895 -278.07285)
		(width 0.127)
		(layer "B.Cu")
		(net "PHY_DRV_A_TO_SCC_A_8_DP")
	)
	(segment
		(start 387.056376 -277.896066)
		(end 373.107712 -287.128204)
		(width 0.127)
		(layer "B.Cu")
		(net "PHY_DRV_A_TO_SCC_A_8_DP")
	)
	(segment
		(start 300.392338 -336.277204)
		(end 291.771324 -341.769192)
		(width 0.127)
		(layer "B.Cu")
		(net "PHY_DRV_A_TO_SCC_A_8_DP")
	)
	(segment
		(start 373.107966 -287.128204)
		(end 359.183686 -296.34434)
		(width 0.127)
		(layer "B.Cu")
		(net "PHY_DRV_A_TO_SCC_A_8_DP")
	)
	(segment
		(start 305.757834 -327.845928)
		(end 300.392338 -336.277204)
		(width 0.127)
		(layer "B.Cu")
		(net "PHY_DRV_A_TO_SCC_A_8_DP")
	)
	(segment
		(start 285.990538 -341.882476)
		(end 285.990538 -341.632032)
		(width 0.127)
		(layer "B.Cu")
		(net "PHY_DRV_A_TO_SCC_A_8_DP")
	)
	(segment
		(start 373.107712 -287.128204)
		(end 373.107966 -287.128204)
		(width 0.127)
		(layer "B.Cu")
		(net "PHY_DRV_A_TO_SCC_A_8_DP")
	)
	(segment
		(start 285.863538 -341.505032)
		(end 285.436564 -341.505032)
		(width 0.127)
		(layer "B.Cu")
		(net "PHY_DRV_A_TO_SCC_A_8_DP")
	)
	(segment
		(start 350.761808 -298.058078)
		(end 305.757834 -327.845928)
		(width 0.127)
		(layer "B.Cu")
		(net "PHY_DRV_A_TO_SCC_A_8_DP")
	)
	(segment
		(start 288.241232 -342.551004)
		(end 286.743902 -342.551004)
		(width 0.127)
		(layer "B.Cu")
		(net "PHY_DRV_A_TO_SCC_A_8_DP")
	)
	(segment
		(start 359.183686 -296.34434)
		(end 350.761808 -298.058078)
		(width 0.127)
		(layer "B.Cu")
		(net "PHY_DRV_A_TO_SCC_A_8_DP")
	)
	(segment
		(start 291.771324 -341.769192)
		(end 288.241232 -342.551004)
		(width 0.127)
		(layer "B.Cu")
		(net "PHY_DRV_A_TO_SCC_A_8_DP")
	)
	(segment
		(start 387.662166 -277.896066)
		(end 387.056376 -277.896066)
		(width 0.127)
		(layer "B.Cu")
		(net "PHY_DRV_A_TO_SCC_A_8_DP")
	)
	(arc
		(start 285.990538 -341.632032)
		(mid 285.953341 -341.542229)
		(end 285.863538 -341.505032)
		(width 0.127)
		(layer "B.Cu")
		(net "PHY_DRV_A_TO_SCC_A_8_DP")
	)
	(arc
		(start 286.743902 -342.551004)
		(mid 286.432565 -342.489075)
		(end 286.168592 -342.312752)
		(width 0.127)
		(layer "B.Cu")
		(net "PHY_DRV_A_TO_SCC_A_8_DP")
	)
	(arc
		(start 286.168592 -342.312752)
		(mid 286.036822 -342.11531)
		(end 285.990538 -341.882476)
		(width 0.127)
		(layer "B.Cu")
		(net "PHY_DRV_A_TO_SCC_A_8_DP")
	)
	(arc
		(start 387.83895 -278.07285)
		(mid 387.787171 -277.947845)
		(end 387.662166 -277.896066)
		(width 0.127)
		(layer "B.Cu")
		(net "PHY_DRV_A_TO_SCC_A_8_DP")
	)
	(segment
		(start 387.966204 -277.603966)
		(end 388.886446 -277.603966)
		(width 0.127)
		(layer "F.Cu")
		(net "PHY_DRV_A_TO_SCC_A_8_DN")
	)
	(segment
		(start 389.013446 -277.242016)
		(end 389.140446 -277.115016)
		(width 0.127)
		(layer "F.Cu")
		(net "PHY_DRV_A_TO_SCC_A_8_DN")
	)
	(segment
		(start 388.886446 -277.603966)
		(end 389.013446 -277.476966)
		(width 0.127)
		(layer "F.Cu")
		(net "PHY_DRV_A_TO_SCC_A_8_DN")
	)
	(segment
		(start 387.83895 -277.178516)
		(end 387.83895 -277.476712)
		(width 0.127)
		(layer "F.Cu")
		(net "PHY_DRV_A_TO_SCC_A_8_DN")
	)
	(segment
		(start 389.013446 -277.476966)
		(end 389.013446 -277.242016)
		(width 0.127)
		(layer "F.Cu")
		(net "PHY_DRV_A_TO_SCC_A_8_DN")
	)
	(segment
		(start 389.140446 -277.115016)
		(end 390.474962 -277.115016)
		(width 0.127)
		(layer "F.Cu")
		(net "PHY_DRV_A_TO_SCC_A_8_DN")
	)
	(arc
		(start 387.83895 -277.476712)
		(mid 387.876222 -277.566694)
		(end 387.966204 -277.603966)
		(width 0.127)
		(layer "F.Cu")
		(net "PHY_DRV_A_TO_SCC_A_8_DN")
	)
	(segment
		(start 304.855626 -328.416666)
		(end 304.90541 -328.640948)
		(width 0.127)
		(layer "B.Cu")
		(net "PHY_DRV_A_TO_SCC_A_8_DN")
	)
	(segment
		(start 305.284632 -328.045318)
		(end 305.060096 -328.095102)
		(width 0.127)
		(layer "B.Cu")
		(net "PHY_DRV_A_TO_SCC_A_8_DN")
	)
	(segment
		(start 387.662166 -277.603966)
		(end 386.968238 -277.603966)
		(width 0.127)
		(layer "B.Cu")
		(net "PHY_DRV_A_TO_SCC_A_8_DN")
	)
	(segment
		(start 304.90541 -328.640948)
		(end 304.70094 -328.962512)
		(width 0.127)
		(layer "B.Cu")
		(net "PHY_DRV_A_TO_SCC_A_8_DN")
	)
	(segment
		(start 304.70094 -328.962512)
		(end 304.476404 -329.012296)
		(width 0.127)
		(layer "B.Cu")
		(net "PHY_DRV_A_TO_SCC_A_8_DN")
	)
	(segment
		(start 303.688242 -330.2508)
		(end 303.738026 -330.475336)
		(width 0.127)
		(layer "B.Cu")
		(net "PHY_DRV_A_TO_SCC_A_8_DN")
	)
	(segment
		(start 303.892966 -329.92949)
		(end 303.688242 -330.2508)
		(width 0.127)
		(layer "B.Cu")
		(net "PHY_DRV_A_TO_SCC_A_8_DN")
	)
	(segment
		(start 359.06964 -296.069258)
		(end 350.647762 -297.782996)
		(width 0.127)
		(layer "B.Cu")
		(net "PHY_DRV_A_TO_SCC_A_8_DN")
	)
	(segment
		(start 291.657786 -341.495126)
		(end 288.209228 -342.258904)
		(width 0.127)
		(layer "B.Cu")
		(net "PHY_DRV_A_TO_SCC_A_8_DN")
	)
	(segment
		(start 300.180502 -336.065622)
		(end 291.657786 -341.495126)
		(width 0.127)
		(layer "B.Cu")
		(net "PHY_DRV_A_TO_SCC_A_8_DN")
	)
	(segment
		(start 288.209228 -342.258904)
		(end 286.743902 -342.258904)
		(width 0.127)
		(layer "B.Cu")
		(net "PHY_DRV_A_TO_SCC_A_8_DN")
	)
	(segment
		(start 387.83895 -277.178516)
		(end 387.83895 -277.427182)
		(width 0.127)
		(layer "B.Cu")
		(net "PHY_DRV_A_TO_SCC_A_8_DN")
	)
	(segment
		(start 305.544728 -327.636632)
		(end 305.284632 -328.045318)
		(width 0.127)
		(layer "B.Cu")
		(net "PHY_DRV_A_TO_SCC_A_8_DN")
	)
	(segment
		(start 304.321718 -329.558142)
		(end 304.117248 -329.879706)
		(width 0.127)
		(layer "B.Cu")
		(net "PHY_DRV_A_TO_SCC_A_8_DN")
	)
	(segment
		(start 304.476404 -329.012296)
		(end 304.271934 -329.33386)
		(width 0.127)
		(layer "B.Cu")
		(net "PHY_DRV_A_TO_SCC_A_8_DN")
	)
	(segment
		(start 304.271934 -329.33386)
		(end 304.321718 -329.558142)
		(width 0.127)
		(layer "B.Cu")
		(net "PHY_DRV_A_TO_SCC_A_8_DN")
	)
	(segment
		(start 305.060096 -328.095102)
		(end 304.855626 -328.416666)
		(width 0.127)
		(layer "B.Cu")
		(net "PHY_DRV_A_TO_SCC_A_8_DN")
	)
	(segment
		(start 304.117248 -329.879706)
		(end 303.892966 -329.92949)
		(width 0.127)
		(layer "B.Cu")
		(net "PHY_DRV_A_TO_SCC_A_8_DN")
	)
	(segment
		(start 286.282638 -341.882476)
		(end 286.282638 -341.632032)
		(width 0.127)
		(layer "B.Cu")
		(net "PHY_DRV_A_TO_SCC_A_8_DN")
	)
	(segment
		(start 350.647762 -297.782996)
		(end 305.544728 -327.636632)
		(width 0.127)
		(layer "B.Cu")
		(net "PHY_DRV_A_TO_SCC_A_8_DN")
	)
	(segment
		(start 286.409638 -341.505032)
		(end 286.836612 -341.505032)
		(width 0.127)
		(layer "B.Cu")
		(net "PHY_DRV_A_TO_SCC_A_8_DN")
	)
	(segment
		(start 303.738026 -330.475336)
		(end 300.180502 -336.065622)
		(width 0.127)
		(layer "B.Cu")
		(net "PHY_DRV_A_TO_SCC_A_8_DN")
	)
	(segment
		(start 386.968238 -277.603966)
		(end 359.06964 -296.069258)
		(width 0.127)
		(layer "B.Cu")
		(net "PHY_DRV_A_TO_SCC_A_8_DN")
	)
	(arc
		(start 286.375348 -342.10625)
		(mid 286.306747 -342.003582)
		(end 286.282638 -341.882476)
		(width 0.127)
		(layer "B.Cu")
		(net "PHY_DRV_A_TO_SCC_A_8_DN")
	)
	(arc
		(start 286.282638 -341.632032)
		(mid 286.319835 -341.542229)
		(end 286.409638 -341.505032)
		(width 0.127)
		(layer "B.Cu")
		(net "PHY_DRV_A_TO_SCC_A_8_DN")
	)
	(arc
		(start 387.83895 -277.427182)
		(mid 387.787171 -277.552187)
		(end 387.662166 -277.603966)
		(width 0.127)
		(layer "B.Cu")
		(net "PHY_DRV_A_TO_SCC_A_8_DN")
	)
	(arc
		(start 286.743902 -342.258904)
		(mid 286.544444 -342.219229)
		(end 286.375348 -342.10625)
		(width 0.127)
		(layer "B.Cu")
		(net "PHY_DRV_A_TO_SCC_A_8_DN")
	)
	(segment
		(start 357.323898 -277.896066)
		(end 357.463598 -278.035766)
		(width 0.127)
		(layer "F.Cu")
		(net "PHY_DRV_A_TO_SCC_A_7_DP")
	)
	(segment
		(start 356.416356 -277.896066)
		(end 357.323898 -277.896066)
		(width 0.127)
		(layer "F.Cu")
		(net "PHY_DRV_A_TO_SCC_A_7_DP")
	)
	(segment
		(start 357.463598 -278.202644)
		(end 357.64597 -278.385016)
		(width 0.127)
		(layer "F.Cu")
		(net "PHY_DRV_A_TO_SCC_A_7_DP")
	)
	(segment
		(start 357.463598 -278.035766)
		(end 357.463598 -278.202644)
		(width 0.127)
		(layer "F.Cu")
		(net "PHY_DRV_A_TO_SCC_A_7_DP")
	)
	(segment
		(start 356.289102 -278.321516)
		(end 356.289102 -278.02332)
		(width 0.127)
		(layer "F.Cu")
		(net "PHY_DRV_A_TO_SCC_A_7_DP")
	)
	(segment
		(start 357.64597 -278.385016)
		(end 358.925114 -278.385016)
		(width 0.127)
		(layer "F.Cu")
		(net "PHY_DRV_A_TO_SCC_A_7_DP")
	)
	(arc
		(start 356.289102 -278.02332)
		(mid 356.326374 -277.933338)
		(end 356.416356 -277.896066)
		(width 0.127)
		(layer "F.Cu")
		(net "PHY_DRV_A_TO_SCC_A_7_DP")
	)
	(segment
		(start 339.176106 -295.759632)
		(end 339.175852 -295.759632)
		(width 0.127)
		(layer "B.Cu")
		(net "PHY_DRV_A_TO_SCC_A_7_DP")
	)
	(segment
		(start 355.592634 -277.896066)
		(end 354.937568 -278.028654)
		(width 0.127)
		(layer "B.Cu")
		(net "PHY_DRV_A_TO_SCC_A_7_DP")
	)
	(segment
		(start 356.112318 -277.896066)
		(end 355.592634 -277.896066)
		(width 0.127)
		(layer "B.Cu")
		(net "PHY_DRV_A_TO_SCC_A_7_DP")
	)
	(segment
		(start 354.937568 -278.028654)
		(end 347.823282 -282.73756)
		(width 0.127)
		(layer "B.Cu")
		(net "PHY_DRV_A_TO_SCC_A_7_DP")
	)
	(segment
		(start 286.863536 -339.705188)
		(end 286.436562 -339.705188)
		(width 0.127)
		(layer "B.Cu")
		(net "PHY_DRV_A_TO_SCC_A_7_DP")
	)
	(segment
		(start 286.990536 -340.082632)
		(end 286.990536 -339.832188)
		(width 0.127)
		(layer "B.Cu")
		(net "PHY_DRV_A_TO_SCC_A_7_DP")
	)
	(segment
		(start 291.098478 -340.272878)
		(end 288.936938 -340.75116)
		(width 0.127)
		(layer "B.Cu")
		(net "PHY_DRV_A_TO_SCC_A_7_DP")
	)
	(segment
		(start 294.70223 -337.979004)
		(end 291.098478 -340.272878)
		(width 0.127)
		(layer "B.Cu")
		(net "PHY_DRV_A_TO_SCC_A_7_DP")
	)
	(segment
		(start 339.175852 -295.759632)
		(end 308.782974 -315.877702)
		(width 0.127)
		(layer "B.Cu")
		(net "PHY_DRV_A_TO_SCC_A_7_DP")
	)
	(segment
		(start 308.782974 -315.877702)
		(end 308.782974 -315.877448)
		(width 0.127)
		(layer "B.Cu")
		(net "PHY_DRV_A_TO_SCC_A_7_DP")
	)
	(segment
		(start 347.823282 -282.73756)
		(end 339.225636 -295.726866)
		(width 0.127)
		(layer "B.Cu")
		(net "PHY_DRV_A_TO_SCC_A_7_DP")
	)
	(segment
		(start 288.936938 -340.75116)
		(end 287.7439 -340.75116)
		(width 0.127)
		(layer "B.Cu")
		(net "PHY_DRV_A_TO_SCC_A_7_DP")
	)
	(segment
		(start 339.225636 -295.726866)
		(end 339.176106 -295.759886)
		(width 0.127)
		(layer "B.Cu")
		(net "PHY_DRV_A_TO_SCC_A_7_DP")
	)
	(segment
		(start 308.782974 -315.877448)
		(end 294.70223 -337.979004)
		(width 0.127)
		(layer "B.Cu")
		(net "PHY_DRV_A_TO_SCC_A_7_DP")
	)
	(segment
		(start 356.289102 -278.321516)
		(end 356.289102 -278.07285)
		(width 0.127)
		(layer "B.Cu")
		(net "PHY_DRV_A_TO_SCC_A_7_DP")
	)
	(segment
		(start 339.176106 -295.759886)
		(end 339.176106 -295.759632)
		(width 0.127)
		(layer "B.Cu")
		(net "PHY_DRV_A_TO_SCC_A_7_DP")
	)
	(arc
		(start 356.289102 -278.07285)
		(mid 356.237323 -277.947845)
		(end 356.112318 -277.896066)
		(width 0.127)
		(layer "B.Cu")
		(net "PHY_DRV_A_TO_SCC_A_7_DP")
	)
	(arc
		(start 286.990536 -339.832188)
		(mid 286.953339 -339.742385)
		(end 286.863536 -339.705188)
		(width 0.127)
		(layer "B.Cu")
		(net "PHY_DRV_A_TO_SCC_A_7_DP")
	)
	(arc
		(start 287.16859 -340.512908)
		(mid 287.03682 -340.315466)
		(end 286.990536 -340.082632)
		(width 0.127)
		(layer "B.Cu")
		(net "PHY_DRV_A_TO_SCC_A_7_DP")
	)
	(arc
		(start 287.7439 -340.75116)
		(mid 287.432563 -340.689231)
		(end 287.16859 -340.512908)
		(width 0.127)
		(layer "B.Cu")
		(net "PHY_DRV_A_TO_SCC_A_7_DP")
	)
	(segment
		(start 357.336598 -277.603966)
		(end 357.463598 -277.476966)
		(width 0.127)
		(layer "F.Cu")
		(net "PHY_DRV_A_TO_SCC_A_7_DN")
	)
	(segment
		(start 357.463598 -277.476966)
		(end 357.463598 -277.242016)
		(width 0.127)
		(layer "F.Cu")
		(net "PHY_DRV_A_TO_SCC_A_7_DN")
	)
	(segment
		(start 356.289102 -277.178516)
		(end 356.289102 -277.476712)
		(width 0.127)
		(layer "F.Cu")
		(net "PHY_DRV_A_TO_SCC_A_7_DN")
	)
	(segment
		(start 357.590598 -277.115016)
		(end 358.925114 -277.115016)
		(width 0.127)
		(layer "F.Cu")
		(net "PHY_DRV_A_TO_SCC_A_7_DN")
	)
	(segment
		(start 357.463598 -277.242016)
		(end 357.590598 -277.115016)
		(width 0.127)
		(layer "F.Cu")
		(net "PHY_DRV_A_TO_SCC_A_7_DN")
	)
	(segment
		(start 356.416356 -277.603966)
		(end 357.336598 -277.603966)
		(width 0.127)
		(layer "F.Cu")
		(net "PHY_DRV_A_TO_SCC_A_7_DN")
	)
	(arc
		(start 356.289102 -277.476712)
		(mid 356.326374 -277.566694)
		(end 356.416356 -277.603966)
		(width 0.127)
		(layer "F.Cu")
		(net "PHY_DRV_A_TO_SCC_A_7_DN")
	)
	(segment
		(start 307.106574 -317.965074)
		(end 306.882038 -318.014858)
		(width 0.127)
		(layer "B.Cu")
		(net "PHY_DRV_A_TO_SCC_A_7_DN")
	)
	(segment
		(start 356.289102 -277.178516)
		(end 356.289102 -277.427182)
		(width 0.127)
		(layer "B.Cu")
		(net "PHY_DRV_A_TO_SCC_A_7_DN")
	)
	(segment
		(start 307.466238 -317.097918)
		(end 307.261514 -317.419228)
		(width 0.127)
		(layer "B.Cu")
		(net "PHY_DRV_A_TO_SCC_A_7_DN")
	)
	(segment
		(start 347.612462 -282.52674)
		(end 339.01507 -295.515538)
		(width 0.127)
		(layer "B.Cu")
		(net "PHY_DRV_A_TO_SCC_A_7_DN")
	)
	(segment
		(start 339.01507 -295.515538)
		(end 308.569868 -315.668152)
		(width 0.127)
		(layer "B.Cu")
		(net "PHY_DRV_A_TO_SCC_A_7_DN")
	)
	(segment
		(start 307.845714 -316.502288)
		(end 307.895498 -316.726824)
		(width 0.127)
		(layer "B.Cu")
		(net "PHY_DRV_A_TO_SCC_A_7_DN")
	)
	(segment
		(start 306.677314 -318.336168)
		(end 306.727098 -318.56045)
		(width 0.127)
		(layer "B.Cu")
		(net "PHY_DRV_A_TO_SCC_A_7_DN")
	)
	(segment
		(start 307.895498 -316.726824)
		(end 307.690774 -317.048134)
		(width 0.127)
		(layer "B.Cu")
		(net "PHY_DRV_A_TO_SCC_A_7_DN")
	)
	(segment
		(start 355.56317 -277.603966)
		(end 354.823776 -277.753572)
		(width 0.127)
		(layer "B.Cu")
		(net "PHY_DRV_A_TO_SCC_A_7_DN")
	)
	(segment
		(start 307.311298 -317.643764)
		(end 307.106574 -317.965074)
		(width 0.127)
		(layer "B.Cu")
		(net "PHY_DRV_A_TO_SCC_A_7_DN")
	)
	(segment
		(start 308.569868 -315.668152)
		(end 308.27472 -316.131194)
		(width 0.127)
		(layer "B.Cu")
		(net "PHY_DRV_A_TO_SCC_A_7_DN")
	)
	(segment
		(start 307.261514 -317.419228)
		(end 307.311298 -317.643764)
		(width 0.127)
		(layer "B.Cu")
		(net "PHY_DRV_A_TO_SCC_A_7_DN")
	)
	(segment
		(start 354.823776 -277.753572)
		(end 347.612462 -282.52674)
		(width 0.127)
		(layer "B.Cu")
		(net "PHY_DRV_A_TO_SCC_A_7_DN")
	)
	(segment
		(start 288.904934 -340.45906)
		(end 287.7439 -340.45906)
		(width 0.127)
		(layer "B.Cu")
		(net "PHY_DRV_A_TO_SCC_A_7_DN")
	)
	(segment
		(start 290.98494 -339.998558)
		(end 288.904934 -340.45906)
		(width 0.127)
		(layer "B.Cu")
		(net "PHY_DRV_A_TO_SCC_A_7_DN")
	)
	(segment
		(start 287.409636 -339.705188)
		(end 287.83661 -339.705188)
		(width 0.127)
		(layer "B.Cu")
		(net "PHY_DRV_A_TO_SCC_A_7_DN")
	)
	(segment
		(start 307.690774 -317.048134)
		(end 307.466238 -317.097918)
		(width 0.127)
		(layer "B.Cu")
		(net "PHY_DRV_A_TO_SCC_A_7_DN")
	)
	(segment
		(start 287.282636 -340.082632)
		(end 287.282636 -339.832188)
		(width 0.127)
		(layer "B.Cu")
		(net "PHY_DRV_A_TO_SCC_A_7_DN")
	)
	(segment
		(start 306.727098 -318.56045)
		(end 294.490648 -337.767422)
		(width 0.127)
		(layer "B.Cu")
		(net "PHY_DRV_A_TO_SCC_A_7_DN")
	)
	(segment
		(start 308.27472 -316.131194)
		(end 308.050438 -316.180978)
		(width 0.127)
		(layer "B.Cu")
		(net "PHY_DRV_A_TO_SCC_A_7_DN")
	)
	(segment
		(start 294.490648 -337.767422)
		(end 290.98494 -339.998558)
		(width 0.127)
		(layer "B.Cu")
		(net "PHY_DRV_A_TO_SCC_A_7_DN")
	)
	(segment
		(start 306.882038 -318.014858)
		(end 306.677314 -318.336168)
		(width 0.127)
		(layer "B.Cu")
		(net "PHY_DRV_A_TO_SCC_A_7_DN")
	)
	(segment
		(start 308.050438 -316.180978)
		(end 307.845714 -316.502288)
		(width 0.127)
		(layer "B.Cu")
		(net "PHY_DRV_A_TO_SCC_A_7_DN")
	)
	(segment
		(start 356.112318 -277.603966)
		(end 355.56317 -277.603966)
		(width 0.127)
		(layer "B.Cu")
		(net "PHY_DRV_A_TO_SCC_A_7_DN")
	)
	(arc
		(start 287.7439 -340.45906)
		(mid 287.544442 -340.419385)
		(end 287.375346 -340.306406)
		(width 0.127)
		(layer "B.Cu")
		(net "PHY_DRV_A_TO_SCC_A_7_DN")
	)
	(arc
		(start 287.375346 -340.306406)
		(mid 287.306745 -340.203738)
		(end 287.282636 -340.082632)
		(width 0.127)
		(layer "B.Cu")
		(net "PHY_DRV_A_TO_SCC_A_7_DN")
	)
	(arc
		(start 356.289102 -277.427182)
		(mid 356.237323 -277.552187)
		(end 356.112318 -277.603966)
		(width 0.127)
		(layer "B.Cu")
		(net "PHY_DRV_A_TO_SCC_A_7_DN")
	)
	(arc
		(start 287.282636 -339.832188)
		(mid 287.319833 -339.742385)
		(end 287.409636 -339.705188)
		(width 0.127)
		(layer "B.Cu")
		(net "PHY_DRV_A_TO_SCC_A_7_DN")
	)
	(segment
		(start 324.866254 -277.896066)
		(end 325.77024 -277.896066)
		(width 0.127)
		(layer "F.Cu")
		(net "PHY_DRV_A_TO_SCC_A_6_DP")
	)
	(segment
		(start 325.77024 -277.896066)
		(end 325.913496 -278.039322)
		(width 0.127)
		(layer "F.Cu")
		(net "PHY_DRV_A_TO_SCC_A_6_DP")
	)
	(segment
		(start 325.913496 -278.039322)
		(end 325.913496 -278.2062)
		(width 0.127)
		(layer "F.Cu")
		(net "PHY_DRV_A_TO_SCC_A_6_DP")
	)
	(segment
		(start 326.092312 -278.385016)
		(end 327.375012 -278.385016)
		(width 0.127)
		(layer "F.Cu")
		(net "PHY_DRV_A_TO_SCC_A_6_DP")
	)
	(segment
		(start 324.739 -278.321516)
		(end 324.739 -278.02332)
		(width 0.127)
		(layer "F.Cu")
		(net "PHY_DRV_A_TO_SCC_A_6_DP")
	)
	(segment
		(start 325.913496 -278.2062)
		(end 326.092312 -278.385016)
		(width 0.127)
		(layer "F.Cu")
		(net "PHY_DRV_A_TO_SCC_A_6_DP")
	)
	(arc
		(start 324.739 -278.02332)
		(mid 324.776272 -277.933338)
		(end 324.866254 -277.896066)
		(width 0.127)
		(layer "F.Cu")
		(net "PHY_DRV_A_TO_SCC_A_6_DP")
	)
	(segment
		(start 320.011044 -295.063164)
		(end 294.034718 -335.836514)
		(width 0.127)
		(layer "B.Cu")
		(net "PHY_DRV_A_TO_SCC_A_6_DP")
	)
	(segment
		(start 323.75983 -278.166576)
		(end 320.011044 -295.063164)
		(width 0.127)
		(layer "B.Cu")
		(net "PHY_DRV_A_TO_SCC_A_6_DP")
	)
	(segment
		(start 289.580574 -338.673948)
		(end 288.329624 -338.951316)
		(width 0.127)
		(layer "B.Cu")
		(net "PHY_DRV_A_TO_SCC_A_6_DP")
	)
	(segment
		(start 288.32937 -338.951062)
		(end 286.743902 -338.951062)
		(width 0.127)
		(layer "B.Cu")
		(net "PHY_DRV_A_TO_SCC_A_6_DP")
	)
	(segment
		(start 324.739 -278.321516)
		(end 324.739 -278.07285)
		(width 0.127)
		(layer "B.Cu")
		(net "PHY_DRV_A_TO_SCC_A_6_DP")
	)
	(segment
		(start 294.034718 -335.836514)
		(end 289.580574 -338.673948)
		(width 0.127)
		(layer "B.Cu")
		(net "PHY_DRV_A_TO_SCC_A_6_DP")
	)
	(segment
		(start 285.863538 -337.90509)
		(end 285.436564 -337.90509)
		(width 0.127)
		(layer "B.Cu")
		(net "PHY_DRV_A_TO_SCC_A_6_DP")
	)
	(segment
		(start 324.185534 -277.896066)
		(end 323.75983 -278.166576)
		(width 0.127)
		(layer "B.Cu")
		(net "PHY_DRV_A_TO_SCC_A_6_DP")
	)
	(segment
		(start 324.562216 -277.896066)
		(end 324.185534 -277.896066)
		(width 0.127)
		(layer "B.Cu")
		(net "PHY_DRV_A_TO_SCC_A_6_DP")
	)
	(segment
		(start 285.990538 -338.282534)
		(end 285.990538 -338.03209)
		(width 0.127)
		(layer "B.Cu")
		(net "PHY_DRV_A_TO_SCC_A_6_DP")
	)
	(segment
		(start 288.329624 -338.951316)
		(end 288.32937 -338.951062)
		(width 0.127)
		(layer "B.Cu")
		(net "PHY_DRV_A_TO_SCC_A_6_DP")
	)
	(arc
		(start 324.739 -278.07285)
		(mid 324.687221 -277.947845)
		(end 324.562216 -277.896066)
		(width 0.127)
		(layer "B.Cu")
		(net "PHY_DRV_A_TO_SCC_A_6_DP")
	)
	(arc
		(start 286.743902 -338.951062)
		(mid 286.432565 -338.889133)
		(end 286.168592 -338.71281)
		(width 0.127)
		(layer "B.Cu")
		(net "PHY_DRV_A_TO_SCC_A_6_DP")
	)
	(arc
		(start 286.168592 -338.71281)
		(mid 286.036822 -338.515368)
		(end 285.990538 -338.282534)
		(width 0.127)
		(layer "B.Cu")
		(net "PHY_DRV_A_TO_SCC_A_6_DP")
	)
	(arc
		(start 285.990538 -338.03209)
		(mid 285.953341 -337.942287)
		(end 285.863538 -337.90509)
		(width 0.127)
		(layer "B.Cu")
		(net "PHY_DRV_A_TO_SCC_A_6_DP")
	)
	(segment
		(start 325.786496 -277.603966)
		(end 325.913496 -277.476966)
		(width 0.127)
		(layer "F.Cu")
		(net "PHY_DRV_A_TO_SCC_A_6_DN")
	)
	(segment
		(start 325.913496 -277.242016)
		(end 326.040496 -277.115016)
		(width 0.127)
		(layer "F.Cu")
		(net "PHY_DRV_A_TO_SCC_A_6_DN")
	)
	(segment
		(start 324.866254 -277.603966)
		(end 325.786496 -277.603966)
		(width 0.127)
		(layer "F.Cu")
		(net "PHY_DRV_A_TO_SCC_A_6_DN")
	)
	(segment
		(start 326.040496 -277.115016)
		(end 327.375012 -277.115016)
		(width 0.127)
		(layer "F.Cu")
		(net "PHY_DRV_A_TO_SCC_A_6_DN")
	)
	(segment
		(start 324.739 -277.178516)
		(end 324.739 -277.476712)
		(width 0.127)
		(layer "F.Cu")
		(net "PHY_DRV_A_TO_SCC_A_6_DN")
	)
	(segment
		(start 325.913496 -277.476966)
		(end 325.913496 -277.242016)
		(width 0.127)
		(layer "F.Cu")
		(net "PHY_DRV_A_TO_SCC_A_6_DN")
	)
	(arc
		(start 324.739 -277.476712)
		(mid 324.776272 -277.566694)
		(end 324.866254 -277.603966)
		(width 0.127)
		(layer "F.Cu")
		(net "PHY_DRV_A_TO_SCC_A_6_DN")
	)
	(segment
		(start 315.56198 -301.200058)
		(end 315.357256 -301.521368)
		(width 0.127)
		(layer "B.Cu")
		(net "PHY_DRV_A_TO_SCC_A_6_DN")
	)
	(segment
		(start 316.73038 -299.366432)
		(end 316.525656 -299.687742)
		(width 0.127)
		(layer "B.Cu")
		(net "PHY_DRV_A_TO_SCC_A_6_DN")
	)
	(segment
		(start 293.823136 -335.624932)
		(end 289.467036 -338.399882)
		(width 0.127)
		(layer "B.Cu")
		(net "PHY_DRV_A_TO_SCC_A_6_DN")
	)
	(segment
		(start 286.282638 -338.282534)
		(end 286.282638 -338.03209)
		(width 0.127)
		(layer "B.Cu")
		(net "PHY_DRV_A_TO_SCC_A_6_DN")
	)
	(segment
		(start 315.40704 -301.745904)
		(end 293.823136 -335.624932)
		(width 0.127)
		(layer "B.Cu")
		(net "PHY_DRV_A_TO_SCC_A_6_DN")
	)
	(segment
		(start 316.57544 -299.912278)
		(end 316.370716 -300.233588)
		(width 0.127)
		(layer "B.Cu")
		(net "PHY_DRV_A_TO_SCC_A_6_DN")
	)
	(segment
		(start 315.941456 -300.604682)
		(end 315.99124 -300.828964)
		(width 0.127)
		(layer "B.Cu")
		(net "PHY_DRV_A_TO_SCC_A_6_DN")
	)
	(segment
		(start 316.525656 -299.687742)
		(end 316.57544 -299.912278)
		(width 0.127)
		(layer "B.Cu")
		(net "PHY_DRV_A_TO_SCC_A_6_DN")
	)
	(segment
		(start 316.370716 -300.233588)
		(end 316.14618 -300.283372)
		(width 0.127)
		(layer "B.Cu")
		(net "PHY_DRV_A_TO_SCC_A_6_DN")
	)
	(segment
		(start 316.954662 -299.316648)
		(end 316.73038 -299.366432)
		(width 0.127)
		(layer "B.Cu")
		(net "PHY_DRV_A_TO_SCC_A_6_DN")
	)
	(segment
		(start 316.14618 -300.283372)
		(end 315.941456 -300.604682)
		(width 0.127)
		(layer "B.Cu")
		(net "PHY_DRV_A_TO_SCC_A_6_DN")
	)
	(segment
		(start 324.562216 -277.603966)
		(end 324.100444 -277.603966)
		(width 0.127)
		(layer "B.Cu")
		(net "PHY_DRV_A_TO_SCC_A_6_DN")
	)
	(segment
		(start 315.99124 -300.828964)
		(end 315.786516 -301.150274)
		(width 0.127)
		(layer "B.Cu")
		(net "PHY_DRV_A_TO_SCC_A_6_DN")
	)
	(segment
		(start 319.736978 -294.949626)
		(end 316.954662 -299.316648)
		(width 0.127)
		(layer "B.Cu")
		(net "PHY_DRV_A_TO_SCC_A_6_DN")
	)
	(segment
		(start 315.357256 -301.521368)
		(end 315.40704 -301.745904)
		(width 0.127)
		(layer "B.Cu")
		(net "PHY_DRV_A_TO_SCC_A_6_DN")
	)
	(segment
		(start 315.786516 -301.150274)
		(end 315.56198 -301.200058)
		(width 0.127)
		(layer "B.Cu")
		(net "PHY_DRV_A_TO_SCC_A_6_DN")
	)
	(segment
		(start 324.100444 -277.603966)
		(end 323.50075 -277.984966)
		(width 0.127)
		(layer "B.Cu")
		(net "PHY_DRV_A_TO_SCC_A_6_DN")
	)
	(segment
		(start 288.297366 -338.658962)
		(end 286.743902 -338.658962)
		(width 0.127)
		(layer "B.Cu")
		(net "PHY_DRV_A_TO_SCC_A_6_DN")
	)
	(segment
		(start 289.467036 -338.399882)
		(end 288.29762 -338.659216)
		(width 0.127)
		(layer "B.Cu")
		(net "PHY_DRV_A_TO_SCC_A_6_DN")
	)
	(segment
		(start 288.29762 -338.659216)
		(end 288.297366 -338.658962)
		(width 0.127)
		(layer "B.Cu")
		(net "PHY_DRV_A_TO_SCC_A_6_DN")
	)
	(segment
		(start 286.409638 -337.90509)
		(end 286.836612 -337.90509)
		(width 0.127)
		(layer "B.Cu")
		(net "PHY_DRV_A_TO_SCC_A_6_DN")
	)
	(segment
		(start 323.50075 -277.984966)
		(end 319.736978 -294.949626)
		(width 0.127)
		(layer "B.Cu")
		(net "PHY_DRV_A_TO_SCC_A_6_DN")
	)
	(segment
		(start 324.739 -277.178516)
		(end 324.739 -277.427182)
		(width 0.127)
		(layer "B.Cu")
		(net "PHY_DRV_A_TO_SCC_A_6_DN")
	)
	(arc
		(start 286.743902 -338.658962)
		(mid 286.544444 -338.619287)
		(end 286.375348 -338.506308)
		(width 0.127)
		(layer "B.Cu")
		(net "PHY_DRV_A_TO_SCC_A_6_DN")
	)
	(arc
		(start 286.375348 -338.506308)
		(mid 286.306747 -338.40364)
		(end 286.282638 -338.282534)
		(width 0.127)
		(layer "B.Cu")
		(net "PHY_DRV_A_TO_SCC_A_6_DN")
	)
	(arc
		(start 286.282638 -338.03209)
		(mid 286.319835 -337.942287)
		(end 286.409638 -337.90509)
		(width 0.127)
		(layer "B.Cu")
		(net "PHY_DRV_A_TO_SCC_A_6_DN")
	)
	(arc
		(start 324.739 -277.427182)
		(mid 324.687221 -277.552187)
		(end 324.562216 -277.603966)
		(width 0.127)
		(layer "B.Cu")
		(net "PHY_DRV_A_TO_SCC_A_6_DN")
	)
	(segment
		(start 189.236604 -278.258016)
		(end 189.109604 -278.385016)
		(width 0.127)
		(layer "F.Cu")
		(net "PHY_DRV_A_TO_SCC_A_5_DP")
	)
	(segment
		(start 189.236604 -278.023066)
		(end 189.236604 -278.258016)
		(width 0.127)
		(layer "F.Cu")
		(net "PHY_DRV_A_TO_SCC_A_5_DP")
	)
	(segment
		(start 190.131954 -277.896066)
		(end 189.363604 -277.896066)
		(width 0.127)
		(layer "F.Cu")
		(net "PHY_DRV_A_TO_SCC_A_5_DP")
	)
	(segment
		(start 189.109604 -278.385016)
		(end 187.775088 -278.385016)
		(width 0.127)
		(layer "F.Cu")
		(net "PHY_DRV_A_TO_SCC_A_5_DP")
	)
	(segment
		(start 189.363604 -277.896066)
		(end 189.236604 -278.023066)
		(width 0.127)
		(layer "F.Cu")
		(net "PHY_DRV_A_TO_SCC_A_5_DP")
	)
	(segment
		(start 190.258954 -278.321516)
		(end 190.258954 -278.023066)
		(width 0.127)
		(layer "F.Cu")
		(net "PHY_DRV_A_TO_SCC_A_5_DP")
	)
	(arc
		(start 190.258954 -278.023066)
		(mid 190.221757 -277.933263)
		(end 190.131954 -277.896066)
		(width 0.127)
		(layer "F.Cu")
		(net "PHY_DRV_A_TO_SCC_A_5_DP")
	)
	(segment
		(start 256.911856 -340.669372)
		(end 238.44504 -328.329544)
		(width 0.1016)
		(layer "In7.Cu")
		(net "PHY_DRV_A_TO_SCC_A_5_DP")
	)
	(segment
		(start 285.973774 -348.57817)
		(end 285.973774 -348.13494)
		(width 0.1016)
		(layer "In7.Cu")
		(net "PHY_DRV_A_TO_SCC_A_5_DP")
	)
	(segment
		(start 270.510508 -345.873324)
		(end 270.38173 -345.596464)
		(width 0.1016)
		(layer "In7.Cu")
		(net "PHY_DRV_A_TO_SCC_A_5_DP")
	)
	(segment
		(start 268.425676 -344.880946)
		(end 256.911856 -340.669372)
		(width 0.1016)
		(layer "In7.Cu")
		(net "PHY_DRV_A_TO_SCC_A_5_DP")
	)
	(segment
		(start 270.095472 -345.491562)
		(end 269.818612 -345.62034)
		(width 0.1016)
		(layer "In7.Cu")
		(net "PHY_DRV_A_TO_SCC_A_5_DP")
	)
	(segment
		(start 269.818612 -345.62034)
		(end 269.532354 -345.515438)
		(width 0.1016)
		(layer "In7.Cu")
		(net "PHY_DRV_A_TO_SCC_A_5_DP")
	)
	(segment
		(start 270.38173 -345.596464)
		(end 270.095472 -345.491562)
		(width 0.1016)
		(layer "In7.Cu")
		(net "PHY_DRV_A_TO_SCC_A_5_DP")
	)
	(segment
		(start 271.073626 -345.849448)
		(end 270.796766 -345.977972)
		(width 0.1016)
		(layer "In7.Cu")
		(net "PHY_DRV_A_TO_SCC_A_5_DP")
	)
	(segment
		(start 285.809182 -347.970348)
		(end 276.872192 -347.970348)
		(width 0.1016)
		(layer "In7.Cu")
		(net "PHY_DRV_A_TO_SCC_A_5_DP")
	)
	(segment
		(start 269.532354 -345.515438)
		(end 269.40383 -345.238578)
		(width 0.1016)
		(layer "In7.Cu")
		(net "PHY_DRV_A_TO_SCC_A_5_DP")
	)
	(segment
		(start 269.117572 -345.13393)
		(end 268.840712 -345.262454)
		(width 0.1016)
		(layer "In7.Cu")
		(net "PHY_DRV_A_TO_SCC_A_5_DP")
	)
	(segment
		(start 238.44504 -328.329544)
		(end 219.962476 -315.97854)
		(width 0.1016)
		(layer "In7.Cu")
		(net "PHY_DRV_A_TO_SCC_A_5_DP")
	)
	(segment
		(start 285.436564 -348.70517)
		(end 285.846774 -348.70517)
		(width 0.1016)
		(layer "In7.Cu")
		(net "PHY_DRV_A_TO_SCC_A_5_DP")
	)
	(segment
		(start 268.840712 -345.262454)
		(end 268.554454 -345.157806)
		(width 0.1016)
		(layer "In7.Cu")
		(net "PHY_DRV_A_TO_SCC_A_5_DP")
	)
	(segment
		(start 268.554454 -345.157806)
		(end 268.425676 -344.880946)
		(width 0.1016)
		(layer "In7.Cu")
		(net "PHY_DRV_A_TO_SCC_A_5_DP")
	)
	(segment
		(start 219.962476 -315.97854)
		(end 193.290952 -279.21204)
		(width 0.1016)
		(layer "In7.Cu")
		(net "PHY_DRV_A_TO_SCC_A_5_DP")
	)
	(segment
		(start 193.290952 -279.21204)
		(end 191.270636 -277.915116)
		(width 0.1016)
		(layer "In7.Cu")
		(net "PHY_DRV_A_TO_SCC_A_5_DP")
	)
	(segment
		(start 270.796766 -345.977972)
		(end 270.510508 -345.873324)
		(width 0.1016)
		(layer "In7.Cu")
		(net "PHY_DRV_A_TO_SCC_A_5_DP")
	)
	(segment
		(start 269.40383 -345.238578)
		(end 269.117572 -345.13393)
		(width 0.1016)
		(layer "In7.Cu")
		(net "PHY_DRV_A_TO_SCC_A_5_DP")
	)
	(segment
		(start 191.270636 -277.915116)
		(end 190.360554 -277.915116)
		(width 0.1016)
		(layer "In7.Cu")
		(net "PHY_DRV_A_TO_SCC_A_5_DP")
	)
	(segment
		(start 276.872192 -347.970348)
		(end 271.073626 -345.849448)
		(width 0.1016)
		(layer "In7.Cu")
		(net "PHY_DRV_A_TO_SCC_A_5_DP")
	)
	(segment
		(start 190.258954 -278.016716)
		(end 190.258954 -278.321516)
		(width 0.1016)
		(layer "In7.Cu")
		(net "PHY_DRV_A_TO_SCC_A_5_DP")
	)
	(arc
		(start 190.360554 -277.915116)
		(mid 190.288712 -277.944874)
		(end 190.258954 -278.016716)
		(width 0.1016)
		(layer "In7.Cu")
		(net "PHY_DRV_A_TO_SCC_A_5_DP")
	)
	(arc
		(start 285.973774 -348.13494)
		(mid 285.925566 -348.018556)
		(end 285.809182 -347.970348)
		(width 0.1016)
		(layer "In7.Cu")
		(net "PHY_DRV_A_TO_SCC_A_5_DP")
	)
	(arc
		(start 285.846774 -348.70517)
		(mid 285.936577 -348.667973)
		(end 285.973774 -348.57817)
		(width 0.1016)
		(layer "In7.Cu")
		(net "PHY_DRV_A_TO_SCC_A_5_DP")
	)
	(segment
		(start 190.258954 -277.178516)
		(end 190.258954 -277.476966)
		(width 0.127)
		(layer "F.Cu")
		(net "PHY_DRV_A_TO_SCC_A_5_DN")
	)
	(segment
		(start 189.109604 -277.115016)
		(end 187.775088 -277.115016)
		(width 0.127)
		(layer "F.Cu")
		(net "PHY_DRV_A_TO_SCC_A_5_DN")
	)
	(segment
		(start 189.236604 -277.476966)
		(end 189.236604 -277.242016)
		(width 0.127)
		(layer "F.Cu")
		(net "PHY_DRV_A_TO_SCC_A_5_DN")
	)
	(segment
		(start 189.363604 -277.603966)
		(end 189.236604 -277.476966)
		(width 0.127)
		(layer "F.Cu")
		(net "PHY_DRV_A_TO_SCC_A_5_DN")
	)
	(segment
		(start 190.131954 -277.603966)
		(end 189.363604 -277.603966)
		(width 0.127)
		(layer "F.Cu")
		(net "PHY_DRV_A_TO_SCC_A_5_DN")
	)
	(segment
		(start 189.236604 -277.242016)
		(end 189.109604 -277.115016)
		(width 0.127)
		(layer "F.Cu")
		(net "PHY_DRV_A_TO_SCC_A_5_DN")
	)
	(arc
		(start 190.258954 -277.476966)
		(mid 190.221757 -277.566769)
		(end 190.131954 -277.603966)
		(width 0.127)
		(layer "F.Cu")
		(net "PHY_DRV_A_TO_SCC_A_5_DN")
	)
	(segment
		(start 285.809182 -347.640148)
		(end 276.930866 -347.640148)
		(width 0.1016)
		(layer "In7.Cu")
		(net "PHY_DRV_A_TO_SCC_A_5_DN")
	)
	(segment
		(start 191.367664 -277.584916)
		(end 190.360554 -277.584916)
		(width 0.1016)
		(layer "In7.Cu")
		(net "PHY_DRV_A_TO_SCC_A_5_DN")
	)
	(segment
		(start 193.521838 -278.967692)
		(end 191.367664 -277.584916)
		(width 0.1016)
		(layer "In7.Cu")
		(net "PHY_DRV_A_TO_SCC_A_5_DN")
	)
	(segment
		(start 257.062478 -340.3727)
		(end 220.19514 -315.736732)
		(width 0.1016)
		(layer "In7.Cu")
		(net "PHY_DRV_A_TO_SCC_A_5_DN")
	)
	(segment
		(start 286.303974 -348.57817)
		(end 286.303974 -348.13494)
		(width 0.1016)
		(layer "In7.Cu")
		(net "PHY_DRV_A_TO_SCC_A_5_DN")
	)
	(segment
		(start 286.836612 -348.70517)
		(end 286.430974 -348.70517)
		(width 0.1016)
		(layer "In7.Cu")
		(net "PHY_DRV_A_TO_SCC_A_5_DN")
	)
	(segment
		(start 276.930866 -347.640148)
		(end 257.062478 -340.3727)
		(width 0.1016)
		(layer "In7.Cu")
		(net "PHY_DRV_A_TO_SCC_A_5_DN")
	)
	(segment
		(start 220.19514 -315.736732)
		(end 193.521838 -278.967692)
		(width 0.1016)
		(layer "In7.Cu")
		(net "PHY_DRV_A_TO_SCC_A_5_DN")
	)
	(segment
		(start 190.258954 -277.483316)
		(end 190.258954 -277.178516)
		(width 0.1016)
		(layer "In7.Cu")
		(net "PHY_DRV_A_TO_SCC_A_5_DN")
	)
	(arc
		(start 286.303974 -348.13494)
		(mid 286.159053 -347.785069)
		(end 285.809182 -347.640148)
		(width 0.1016)
		(layer "In7.Cu")
		(net "PHY_DRV_A_TO_SCC_A_5_DN")
	)
	(arc
		(start 190.360554 -277.584916)
		(mid 190.288712 -277.555158)
		(end 190.258954 -277.483316)
		(width 0.1016)
		(layer "In7.Cu")
		(net "PHY_DRV_A_TO_SCC_A_5_DN")
	)
	(arc
		(start 286.430974 -348.70517)
		(mid 286.341171 -348.667973)
		(end 286.303974 -348.57817)
		(width 0.1016)
		(layer "In7.Cu")
		(net "PHY_DRV_A_TO_SCC_A_5_DN")
	)
	(segment
		(start 157.686502 -278.023066)
		(end 157.686502 -278.258016)
		(width 0.127)
		(layer "F.Cu")
		(net "PHY_DRV_A_TO_SCC_A_4_DP")
	)
	(segment
		(start 158.581852 -277.896066)
		(end 157.813502 -277.896066)
		(width 0.127)
		(layer "F.Cu")
		(net "PHY_DRV_A_TO_SCC_A_4_DP")
	)
	(segment
		(start 158.708852 -278.321516)
		(end 158.708852 -278.023066)
		(width 0.127)
		(layer "F.Cu")
		(net "PHY_DRV_A_TO_SCC_A_4_DP")
	)
	(segment
		(start 157.559502 -278.385016)
		(end 156.224986 -278.385016)
		(width 0.127)
		(layer "F.Cu")
		(net "PHY_DRV_A_TO_SCC_A_4_DP")
	)
	(segment
		(start 157.813502 -277.896066)
		(end 157.686502 -278.023066)
		(width 0.127)
		(layer "F.Cu")
		(net "PHY_DRV_A_TO_SCC_A_4_DP")
	)
	(segment
		(start 157.686502 -278.258016)
		(end 157.559502 -278.385016)
		(width 0.127)
		(layer "F.Cu")
		(net "PHY_DRV_A_TO_SCC_A_4_DP")
	)
	(arc
		(start 158.708852 -278.023066)
		(mid 158.671655 -277.933263)
		(end 158.581852 -277.896066)
		(width 0.127)
		(layer "F.Cu")
		(net "PHY_DRV_A_TO_SCC_A_4_DP")
	)
	(segment
		(start 161.967926 -279.333452)
		(end 172.957744 -296.58183)
		(width 0.1016)
		(layer "In7.Cu")
		(net "PHY_DRV_A_TO_SCC_A_4_DP")
	)
	(segment
		(start 158.708852 -278.321516)
		(end 158.708852 -278.016716)
		(width 0.1016)
		(layer "In7.Cu")
		(net "PHY_DRV_A_TO_SCC_A_4_DP")
	)
	(segment
		(start 267.650976 -347.220286)
		(end 267.927836 -347.091762)
		(width 0.1016)
		(layer "In7.Cu")
		(net "PHY_DRV_A_TO_SCC_A_4_DP")
	)
	(segment
		(start 269.320772 -347.831156)
		(end 269.60703 -347.935804)
		(width 0.1016)
		(layer "In7.Cu")
		(net "PHY_DRV_A_TO_SCC_A_4_DP")
	)
	(segment
		(start 267.364718 -347.115638)
		(end 267.650976 -347.220286)
		(width 0.1016)
		(layer "In7.Cu")
		(net "PHY_DRV_A_TO_SCC_A_4_DP")
	)
	(segment
		(start 204.368908 -316.59322)
		(end 204.418184 -316.624462)
		(width 0.1016)
		(layer "In7.Cu")
		(net "PHY_DRV_A_TO_SCC_A_4_DP")
	)
	(segment
		(start 172.957744 -296.58183)
		(end 204.369162 -316.59322)
		(width 0.1016)
		(layer "In7.Cu")
		(net "PHY_DRV_A_TO_SCC_A_4_DP")
	)
	(segment
		(start 269.60703 -347.935804)
		(end 269.88389 -347.80728)
		(width 0.1016)
		(layer "In7.Cu")
		(net "PHY_DRV_A_TO_SCC_A_4_DP")
	)
	(segment
		(start 204.418184 -316.624462)
		(end 221.574614 -320.428112)
		(width 0.1016)
		(layer "In7.Cu")
		(net "PHY_DRV_A_TO_SCC_A_4_DP")
	)
	(segment
		(start 268.214094 -347.19641)
		(end 268.342618 -347.47327)
		(width 0.1016)
		(layer "In7.Cu")
		(net "PHY_DRV_A_TO_SCC_A_4_DP")
	)
	(segment
		(start 286.973772 -349.935038)
		(end 286.973772 -350.378268)
		(width 0.1016)
		(layer "In7.Cu")
		(net "PHY_DRV_A_TO_SCC_A_4_DP")
	)
	(segment
		(start 268.342618 -347.47327)
		(end 268.628876 -347.578172)
		(width 0.1016)
		(layer "In7.Cu")
		(net "PHY_DRV_A_TO_SCC_A_4_DP")
	)
	(segment
		(start 257.367024 -343.229184)
		(end 262.3185 -345.040204)
		(width 0.1016)
		(layer "In7.Cu")
		(net "PHY_DRV_A_TO_SCC_A_4_DP")
	)
	(segment
		(start 267.927836 -347.091762)
		(end 268.214094 -347.19641)
		(width 0.1016)
		(layer "In7.Cu")
		(net "PHY_DRV_A_TO_SCC_A_4_DP")
	)
	(segment
		(start 221.574614 -320.428112)
		(end 257.367024 -343.229184)
		(width 0.1016)
		(layer "In7.Cu")
		(net "PHY_DRV_A_TO_SCC_A_4_DP")
	)
	(segment
		(start 269.88389 -347.80728)
		(end 275.251672 -349.770446)
		(width 0.1016)
		(layer "In7.Cu")
		(net "PHY_DRV_A_TO_SCC_A_4_DP")
	)
	(segment
		(start 268.905736 -347.449394)
		(end 269.191994 -347.554042)
		(width 0.1016)
		(layer "In7.Cu")
		(net "PHY_DRV_A_TO_SCC_A_4_DP")
	)
	(segment
		(start 269.191994 -347.554042)
		(end 269.320772 -347.831156)
		(width 0.1016)
		(layer "In7.Cu")
		(net "PHY_DRV_A_TO_SCC_A_4_DP")
	)
	(segment
		(start 275.251672 -349.770446)
		(end 286.80918 -349.770446)
		(width 0.1016)
		(layer "In7.Cu")
		(net "PHY_DRV_A_TO_SCC_A_4_DP")
	)
	(segment
		(start 159.946086 -278.045418)
		(end 161.967926 -279.333452)
		(width 0.1016)
		(layer "In7.Cu")
		(net "PHY_DRV_A_TO_SCC_A_4_DP")
	)
	(segment
		(start 267.23594 -346.838778)
		(end 267.364718 -347.115638)
		(width 0.1016)
		(layer "In7.Cu")
		(net "PHY_DRV_A_TO_SCC_A_4_DP")
	)
	(segment
		(start 286.846772 -350.505268)
		(end 286.436562 -350.505268)
		(width 0.1016)
		(layer "In7.Cu")
		(net "PHY_DRV_A_TO_SCC_A_4_DP")
	)
	(segment
		(start 262.3185 -345.040204)
		(end 267.23594 -346.838778)
		(width 0.1016)
		(layer "In7.Cu")
		(net "PHY_DRV_A_TO_SCC_A_4_DP")
	)
	(segment
		(start 268.628876 -347.578172)
		(end 268.905736 -347.449394)
		(width 0.1016)
		(layer "In7.Cu")
		(net "PHY_DRV_A_TO_SCC_A_4_DP")
	)
	(segment
		(start 158.810452 -277.915116)
		(end 159.35833 -277.915116)
		(width 0.1016)
		(layer "In7.Cu")
		(net "PHY_DRV_A_TO_SCC_A_4_DP")
	)
	(segment
		(start 159.35833 -277.915116)
		(end 159.946086 -278.045418)
		(width 0.1016)
		(layer "In7.Cu")
		(net "PHY_DRV_A_TO_SCC_A_4_DP")
	)
	(segment
		(start 204.369162 -316.59322)
		(end 204.368908 -316.59322)
		(width 0.1016)
		(layer "In7.Cu")
		(net "PHY_DRV_A_TO_SCC_A_4_DP")
	)
	(arc
		(start 286.80918 -349.770446)
		(mid 286.925564 -349.818654)
		(end 286.973772 -349.935038)
		(width 0.1016)
		(layer "In7.Cu")
		(net "PHY_DRV_A_TO_SCC_A_4_DP")
	)
	(arc
		(start 158.708852 -278.016716)
		(mid 158.73861 -277.944874)
		(end 158.810452 -277.915116)
		(width 0.1016)
		(layer "In7.Cu")
		(net "PHY_DRV_A_TO_SCC_A_4_DP")
	)
	(arc
		(start 286.973772 -350.378268)
		(mid 286.936575 -350.468071)
		(end 286.846772 -350.505268)
		(width 0.1016)
		(layer "In7.Cu")
		(net "PHY_DRV_A_TO_SCC_A_4_DP")
	)
	(segment
		(start 158.581852 -277.603966)
		(end 157.813502 -277.603966)
		(width 0.127)
		(layer "F.Cu")
		(net "PHY_DRV_A_TO_SCC_A_4_DN")
	)
	(segment
		(start 157.686502 -277.476966)
		(end 157.686502 -277.242016)
		(width 0.127)
		(layer "F.Cu")
		(net "PHY_DRV_A_TO_SCC_A_4_DN")
	)
	(segment
		(start 157.559502 -277.115016)
		(end 156.224986 -277.115016)
		(width 0.127)
		(layer "F.Cu")
		(net "PHY_DRV_A_TO_SCC_A_4_DN")
	)
	(segment
		(start 157.686502 -277.242016)
		(end 157.559502 -277.115016)
		(width 0.127)
		(layer "F.Cu")
		(net "PHY_DRV_A_TO_SCC_A_4_DN")
	)
	(segment
		(start 157.813502 -277.603966)
		(end 157.686502 -277.476966)
		(width 0.127)
		(layer "F.Cu")
		(net "PHY_DRV_A_TO_SCC_A_4_DN")
	)
	(segment
		(start 158.708852 -277.178516)
		(end 158.708852 -277.476966)
		(width 0.127)
		(layer "F.Cu")
		(net "PHY_DRV_A_TO_SCC_A_4_DN")
	)
	(arc
		(start 158.708852 -277.476966)
		(mid 158.671655 -277.566769)
		(end 158.581852 -277.603966)
		(width 0.127)
		(layer "F.Cu")
		(net "PHY_DRV_A_TO_SCC_A_4_DN")
	)
	(segment
		(start 159.394652 -277.584916)
		(end 160.074356 -277.735538)
		(width 0.1016)
		(layer "In7.Cu")
		(net "PHY_DRV_A_TO_SCC_A_4_DN")
	)
	(segment
		(start 173.197012 -296.342562)
		(end 204.546454 -316.314582)
		(width 0.1016)
		(layer "In7.Cu")
		(net "PHY_DRV_A_TO_SCC_A_4_DN")
	)
	(segment
		(start 257.514344 -342.931242)
		(end 275.310346 -349.440246)
		(width 0.1016)
		(layer "In7.Cu")
		(net "PHY_DRV_A_TO_SCC_A_4_DN")
	)
	(segment
		(start 287.303972 -349.935038)
		(end 287.303972 -350.378268)
		(width 0.1016)
		(layer "In7.Cu")
		(net "PHY_DRV_A_TO_SCC_A_4_DN")
	)
	(segment
		(start 160.074356 -277.735538)
		(end 162.207194 -279.094184)
		(width 0.1016)
		(layer "In7.Cu")
		(net "PHY_DRV_A_TO_SCC_A_4_DN")
	)
	(segment
		(start 287.430972 -350.505268)
		(end 287.83661 -350.505268)
		(width 0.1016)
		(layer "In7.Cu")
		(net "PHY_DRV_A_TO_SCC_A_4_DN")
	)
	(segment
		(start 204.546454 -316.314582)
		(end 221.702884 -320.118232)
		(width 0.1016)
		(layer "In7.Cu")
		(net "PHY_DRV_A_TO_SCC_A_4_DN")
	)
	(segment
		(start 162.207194 -279.094184)
		(end 173.197012 -296.342562)
		(width 0.1016)
		(layer "In7.Cu")
		(net "PHY_DRV_A_TO_SCC_A_4_DN")
	)
	(segment
		(start 221.702884 -320.118232)
		(end 257.514344 -342.931242)
		(width 0.1016)
		(layer "In7.Cu")
		(net "PHY_DRV_A_TO_SCC_A_4_DN")
	)
	(segment
		(start 275.310346 -349.440246)
		(end 286.80918 -349.440246)
		(width 0.1016)
		(layer "In7.Cu")
		(net "PHY_DRV_A_TO_SCC_A_4_DN")
	)
	(segment
		(start 158.810452 -277.584916)
		(end 159.394652 -277.584916)
		(width 0.1016)
		(layer "In7.Cu")
		(net "PHY_DRV_A_TO_SCC_A_4_DN")
	)
	(segment
		(start 158.708852 -277.178516)
		(end 158.708852 -277.483316)
		(width 0.1016)
		(layer "In7.Cu")
		(net "PHY_DRV_A_TO_SCC_A_4_DN")
	)
	(arc
		(start 158.708852 -277.483316)
		(mid 158.73861 -277.555158)
		(end 158.810452 -277.584916)
		(width 0.1016)
		(layer "In7.Cu")
		(net "PHY_DRV_A_TO_SCC_A_4_DN")
	)
	(arc
		(start 287.303972 -350.378268)
		(mid 287.341169 -350.468071)
		(end 287.430972 -350.505268)
		(width 0.1016)
		(layer "In7.Cu")
		(net "PHY_DRV_A_TO_SCC_A_4_DN")
	)
	(arc
		(start 286.80918 -349.440246)
		(mid 287.159051 -349.585167)
		(end 287.303972 -349.935038)
		(width 0.1016)
		(layer "In7.Cu")
		(net "PHY_DRV_A_TO_SCC_A_4_DN")
	)
	(segment
		(start 483.52837 -47.896018)
		(end 482.644704 -47.896018)
		(width 0.127)
		(layer "F.Cu")
		(net "PHY_DRV_A_TO_SCC_A_35_DP")
	)
	(segment
		(start 485.125014 -48.384968)
		(end 483.849934 -48.384968)
		(width 0.127)
		(layer "F.Cu")
		(net "PHY_DRV_A_TO_SCC_A_35_DP")
	)
	(segment
		(start 483.849934 -48.384968)
		(end 483.663498 -48.198532)
		(width 0.127)
		(layer "F.Cu")
		(net "PHY_DRV_A_TO_SCC_A_35_DP")
	)
	(segment
		(start 483.663498 -48.198532)
		(end 483.663498 -48.031146)
		(width 0.127)
		(layer "F.Cu")
		(net "PHY_DRV_A_TO_SCC_A_35_DP")
	)
	(segment
		(start 482.489002 -48.05172)
		(end 482.489002 -48.321468)
		(width 0.127)
		(layer "F.Cu")
		(net "PHY_DRV_A_TO_SCC_A_35_DP")
	)
	(segment
		(start 483.663498 -48.031146)
		(end 483.52837 -47.896018)
		(width 0.127)
		(layer "F.Cu")
		(net "PHY_DRV_A_TO_SCC_A_35_DP")
	)
	(arc
		(start 482.644704 -47.896018)
		(mid 482.534606 -47.941622)
		(end 482.489002 -48.05172)
		(width 0.127)
		(layer "F.Cu")
		(net "PHY_DRV_A_TO_SCC_A_35_DP")
	)
	(segment
		(start 308.634384 -217.020902)
		(end 308.634638 -217.019886)
		(width 0.127)
		(layer "B.Cu")
		(net "PHY_DRV_A_TO_SCC_A_35_DP")
	)
	(segment
		(start 308.634638 -217.019886)
		(end 321.9958 -156.761434)
		(width 0.127)
		(layer "B.Cu")
		(net "PHY_DRV_A_TO_SCC_A_35_DP")
	)
	(segment
		(start 315.163708 -246.476266)
		(end 308.634384 -217.020902)
		(width 0.127)
		(layer "B.Cu")
		(net "PHY_DRV_A_TO_SCC_A_35_DP")
	)
	(segment
		(start 472.205558 -48.747426)
		(end 480.9744 -47.896018)
		(width 0.127)
		(layer "B.Cu")
		(net "PHY_DRV_A_TO_SCC_A_35_DP")
	)
	(segment
		(start 355.183694 -108.520992)
		(end 419.095174 -67.10553)
		(width 0.127)
		(layer "B.Cu")
		(net "PHY_DRV_A_TO_SCC_A_35_DP")
	)
	(segment
		(start 431.05197 -64.56426)
		(end 463.701638 -49.572926)
		(width 0.127)
		(layer "B.Cu")
		(net "PHY_DRV_A_TO_SCC_A_35_DP")
	)
	(segment
		(start 480.9744 -47.896018)
		(end 482.312218 -47.896018)
		(width 0.127)
		(layer "B.Cu")
		(net "PHY_DRV_A_TO_SCC_A_35_DP")
	)
	(segment
		(start 472.205812 -48.747426)
		(end 472.205558 -48.747426)
		(width 0.127)
		(layer "B.Cu")
		(net "PHY_DRV_A_TO_SCC_A_35_DP")
	)
	(segment
		(start 296.157396 -300.489112)
		(end 307.000656 -283.467048)
		(width 0.127)
		(layer "B.Cu")
		(net "PHY_DRV_A_TO_SCC_A_35_DP")
	)
	(segment
		(start 431.05197 -64.564768)
		(end 431.05197 -64.56426)
		(width 0.127)
		(layer "B.Cu")
		(net "PHY_DRV_A_TO_SCC_A_35_DP")
	)
	(segment
		(start 288.302954 -304.751232)
		(end 289.99561 -304.376074)
		(width 0.127)
		(layer "B.Cu")
		(net "PHY_DRV_A_TO_SCC_A_35_DP")
	)
	(segment
		(start 419.095174 -67.10553)
		(end 431.05197 -64.564768)
		(width 0.127)
		(layer "B.Cu")
		(net "PHY_DRV_A_TO_SCC_A_35_DP")
	)
	(segment
		(start 482.489002 -48.072802)
		(end 482.489002 -48.321468)
		(width 0.127)
		(layer "B.Cu")
		(net "PHY_DRV_A_TO_SCC_A_35_DP")
	)
	(segment
		(start 321.9958 -156.761434)
		(end 355.183694 -108.520992)
		(width 0.127)
		(layer "B.Cu")
		(net "PHY_DRV_A_TO_SCC_A_35_DP")
	)
	(segment
		(start 286.436562 -303.70526)
		(end 286.863536 -303.70526)
		(width 0.127)
		(layer "B.Cu")
		(net "PHY_DRV_A_TO_SCC_A_35_DP")
	)
	(segment
		(start 287.7439 -304.751232)
		(end 288.302954 -304.751232)
		(width 0.127)
		(layer "B.Cu")
		(net "PHY_DRV_A_TO_SCC_A_35_DP")
	)
	(segment
		(start 463.701638 -49.572926)
		(end 472.205812 -48.747426)
		(width 0.127)
		(layer "B.Cu")
		(net "PHY_DRV_A_TO_SCC_A_35_DP")
	)
	(segment
		(start 307.000656 -283.467048)
		(end 315.163708 -246.476266)
		(width 0.127)
		(layer "B.Cu")
		(net "PHY_DRV_A_TO_SCC_A_35_DP")
	)
	(segment
		(start 286.990536 -303.83226)
		(end 286.990536 -304.082704)
		(width 0.127)
		(layer "B.Cu")
		(net "PHY_DRV_A_TO_SCC_A_35_DP")
	)
	(segment
		(start 289.99561 -304.376074)
		(end 296.157396 -300.489112)
		(width 0.127)
		(layer "B.Cu")
		(net "PHY_DRV_A_TO_SCC_A_35_DP")
	)
	(arc
		(start 482.312218 -47.896018)
		(mid 482.437223 -47.947797)
		(end 482.489002 -48.072802)
		(width 0.127)
		(layer "B.Cu")
		(net "PHY_DRV_A_TO_SCC_A_35_DP")
	)
	(arc
		(start 286.863536 -303.70526)
		(mid 286.953339 -303.742457)
		(end 286.990536 -303.83226)
		(width 0.127)
		(layer "B.Cu")
		(net "PHY_DRV_A_TO_SCC_A_35_DP")
	)
	(arc
		(start 287.16859 -304.51298)
		(mid 287.432544 -304.689349)
		(end 287.7439 -304.751232)
		(width 0.127)
		(layer "B.Cu")
		(net "PHY_DRV_A_TO_SCC_A_35_DP")
	)
	(arc
		(start 286.990536 -304.082704)
		(mid 287.036744 -304.31557)
		(end 287.16859 -304.51298)
		(width 0.127)
		(layer "B.Cu")
		(net "PHY_DRV_A_TO_SCC_A_35_DP")
	)
	(segment
		(start 483.663498 -47.476918)
		(end 483.663498 -47.241968)
		(width 0.127)
		(layer "F.Cu")
		(net "PHY_DRV_A_TO_SCC_A_35_DN")
	)
	(segment
		(start 483.790498 -47.114968)
		(end 485.125014 -47.114968)
		(width 0.127)
		(layer "F.Cu")
		(net "PHY_DRV_A_TO_SCC_A_35_DN")
	)
	(segment
		(start 482.644704 -47.603918)
		(end 483.536498 -47.603918)
		(width 0.127)
		(layer "F.Cu")
		(net "PHY_DRV_A_TO_SCC_A_35_DN")
	)
	(segment
		(start 483.536498 -47.603918)
		(end 483.663498 -47.476918)
		(width 0.127)
		(layer "F.Cu")
		(net "PHY_DRV_A_TO_SCC_A_35_DN")
	)
	(segment
		(start 483.663498 -47.241968)
		(end 483.790498 -47.114968)
		(width 0.127)
		(layer "F.Cu")
		(net "PHY_DRV_A_TO_SCC_A_35_DN")
	)
	(segment
		(start 482.489002 -47.178468)
		(end 482.489002 -47.448216)
		(width 0.127)
		(layer "F.Cu")
		(net "PHY_DRV_A_TO_SCC_A_35_DN")
	)
	(arc
		(start 482.489002 -47.448216)
		(mid 482.534606 -47.558314)
		(end 482.644704 -47.603918)
		(width 0.127)
		(layer "F.Cu")
		(net "PHY_DRV_A_TO_SCC_A_35_DN")
	)
	(segment
		(start 297.698414 -297.526202)
		(end 297.473878 -297.575986)
		(width 0.127)
		(layer "B.Cu")
		(net "PHY_DRV_A_TO_SCC_A_35_DN")
	)
	(segment
		(start 482.312218 -47.603918)
		(end 480.960176 -47.603918)
		(width 0.127)
		(layer "B.Cu")
		(net "PHY_DRV_A_TO_SCC_A_35_DN")
	)
	(segment
		(start 296.889678 -298.492672)
		(end 296.684954 -298.813982)
		(width 0.127)
		(layer "B.Cu")
		(net "PHY_DRV_A_TO_SCC_A_35_DN")
	)
	(segment
		(start 289.88258 -304.101754)
		(end 288.27095 -304.459132)
		(width 0.127)
		(layer "B.Cu")
		(net "PHY_DRV_A_TO_SCC_A_35_DN")
	)
	(segment
		(start 287.409636 -303.70526)
		(end 287.83661 -303.70526)
		(width 0.127)
		(layer "B.Cu")
		(net "PHY_DRV_A_TO_SCC_A_35_DN")
	)
	(segment
		(start 295.946068 -300.276768)
		(end 289.88258 -304.101754)
		(width 0.127)
		(layer "B.Cu")
		(net "PHY_DRV_A_TO_SCC_A_35_DN")
	)
	(segment
		(start 297.269154 -297.897296)
		(end 297.318938 -298.121578)
		(width 0.127)
		(layer "B.Cu")
		(net "PHY_DRV_A_TO_SCC_A_35_DN")
	)
	(segment
		(start 288.27095 -304.459132)
		(end 287.7439 -304.459132)
		(width 0.127)
		(layer "B.Cu")
		(net "PHY_DRV_A_TO_SCC_A_35_DN")
	)
	(segment
		(start 418.981636 -66.830956)
		(end 354.975922 -108.307378)
		(width 0.127)
		(layer "B.Cu")
		(net "PHY_DRV_A_TO_SCC_A_35_DN")
	)
	(segment
		(start 296.150792 -299.955458)
		(end 295.946068 -300.276768)
		(width 0.127)
		(layer "B.Cu")
		(net "PHY_DRV_A_TO_SCC_A_35_DN")
	)
	(segment
		(start 463.624422 -49.286922)
		(end 430.959514 -64.285114)
		(width 0.127)
		(layer "B.Cu")
		(net "PHY_DRV_A_TO_SCC_A_35_DN")
	)
	(segment
		(start 296.305732 -299.409612)
		(end 296.101008 -299.730922)
		(width 0.127)
		(layer "B.Cu")
		(net "PHY_DRV_A_TO_SCC_A_35_DN")
	)
	(segment
		(start 430.959514 -64.285622)
		(end 418.981636 -66.830956)
		(width 0.127)
		(layer "B.Cu")
		(net "PHY_DRV_A_TO_SCC_A_35_DN")
	)
	(segment
		(start 308.334156 -217.016838)
		(end 308.349142 -217.084402)
		(width 0.127)
		(layer "B.Cu")
		(net "PHY_DRV_A_TO_SCC_A_35_DN")
	)
	(segment
		(start 308.349142 -217.084402)
		(end 314.864496 -246.47652)
		(width 0.127)
		(layer "B.Cu")
		(net "PHY_DRV_A_TO_SCC_A_35_DN")
	)
	(segment
		(start 306.726336 -283.35351)
		(end 297.698414 -297.526202)
		(width 0.127)
		(layer "B.Cu")
		(net "PHY_DRV_A_TO_SCC_A_35_DN")
	)
	(segment
		(start 296.530268 -299.359828)
		(end 296.305732 -299.409612)
		(width 0.127)
		(layer "B.Cu")
		(net "PHY_DRV_A_TO_SCC_A_35_DN")
	)
	(segment
		(start 297.318938 -298.121578)
		(end 297.114214 -298.442888)
		(width 0.127)
		(layer "B.Cu")
		(net "PHY_DRV_A_TO_SCC_A_35_DN")
	)
	(segment
		(start 308.350158 -216.95283)
		(end 308.334156 -217.016838)
		(width 0.127)
		(layer "B.Cu")
		(net "PHY_DRV_A_TO_SCC_A_35_DN")
	)
	(segment
		(start 480.960176 -47.603918)
		(end 463.624422 -49.286922)
		(width 0.127)
		(layer "B.Cu")
		(net "PHY_DRV_A_TO_SCC_A_35_DN")
	)
	(segment
		(start 297.114214 -298.442888)
		(end 296.889678 -298.492672)
		(width 0.127)
		(layer "B.Cu")
		(net "PHY_DRV_A_TO_SCC_A_35_DN")
	)
	(segment
		(start 296.684954 -298.813982)
		(end 296.734738 -299.038518)
		(width 0.127)
		(layer "B.Cu")
		(net "PHY_DRV_A_TO_SCC_A_35_DN")
	)
	(segment
		(start 482.489002 -47.178468)
		(end 482.489002 -47.427134)
		(width 0.127)
		(layer "B.Cu")
		(net "PHY_DRV_A_TO_SCC_A_35_DN")
	)
	(segment
		(start 314.864496 -246.47652)
		(end 306.726336 -283.35351)
		(width 0.127)
		(layer "B.Cu")
		(net "PHY_DRV_A_TO_SCC_A_35_DN")
	)
	(segment
		(start 321.72275 -156.642308)
		(end 308.350158 -216.95283)
		(width 0.127)
		(layer "B.Cu")
		(net "PHY_DRV_A_TO_SCC_A_35_DN")
	)
	(segment
		(start 354.975922 -108.307378)
		(end 321.72275 -156.642308)
		(width 0.127)
		(layer "B.Cu")
		(net "PHY_DRV_A_TO_SCC_A_35_DN")
	)
	(segment
		(start 296.734738 -299.038518)
		(end 296.530268 -299.359828)
		(width 0.127)
		(layer "B.Cu")
		(net "PHY_DRV_A_TO_SCC_A_35_DN")
	)
	(segment
		(start 296.101008 -299.730922)
		(end 296.150792 -299.955458)
		(width 0.127)
		(layer "B.Cu")
		(net "PHY_DRV_A_TO_SCC_A_35_DN")
	)
	(segment
		(start 297.473878 -297.575986)
		(end 297.269154 -297.897296)
		(width 0.127)
		(layer "B.Cu")
		(net "PHY_DRV_A_TO_SCC_A_35_DN")
	)
	(segment
		(start 287.282636 -304.082704)
		(end 287.282636 -303.83226)
		(width 0.127)
		(layer "B.Cu")
		(net "PHY_DRV_A_TO_SCC_A_35_DN")
	)
	(segment
		(start 430.959514 -64.285114)
		(end 430.959514 -64.285622)
		(width 0.127)
		(layer "B.Cu")
		(net "PHY_DRV_A_TO_SCC_A_35_DN")
	)
	(arc
		(start 287.282636 -303.83226)
		(mid 287.319833 -303.742457)
		(end 287.409636 -303.70526)
		(width 0.127)
		(layer "B.Cu")
		(net "PHY_DRV_A_TO_SCC_A_35_DN")
	)
	(arc
		(start 287.375346 -304.306478)
		(mid 287.306745 -304.20381)
		(end 287.282636 -304.082704)
		(width 0.127)
		(layer "B.Cu")
		(net "PHY_DRV_A_TO_SCC_A_35_DN")
	)
	(arc
		(start 482.489002 -47.427134)
		(mid 482.437223 -47.552139)
		(end 482.312218 -47.603918)
		(width 0.127)
		(layer "B.Cu")
		(net "PHY_DRV_A_TO_SCC_A_35_DN")
	)
	(arc
		(start 287.7439 -304.459132)
		(mid 287.544442 -304.419457)
		(end 287.375346 -304.306478)
		(width 0.127)
		(layer "B.Cu")
		(net "PHY_DRV_A_TO_SCC_A_35_DN")
	)
	(segment
		(start 451.972172 -47.896018)
		(end 452.113396 -48.037242)
		(width 0.127)
		(layer "F.Cu")
		(net "PHY_DRV_A_TO_SCC_A_34_DP")
	)
	(segment
		(start 452.113396 -48.037242)
		(end 452.113396 -48.202088)
		(width 0.127)
		(layer "F.Cu")
		(net "PHY_DRV_A_TO_SCC_A_34_DP")
	)
	(segment
		(start 452.296276 -48.384968)
		(end 453.574912 -48.384968)
		(width 0.127)
		(layer "F.Cu")
		(net "PHY_DRV_A_TO_SCC_A_34_DP")
	)
	(segment
		(start 452.113396 -48.202088)
		(end 452.296276 -48.384968)
		(width 0.127)
		(layer "F.Cu")
		(net "PHY_DRV_A_TO_SCC_A_34_DP")
	)
	(segment
		(start 451.09892 -47.896018)
		(end 451.972172 -47.896018)
		(width 0.127)
		(layer "F.Cu")
		(net "PHY_DRV_A_TO_SCC_A_34_DP")
	)
	(segment
		(start 450.9389 -48.321468)
		(end 450.9389 -48.056038)
		(width 0.127)
		(layer "F.Cu")
		(net "PHY_DRV_A_TO_SCC_A_34_DP")
	)
	(arc
		(start 450.9389 -48.056038)
		(mid 450.985769 -47.942887)
		(end 451.09892 -47.896018)
		(width 0.127)
		(layer "F.Cu")
		(net "PHY_DRV_A_TO_SCC_A_34_DP")
	)
	(segment
		(start 286.743902 -302.951134)
		(end 288.093404 -302.951134)
		(width 0.127)
		(layer "B.Cu")
		(net "PHY_DRV_A_TO_SCC_A_34_DP")
	)
	(segment
		(start 313.544712 -246.638318)
		(end 306.602384 -215.34247)
		(width 0.127)
		(layer "B.Cu")
		(net "PHY_DRV_A_TO_SCC_A_34_DP")
	)
	(segment
		(start 285.436564 -301.905162)
		(end 285.863538 -301.905162)
		(width 0.127)
		(layer "B.Cu")
		(net "PHY_DRV_A_TO_SCC_A_34_DP")
	)
	(segment
		(start 449.49745 -48.116236)
		(end 450.326252 -47.896018)
		(width 0.127)
		(layer "B.Cu")
		(net "PHY_DRV_A_TO_SCC_A_34_DP")
	)
	(segment
		(start 306.602384 -215.34247)
		(end 319.5701 -156.92374)
		(width 0.127)
		(layer "B.Cu")
		(net "PHY_DRV_A_TO_SCC_A_34_DP")
	)
	(segment
		(start 294.79621 -299.444156)
		(end 305.593496 -282.489402)
		(width 0.127)
		(layer "B.Cu")
		(net "PHY_DRV_A_TO_SCC_A_34_DP")
	)
	(segment
		(start 450.9389 -48.072802)
		(end 450.9389 -48.321468)
		(width 0.127)
		(layer "B.Cu")
		(net "PHY_DRV_A_TO_SCC_A_34_DP")
	)
	(segment
		(start 429.396398 -62.493398)
		(end 449.49745 -48.116236)
		(width 0.127)
		(layer "B.Cu")
		(net "PHY_DRV_A_TO_SCC_A_34_DP")
	)
	(segment
		(start 418.625274 -64.783208)
		(end 429.396398 -62.493398)
		(width 0.127)
		(layer "B.Cu")
		(net "PHY_DRV_A_TO_SCC_A_34_DP")
	)
	(segment
		(start 450.326252 -47.896018)
		(end 450.762116 -47.896018)
		(width 0.127)
		(layer "B.Cu")
		(net "PHY_DRV_A_TO_SCC_A_34_DP")
	)
	(segment
		(start 288.093404 -302.951134)
		(end 289.93084 -302.54321)
		(width 0.127)
		(layer "B.Cu")
		(net "PHY_DRV_A_TO_SCC_A_34_DP")
	)
	(segment
		(start 289.93084 -302.54321)
		(end 294.79621 -299.444156)
		(width 0.127)
		(layer "B.Cu")
		(net "PHY_DRV_A_TO_SCC_A_34_DP")
	)
	(segment
		(start 319.5701 -156.92374)
		(end 354.148136 -106.652314)
		(width 0.127)
		(layer "B.Cu")
		(net "PHY_DRV_A_TO_SCC_A_34_DP")
	)
	(segment
		(start 354.148136 -106.652314)
		(end 418.625274 -64.783208)
		(width 0.127)
		(layer "B.Cu")
		(net "PHY_DRV_A_TO_SCC_A_34_DP")
	)
	(segment
		(start 305.593496 -282.489402)
		(end 313.544712 -246.638318)
		(width 0.127)
		(layer "B.Cu")
		(net "PHY_DRV_A_TO_SCC_A_34_DP")
	)
	(segment
		(start 285.990538 -302.032162)
		(end 285.990538 -302.282606)
		(width 0.127)
		(layer "B.Cu")
		(net "PHY_DRV_A_TO_SCC_A_34_DP")
	)
	(arc
		(start 285.863538 -301.905162)
		(mid 285.953341 -301.942359)
		(end 285.990538 -302.032162)
		(width 0.127)
		(layer "B.Cu")
		(net "PHY_DRV_A_TO_SCC_A_34_DP")
	)
	(arc
		(start 286.168592 -302.712882)
		(mid 286.432546 -302.889251)
		(end 286.743902 -302.951134)
		(width 0.127)
		(layer "B.Cu")
		(net "PHY_DRV_A_TO_SCC_A_34_DP")
	)
	(arc
		(start 450.762116 -47.896018)
		(mid 450.887121 -47.947797)
		(end 450.9389 -48.072802)
		(width 0.127)
		(layer "B.Cu")
		(net "PHY_DRV_A_TO_SCC_A_34_DP")
	)
	(arc
		(start 285.990538 -302.282606)
		(mid 286.036746 -302.515472)
		(end 286.168592 -302.712882)
		(width 0.127)
		(layer "B.Cu")
		(net "PHY_DRV_A_TO_SCC_A_34_DP")
	)
	(segment
		(start 452.113396 -47.476918)
		(end 452.113396 -47.241968)
		(width 0.127)
		(layer "F.Cu")
		(net "PHY_DRV_A_TO_SCC_A_34_DN")
	)
	(segment
		(start 452.113396 -47.241968)
		(end 452.240396 -47.114968)
		(width 0.127)
		(layer "F.Cu")
		(net "PHY_DRV_A_TO_SCC_A_34_DN")
	)
	(segment
		(start 450.9389 -47.178468)
		(end 450.9389 -47.443898)
		(width 0.127)
		(layer "F.Cu")
		(net "PHY_DRV_A_TO_SCC_A_34_DN")
	)
	(segment
		(start 451.986396 -47.603918)
		(end 452.113396 -47.476918)
		(width 0.127)
		(layer "F.Cu")
		(net "PHY_DRV_A_TO_SCC_A_34_DN")
	)
	(segment
		(start 451.09892 -47.603918)
		(end 451.986396 -47.603918)
		(width 0.127)
		(layer "F.Cu")
		(net "PHY_DRV_A_TO_SCC_A_34_DN")
	)
	(segment
		(start 452.240396 -47.114968)
		(end 453.574912 -47.114968)
		(width 0.127)
		(layer "F.Cu")
		(net "PHY_DRV_A_TO_SCC_A_34_DN")
	)
	(arc
		(start 450.9389 -47.443898)
		(mid 450.985769 -47.557049)
		(end 451.09892 -47.603918)
		(width 0.127)
		(layer "F.Cu")
		(net "PHY_DRV_A_TO_SCC_A_34_DN")
	)
	(segment
		(start 306.303172 -215.34247)
		(end 319.29705 -156.804868)
		(width 0.127)
		(layer "B.Cu")
		(net "PHY_DRV_A_TO_SCC_A_34_DN")
	)
	(segment
		(start 288.061146 -302.659034)
		(end 289.817302 -302.269144)
		(width 0.127)
		(layer "B.Cu")
		(net "PHY_DRV_A_TO_SCC_A_34_DN")
	)
	(segment
		(start 295.768014 -297.071542)
		(end 295.972738 -296.750232)
		(width 0.127)
		(layer "B.Cu")
		(net "PHY_DRV_A_TO_SCC_A_34_DN")
	)
	(segment
		(start 296.780966 -295.783508)
		(end 305.31943 -282.375864)
		(width 0.127)
		(layer "B.Cu")
		(net "PHY_DRV_A_TO_SCC_A_34_DN")
	)
	(segment
		(start 295.184068 -297.988482)
		(end 295.388792 -297.667172)
		(width 0.127)
		(layer "B.Cu")
		(net "PHY_DRV_A_TO_SCC_A_34_DN")
	)
	(segment
		(start 296.401744 -296.379138)
		(end 296.35196 -296.154602)
		(width 0.127)
		(layer "B.Cu")
		(net "PHY_DRV_A_TO_SCC_A_34_DN")
	)
	(segment
		(start 286.743902 -302.659034)
		(end 288.061146 -302.659034)
		(width 0.127)
		(layer "B.Cu")
		(net "PHY_DRV_A_TO_SCC_A_34_DN")
	)
	(segment
		(start 313.2455 -246.638318)
		(end 306.303172 -215.34247)
		(width 0.127)
		(layer "B.Cu")
		(net "PHY_DRV_A_TO_SCC_A_34_DN")
	)
	(segment
		(start 305.31943 -282.375864)
		(end 313.2455 -246.638318)
		(width 0.127)
		(layer "B.Cu")
		(net "PHY_DRV_A_TO_SCC_A_34_DN")
	)
	(segment
		(start 295.613074 -297.617388)
		(end 295.817798 -297.296078)
		(width 0.127)
		(layer "B.Cu")
		(net "PHY_DRV_A_TO_SCC_A_34_DN")
	)
	(segment
		(start 289.817302 -302.269144)
		(end 294.584628 -299.232574)
		(width 0.127)
		(layer "B.Cu")
		(net "PHY_DRV_A_TO_SCC_A_34_DN")
	)
	(segment
		(start 421.229028 -63.931038)
		(end 429.276002 -62.220348)
		(width 0.127)
		(layer "B.Cu")
		(net "PHY_DRV_A_TO_SCC_A_34_DN")
	)
	(segment
		(start 296.556684 -295.833292)
		(end 296.780966 -295.783508)
		(width 0.127)
		(layer "B.Cu")
		(net "PHY_DRV_A_TO_SCC_A_34_DN")
	)
	(segment
		(start 450.9389 -47.427134)
		(end 450.9389 -47.178468)
		(width 0.127)
		(layer "B.Cu")
		(net "PHY_DRV_A_TO_SCC_A_34_DN")
	)
	(segment
		(start 296.19702 -296.700448)
		(end 296.401744 -296.379138)
		(width 0.127)
		(layer "B.Cu")
		(net "PHY_DRV_A_TO_SCC_A_34_DN")
	)
	(segment
		(start 449.371466 -47.846996)
		(end 450.287898 -47.603918)
		(width 0.127)
		(layer "B.Cu")
		(net "PHY_DRV_A_TO_SCC_A_34_DN")
	)
	(segment
		(start 450.287898 -47.603918)
		(end 450.762116 -47.603918)
		(width 0.127)
		(layer "B.Cu")
		(net "PHY_DRV_A_TO_SCC_A_34_DN")
	)
	(segment
		(start 286.836612 -301.905162)
		(end 286.409638 -301.905162)
		(width 0.127)
		(layer "B.Cu")
		(net "PHY_DRV_A_TO_SCC_A_34_DN")
	)
	(segment
		(start 295.388792 -297.667172)
		(end 295.613074 -297.617388)
		(width 0.127)
		(layer "B.Cu")
		(net "PHY_DRV_A_TO_SCC_A_34_DN")
	)
	(segment
		(start 294.584628 -299.232574)
		(end 295.233852 -298.213018)
		(width 0.127)
		(layer "B.Cu")
		(net "PHY_DRV_A_TO_SCC_A_34_DN")
	)
	(segment
		(start 429.276002 -62.220348)
		(end 449.371466 -47.846996)
		(width 0.127)
		(layer "B.Cu")
		(net "PHY_DRV_A_TO_SCC_A_34_DN")
	)
	(segment
		(start 418.511482 -64.508634)
		(end 421.229028 -63.931038)
		(width 0.127)
		(layer "B.Cu")
		(net "PHY_DRV_A_TO_SCC_A_34_DN")
	)
	(segment
		(start 286.282638 -302.032162)
		(end 286.282638 -302.282606)
		(width 0.127)
		(layer "B.Cu")
		(net "PHY_DRV_A_TO_SCC_A_34_DN")
	)
	(segment
		(start 295.233852 -298.213018)
		(end 295.184068 -297.988482)
		(width 0.127)
		(layer "B.Cu")
		(net "PHY_DRV_A_TO_SCC_A_34_DN")
	)
	(segment
		(start 295.972738 -296.750232)
		(end 296.19702 -296.700448)
		(width 0.127)
		(layer "B.Cu")
		(net "PHY_DRV_A_TO_SCC_A_34_DN")
	)
	(segment
		(start 319.29705 -156.804868)
		(end 353.94011 -106.4387)
		(width 0.127)
		(layer "B.Cu")
		(net "PHY_DRV_A_TO_SCC_A_34_DN")
	)
	(segment
		(start 295.817798 -297.296078)
		(end 295.768014 -297.071542)
		(width 0.127)
		(layer "B.Cu")
		(net "PHY_DRV_A_TO_SCC_A_34_DN")
	)
	(segment
		(start 353.94011 -106.4387)
		(end 418.511482 -64.508634)
		(width 0.127)
		(layer "B.Cu")
		(net "PHY_DRV_A_TO_SCC_A_34_DN")
	)
	(segment
		(start 296.35196 -296.154602)
		(end 296.556684 -295.833292)
		(width 0.127)
		(layer "B.Cu")
		(net "PHY_DRV_A_TO_SCC_A_34_DN")
	)
	(arc
		(start 450.762116 -47.603918)
		(mid 450.887121 -47.552139)
		(end 450.9389 -47.427134)
		(width 0.127)
		(layer "B.Cu")
		(net "PHY_DRV_A_TO_SCC_A_34_DN")
	)
	(arc
		(start 286.409638 -301.905162)
		(mid 286.319835 -301.942359)
		(end 286.282638 -302.032162)
		(width 0.127)
		(layer "B.Cu")
		(net "PHY_DRV_A_TO_SCC_A_34_DN")
	)
	(arc
		(start 286.282638 -302.282606)
		(mid 286.306729 -302.403719)
		(end 286.375348 -302.50638)
		(width 0.127)
		(layer "B.Cu")
		(net "PHY_DRV_A_TO_SCC_A_34_DN")
	)
	(arc
		(start 286.375348 -302.50638)
		(mid 286.544442 -302.619365)
		(end 286.743902 -302.659034)
		(width 0.127)
		(layer "B.Cu")
		(net "PHY_DRV_A_TO_SCC_A_34_DN")
	)
	(segment
		(start 420.718996 -48.384968)
		(end 422.025064 -48.384968)
		(width 0.127)
		(layer "F.Cu")
		(net "PHY_DRV_A_TO_SCC_A_33_DP")
	)
	(segment
		(start 419.389052 -48.321468)
		(end 419.389052 -48.023272)
		(width 0.127)
		(layer "F.Cu")
		(net "PHY_DRV_A_TO_SCC_A_33_DP")
	)
	(segment
		(start 420.563548 -48.041306)
		(end 420.563548 -48.22952)
		(width 0.127)
		(layer "F.Cu")
		(net "PHY_DRV_A_TO_SCC_A_33_DP")
	)
	(segment
		(start 419.516306 -47.896018)
		(end 420.41826 -47.896018)
		(width 0.127)
		(layer "F.Cu")
		(net "PHY_DRV_A_TO_SCC_A_33_DP")
	)
	(segment
		(start 420.563548 -48.22952)
		(end 420.718996 -48.384968)
		(width 0.127)
		(layer "F.Cu")
		(net "PHY_DRV_A_TO_SCC_A_33_DP")
	)
	(segment
		(start 420.41826 -47.896018)
		(end 420.563548 -48.041306)
		(width 0.127)
		(layer "F.Cu")
		(net "PHY_DRV_A_TO_SCC_A_33_DP")
	)
	(arc
		(start 419.389052 -48.023272)
		(mid 419.426324 -47.93329)
		(end 419.516306 -47.896018)
		(width 0.127)
		(layer "F.Cu")
		(net "PHY_DRV_A_TO_SCC_A_33_DP")
	)
	(segment
		(start 418.699188 -47.896018)
		(end 419.212268 -47.896018)
		(width 0.127)
		(layer "B.Cu")
		(net "PHY_DRV_A_TO_SCC_A_33_DP")
	)
	(segment
		(start 289.437572 -300.975268)
		(end 293.270178 -298.532804)
		(width 0.127)
		(layer "B.Cu")
		(net "PHY_DRV_A_TO_SCC_A_33_DP")
	)
	(segment
		(start 418.21481 -48.024542)
		(end 418.699188 -47.896018)
		(width 0.127)
		(layer "B.Cu")
		(net "PHY_DRV_A_TO_SCC_A_33_DP")
	)
	(segment
		(start 289.178238 -301.032926)
		(end 289.437572 -300.975268)
		(width 0.127)
		(layer "B.Cu")
		(net "PHY_DRV_A_TO_SCC_A_33_DP")
	)
	(segment
		(start 304.841402 -215.787478)
		(end 304.84191 -215.786716)
		(width 0.127)
		(layer "B.Cu")
		(net "PHY_DRV_A_TO_SCC_A_33_DP")
	)
	(segment
		(start 304.29327 -281.231594)
		(end 311.82183 -247.263666)
		(width 0.127)
		(layer "B.Cu")
		(net "PHY_DRV_A_TO_SCC_A_33_DP")
	)
	(segment
		(start 286.436562 -300.105064)
		(end 286.863536 -300.105064)
		(width 0.127)
		(layer "B.Cu")
		(net "PHY_DRV_A_TO_SCC_A_33_DP")
	)
	(segment
		(start 419.389052 -48.072802)
		(end 419.389052 -48.321468)
		(width 0.127)
		(layer "B.Cu")
		(net "PHY_DRV_A_TO_SCC_A_33_DP")
	)
	(segment
		(start 304.84191 -215.786716)
		(end 304.853086 -215.736424)
		(width 0.127)
		(layer "B.Cu")
		(net "PHY_DRV_A_TO_SCC_A_33_DP")
	)
	(segment
		(start 288.644076 -301.151036)
		(end 289.178238 -301.032926)
		(width 0.127)
		(layer "B.Cu")
		(net "PHY_DRV_A_TO_SCC_A_33_DP")
	)
	(segment
		(start 417.800536 -48.13427)
		(end 418.21481 -48.024542)
		(width 0.127)
		(layer "B.Cu")
		(net "PHY_DRV_A_TO_SCC_A_33_DP")
	)
	(segment
		(start 304.853086 -215.73617)
		(end 318.120014 -155.898596)
		(width 0.127)
		(layer "B.Cu")
		(net "PHY_DRV_A_TO_SCC_A_33_DP")
	)
	(segment
		(start 367.503202 -84.107274)
		(end 417.800536 -48.13427)
		(width 0.127)
		(layer "B.Cu")
		(net "PHY_DRV_A_TO_SCC_A_33_DP")
	)
	(segment
		(start 286.990536 -300.232064)
		(end 286.990536 -300.482508)
		(width 0.127)
		(layer "B.Cu")
		(net "PHY_DRV_A_TO_SCC_A_33_DP")
	)
	(segment
		(start 293.270178 -298.532804)
		(end 304.29327 -281.231594)
		(width 0.127)
		(layer "B.Cu")
		(net "PHY_DRV_A_TO_SCC_A_33_DP")
	)
	(segment
		(start 318.120014 -155.898596)
		(end 367.503202 -84.107274)
		(width 0.127)
		(layer "B.Cu")
		(net "PHY_DRV_A_TO_SCC_A_33_DP")
	)
	(segment
		(start 287.7439 -301.151036)
		(end 288.644076 -301.151036)
		(width 0.127)
		(layer "B.Cu")
		(net "PHY_DRV_A_TO_SCC_A_33_DP")
	)
	(segment
		(start 304.853086 -215.736424)
		(end 304.853086 -215.73617)
		(width 0.127)
		(layer "B.Cu")
		(net "PHY_DRV_A_TO_SCC_A_33_DP")
	)
	(segment
		(start 311.82183 -247.263666)
		(end 304.841402 -215.787478)
		(width 0.127)
		(layer "B.Cu")
		(net "PHY_DRV_A_TO_SCC_A_33_DP")
	)
	(arc
		(start 419.212268 -47.896018)
		(mid 419.337273 -47.947797)
		(end 419.389052 -48.072802)
		(width 0.127)
		(layer "B.Cu")
		(net "PHY_DRV_A_TO_SCC_A_33_DP")
	)
	(arc
		(start 286.990536 -300.482508)
		(mid 287.036744 -300.715374)
		(end 287.16859 -300.912784)
		(width 0.127)
		(layer "B.Cu")
		(net "PHY_DRV_A_TO_SCC_A_33_DP")
	)
	(arc
		(start 286.863536 -300.105064)
		(mid 286.953339 -300.142261)
		(end 286.990536 -300.232064)
		(width 0.127)
		(layer "B.Cu")
		(net "PHY_DRV_A_TO_SCC_A_33_DP")
	)
	(arc
		(start 287.16859 -300.912784)
		(mid 287.432544 -301.089153)
		(end 287.7439 -301.151036)
		(width 0.127)
		(layer "B.Cu")
		(net "PHY_DRV_A_TO_SCC_A_33_DP")
	)
	(segment
		(start 420.563548 -47.476918)
		(end 420.563548 -47.241968)
		(width 0.127)
		(layer "F.Cu")
		(net "PHY_DRV_A_TO_SCC_A_33_DN")
	)
	(segment
		(start 420.436548 -47.603918)
		(end 420.563548 -47.476918)
		(width 0.127)
		(layer "F.Cu")
		(net "PHY_DRV_A_TO_SCC_A_33_DN")
	)
	(segment
		(start 420.563548 -47.241968)
		(end 420.690548 -47.114968)
		(width 0.127)
		(layer "F.Cu")
		(net "PHY_DRV_A_TO_SCC_A_33_DN")
	)
	(segment
		(start 419.389052 -47.178468)
		(end 419.389052 -47.476664)
		(width 0.127)
		(layer "F.Cu")
		(net "PHY_DRV_A_TO_SCC_A_33_DN")
	)
	(segment
		(start 420.690548 -47.114968)
		(end 422.025064 -47.114968)
		(width 0.127)
		(layer "F.Cu")
		(net "PHY_DRV_A_TO_SCC_A_33_DN")
	)
	(segment
		(start 419.516306 -47.603918)
		(end 420.436548 -47.603918)
		(width 0.127)
		(layer "F.Cu")
		(net "PHY_DRV_A_TO_SCC_A_33_DN")
	)
	(arc
		(start 419.389052 -47.476664)
		(mid 419.426324 -47.566646)
		(end 419.516306 -47.603918)
		(width 0.127)
		(layer "F.Cu")
		(net "PHY_DRV_A_TO_SCC_A_33_DN")
	)
	(segment
		(start 293.638478 -297.108626)
		(end 293.688008 -297.333162)
		(width 0.127)
		(layer "B.Cu")
		(net "PHY_DRV_A_TO_SCC_A_33_DN")
	)
	(segment
		(start 287.282636 -300.482508)
		(end 287.282636 -300.232064)
		(width 0.127)
		(layer "B.Cu")
		(net "PHY_DRV_A_TO_SCC_A_33_DN")
	)
	(segment
		(start 293.058596 -298.321222)
		(end 289.32378 -300.701202)
		(width 0.127)
		(layer "B.Cu")
		(net "PHY_DRV_A_TO_SCC_A_33_DN")
	)
	(segment
		(start 293.688008 -297.333162)
		(end 293.058596 -298.321222)
		(width 0.127)
		(layer "B.Cu")
		(net "PHY_DRV_A_TO_SCC_A_33_DN")
	)
	(segment
		(start 295.235884 -294.903906)
		(end 295.011348 -294.95369)
		(width 0.127)
		(layer "B.Cu")
		(net "PHY_DRV_A_TO_SCC_A_33_DN")
	)
	(segment
		(start 293.843202 -296.787316)
		(end 293.638478 -297.108626)
		(width 0.127)
		(layer "B.Cu")
		(net "PHY_DRV_A_TO_SCC_A_33_DN")
	)
	(segment
		(start 289.219132 -300.72457)
		(end 288.612072 -300.858936)
		(width 0.127)
		(layer "B.Cu")
		(net "PHY_DRV_A_TO_SCC_A_33_DN")
	)
	(segment
		(start 418.661088 -47.603918)
		(end 418.288978 -47.70247)
		(width 0.127)
		(layer "B.Cu")
		(net "PHY_DRV_A_TO_SCC_A_33_DN")
	)
	(segment
		(start 294.222424 -296.19194)
		(end 294.272208 -296.416222)
		(width 0.127)
		(layer "B.Cu")
		(net "PHY_DRV_A_TO_SCC_A_33_DN")
	)
	(segment
		(start 311.522618 -247.263666)
		(end 304.019204 -281.118056)
		(width 0.127)
		(layer "B.Cu")
		(net "PHY_DRV_A_TO_SCC_A_33_DN")
	)
	(segment
		(start 419.212268 -47.603918)
		(end 418.661088 -47.603918)
		(width 0.127)
		(layer "B.Cu")
		(net "PHY_DRV_A_TO_SCC_A_33_DN")
	)
	(segment
		(start 294.651684 -295.820846)
		(end 294.427148 -295.87063)
		(width 0.127)
		(layer "B.Cu")
		(net "PHY_DRV_A_TO_SCC_A_33_DN")
	)
	(segment
		(start 417.674044 -47.865538)
		(end 367.291366 -83.899248)
		(width 0.127)
		(layer "B.Cu")
		(net "PHY_DRV_A_TO_SCC_A_33_DN")
	)
	(segment
		(start 304.019204 -281.118056)
		(end 295.235884 -294.903906)
		(width 0.127)
		(layer "B.Cu")
		(net "PHY_DRV_A_TO_SCC_A_33_DN")
	)
	(segment
		(start 294.806624 -295.275)
		(end 294.856408 -295.499536)
		(width 0.127)
		(layer "B.Cu")
		(net "PHY_DRV_A_TO_SCC_A_33_DN")
	)
	(segment
		(start 294.067484 -296.737532)
		(end 293.843202 -296.787316)
		(width 0.127)
		(layer "B.Cu")
		(net "PHY_DRV_A_TO_SCC_A_33_DN")
	)
	(segment
		(start 294.856408 -295.499536)
		(end 294.651684 -295.820846)
		(width 0.127)
		(layer "B.Cu")
		(net "PHY_DRV_A_TO_SCC_A_33_DN")
	)
	(segment
		(start 287.409636 -300.105064)
		(end 287.83661 -300.105064)
		(width 0.127)
		(layer "B.Cu")
		(net "PHY_DRV_A_TO_SCC_A_33_DN")
	)
	(segment
		(start 419.389052 -47.178468)
		(end 419.389052 -47.427134)
		(width 0.127)
		(layer "B.Cu")
		(net "PHY_DRV_A_TO_SCC_A_33_DN")
	)
	(segment
		(start 294.272208 -296.416222)
		(end 294.067484 -296.737532)
		(width 0.127)
		(layer "B.Cu")
		(net "PHY_DRV_A_TO_SCC_A_33_DN")
	)
	(segment
		(start 317.846964 -155.779724)
		(end 304.567844 -215.673178)
		(width 0.127)
		(layer "B.Cu")
		(net "PHY_DRV_A_TO_SCC_A_33_DN")
	)
	(segment
		(start 367.291366 -83.899248)
		(end 317.846964 -155.779724)
		(width 0.127)
		(layer "B.Cu")
		(net "PHY_DRV_A_TO_SCC_A_33_DN")
	)
	(segment
		(start 304.529998 -215.732614)
		(end 311.522618 -247.263666)
		(width 0.127)
		(layer "B.Cu")
		(net "PHY_DRV_A_TO_SCC_A_33_DN")
	)
	(segment
		(start 295.011348 -294.95369)
		(end 294.806624 -295.275)
		(width 0.127)
		(layer "B.Cu")
		(net "PHY_DRV_A_TO_SCC_A_33_DN")
	)
	(segment
		(start 418.288978 -47.70247)
		(end 417.674044 -47.865538)
		(width 0.127)
		(layer "B.Cu")
		(net "PHY_DRV_A_TO_SCC_A_33_DN")
	)
	(segment
		(start 294.427148 -295.87063)
		(end 294.222424 -296.19194)
		(width 0.127)
		(layer "B.Cu")
		(net "PHY_DRV_A_TO_SCC_A_33_DN")
	)
	(segment
		(start 304.567844 -215.673178)
		(end 304.529998 -215.732614)
		(width 0.127)
		(layer "B.Cu")
		(net "PHY_DRV_A_TO_SCC_A_33_DN")
	)
	(segment
		(start 289.32378 -300.701202)
		(end 289.219132 -300.72457)
		(width 0.127)
		(layer "B.Cu")
		(net "PHY_DRV_A_TO_SCC_A_33_DN")
	)
	(segment
		(start 288.612072 -300.858936)
		(end 287.7439 -300.858936)
		(width 0.127)
		(layer "B.Cu")
		(net "PHY_DRV_A_TO_SCC_A_33_DN")
	)
	(arc
		(start 287.7439 -300.858936)
		(mid 287.544442 -300.819261)
		(end 287.375346 -300.706282)
		(width 0.127)
		(layer "B.Cu")
		(net "PHY_DRV_A_TO_SCC_A_33_DN")
	)
	(arc
		(start 287.375346 -300.706282)
		(mid 287.306745 -300.603614)
		(end 287.282636 -300.482508)
		(width 0.127)
		(layer "B.Cu")
		(net "PHY_DRV_A_TO_SCC_A_33_DN")
	)
	(arc
		(start 287.282636 -300.232064)
		(mid 287.319833 -300.142261)
		(end 287.409636 -300.105064)
		(width 0.127)
		(layer "B.Cu")
		(net "PHY_DRV_A_TO_SCC_A_33_DN")
	)
	(arc
		(start 419.389052 -47.427134)
		(mid 419.337273 -47.552139)
		(end 419.212268 -47.603918)
		(width 0.127)
		(layer "B.Cu")
		(net "PHY_DRV_A_TO_SCC_A_33_DN")
	)
	(segment
		(start 389.18515 -48.384968)
		(end 390.474962 -48.384968)
		(width 0.127)
		(layer "F.Cu")
		(net "PHY_DRV_A_TO_SCC_A_32_DP")
	)
	(segment
		(start 389.013446 -48.023018)
		(end 389.013446 -48.213264)
		(width 0.127)
		(layer "F.Cu")
		(net "PHY_DRV_A_TO_SCC_A_32_DP")
	)
	(segment
		(start 389.013446 -48.213264)
		(end 389.18515 -48.384968)
		(width 0.127)
		(layer "F.Cu")
		(net "PHY_DRV_A_TO_SCC_A_32_DP")
	)
	(segment
		(start 387.83895 -48.321468)
		(end 387.83895 -48.023272)
		(width 0.127)
		(layer "F.Cu")
		(net "PHY_DRV_A_TO_SCC_A_32_DP")
	)
	(segment
		(start 387.966204 -47.896018)
		(end 388.886446 -47.896018)
		(width 0.127)
		(layer "F.Cu")
		(net "PHY_DRV_A_TO_SCC_A_32_DP")
	)
	(segment
		(start 388.886446 -47.896018)
		(end 389.013446 -48.023018)
		(width 0.127)
		(layer "F.Cu")
		(net "PHY_DRV_A_TO_SCC_A_32_DP")
	)
	(arc
		(start 387.83895 -48.023272)
		(mid 387.876222 -47.93329)
		(end 387.966204 -47.896018)
		(width 0.127)
		(layer "F.Cu")
		(net "PHY_DRV_A_TO_SCC_A_32_DP")
	)
	(segment
		(start 316.328806 -155.672028)
		(end 303.067974 -215.500458)
		(width 0.127)
		(layer "B.Cu")
		(net "PHY_DRV_A_TO_SCC_A_32_DP")
	)
	(segment
		(start 285.863538 -298.30522)
		(end 285.436564 -298.30522)
		(width 0.127)
		(layer "B.Cu")
		(net "PHY_DRV_A_TO_SCC_A_32_DP")
	)
	(segment
		(start 387.662166 -47.896018)
		(end 387.115812 -47.896018)
		(width 0.127)
		(layer "B.Cu")
		(net "PHY_DRV_A_TO_SCC_A_32_DP")
	)
	(segment
		(start 387.115812 -47.896018)
		(end 386.984494 -48.027336)
		(width 0.127)
		(layer "B.Cu")
		(net "PHY_DRV_A_TO_SCC_A_32_DP")
	)
	(segment
		(start 288.586672 -299.214032)
		(end 287.965642 -299.351192)
		(width 0.127)
		(layer "B.Cu")
		(net "PHY_DRV_A_TO_SCC_A_32_DP")
	)
	(segment
		(start 287.965642 -299.351192)
		(end 286.743902 -299.351192)
		(width 0.127)
		(layer "B.Cu")
		(net "PHY_DRV_A_TO_SCC_A_32_DP")
	)
	(segment
		(start 291.728398 -297.21175)
		(end 288.586672 -299.214032)
		(width 0.127)
		(layer "B.Cu")
		(net "PHY_DRV_A_TO_SCC_A_32_DP")
	)
	(segment
		(start 387.83895 -48.321468)
		(end 387.83895 -48.072802)
		(width 0.127)
		(layer "B.Cu")
		(net "PHY_DRV_A_TO_SCC_A_32_DP")
	)
	(segment
		(start 381.746506 -60.21324)
		(end 316.328806 -155.672028)
		(width 0.127)
		(layer "B.Cu")
		(net "PHY_DRV_A_TO_SCC_A_32_DP")
	)
	(segment
		(start 303.139348 -279.300178)
		(end 291.728398 -297.21175)
		(width 0.127)
		(layer "B.Cu")
		(net "PHY_DRV_A_TO_SCC_A_32_DP")
	)
	(segment
		(start 303.067974 -215.500458)
		(end 310.175656 -247.568974)
		(width 0.127)
		(layer "B.Cu")
		(net "PHY_DRV_A_TO_SCC_A_32_DP")
	)
	(segment
		(start 381.776478 -60.201048)
		(end 381.746506 -60.21324)
		(width 0.127)
		(layer "B.Cu")
		(net "PHY_DRV_A_TO_SCC_A_32_DP")
	)
	(segment
		(start 310.175656 -247.568974)
		(end 303.139348 -279.300178)
		(width 0.127)
		(layer "B.Cu")
		(net "PHY_DRV_A_TO_SCC_A_32_DP")
	)
	(segment
		(start 285.990538 -298.682664)
		(end 285.990538 -298.43222)
		(width 0.127)
		(layer "B.Cu")
		(net "PHY_DRV_A_TO_SCC_A_32_DP")
	)
	(segment
		(start 386.984494 -48.027336)
		(end 381.776478 -60.201048)
		(width 0.127)
		(layer "B.Cu")
		(net "PHY_DRV_A_TO_SCC_A_32_DP")
	)
	(arc
		(start 387.83895 -48.072802)
		(mid 387.787171 -47.947797)
		(end 387.662166 -47.896018)
		(width 0.127)
		(layer "B.Cu")
		(net "PHY_DRV_A_TO_SCC_A_32_DP")
	)
	(arc
		(start 285.990538 -298.43222)
		(mid 285.953341 -298.342417)
		(end 285.863538 -298.30522)
		(width 0.127)
		(layer "B.Cu")
		(net "PHY_DRV_A_TO_SCC_A_32_DP")
	)
	(arc
		(start 286.168592 -299.11294)
		(mid 286.036822 -298.915498)
		(end 285.990538 -298.682664)
		(width 0.127)
		(layer "B.Cu")
		(net "PHY_DRV_A_TO_SCC_A_32_DP")
	)
	(arc
		(start 286.743902 -299.351192)
		(mid 286.432565 -299.289263)
		(end 286.168592 -299.11294)
		(width 0.127)
		(layer "B.Cu")
		(net "PHY_DRV_A_TO_SCC_A_32_DP")
	)
	(segment
		(start 389.013446 -47.241968)
		(end 389.140446 -47.114968)
		(width 0.127)
		(layer "F.Cu")
		(net "PHY_DRV_A_TO_SCC_A_32_DN")
	)
	(segment
		(start 387.83895 -47.178468)
		(end 387.83895 -47.476664)
		(width 0.127)
		(layer "F.Cu")
		(net "PHY_DRV_A_TO_SCC_A_32_DN")
	)
	(segment
		(start 389.140446 -47.114968)
		(end 390.474962 -47.114968)
		(width 0.127)
		(layer "F.Cu")
		(net "PHY_DRV_A_TO_SCC_A_32_DN")
	)
	(segment
		(start 387.966204 -47.603918)
		(end 388.886446 -47.603918)
		(width 0.127)
		(layer "F.Cu")
		(net "PHY_DRV_A_TO_SCC_A_32_DN")
	)
	(segment
		(start 388.886446 -47.603918)
		(end 389.013446 -47.476918)
		(width 0.127)
		(layer "F.Cu")
		(net "PHY_DRV_A_TO_SCC_A_32_DN")
	)
	(segment
		(start 389.013446 -47.476918)
		(end 389.013446 -47.241968)
		(width 0.127)
		(layer "F.Cu")
		(net "PHY_DRV_A_TO_SCC_A_32_DN")
	)
	(arc
		(start 387.83895 -47.476664)
		(mid 387.876222 -47.566646)
		(end 387.966204 -47.603918)
		(width 0.127)
		(layer "F.Cu")
		(net "PHY_DRV_A_TO_SCC_A_32_DN")
	)
	(segment
		(start 384.255264 -53.664104)
		(end 384.25501 -53.664104)
		(width 0.127)
		(layer "B.Cu")
		(net "PHY_DRV_A_TO_SCC_A_32_DN")
	)
	(segment
		(start 291.516562 -297.000168)
		(end 291.516816 -297.000168)
		(width 0.127)
		(layer "B.Cu")
		(net "PHY_DRV_A_TO_SCC_A_32_DN")
	)
	(segment
		(start 292.564312 -295.355518)
		(end 292.359588 -295.676828)
		(width 0.127)
		(layer "B.Cu")
		(net "PHY_DRV_A_TO_SCC_A_32_DN")
	)
	(segment
		(start 286.282638 -298.682664)
		(end 286.282638 -298.43222)
		(width 0.127)
		(layer "B.Cu")
		(net "PHY_DRV_A_TO_SCC_A_32_DN")
	)
	(segment
		(start 386.994654 -47.603918)
		(end 386.849112 -47.74946)
		(width 0.127)
		(layer "B.Cu")
		(net "PHY_DRV_A_TO_SCC_A_32_DN")
	)
	(segment
		(start 293.148512 -294.438832)
		(end 292.943788 -294.760142)
		(width 0.127)
		(layer "B.Cu")
		(net "PHY_DRV_A_TO_SCC_A_32_DN")
	)
	(segment
		(start 286.409638 -298.30522)
		(end 286.836612 -298.30522)
		(width 0.127)
		(layer "B.Cu")
		(net "PHY_DRV_A_TO_SCC_A_32_DN")
	)
	(segment
		(start 291.930328 -296.047922)
		(end 291.980112 -296.272458)
		(width 0.127)
		(layer "B.Cu")
		(net "PHY_DRV_A_TO_SCC_A_32_DN")
	)
	(segment
		(start 381.555244 -59.975496)
		(end 316.055756 -155.553664)
		(width 0.127)
		(layer "B.Cu")
		(net "PHY_DRV_A_TO_SCC_A_32_DN")
	)
	(segment
		(start 384.25501 -53.664104)
		(end 381.555244 -59.975496)
		(width 0.127)
		(layer "B.Cu")
		(net "PHY_DRV_A_TO_SCC_A_32_DN")
	)
	(segment
		(start 291.516816 -297.000168)
		(end 288.473134 -298.939966)
		(width 0.127)
		(layer "B.Cu")
		(net "PHY_DRV_A_TO_SCC_A_32_DN")
	)
	(segment
		(start 292.514528 -295.131236)
		(end 292.564312 -295.355518)
		(width 0.127)
		(layer "B.Cu")
		(net "PHY_DRV_A_TO_SCC_A_32_DN")
	)
	(segment
		(start 293.527734 -293.843202)
		(end 293.303452 -293.892986)
		(width 0.127)
		(layer "B.Cu")
		(net "PHY_DRV_A_TO_SCC_A_32_DN")
	)
	(segment
		(start 302.768762 -215.500458)
		(end 309.876444 -247.568974)
		(width 0.127)
		(layer "B.Cu")
		(net "PHY_DRV_A_TO_SCC_A_32_DN")
	)
	(segment
		(start 293.303452 -293.892986)
		(end 293.098728 -294.214296)
		(width 0.127)
		(layer "B.Cu")
		(net "PHY_DRV_A_TO_SCC_A_32_DN")
	)
	(segment
		(start 309.876444 -247.568974)
		(end 302.865282 -279.18664)
		(width 0.127)
		(layer "B.Cu")
		(net "PHY_DRV_A_TO_SCC_A_32_DN")
	)
	(segment
		(start 293.527988 -293.843202)
		(end 293.527734 -293.843202)
		(width 0.127)
		(layer "B.Cu")
		(net "PHY_DRV_A_TO_SCC_A_32_DN")
	)
	(segment
		(start 287.933638 -299.059092)
		(end 286.743902 -299.059092)
		(width 0.127)
		(layer "B.Cu")
		(net "PHY_DRV_A_TO_SCC_A_32_DN")
	)
	(segment
		(start 288.473134 -298.939966)
		(end 287.933638 -299.059092)
		(width 0.127)
		(layer "B.Cu")
		(net "PHY_DRV_A_TO_SCC_A_32_DN")
	)
	(segment
		(start 316.055756 -155.553664)
		(end 302.768762 -215.500458)
		(width 0.127)
		(layer "B.Cu")
		(net "PHY_DRV_A_TO_SCC_A_32_DN")
	)
	(segment
		(start 292.359588 -295.676828)
		(end 292.135052 -295.726612)
		(width 0.127)
		(layer "B.Cu")
		(net "PHY_DRV_A_TO_SCC_A_32_DN")
	)
	(segment
		(start 292.719252 -294.809926)
		(end 292.514528 -295.131236)
		(width 0.127)
		(layer "B.Cu")
		(net "PHY_DRV_A_TO_SCC_A_32_DN")
	)
	(segment
		(start 386.73786 -47.860458)
		(end 384.255264 -53.664104)
		(width 0.127)
		(layer "B.Cu")
		(net "PHY_DRV_A_TO_SCC_A_32_DN")
	)
	(segment
		(start 386.849112 -47.74946)
		(end 386.73786 -47.860458)
		(width 0.127)
		(layer "B.Cu")
		(net "PHY_DRV_A_TO_SCC_A_32_DN")
	)
	(segment
		(start 302.865282 -279.18664)
		(end 293.527988 -293.843202)
		(width 0.127)
		(layer "B.Cu")
		(net "PHY_DRV_A_TO_SCC_A_32_DN")
	)
	(segment
		(start 292.943788 -294.760142)
		(end 292.719252 -294.809926)
		(width 0.127)
		(layer "B.Cu")
		(net "PHY_DRV_A_TO_SCC_A_32_DN")
	)
	(segment
		(start 292.135052 -295.726612)
		(end 291.930328 -296.047922)
		(width 0.127)
		(layer "B.Cu")
		(net "PHY_DRV_A_TO_SCC_A_32_DN")
	)
	(segment
		(start 387.83895 -47.178468)
		(end 387.83895 -47.427134)
		(width 0.127)
		(layer "B.Cu")
		(net "PHY_DRV_A_TO_SCC_A_32_DN")
	)
	(segment
		(start 387.662166 -47.603918)
		(end 386.994654 -47.603918)
		(width 0.127)
		(layer "B.Cu")
		(net "PHY_DRV_A_TO_SCC_A_32_DN")
	)
	(segment
		(start 291.980112 -296.272458)
		(end 291.516562 -297.000168)
		(width 0.127)
		(layer "B.Cu")
		(net "PHY_DRV_A_TO_SCC_A_32_DN")
	)
	(segment
		(start 293.098728 -294.214296)
		(end 293.148512 -294.438832)
		(width 0.127)
		(layer "B.Cu")
		(net "PHY_DRV_A_TO_SCC_A_32_DN")
	)
	(arc
		(start 286.743902 -299.059092)
		(mid 286.544444 -299.019417)
		(end 286.375348 -298.906438)
		(width 0.127)
		(layer "B.Cu")
		(net "PHY_DRV_A_TO_SCC_A_32_DN")
	)
	(arc
		(start 286.282638 -298.43222)
		(mid 286.319835 -298.342417)
		(end 286.409638 -298.30522)
		(width 0.127)
		(layer "B.Cu")
		(net "PHY_DRV_A_TO_SCC_A_32_DN")
	)
	(arc
		(start 286.375348 -298.906438)
		(mid 286.306747 -298.80377)
		(end 286.282638 -298.682664)
		(width 0.127)
		(layer "B.Cu")
		(net "PHY_DRV_A_TO_SCC_A_32_DN")
	)
	(arc
		(start 387.83895 -47.427134)
		(mid 387.787171 -47.552139)
		(end 387.662166 -47.603918)
		(width 0.127)
		(layer "B.Cu")
		(net "PHY_DRV_A_TO_SCC_A_32_DN")
	)
	(segment
		(start 357.463598 -48.023018)
		(end 357.463598 -48.257968)
		(width 0.127)
		(layer "F.Cu")
		(net "PHY_DRV_A_TO_SCC_A_31_DP")
	)
	(segment
		(start 356.416102 -47.896018)
		(end 357.336598 -47.896018)
		(width 0.127)
		(layer "F.Cu")
		(net "PHY_DRV_A_TO_SCC_A_31_DP")
	)
	(segment
		(start 357.336598 -47.896018)
		(end 357.463598 -48.023018)
		(width 0.127)
		(layer "F.Cu")
		(net "PHY_DRV_A_TO_SCC_A_31_DP")
	)
	(segment
		(start 357.463598 -48.257968)
		(end 357.590598 -48.384968)
		(width 0.127)
		(layer "F.Cu")
		(net "PHY_DRV_A_TO_SCC_A_31_DP")
	)
	(segment
		(start 356.289102 -48.321468)
		(end 356.289102 -48.023018)
		(width 0.127)
		(layer "F.Cu")
		(net "PHY_DRV_A_TO_SCC_A_31_DP")
	)
	(segment
		(start 357.590598 -48.384968)
		(end 358.925114 -48.384968)
		(width 0.127)
		(layer "F.Cu")
		(net "PHY_DRV_A_TO_SCC_A_31_DP")
	)
	(arc
		(start 356.289102 -48.023018)
		(mid 356.326299 -47.933215)
		(end 356.416102 -47.896018)
		(width 0.127)
		(layer "F.Cu")
		(net "PHY_DRV_A_TO_SCC_A_31_DP")
	)
	(segment
		(start 289.484308 -297.286172)
		(end 288.615628 -297.570144)
		(width 0.1016)
		(layer "In7.Cu")
		(net "PHY_DRV_A_TO_SCC_A_31_DP")
	)
	(segment
		(start 335.150206 -132.934456)
		(end 346.783152 -190.813182)
		(width 0.1016)
		(layer "In7.Cu")
		(net "PHY_DRV_A_TO_SCC_A_31_DP")
	)
	(segment
		(start 286.8422 -296.505122)
		(end 286.436562 -296.505122)
		(width 0.1016)
		(layer "In7.Cu")
		(net "PHY_DRV_A_TO_SCC_A_31_DP")
	)
	(segment
		(start 301.515272 -288.446972)
		(end 289.484308 -297.286172)
		(width 0.1016)
		(layer "In7.Cu")
		(net "PHY_DRV_A_TO_SCC_A_31_DP")
	)
	(segment
		(start 355.230176 -48.012096)
		(end 354.24999 -48.636936)
		(width 0.1016)
		(layer "In7.Cu")
		(net "PHY_DRV_A_TO_SCC_A_31_DP")
	)
	(segment
		(start 353.48799 -49.832768)
		(end 349.215964 -59.734958)
		(width 0.1016)
		(layer "In7.Cu")
		(net "PHY_DRV_A_TO_SCC_A_31_DP")
	)
	(segment
		(start 335.523332 -240.756694)
		(end 322.402454 -261.335266)
		(width 0.1016)
		(layer "In7.Cu")
		(net "PHY_DRV_A_TO_SCC_A_31_DP")
	)
	(segment
		(start 346.783152 -190.813182)
		(end 335.523332 -240.756694)
		(width 0.1016)
		(layer "In7.Cu")
		(net "PHY_DRV_A_TO_SCC_A_31_DP")
	)
	(segment
		(start 288.615628 -297.570144)
		(end 287.463992 -297.570144)
		(width 0.1016)
		(layer "In7.Cu")
		(net "PHY_DRV_A_TO_SCC_A_31_DP")
	)
	(segment
		(start 356.289102 -48.321468)
		(end 356.289102 -48.016668)
		(width 0.1016)
		(layer "In7.Cu")
		(net "PHY_DRV_A_TO_SCC_A_31_DP")
	)
	(segment
		(start 356.187502 -47.915068)
		(end 355.667056 -47.915068)
		(width 0.1016)
		(layer "In7.Cu")
		(net "PHY_DRV_A_TO_SCC_A_31_DP")
	)
	(segment
		(start 355.230176 -48.01235)
		(end 355.230176 -48.012096)
		(width 0.1016)
		(layer "In7.Cu")
		(net "PHY_DRV_A_TO_SCC_A_31_DP")
	)
	(segment
		(start 349.215964 -59.734958)
		(end 335.150206 -132.934456)
		(width 0.1016)
		(layer "In7.Cu")
		(net "PHY_DRV_A_TO_SCC_A_31_DP")
	)
	(segment
		(start 354.24999 -48.636936)
		(end 353.48799 -49.832768)
		(width 0.1016)
		(layer "In7.Cu")
		(net "PHY_DRV_A_TO_SCC_A_31_DP")
	)
	(segment
		(start 286.9692 -297.075352)
		(end 286.9692 -296.632122)
		(width 0.1016)
		(layer "In7.Cu")
		(net "PHY_DRV_A_TO_SCC_A_31_DP")
	)
	(segment
		(start 322.402454 -261.335266)
		(end 301.515272 -288.446972)
		(width 0.1016)
		(layer "In7.Cu")
		(net "PHY_DRV_A_TO_SCC_A_31_DP")
	)
	(segment
		(start 355.667056 -47.915068)
		(end 355.230176 -48.01235)
		(width 0.1016)
		(layer "In7.Cu")
		(net "PHY_DRV_A_TO_SCC_A_31_DP")
	)
	(arc
		(start 287.463992 -297.570144)
		(mid 287.114121 -297.425223)
		(end 286.9692 -297.075352)
		(width 0.1016)
		(layer "In7.Cu")
		(net "PHY_DRV_A_TO_SCC_A_31_DP")
	)
	(arc
		(start 356.289102 -48.016668)
		(mid 356.259344 -47.944826)
		(end 356.187502 -47.915068)
		(width 0.1016)
		(layer "In7.Cu")
		(net "PHY_DRV_A_TO_SCC_A_31_DP")
	)
	(arc
		(start 286.9692 -296.632122)
		(mid 286.932003 -296.542319)
		(end 286.8422 -296.505122)
		(width 0.1016)
		(layer "In7.Cu")
		(net "PHY_DRV_A_TO_SCC_A_31_DP")
	)
	(segment
		(start 356.289102 -47.178468)
		(end 356.289102 -47.476918)
		(width 0.127)
		(layer "F.Cu")
		(net "PHY_DRV_A_TO_SCC_A_31_DN")
	)
	(segment
		(start 356.416102 -47.603918)
		(end 357.336598 -47.603918)
		(width 0.127)
		(layer "F.Cu")
		(net "PHY_DRV_A_TO_SCC_A_31_DN")
	)
	(segment
		(start 357.590598 -47.114968)
		(end 358.925114 -47.114968)
		(width 0.127)
		(layer "F.Cu")
		(net "PHY_DRV_A_TO_SCC_A_31_DN")
	)
	(segment
		(start 357.463598 -47.476918)
		(end 357.463598 -47.241968)
		(width 0.127)
		(layer "F.Cu")
		(net "PHY_DRV_A_TO_SCC_A_31_DN")
	)
	(segment
		(start 357.336598 -47.603918)
		(end 357.463598 -47.476918)
		(width 0.127)
		(layer "F.Cu")
		(net "PHY_DRV_A_TO_SCC_A_31_DN")
	)
	(segment
		(start 357.463598 -47.241968)
		(end 357.590598 -47.114968)
		(width 0.127)
		(layer "F.Cu")
		(net "PHY_DRV_A_TO_SCC_A_31_DN")
	)
	(arc
		(start 356.289102 -47.476918)
		(mid 356.326299 -47.566721)
		(end 356.416102 -47.603918)
		(width 0.127)
		(layer "F.Cu")
		(net "PHY_DRV_A_TO_SCC_A_31_DN")
	)
	(segment
		(start 293.79291 -293.442898)
		(end 293.547292 -293.623238)
		(width 0.1016)
		(layer "In7.Cu")
		(net "PHY_DRV_A_TO_SCC_A_31_DN")
	)
	(segment
		(start 301.2821 -288.208466)
		(end 294.094662 -293.489126)
		(width 0.1016)
		(layer "In7.Cu")
		(net "PHY_DRV_A_TO_SCC_A_31_DN")
	)
	(segment
		(start 292.41623 -294.722296)
		(end 292.114478 -294.676068)
		(width 0.1016)
		(layer "In7.Cu")
		(net "PHY_DRV_A_TO_SCC_A_31_DN")
	)
	(segment
		(start 322.131944 -261.145274)
		(end 301.2821 -288.208466)
		(width 0.1016)
		(layer "In7.Cu")
		(net "PHY_DRV_A_TO_SCC_A_31_DN")
	)
	(segment
		(start 291.86886 -294.856662)
		(end 291.822632 -295.158414)
		(width 0.1016)
		(layer "In7.Cu")
		(net "PHY_DRV_A_TO_SCC_A_31_DN")
	)
	(segment
		(start 292.661848 -294.541702)
		(end 292.41623 -294.722296)
		(width 0.1016)
		(layer "In7.Cu")
		(net "PHY_DRV_A_TO_SCC_A_31_DN")
	)
	(segment
		(start 335.213706 -240.627662)
		(end 322.131944 -261.145274)
		(width 0.1016)
		(layer "In7.Cu")
		(net "PHY_DRV_A_TO_SCC_A_31_DN")
	)
	(segment
		(start 292.953694 -294.059356)
		(end 292.708076 -294.23995)
		(width 0.1016)
		(layer "In7.Cu")
		(net "PHY_DRV_A_TO_SCC_A_31_DN")
	)
	(segment
		(start 355.101652 -47.702216)
		(end 354.010722 -48.397668)
		(width 0.1016)
		(layer "In7.Cu")
		(net "PHY_DRV_A_TO_SCC_A_31_DN")
	)
	(segment
		(start 354.010722 -48.397668)
		(end 353.195128 -49.677574)
		(width 0.1016)
		(layer "In7.Cu")
		(net "PHY_DRV_A_TO_SCC_A_31_DN")
	)
	(segment
		(start 288.562796 -297.239944)
		(end 287.463992 -297.239944)
		(width 0.1016)
		(layer "In7.Cu")
		(net "PHY_DRV_A_TO_SCC_A_31_DN")
	)
	(segment
		(start 356.289102 -47.178468)
		(end 356.289102 -47.483268)
		(width 0.1016)
		(layer "In7.Cu")
		(net "PHY_DRV_A_TO_SCC_A_31_DN")
	)
	(segment
		(start 355.630734 -47.584868)
		(end 355.101652 -47.702216)
		(width 0.1016)
		(layer "In7.Cu")
		(net "PHY_DRV_A_TO_SCC_A_31_DN")
	)
	(segment
		(start 291.822632 -295.158414)
		(end 289.3314 -296.988738)
		(width 0.1016)
		(layer "In7.Cu")
		(net "PHY_DRV_A_TO_SCC_A_31_DN")
	)
	(segment
		(start 334.813656 -132.935726)
		(end 346.445078 -190.809626)
		(width 0.1016)
		(layer "In7.Cu")
		(net "PHY_DRV_A_TO_SCC_A_31_DN")
	)
	(segment
		(start 356.187502 -47.584868)
		(end 355.630734 -47.584868)
		(width 0.1016)
		(layer "In7.Cu")
		(net "PHY_DRV_A_TO_SCC_A_31_DN")
	)
	(segment
		(start 294.094662 -293.489126)
		(end 293.79291 -293.442898)
		(width 0.1016)
		(layer "In7.Cu")
		(net "PHY_DRV_A_TO_SCC_A_31_DN")
	)
	(segment
		(start 353.195128 -49.677574)
		(end 348.898464 -59.637168)
		(width 0.1016)
		(layer "In7.Cu")
		(net "PHY_DRV_A_TO_SCC_A_31_DN")
	)
	(segment
		(start 293.547292 -293.623238)
		(end 293.501064 -293.925244)
		(width 0.1016)
		(layer "In7.Cu")
		(net "PHY_DRV_A_TO_SCC_A_31_DN")
	)
	(segment
		(start 293.255446 -294.105584)
		(end 292.953694 -294.059356)
		(width 0.1016)
		(layer "In7.Cu")
		(net "PHY_DRV_A_TO_SCC_A_31_DN")
	)
	(segment
		(start 293.501064 -293.925244)
		(end 293.255446 -294.105584)
		(width 0.1016)
		(layer "In7.Cu")
		(net "PHY_DRV_A_TO_SCC_A_31_DN")
	)
	(segment
		(start 346.445078 -190.809626)
		(end 335.213706 -240.627662)
		(width 0.1016)
		(layer "In7.Cu")
		(net "PHY_DRV_A_TO_SCC_A_31_DN")
	)
	(segment
		(start 348.898464 -59.637168)
		(end 334.813656 -132.935726)
		(width 0.1016)
		(layer "In7.Cu")
		(net "PHY_DRV_A_TO_SCC_A_31_DN")
	)
	(segment
		(start 289.3314 -296.988738)
		(end 288.562796 -297.239944)
		(width 0.1016)
		(layer "In7.Cu")
		(net "PHY_DRV_A_TO_SCC_A_31_DN")
	)
	(segment
		(start 292.708076 -294.23995)
		(end 292.661848 -294.541702)
		(width 0.1016)
		(layer "In7.Cu")
		(net "PHY_DRV_A_TO_SCC_A_31_DN")
	)
	(segment
		(start 287.4264 -296.505122)
		(end 287.83661 -296.505122)
		(width 0.1016)
		(layer "In7.Cu")
		(net "PHY_DRV_A_TO_SCC_A_31_DN")
	)
	(segment
		(start 287.2994 -297.075352)
		(end 287.2994 -296.632122)
		(width 0.1016)
		(layer "In7.Cu")
		(net "PHY_DRV_A_TO_SCC_A_31_DN")
	)
	(segment
		(start 292.114478 -294.676068)
		(end 291.86886 -294.856662)
		(width 0.1016)
		(layer "In7.Cu")
		(net "PHY_DRV_A_TO_SCC_A_31_DN")
	)
	(arc
		(start 287.463992 -297.239944)
		(mid 287.347608 -297.191736)
		(end 287.2994 -297.075352)
		(width 0.1016)
		(layer "In7.Cu")
		(net "PHY_DRV_A_TO_SCC_A_31_DN")
	)
	(arc
		(start 356.289102 -47.483268)
		(mid 356.259344 -47.55511)
		(end 356.187502 -47.584868)
		(width 0.1016)
		(layer "In7.Cu")
		(net "PHY_DRV_A_TO_SCC_A_31_DN")
	)
	(arc
		(start 287.2994 -296.632122)
		(mid 287.336597 -296.542319)
		(end 287.4264 -296.505122)
		(width 0.1016)
		(layer "In7.Cu")
		(net "PHY_DRV_A_TO_SCC_A_31_DN")
	)
	(segment
		(start 325.913496 -48.257968)
		(end 326.040496 -48.384968)
		(width 0.127)
		(layer "F.Cu")
		(net "PHY_DRV_A_TO_SCC_A_30_DP")
	)
	(segment
		(start 323.10705 -46.683168)
		(end 323.10705 -47.217584)
		(width 0.127)
		(layer "F.Cu")
		(net "PHY_DRV_A_TO_SCC_A_30_DP")
	)
	(segment
		(start 326.040496 -48.384968)
		(end 327.375012 -48.384968)
		(width 0.127)
		(layer "F.Cu")
		(net "PHY_DRV_A_TO_SCC_A_30_DP")
	)
	(segment
		(start 322.6816 -46.437042)
		(end 322.860924 -46.437042)
		(width 0.127)
		(layer "F.Cu")
		(net "PHY_DRV_A_TO_SCC_A_30_DP")
	)
	(segment
		(start 325.786496 -47.896018)
		(end 325.913496 -48.023018)
		(width 0.127)
		(layer "F.Cu")
		(net "PHY_DRV_A_TO_SCC_A_30_DP")
	)
	(segment
		(start 323.10705 -47.217584)
		(end 323.785484 -47.896018)
		(width 0.127)
		(layer "F.Cu")
		(net "PHY_DRV_A_TO_SCC_A_30_DP")
	)
	(segment
		(start 323.785484 -47.896018)
		(end 325.786496 -47.896018)
		(width 0.127)
		(layer "F.Cu")
		(net "PHY_DRV_A_TO_SCC_A_30_DP")
	)
	(segment
		(start 325.913496 -48.023018)
		(end 325.913496 -48.257968)
		(width 0.127)
		(layer "F.Cu")
		(net "PHY_DRV_A_TO_SCC_A_30_DP")
	)
	(arc
		(start 322.860924 -46.437042)
		(mid 323.034961 -46.509131)
		(end 323.10705 -46.683168)
		(width 0.127)
		(layer "F.Cu")
		(net "PHY_DRV_A_TO_SCC_A_30_DP")
	)
	(segment
		(start 312.355992 -142.516352)
		(end 307.318664 -117.44833)
		(width 0.1016)
		(layer "In7.Cu")
		(net "PHY_DRV_A_TO_SCC_A_30_DP")
	)
	(segment
		(start 285.973774 -294.578278)
		(end 285.973774 -294.135048)
		(width 0.1016)
		(layer "In7.Cu")
		(net "PHY_DRV_A_TO_SCC_A_30_DP")
	)
	(segment
		(start 321.460114 -237.533434)
		(end 317.900812 -219.818204)
		(width 0.1016)
		(layer "In7.Cu")
		(net "PHY_DRV_A_TO_SCC_A_30_DP")
	)
	(segment
		(start 317.900812 -219.81795)
		(end 307.222906 -166.672768)
		(width 0.1016)
		(layer "In7.Cu")
		(net "PHY_DRV_A_TO_SCC_A_30_DP")
	)
	(segment
		(start 299.515022 -283.912056)
		(end 315.914278 -262.135112)
		(width 0.1016)
		(layer "In7.Cu")
		(net "PHY_DRV_A_TO_SCC_A_30_DP")
	)
	(segment
		(start 317.900812 -219.818204)
		(end 317.900812 -219.81795)
		(width 0.1016)
		(layer "In7.Cu")
		(net "PHY_DRV_A_TO_SCC_A_30_DP")
	)
	(segment
		(start 323.088 -47.699422)
		(end 323.088 -46.538642)
		(width 0.1016)
		(layer "In7.Cu")
		(net "PHY_DRV_A_TO_SCC_A_30_DP")
	)
	(segment
		(start 307.222906 -166.672768)
		(end 312.355992 -142.516352)
		(width 0.1016)
		(layer "In7.Cu")
		(net "PHY_DRV_A_TO_SCC_A_30_DP")
	)
	(segment
		(start 322.9864 -46.437042)
		(end 322.6816 -46.437042)
		(width 0.1016)
		(layer "In7.Cu")
		(net "PHY_DRV_A_TO_SCC_A_30_DP")
	)
	(segment
		(start 286.300672 -293.621968)
		(end 299.515022 -283.912056)
		(width 0.1016)
		(layer "In7.Cu")
		(net "PHY_DRV_A_TO_SCC_A_30_DP")
	)
	(segment
		(start 286.105092 -293.817548)
		(end 286.300672 -293.621968)
		(width 0.1016)
		(layer "In7.Cu")
		(net "PHY_DRV_A_TO_SCC_A_30_DP")
	)
	(segment
		(start 285.436564 -294.705278)
		(end 285.846774 -294.705278)
		(width 0.1016)
		(layer "In7.Cu")
		(net "PHY_DRV_A_TO_SCC_A_30_DP")
	)
	(segment
		(start 307.318664 -117.44833)
		(end 323.088 -47.699422)
		(width 0.1016)
		(layer "In7.Cu")
		(net "PHY_DRV_A_TO_SCC_A_30_DP")
	)
	(segment
		(start 315.914278 -262.135112)
		(end 321.460114 -237.533434)
		(width 0.1016)
		(layer "In7.Cu")
		(net "PHY_DRV_A_TO_SCC_A_30_DP")
	)
	(arc
		(start 323.088 -46.538642)
		(mid 323.058242 -46.4668)
		(end 322.9864 -46.437042)
		(width 0.1016)
		(layer "In7.Cu")
		(net "PHY_DRV_A_TO_SCC_A_30_DP")
	)
	(arc
		(start 285.846774 -294.705278)
		(mid 285.936577 -294.668081)
		(end 285.973774 -294.578278)
		(width 0.1016)
		(layer "In7.Cu")
		(net "PHY_DRV_A_TO_SCC_A_30_DP")
	)
	(arc
		(start 286.10433 -293.818056)
		(mid 286.104711 -293.817802)
		(end 286.105092 -293.817548)
		(width 0.1016)
		(layer "In7.Cu")
		(net "PHY_DRV_A_TO_SCC_A_30_DP")
	)
	(arc
		(start 285.973774 -294.135048)
		(mid 286.007601 -293.9636)
		(end 286.10433 -293.818056)
		(width 0.1016)
		(layer "In7.Cu")
		(net "PHY_DRV_A_TO_SCC_A_30_DP")
	)
	(segment
		(start 323.39915 -47.096426)
		(end 323.906642 -47.603918)
		(width 0.127)
		(layer "F.Cu")
		(net "PHY_DRV_A_TO_SCC_A_30_DN")
	)
	(segment
		(start 325.913496 -47.417482)
		(end 325.913496 -47.251112)
		(width 0.127)
		(layer "F.Cu")
		(net "PHY_DRV_A_TO_SCC_A_30_DN")
	)
	(segment
		(start 325.913496 -47.251112)
		(end 326.04964 -47.114968)
		(width 0.127)
		(layer "F.Cu")
		(net "PHY_DRV_A_TO_SCC_A_30_DN")
	)
	(segment
		(start 326.04964 -47.114968)
		(end 327.375012 -47.114968)
		(width 0.127)
		(layer "F.Cu")
		(net "PHY_DRV_A_TO_SCC_A_30_DN")
	)
	(segment
		(start 323.8246 -46.437042)
		(end 323.645276 -46.437042)
		(width 0.127)
		(layer "F.Cu")
		(net "PHY_DRV_A_TO_SCC_A_30_DN")
	)
	(segment
		(start 323.39915 -46.683168)
		(end 323.39915 -47.096426)
		(width 0.127)
		(layer "F.Cu")
		(net "PHY_DRV_A_TO_SCC_A_30_DN")
	)
	(segment
		(start 325.72706 -47.603918)
		(end 325.913496 -47.417482)
		(width 0.127)
		(layer "F.Cu")
		(net "PHY_DRV_A_TO_SCC_A_30_DN")
	)
	(segment
		(start 323.906642 -47.603918)
		(end 325.72706 -47.603918)
		(width 0.127)
		(layer "F.Cu")
		(net "PHY_DRV_A_TO_SCC_A_30_DN")
	)
	(arc
		(start 323.645276 -46.437042)
		(mid 323.471239 -46.509131)
		(end 323.39915 -46.683168)
		(width 0.127)
		(layer "F.Cu")
		(net "PHY_DRV_A_TO_SCC_A_30_DN")
	)
	(segment
		(start 316.220856 -262.277098)
		(end 321.797934 -237.537498)
		(width 0.1016)
		(layer "In7.Cu")
		(net "PHY_DRV_A_TO_SCC_A_30_DN")
	)
	(segment
		(start 288.60242 -292.608762)
		(end 288.848038 -292.428168)
		(width 0.1016)
		(layer "In7.Cu")
		(net "PHY_DRV_A_TO_SCC_A_30_DN")
	)
	(segment
		(start 323.5198 -46.437042)
		(end 323.8246 -46.437042)
		(width 0.1016)
		(layer "In7.Cu")
		(net "PHY_DRV_A_TO_SCC_A_30_DN")
	)
	(segment
		(start 289.441636 -291.99205)
		(end 289.687254 -291.811456)
		(width 0.1016)
		(layer "In7.Cu")
		(net "PHY_DRV_A_TO_SCC_A_30_DN")
	)
	(segment
		(start 323.4182 -47.736506)
		(end 323.4182 -46.538642)
		(width 0.1016)
		(layer "In7.Cu")
		(net "PHY_DRV_A_TO_SCC_A_30_DN")
	)
	(segment
		(start 286.836612 -294.705278)
		(end 286.430974 -294.705278)
		(width 0.1016)
		(layer "In7.Cu")
		(net "PHY_DRV_A_TO_SCC_A_30_DN")
	)
	(segment
		(start 287.763204 -293.22522)
		(end 288.008822 -293.04488)
		(width 0.1016)
		(layer "In7.Cu")
		(net "PHY_DRV_A_TO_SCC_A_30_DN")
	)
	(segment
		(start 286.303974 -294.578278)
		(end 286.303974 -294.135048)
		(width 0.1016)
		(layer "In7.Cu")
		(net "PHY_DRV_A_TO_SCC_A_30_DN")
	)
	(segment
		(start 286.426656 -293.963344)
		(end 286.516572 -293.873428)
		(width 0.1016)
		(layer "In7.Cu")
		(net "PHY_DRV_A_TO_SCC_A_30_DN")
	)
	(segment
		(start 289.687254 -291.811456)
		(end 289.733228 -291.509704)
		(width 0.1016)
		(layer "In7.Cu")
		(net "PHY_DRV_A_TO_SCC_A_30_DN")
	)
	(segment
		(start 307.560218 -166.674546)
		(end 312.693304 -142.51813)
		(width 0.1016)
		(layer "In7.Cu")
		(net "PHY_DRV_A_TO_SCC_A_30_DN")
	)
	(segment
		(start 288.300668 -292.562534)
		(end 288.60242 -292.608762)
		(width 0.1016)
		(layer "In7.Cu")
		(net "PHY_DRV_A_TO_SCC_A_30_DN")
	)
	(segment
		(start 288.848038 -292.428168)
		(end 288.894266 -292.126416)
		(width 0.1016)
		(layer "In7.Cu")
		(net "PHY_DRV_A_TO_SCC_A_30_DN")
	)
	(segment
		(start 286.338518 -294.051228)
		(end 286.426656 -293.963344)
		(width 0.1016)
		(layer "In7.Cu")
		(net "PHY_DRV_A_TO_SCC_A_30_DN")
	)
	(segment
		(start 289.139884 -291.945822)
		(end 289.441636 -291.99205)
		(width 0.1016)
		(layer "In7.Cu")
		(net "PHY_DRV_A_TO_SCC_A_30_DN")
	)
	(segment
		(start 312.693304 -142.51813)
		(end 307.656484 -117.452394)
		(width 0.1016)
		(layer "In7.Cu")
		(net "PHY_DRV_A_TO_SCC_A_30_DN")
	)
	(segment
		(start 287.461452 -293.179246)
		(end 287.763204 -293.22522)
		(width 0.1016)
		(layer "In7.Cu")
		(net "PHY_DRV_A_TO_SCC_A_30_DN")
	)
	(segment
		(start 289.733228 -291.509704)
		(end 299.749718 -284.149546)
		(width 0.1016)
		(layer "In7.Cu")
		(net "PHY_DRV_A_TO_SCC_A_30_DN")
	)
	(segment
		(start 307.656484 -117.452394)
		(end 323.4182 -47.736506)
		(width 0.1016)
		(layer "In7.Cu")
		(net "PHY_DRV_A_TO_SCC_A_30_DN")
	)
	(segment
		(start 321.797934 -237.537498)
		(end 307.560218 -166.674546)
		(width 0.1016)
		(layer "In7.Cu")
		(net "PHY_DRV_A_TO_SCC_A_30_DN")
	)
	(segment
		(start 288.05505 -292.743128)
		(end 288.300668 -292.562534)
		(width 0.1016)
		(layer "In7.Cu")
		(net "PHY_DRV_A_TO_SCC_A_30_DN")
	)
	(segment
		(start 299.749718 -284.149546)
		(end 316.220856 -262.277098)
		(width 0.1016)
		(layer "In7.Cu")
		(net "PHY_DRV_A_TO_SCC_A_30_DN")
	)
	(segment
		(start 286.516572 -293.873428)
		(end 287.461452 -293.179246)
		(width 0.1016)
		(layer "In7.Cu")
		(net "PHY_DRV_A_TO_SCC_A_30_DN")
	)
	(segment
		(start 288.008822 -293.04488)
		(end 288.05505 -292.743128)
		(width 0.1016)
		(layer "In7.Cu")
		(net "PHY_DRV_A_TO_SCC_A_30_DN")
	)
	(segment
		(start 288.894266 -292.126416)
		(end 289.139884 -291.945822)
		(width 0.1016)
		(layer "In7.Cu")
		(net "PHY_DRV_A_TO_SCC_A_30_DN")
	)
	(arc
		(start 286.303974 -294.135048)
		(mid 286.312901 -294.089698)
		(end 286.338518 -294.051228)
		(width 0.1016)
		(layer "In7.Cu")
		(net "PHY_DRV_A_TO_SCC_A_30_DN")
	)
	(arc
		(start 323.4182 -46.538642)
		(mid 323.447958 -46.4668)
		(end 323.5198 -46.437042)
		(width 0.1016)
		(layer "In7.Cu")
		(net "PHY_DRV_A_TO_SCC_A_30_DN")
	)
	(arc
		(start 286.430974 -294.705278)
		(mid 286.341171 -294.668081)
		(end 286.303974 -294.578278)
		(width 0.1016)
		(layer "In7.Cu")
		(net "PHY_DRV_A_TO_SCC_A_30_DN")
	)
	(segment
		(start 126.295404 -277.896066)
		(end 126.1364 -278.05507)
		(width 0.127)
		(layer "F.Cu")
		(net "PHY_DRV_A_TO_SCC_A_3_DP")
	)
	(segment
		(start 127.15875 -278.321516)
		(end 127.15875 -278.023066)
		(width 0.127)
		(layer "F.Cu")
		(net "PHY_DRV_A_TO_SCC_A_3_DP")
	)
	(segment
		(start 126.1364 -278.235664)
		(end 125.987048 -278.385016)
		(width 0.127)
		(layer "F.Cu")
		(net "PHY_DRV_A_TO_SCC_A_3_DP")
	)
	(segment
		(start 127.03175 -277.896066)
		(end 126.295404 -277.896066)
		(width 0.127)
		(layer "F.Cu")
		(net "PHY_DRV_A_TO_SCC_A_3_DP")
	)
	(segment
		(start 126.1364 -278.05507)
		(end 126.1364 -278.235664)
		(width 0.127)
		(layer "F.Cu")
		(net "PHY_DRV_A_TO_SCC_A_3_DP")
	)
	(segment
		(start 125.987048 -278.385016)
		(end 124.674884 -278.385016)
		(width 0.127)
		(layer "F.Cu")
		(net "PHY_DRV_A_TO_SCC_A_3_DP")
	)
	(arc
		(start 127.15875 -278.023066)
		(mid 127.121553 -277.933263)
		(end 127.03175 -277.896066)
		(width 0.127)
		(layer "F.Cu")
		(net "PHY_DRV_A_TO_SCC_A_3_DP")
	)
	(segment
		(start 266.826492 -350.129094)
		(end 263.454642 -348.895924)
		(width 0.1016)
		(layer "In7.Cu")
		(net "PHY_DRV_A_TO_SCC_A_3_DP")
	)
	(segment
		(start 267.518388 -350.382078)
		(end 267.241528 -350.510602)
		(width 0.1016)
		(layer "In7.Cu")
		(net "PHY_DRV_A_TO_SCC_A_3_DP")
	)
	(segment
		(start 268.496542 -350.73971)
		(end 268.219428 -350.868234)
		(width 0.1016)
		(layer "In7.Cu")
		(net "PHY_DRV_A_TO_SCC_A_3_DP")
	)
	(segment
		(start 267.241528 -350.510602)
		(end 266.95527 -350.405954)
		(width 0.1016)
		(layer "In7.Cu")
		(net "PHY_DRV_A_TO_SCC_A_3_DP")
	)
	(segment
		(start 268.7828 -350.844358)
		(end 268.496542 -350.73971)
		(width 0.1016)
		(layer "In7.Cu")
		(net "PHY_DRV_A_TO_SCC_A_3_DP")
	)
	(segment
		(start 285.809182 -351.57029)
		(end 270.767556 -351.57029)
		(width 0.1016)
		(layer "In7.Cu")
		(net "PHY_DRV_A_TO_SCC_A_3_DP")
	)
	(segment
		(start 130.446272 -277.915116)
		(end 127.26035 -277.915116)
		(width 0.1016)
		(layer "In7.Cu")
		(net "PHY_DRV_A_TO_SCC_A_3_DP")
	)
	(segment
		(start 267.93317 -350.763586)
		(end 267.804646 -350.486726)
		(width 0.1016)
		(layer "In7.Cu")
		(net "PHY_DRV_A_TO_SCC_A_3_DP")
	)
	(segment
		(start 193.560954 -316.157864)
		(end 135.18769 -278.966676)
		(width 0.1016)
		(layer "In7.Cu")
		(net "PHY_DRV_A_TO_SCC_A_3_DP")
	)
	(segment
		(start 263.454642 -348.895924)
		(end 221.942406 -322.45046)
		(width 0.1016)
		(layer "In7.Cu")
		(net "PHY_DRV_A_TO_SCC_A_3_DP")
	)
	(segment
		(start 268.219428 -350.868234)
		(end 267.93317 -350.763586)
		(width 0.1016)
		(layer "In7.Cu")
		(net "PHY_DRV_A_TO_SCC_A_3_DP")
	)
	(segment
		(start 285.436564 -352.305112)
		(end 285.846774 -352.305112)
		(width 0.1016)
		(layer "In7.Cu")
		(net "PHY_DRV_A_TO_SCC_A_3_DP")
	)
	(segment
		(start 270.767556 -351.57029)
		(end 269.474442 -351.097342)
		(width 0.1016)
		(layer "In7.Cu")
		(net "PHY_DRV_A_TO_SCC_A_3_DP")
	)
	(segment
		(start 285.973774 -352.178112)
		(end 285.973774 -351.734882)
		(width 0.1016)
		(layer "In7.Cu")
		(net "PHY_DRV_A_TO_SCC_A_3_DP")
	)
	(segment
		(start 127.15875 -278.016716)
		(end 127.15875 -278.321516)
		(width 0.1016)
		(layer "In7.Cu")
		(net "PHY_DRV_A_TO_SCC_A_3_DP")
	)
	(segment
		(start 268.911324 -351.121218)
		(end 268.7828 -350.844358)
		(width 0.1016)
		(layer "In7.Cu")
		(net "PHY_DRV_A_TO_SCC_A_3_DP")
	)
	(segment
		(start 135.18769 -278.966676)
		(end 130.446272 -277.915116)
		(width 0.1016)
		(layer "In7.Cu")
		(net "PHY_DRV_A_TO_SCC_A_3_DP")
	)
	(segment
		(start 269.197582 -351.22612)
		(end 268.911324 -351.121218)
		(width 0.1016)
		(layer "In7.Cu")
		(net "PHY_DRV_A_TO_SCC_A_3_DP")
	)
	(segment
		(start 266.95527 -350.405954)
		(end 266.826492 -350.129094)
		(width 0.1016)
		(layer "In7.Cu")
		(net "PHY_DRV_A_TO_SCC_A_3_DP")
	)
	(segment
		(start 269.474442 -351.097342)
		(end 269.197582 -351.22612)
		(width 0.1016)
		(layer "In7.Cu")
		(net "PHY_DRV_A_TO_SCC_A_3_DP")
	)
	(segment
		(start 221.942406 -322.45046)
		(end 193.560954 -316.157864)
		(width 0.1016)
		(layer "In7.Cu")
		(net "PHY_DRV_A_TO_SCC_A_3_DP")
	)
	(segment
		(start 267.804646 -350.486726)
		(end 267.518388 -350.382078)
		(width 0.1016)
		(layer "In7.Cu")
		(net "PHY_DRV_A_TO_SCC_A_3_DP")
	)
	(arc
		(start 285.973774 -351.734882)
		(mid 285.925566 -351.618498)
		(end 285.809182 -351.57029)
		(width 0.1016)
		(layer "In7.Cu")
		(net "PHY_DRV_A_TO_SCC_A_3_DP")
	)
	(arc
		(start 285.846774 -352.305112)
		(mid 285.936577 -352.267915)
		(end 285.973774 -352.178112)
		(width 0.1016)
		(layer "In7.Cu")
		(net "PHY_DRV_A_TO_SCC_A_3_DP")
	)
	(arc
		(start 127.26035 -277.915116)
		(mid 127.188508 -277.944874)
		(end 127.15875 -278.016716)
		(width 0.1016)
		(layer "In7.Cu")
		(net "PHY_DRV_A_TO_SCC_A_3_DP")
	)
	(segment
		(start 126.1364 -277.242016)
		(end 126.0094 -277.115016)
		(width 0.127)
		(layer "F.Cu")
		(net "PHY_DRV_A_TO_SCC_A_3_DN")
	)
	(segment
		(start 126.1364 -277.476966)
		(end 126.1364 -277.242016)
		(width 0.127)
		(layer "F.Cu")
		(net "PHY_DRV_A_TO_SCC_A_3_DN")
	)
	(segment
		(start 126.2634 -277.603966)
		(end 126.1364 -277.476966)
		(width 0.127)
		(layer "F.Cu")
		(net "PHY_DRV_A_TO_SCC_A_3_DN")
	)
	(segment
		(start 127.15875 -277.178516)
		(end 127.15875 -277.476966)
		(width 0.127)
		(layer "F.Cu")
		(net "PHY_DRV_A_TO_SCC_A_3_DN")
	)
	(segment
		(start 126.0094 -277.115016)
		(end 124.674884 -277.115016)
		(width 0.127)
		(layer "F.Cu")
		(net "PHY_DRV_A_TO_SCC_A_3_DN")
	)
	(segment
		(start 127.03175 -277.603966)
		(end 126.2634 -277.603966)
		(width 0.127)
		(layer "F.Cu")
		(net "PHY_DRV_A_TO_SCC_A_3_DN")
	)
	(arc
		(start 127.15875 -277.476966)
		(mid 127.121553 -277.566769)
		(end 127.03175 -277.603966)
		(width 0.127)
		(layer "F.Cu")
		(net "PHY_DRV_A_TO_SCC_A_3_DN")
	)
	(segment
		(start 127.26035 -277.584916)
		(end 130.482594 -277.584916)
		(width 0.1016)
		(layer "In7.Cu")
		(net "PHY_DRV_A_TO_SCC_A_3_DN")
	)
	(segment
		(start 222.070676 -322.14058)
		(end 263.601962 -348.597982)
		(width 0.1016)
		(layer "In7.Cu")
		(net "PHY_DRV_A_TO_SCC_A_3_DN")
	)
	(segment
		(start 286.303974 -351.734882)
		(end 286.303974 -352.178112)
		(width 0.1016)
		(layer "In7.Cu")
		(net "PHY_DRV_A_TO_SCC_A_3_DN")
	)
	(segment
		(start 286.430974 -352.305112)
		(end 286.836612 -352.305112)
		(width 0.1016)
		(layer "In7.Cu")
		(net "PHY_DRV_A_TO_SCC_A_3_DN")
	)
	(segment
		(start 135.31596 -278.656796)
		(end 193.689224 -315.847984)
		(width 0.1016)
		(layer "In7.Cu")
		(net "PHY_DRV_A_TO_SCC_A_3_DN")
	)
	(segment
		(start 263.601962 -348.597982)
		(end 270.82623 -351.24009)
		(width 0.1016)
		(layer "In7.Cu")
		(net "PHY_DRV_A_TO_SCC_A_3_DN")
	)
	(segment
		(start 130.482594 -277.584916)
		(end 135.31596 -278.656796)
		(width 0.1016)
		(layer "In7.Cu")
		(net "PHY_DRV_A_TO_SCC_A_3_DN")
	)
	(segment
		(start 127.15875 -277.178516)
		(end 127.15875 -277.483316)
		(width 0.1016)
		(layer "In7.Cu")
		(net "PHY_DRV_A_TO_SCC_A_3_DN")
	)
	(segment
		(start 193.689224 -315.847984)
		(end 222.070676 -322.14058)
		(width 0.1016)
		(layer "In7.Cu")
		(net "PHY_DRV_A_TO_SCC_A_3_DN")
	)
	(segment
		(start 270.82623 -351.24009)
		(end 285.809182 -351.24009)
		(width 0.1016)
		(layer "In7.Cu")
		(net "PHY_DRV_A_TO_SCC_A_3_DN")
	)
	(arc
		(start 127.15875 -277.483316)
		(mid 127.188508 -277.555158)
		(end 127.26035 -277.584916)
		(width 0.1016)
		(layer "In7.Cu")
		(net "PHY_DRV_A_TO_SCC_A_3_DN")
	)
	(arc
		(start 286.303974 -352.178112)
		(mid 286.341171 -352.267915)
		(end 286.430974 -352.305112)
		(width 0.1016)
		(layer "In7.Cu")
		(net "PHY_DRV_A_TO_SCC_A_3_DN")
	)
	(arc
		(start 285.809182 -351.24009)
		(mid 286.159053 -351.385011)
		(end 286.303974 -351.734882)
		(width 0.1016)
		(layer "In7.Cu")
		(net "PHY_DRV_A_TO_SCC_A_3_DN")
	)
	(segment
		(start 189.363604 -47.896018)
		(end 189.236604 -48.023018)
		(width 0.127)
		(layer "F.Cu")
		(net "PHY_DRV_A_TO_SCC_A_29_DP")
	)
	(segment
		(start 190.258954 -48.321468)
		(end 190.258954 -48.023018)
		(width 0.127)
		(layer "F.Cu")
		(net "PHY_DRV_A_TO_SCC_A_29_DP")
	)
	(segment
		(start 189.236604 -48.227488)
		(end 189.079124 -48.384968)
		(width 0.127)
		(layer "F.Cu")
		(net "PHY_DRV_A_TO_SCC_A_29_DP")
	)
	(segment
		(start 190.131954 -47.896018)
		(end 189.363604 -47.896018)
		(width 0.127)
		(layer "F.Cu")
		(net "PHY_DRV_A_TO_SCC_A_29_DP")
	)
	(segment
		(start 189.079124 -48.384968)
		(end 187.775088 -48.384968)
		(width 0.127)
		(layer "F.Cu")
		(net "PHY_DRV_A_TO_SCC_A_29_DP")
	)
	(segment
		(start 189.236604 -48.023018)
		(end 189.236604 -48.227488)
		(width 0.127)
		(layer "F.Cu")
		(net "PHY_DRV_A_TO_SCC_A_29_DP")
	)
	(arc
		(start 190.258954 -48.023018)
		(mid 190.221757 -47.933215)
		(end 190.131954 -47.896018)
		(width 0.127)
		(layer "F.Cu")
		(net "PHY_DRV_A_TO_SCC_A_29_DP")
	)
	(segment
		(start 272.92554 -304.269902)
		(end 272.631916 -304.353722)
		(width 0.1016)
		(layer "In7.Cu")
		(net "PHY_DRV_A_TO_SCC_A_29_DP")
	)
	(segment
		(start 271.721834 -303.847246)
		(end 271.455388 -303.699164)
		(width 0.1016)
		(layer "In7.Cu")
		(net "PHY_DRV_A_TO_SCC_A_29_DP")
	)
	(segment
		(start 230.279448 -272.995136)
		(end 213.445344 -205.81747)
		(width 0.1016)
		(layer "In7.Cu")
		(net "PHY_DRV_A_TO_SCC_A_29_DP")
	)
	(segment
		(start 193.039492 -54.529228)
		(end 191.860678 -48.66005)
		(width 0.1016)
		(layer "In7.Cu")
		(net "PHY_DRV_A_TO_SCC_A_29_DP")
	)
	(segment
		(start 217.669618 -188.685678)
		(end 217.669364 -188.685678)
		(width 0.1016)
		(layer "In7.Cu")
		(net "PHY_DRV_A_TO_SCC_A_29_DP")
	)
	(segment
		(start 217.669364 -188.685678)
		(end 189.32144 -76.11491)
		(width 0.1016)
		(layer "In7.Cu")
		(net "PHY_DRV_A_TO_SCC_A_29_DP")
	)
	(segment
		(start 194.218052 -60.39866)
		(end 193.039492 -54.529228)
		(width 0.1016)
		(layer "In7.Cu")
		(net "PHY_DRV_A_TO_SCC_A_29_DP")
	)
	(segment
		(start 213.445344 -205.81747)
		(end 217.669618 -188.685678)
		(width 0.1016)
		(layer "In7.Cu")
		(net "PHY_DRV_A_TO_SCC_A_29_DP")
	)
	(segment
		(start 272.36547 -304.205386)
		(end 272.281904 -303.911762)
		(width 0.1016)
		(layer "In7.Cu")
		(net "PHY_DRV_A_TO_SCC_A_29_DP")
	)
	(segment
		(start 271.105376 -303.257458)
		(end 270.811752 -303.341024)
		(width 0.1016)
		(layer "In7.Cu")
		(net "PHY_DRV_A_TO_SCC_A_29_DP")
	)
	(segment
		(start 272.015458 -303.76368)
		(end 271.721834 -303.847246)
		(width 0.1016)
		(layer "In7.Cu")
		(net "PHY_DRV_A_TO_SCC_A_29_DP")
	)
	(segment
		(start 285.436564 -305.505104)
		(end 285.846774 -305.505104)
		(width 0.1016)
		(layer "In7.Cu")
		(net "PHY_DRV_A_TO_SCC_A_29_DP")
	)
	(segment
		(start 191.860678 -48.66005)
		(end 191.614552 -48.289464)
		(width 0.1016)
		(layer "In7.Cu")
		(net "PHY_DRV_A_TO_SCC_A_29_DP")
	)
	(segment
		(start 270.811752 -303.341024)
		(end 270.545306 -303.192942)
		(width 0.1016)
		(layer "In7.Cu")
		(net "PHY_DRV_A_TO_SCC_A_29_DP")
	)
	(segment
		(start 235.340906 -283.360622)
		(end 230.279448 -272.995136)
		(width 0.1016)
		(layer "In7.Cu")
		(net "PHY_DRV_A_TO_SCC_A_29_DP")
	)
	(segment
		(start 270.545306 -303.192942)
		(end 270.46174 -302.899318)
		(width 0.1016)
		(layer "In7.Cu")
		(net "PHY_DRV_A_TO_SCC_A_29_DP")
	)
	(segment
		(start 272.281904 -303.911762)
		(end 272.015458 -303.76368)
		(width 0.1016)
		(layer "In7.Cu")
		(net "PHY_DRV_A_TO_SCC_A_29_DP")
	)
	(segment
		(start 191.614552 -48.289464)
		(end 190.95339 -47.915068)
		(width 0.1016)
		(layer "In7.Cu")
		(net "PHY_DRV_A_TO_SCC_A_29_DP")
	)
	(segment
		(start 189.32144 -76.11491)
		(end 194.218052 -60.39866)
		(width 0.1016)
		(layer "In7.Cu")
		(net "PHY_DRV_A_TO_SCC_A_29_DP")
	)
	(segment
		(start 270.46174 -302.899318)
		(end 235.340906 -283.360622)
		(width 0.1016)
		(layer "In7.Cu")
		(net "PHY_DRV_A_TO_SCC_A_29_DP")
	)
	(segment
		(start 272.631916 -304.353722)
		(end 272.36547 -304.205386)
		(width 0.1016)
		(layer "In7.Cu")
		(net "PHY_DRV_A_TO_SCC_A_29_DP")
	)
	(segment
		(start 271.371822 -303.40554)
		(end 271.105376 -303.257458)
		(width 0.1016)
		(layer "In7.Cu")
		(net "PHY_DRV_A_TO_SCC_A_29_DP")
	)
	(segment
		(start 285.809182 -304.770282)
		(end 273.824954 -304.770282)
		(width 0.1016)
		(layer "In7.Cu")
		(net "PHY_DRV_A_TO_SCC_A_29_DP")
	)
	(segment
		(start 271.455388 -303.699164)
		(end 271.371822 -303.40554)
		(width 0.1016)
		(layer "In7.Cu")
		(net "PHY_DRV_A_TO_SCC_A_29_DP")
	)
	(segment
		(start 285.973774 -305.378104)
		(end 285.973774 -304.934874)
		(width 0.1016)
		(layer "In7.Cu")
		(net "PHY_DRV_A_TO_SCC_A_29_DP")
	)
	(segment
		(start 190.95339 -47.915068)
		(end 190.360554 -47.915068)
		(width 0.1016)
		(layer "In7.Cu")
		(net "PHY_DRV_A_TO_SCC_A_29_DP")
	)
	(segment
		(start 273.824954 -304.770282)
		(end 272.92554 -304.269902)
		(width 0.1016)
		(layer "In7.Cu")
		(net "PHY_DRV_A_TO_SCC_A_29_DP")
	)
	(segment
		(start 190.258954 -48.016668)
		(end 190.258954 -48.321468)
		(width 0.1016)
		(layer "In7.Cu")
		(net "PHY_DRV_A_TO_SCC_A_29_DP")
	)
	(arc
		(start 285.973774 -304.934874)
		(mid 285.925566 -304.81849)
		(end 285.809182 -304.770282)
		(width 0.1016)
		(layer "In7.Cu")
		(net "PHY_DRV_A_TO_SCC_A_29_DP")
	)
	(arc
		(start 285.846774 -305.505104)
		(mid 285.936577 -305.467907)
		(end 285.973774 -305.378104)
		(width 0.1016)
		(layer "In7.Cu")
		(net "PHY_DRV_A_TO_SCC_A_29_DP")
	)
	(arc
		(start 190.360554 -47.915068)
		(mid 190.288712 -47.944826)
		(end 190.258954 -48.016668)
		(width 0.1016)
		(layer "In7.Cu")
		(net "PHY_DRV_A_TO_SCC_A_29_DP")
	)
	(segment
		(start 189.363604 -47.603918)
		(end 189.236604 -47.476918)
		(width 0.127)
		(layer "F.Cu")
		(net "PHY_DRV_A_TO_SCC_A_29_DN")
	)
	(segment
		(start 190.258954 -47.178468)
		(end 190.258954 -47.476918)
		(width 0.127)
		(layer "F.Cu")
		(net "PHY_DRV_A_TO_SCC_A_29_DN")
	)
	(segment
		(start 189.236604 -47.476918)
		(end 189.236604 -47.241968)
		(width 0.127)
		(layer "F.Cu")
		(net "PHY_DRV_A_TO_SCC_A_29_DN")
	)
	(segment
		(start 189.236604 -47.241968)
		(end 189.109604 -47.114968)
		(width 0.127)
		(layer "F.Cu")
		(net "PHY_DRV_A_TO_SCC_A_29_DN")
	)
	(segment
		(start 190.131954 -47.603918)
		(end 189.363604 -47.603918)
		(width 0.127)
		(layer "F.Cu")
		(net "PHY_DRV_A_TO_SCC_A_29_DN")
	)
	(segment
		(start 189.109604 -47.114968)
		(end 187.775088 -47.114968)
		(width 0.127)
		(layer "F.Cu")
		(net "PHY_DRV_A_TO_SCC_A_29_DN")
	)
	(arc
		(start 190.258954 -47.476918)
		(mid 190.221757 -47.566721)
		(end 190.131954 -47.603918)
		(width 0.127)
		(layer "F.Cu")
		(net "PHY_DRV_A_TO_SCC_A_29_DN")
	)
	(segment
		(start 192.171828 -48.531272)
		(end 191.845946 -48.040798)
		(width 0.1016)
		(layer "In7.Cu")
		(net "PHY_DRV_A_TO_SCC_A_29_DN")
	)
	(segment
		(start 218.009978 -188.684916)
		(end 189.664594 -76.124308)
		(width 0.1016)
		(layer "In7.Cu")
		(net "PHY_DRV_A_TO_SCC_A_29_DN")
	)
	(segment
		(start 213.785704 -205.816708)
		(end 215.888062 -197.290944)
		(width 0.1016)
		(layer "In7.Cu")
		(net "PHY_DRV_A_TO_SCC_A_29_DN")
	)
	(segment
		(start 286.836612 -305.505104)
		(end 286.430974 -305.505104)
		(width 0.1016)
		(layer "In7.Cu")
		(net "PHY_DRV_A_TO_SCC_A_29_DN")
	)
	(segment
		(start 285.809182 -304.440082)
		(end 273.910806 -304.440082)
		(width 0.1016)
		(layer "In7.Cu")
		(net "PHY_DRV_A_TO_SCC_A_29_DN")
	)
	(segment
		(start 230.59136 -272.881344)
		(end 215.723724 -213.549484)
		(width 0.1016)
		(layer "In7.Cu")
		(net "PHY_DRV_A_TO_SCC_A_29_DN")
	)
	(segment
		(start 213.785958 -205.816962)
		(end 213.785704 -205.816708)
		(width 0.1016)
		(layer "In7.Cu")
		(net "PHY_DRV_A_TO_SCC_A_29_DN")
	)
	(segment
		(start 215.888062 -197.290944)
		(end 218.009978 -188.684916)
		(width 0.1016)
		(layer "In7.Cu")
		(net "PHY_DRV_A_TO_SCC_A_29_DN")
	)
	(segment
		(start 194.558666 -60.41644)
		(end 192.171828 -48.531272)
		(width 0.1016)
		(layer "In7.Cu")
		(net "PHY_DRV_A_TO_SCC_A_29_DN")
	)
	(segment
		(start 191.040512 -47.584868)
		(end 190.360554 -47.584868)
		(width 0.1016)
		(layer "In7.Cu")
		(net "PHY_DRV_A_TO_SCC_A_29_DN")
	)
	(segment
		(start 191.845946 -48.040798)
		(end 191.040512 -47.584868)
		(width 0.1016)
		(layer "In7.Cu")
		(net "PHY_DRV_A_TO_SCC_A_29_DN")
	)
	(segment
		(start 235.592366 -283.12237)
		(end 230.59136 -272.881344)
		(width 0.1016)
		(layer "In7.Cu")
		(net "PHY_DRV_A_TO_SCC_A_29_DN")
	)
	(segment
		(start 213.785704 -205.816962)
		(end 213.785958 -205.816962)
		(width 0.1016)
		(layer "In7.Cu")
		(net "PHY_DRV_A_TO_SCC_A_29_DN")
	)
	(segment
		(start 273.910806 -304.440082)
		(end 235.592366 -283.12237)
		(width 0.1016)
		(layer "In7.Cu")
		(net "PHY_DRV_A_TO_SCC_A_29_DN")
	)
	(segment
		(start 190.258954 -47.483268)
		(end 190.258954 -47.178468)
		(width 0.1016)
		(layer "In7.Cu")
		(net "PHY_DRV_A_TO_SCC_A_29_DN")
	)
	(segment
		(start 215.723724 -213.549484)
		(end 213.785704 -205.816962)
		(width 0.1016)
		(layer "In7.Cu")
		(net "PHY_DRV_A_TO_SCC_A_29_DN")
	)
	(segment
		(start 286.303974 -305.378104)
		(end 286.303974 -304.934874)
		(width 0.1016)
		(layer "In7.Cu")
		(net "PHY_DRV_A_TO_SCC_A_29_DN")
	)
	(segment
		(start 189.664594 -76.124308)
		(end 194.558666 -60.41644)
		(width 0.1016)
		(layer "In7.Cu")
		(net "PHY_DRV_A_TO_SCC_A_29_DN")
	)
	(arc
		(start 286.303974 -304.934874)
		(mid 286.159053 -304.585003)
		(end 285.809182 -304.440082)
		(width 0.1016)
		(layer "In7.Cu")
		(net "PHY_DRV_A_TO_SCC_A_29_DN")
	)
	(arc
		(start 286.430974 -305.505104)
		(mid 286.341171 -305.467907)
		(end 286.303974 -305.378104)
		(width 0.1016)
		(layer "In7.Cu")
		(net "PHY_DRV_A_TO_SCC_A_29_DN")
	)
	(arc
		(start 190.360554 -47.584868)
		(mid 190.288712 -47.55511)
		(end 190.258954 -47.483268)
		(width 0.1016)
		(layer "In7.Cu")
		(net "PHY_DRV_A_TO_SCC_A_29_DN")
	)
	(segment
		(start 158.708852 -48.321468)
		(end 158.708852 -48.023018)
		(width 0.127)
		(layer "F.Cu")
		(net "PHY_DRV_A_TO_SCC_A_28_DP")
	)
	(segment
		(start 157.686502 -48.040798)
		(end 157.686502 -48.257968)
		(width 0.127)
		(layer "F.Cu")
		(net "PHY_DRV_A_TO_SCC_A_28_DP")
	)
	(segment
		(start 157.559502 -48.384968)
		(end 156.224986 -48.384968)
		(width 0.127)
		(layer "F.Cu")
		(net "PHY_DRV_A_TO_SCC_A_28_DP")
	)
	(segment
		(start 157.686502 -48.257968)
		(end 157.559502 -48.384968)
		(width 0.127)
		(layer "F.Cu")
		(net "PHY_DRV_A_TO_SCC_A_28_DP")
	)
	(segment
		(start 157.831282 -47.896018)
		(end 157.686502 -48.040798)
		(width 0.127)
		(layer "F.Cu")
		(net "PHY_DRV_A_TO_SCC_A_28_DP")
	)
	(segment
		(start 158.581852 -47.896018)
		(end 157.831282 -47.896018)
		(width 0.127)
		(layer "F.Cu")
		(net "PHY_DRV_A_TO_SCC_A_28_DP")
	)
	(arc
		(start 158.708852 -48.023018)
		(mid 158.671655 -47.933215)
		(end 158.581852 -47.896018)
		(width 0.127)
		(layer "F.Cu")
		(net "PHY_DRV_A_TO_SCC_A_28_DP")
	)
	(segment
		(start 270.619474 -304.459386)
		(end 270.353028 -304.311304)
		(width 0.1016)
		(layer "In7.Cu")
		(net "PHY_DRV_A_TO_SCC_A_28_DP")
	)
	(segment
		(start 160.852612 -48.468534)
		(end 159.87522 -47.915068)
		(width 0.1016)
		(layer "In7.Cu")
		(net "PHY_DRV_A_TO_SCC_A_28_DP")
	)
	(segment
		(start 270.969486 -304.901346)
		(end 270.70304 -304.75301)
		(width 0.1016)
		(layer "In7.Cu")
		(net "PHY_DRV_A_TO_SCC_A_28_DP")
	)
	(segment
		(start 228.103684 -271.84985)
		(end 211.693506 -206.36865)
		(width 0.1016)
		(layer "In7.Cu")
		(net "PHY_DRV_A_TO_SCC_A_28_DP")
	)
	(segment
		(start 269.709392 -303.953164)
		(end 234.107482 -284.145228)
		(width 0.1016)
		(layer "In7.Cu")
		(net "PHY_DRV_A_TO_SCC_A_28_DP")
	)
	(segment
		(start 286.973772 -307.178202)
		(end 286.973772 -306.734972)
		(width 0.1016)
		(layer "In7.Cu")
		(net "PHY_DRV_A_TO_SCC_A_28_DP")
	)
	(segment
		(start 270.353028 -304.311304)
		(end 270.059404 -304.39487)
		(width 0.1016)
		(layer "In7.Cu")
		(net "PHY_DRV_A_TO_SCC_A_28_DP")
	)
	(segment
		(start 274.413472 -306.57038)
		(end 272.173192 -305.324002)
		(width 0.1016)
		(layer "In7.Cu")
		(net "PHY_DRV_A_TO_SCC_A_28_DP")
	)
	(segment
		(start 270.059404 -304.39487)
		(end 269.792958 -304.246788)
		(width 0.1016)
		(layer "In7.Cu")
		(net "PHY_DRV_A_TO_SCC_A_28_DP")
	)
	(segment
		(start 158.708852 -48.016668)
		(end 158.708852 -48.321468)
		(width 0.1016)
		(layer "In7.Cu")
		(net "PHY_DRV_A_TO_SCC_A_28_DP")
	)
	(segment
		(start 270.70304 -304.75301)
		(end 270.619474 -304.459386)
		(width 0.1016)
		(layer "In7.Cu")
		(net "PHY_DRV_A_TO_SCC_A_28_DP")
	)
	(segment
		(start 234.107482 -284.145228)
		(end 228.103684 -271.84985)
		(width 0.1016)
		(layer "In7.Cu")
		(net "PHY_DRV_A_TO_SCC_A_28_DP")
	)
	(segment
		(start 159.87522 -47.915068)
		(end 158.810452 -47.915068)
		(width 0.1016)
		(layer "In7.Cu")
		(net "PHY_DRV_A_TO_SCC_A_28_DP")
	)
	(segment
		(start 216.290652 -187.744354)
		(end 192.27927 -91.908376)
		(width 0.1016)
		(layer "In7.Cu")
		(net "PHY_DRV_A_TO_SCC_A_28_DP")
	)
	(segment
		(start 286.80918 -306.57038)
		(end 274.413472 -306.57038)
		(width 0.1016)
		(layer "In7.Cu")
		(net "PHY_DRV_A_TO_SCC_A_28_DP")
	)
	(segment
		(start 271.529302 -304.965862)
		(end 271.26311 -304.817526)
		(width 0.1016)
		(layer "In7.Cu")
		(net "PHY_DRV_A_TO_SCC_A_28_DP")
	)
	(segment
		(start 272.173192 -305.324002)
		(end 271.879568 -305.407568)
		(width 0.1016)
		(layer "In7.Cu")
		(net "PHY_DRV_A_TO_SCC_A_28_DP")
	)
	(segment
		(start 269.792958 -304.246788)
		(end 269.709392 -303.953164)
		(width 0.1016)
		(layer "In7.Cu")
		(net "PHY_DRV_A_TO_SCC_A_28_DP")
	)
	(segment
		(start 192.27927 -91.908376)
		(end 160.852612 -48.468534)
		(width 0.1016)
		(layer "In7.Cu")
		(net "PHY_DRV_A_TO_SCC_A_28_DP")
	)
	(segment
		(start 271.879568 -305.407568)
		(end 271.613122 -305.259486)
		(width 0.1016)
		(layer "In7.Cu")
		(net "PHY_DRV_A_TO_SCC_A_28_DP")
	)
	(segment
		(start 211.693506 -206.36865)
		(end 216.290652 -187.744354)
		(width 0.1016)
		(layer "In7.Cu")
		(net "PHY_DRV_A_TO_SCC_A_28_DP")
	)
	(segment
		(start 286.436562 -307.305202)
		(end 286.846772 -307.305202)
		(width 0.1016)
		(layer "In7.Cu")
		(net "PHY_DRV_A_TO_SCC_A_28_DP")
	)
	(segment
		(start 271.26311 -304.817526)
		(end 270.969486 -304.901346)
		(width 0.1016)
		(layer "In7.Cu")
		(net "PHY_DRV_A_TO_SCC_A_28_DP")
	)
	(segment
		(start 271.613122 -305.259486)
		(end 271.529302 -304.965862)
		(width 0.1016)
		(layer "In7.Cu")
		(net "PHY_DRV_A_TO_SCC_A_28_DP")
	)
	(arc
		(start 286.973772 -306.734972)
		(mid 286.925564 -306.618588)
		(end 286.80918 -306.57038)
		(width 0.1016)
		(layer "In7.Cu")
		(net "PHY_DRV_A_TO_SCC_A_28_DP")
	)
	(arc
		(start 158.810452 -47.915068)
		(mid 158.73861 -47.944826)
		(end 158.708852 -48.016668)
		(width 0.1016)
		(layer "In7.Cu")
		(net "PHY_DRV_A_TO_SCC_A_28_DP")
	)
	(arc
		(start 286.846772 -307.305202)
		(mid 286.936575 -307.268005)
		(end 286.973772 -307.178202)
		(width 0.1016)
		(layer "In7.Cu")
		(net "PHY_DRV_A_TO_SCC_A_28_DP")
	)
	(segment
		(start 157.686502 -47.241968)
		(end 157.559502 -47.114968)
		(width 0.127)
		(layer "F.Cu")
		(net "PHY_DRV_A_TO_SCC_A_28_DN")
	)
	(segment
		(start 157.559502 -47.114968)
		(end 156.224986 -47.114968)
		(width 0.127)
		(layer "F.Cu")
		(net "PHY_DRV_A_TO_SCC_A_28_DN")
	)
	(segment
		(start 157.686502 -47.476918)
		(end 157.686502 -47.241968)
		(width 0.127)
		(layer "F.Cu")
		(net "PHY_DRV_A_TO_SCC_A_28_DN")
	)
	(segment
		(start 157.813502 -47.603918)
		(end 157.686502 -47.476918)
		(width 0.127)
		(layer "F.Cu")
		(net "PHY_DRV_A_TO_SCC_A_28_DN")
	)
	(segment
		(start 158.581852 -47.603918)
		(end 157.813502 -47.603918)
		(width 0.127)
		(layer "F.Cu")
		(net "PHY_DRV_A_TO_SCC_A_28_DN")
	)
	(segment
		(start 158.708852 -47.178468)
		(end 158.708852 -47.476918)
		(width 0.127)
		(layer "F.Cu")
		(net "PHY_DRV_A_TO_SCC_A_28_DN")
	)
	(arc
		(start 158.708852 -47.476918)
		(mid 158.671655 -47.566721)
		(end 158.581852 -47.603918)
		(width 0.127)
		(layer "F.Cu")
		(net "PHY_DRV_A_TO_SCC_A_28_DN")
	)
	(segment
		(start 286.80918 -306.24018)
		(end 274.499324 -306.24018)
		(width 0.1016)
		(layer "In7.Cu")
		(net "PHY_DRV_A_TO_SCC_A_28_DN")
	)
	(segment
		(start 161.07791 -48.216566)
		(end 159.962342 -47.584868)
		(width 0.1016)
		(layer "In7.Cu")
		(net "PHY_DRV_A_TO_SCC_A_28_DN")
	)
	(segment
		(start 228.415596 -271.736058)
		(end 220.225112 -239.0521)
		(width 0.1016)
		(layer "In7.Cu")
		(net "PHY_DRV_A_TO_SCC_A_28_DN")
	)
	(segment
		(start 274.499324 -306.24018)
		(end 234.358942 -283.906976)
		(width 0.1016)
		(layer "In7.Cu")
		(net "PHY_DRV_A_TO_SCC_A_28_DN")
	)
	(segment
		(start 287.303972 -307.178202)
		(end 287.303972 -306.734972)
		(width 0.1016)
		(layer "In7.Cu")
		(net "PHY_DRV_A_TO_SCC_A_28_DN")
	)
	(segment
		(start 216.631012 -187.743846)
		(end 192.584324 -91.76639)
		(width 0.1016)
		(layer "In7.Cu")
		(net "PHY_DRV_A_TO_SCC_A_28_DN")
	)
	(segment
		(start 158.708852 -47.483268)
		(end 158.708852 -47.178468)
		(width 0.1016)
		(layer "In7.Cu")
		(net "PHY_DRV_A_TO_SCC_A_28_DN")
	)
	(segment
		(start 192.584324 -91.76639)
		(end 161.07791 -48.216566)
		(width 0.1016)
		(layer "In7.Cu")
		(net "PHY_DRV_A_TO_SCC_A_28_DN")
	)
	(segment
		(start 287.83661 -307.305202)
		(end 287.430972 -307.305202)
		(width 0.1016)
		(layer "In7.Cu")
		(net "PHY_DRV_A_TO_SCC_A_28_DN")
	)
	(segment
		(start 220.225112 -239.0521)
		(end 212.033866 -206.368142)
		(width 0.1016)
		(layer "In7.Cu")
		(net "PHY_DRV_A_TO_SCC_A_28_DN")
	)
	(segment
		(start 159.962342 -47.584868)
		(end 158.810452 -47.584868)
		(width 0.1016)
		(layer "In7.Cu")
		(net "PHY_DRV_A_TO_SCC_A_28_DN")
	)
	(segment
		(start 234.358942 -283.906976)
		(end 228.415596 -271.736058)
		(width 0.1016)
		(layer "In7.Cu")
		(net "PHY_DRV_A_TO_SCC_A_28_DN")
	)
	(segment
		(start 212.033866 -206.368142)
		(end 216.631012 -187.743846)
		(width 0.1016)
		(layer "In7.Cu")
		(net "PHY_DRV_A_TO_SCC_A_28_DN")
	)
	(arc
		(start 158.810452 -47.584868)
		(mid 158.73861 -47.55511)
		(end 158.708852 -47.483268)
		(width 0.1016)
		(layer "In7.Cu")
		(net "PHY_DRV_A_TO_SCC_A_28_DN")
	)
	(arc
		(start 287.430972 -307.305202)
		(mid 287.341169 -307.268005)
		(end 287.303972 -307.178202)
		(width 0.1016)
		(layer "In7.Cu")
		(net "PHY_DRV_A_TO_SCC_A_28_DN")
	)
	(arc
		(start 287.303972 -306.734972)
		(mid 287.159051 -306.385101)
		(end 286.80918 -306.24018)
		(width 0.1016)
		(layer "In7.Cu")
		(net "PHY_DRV_A_TO_SCC_A_28_DN")
	)
	(segment
		(start 126.2634 -47.896018)
		(end 126.1364 -48.023018)
		(width 0.127)
		(layer "F.Cu")
		(net "PHY_DRV_A_TO_SCC_A_27_DP")
	)
	(segment
		(start 126.0094 -48.384968)
		(end 124.674884 -48.384968)
		(width 0.127)
		(layer "F.Cu")
		(net "PHY_DRV_A_TO_SCC_A_27_DP")
	)
	(segment
		(start 127.03175 -47.896018)
		(end 126.2634 -47.896018)
		(width 0.127)
		(layer "F.Cu")
		(net "PHY_DRV_A_TO_SCC_A_27_DP")
	)
	(segment
		(start 127.15875 -48.321468)
		(end 127.15875 -48.023018)
		(width 0.127)
		(layer "F.Cu")
		(net "PHY_DRV_A_TO_SCC_A_27_DP")
	)
	(segment
		(start 126.1364 -48.257968)
		(end 126.0094 -48.384968)
		(width 0.127)
		(layer "F.Cu")
		(net "PHY_DRV_A_TO_SCC_A_27_DP")
	)
	(segment
		(start 126.1364 -48.023018)
		(end 126.1364 -48.257968)
		(width 0.127)
		(layer "F.Cu")
		(net "PHY_DRV_A_TO_SCC_A_27_DP")
	)
	(arc
		(start 127.15875 -48.023018)
		(mid 127.121553 -47.933215)
		(end 127.03175 -47.896018)
		(width 0.127)
		(layer "F.Cu")
		(net "PHY_DRV_A_TO_SCC_A_27_DP")
	)
	(segment
		(start 268.3764 -307.288692)
		(end 268.109954 -307.14061)
		(width 0.1016)
		(layer "In7.Cu")
		(net "PHY_DRV_A_TO_SCC_A_27_DP")
	)
	(segment
		(start 155.941268 -73.727564)
		(end 136.123426 -60.85713)
		(width 0.1016)
		(layer "In7.Cu")
		(net "PHY_DRV_A_TO_SCC_A_27_DP")
	)
	(segment
		(start 136.123426 -60.85713)
		(end 128.284732 -48.17618)
		(width 0.1016)
		(layer "In7.Cu")
		(net "PHY_DRV_A_TO_SCC_A_27_DP")
	)
	(segment
		(start 285.809182 -308.370224)
		(end 270.764508 -308.370224)
		(width 0.1016)
		(layer "In7.Cu")
		(net "PHY_DRV_A_TO_SCC_A_27_DP")
	)
	(segment
		(start 268.026388 -306.846986)
		(end 267.759942 -306.69865)
		(width 0.1016)
		(layer "In7.Cu")
		(net "PHY_DRV_A_TO_SCC_A_27_DP")
	)
	(segment
		(start 268.670024 -307.204872)
		(end 268.3764 -307.288692)
		(width 0.1016)
		(layer "In7.Cu")
		(net "PHY_DRV_A_TO_SCC_A_27_DP")
	)
	(segment
		(start 269.020036 -307.646832)
		(end 268.93647 -307.353208)
		(width 0.1016)
		(layer "In7.Cu")
		(net "PHY_DRV_A_TO_SCC_A_27_DP")
	)
	(segment
		(start 127.856234 -47.915068)
		(end 127.26035 -47.915068)
		(width 0.1016)
		(layer "In7.Cu")
		(net "PHY_DRV_A_TO_SCC_A_27_DP")
	)
	(segment
		(start 270.764508 -308.370224)
		(end 269.580106 -307.711348)
		(width 0.1016)
		(layer "In7.Cu")
		(net "PHY_DRV_A_TO_SCC_A_27_DP")
	)
	(segment
		(start 269.580106 -307.711348)
		(end 269.286482 -307.794914)
		(width 0.1016)
		(layer "In7.Cu")
		(net "PHY_DRV_A_TO_SCC_A_27_DP")
	)
	(segment
		(start 285.436564 -309.105046)
		(end 285.846774 -309.105046)
		(width 0.1016)
		(layer "In7.Cu")
		(net "PHY_DRV_A_TO_SCC_A_27_DP")
	)
	(segment
		(start 233.86542 -287.841944)
		(end 225.52025 -270.753586)
		(width 0.1016)
		(layer "In7.Cu")
		(net "PHY_DRV_A_TO_SCC_A_27_DP")
	)
	(segment
		(start 285.973774 -308.978046)
		(end 285.973774 -308.534816)
		(width 0.1016)
		(layer "In7.Cu")
		(net "PHY_DRV_A_TO_SCC_A_27_DP")
	)
	(segment
		(start 269.286482 -307.794914)
		(end 269.020036 -307.646832)
		(width 0.1016)
		(layer "In7.Cu")
		(net "PHY_DRV_A_TO_SCC_A_27_DP")
	)
	(segment
		(start 268.93647 -307.353208)
		(end 268.670024 -307.204872)
		(width 0.1016)
		(layer "In7.Cu")
		(net "PHY_DRV_A_TO_SCC_A_27_DP")
	)
	(segment
		(start 268.109954 -307.14061)
		(end 268.026388 -306.846986)
		(width 0.1016)
		(layer "In7.Cu")
		(net "PHY_DRV_A_TO_SCC_A_27_DP")
	)
	(segment
		(start 267.116306 -306.34051)
		(end 233.86542 -287.841944)
		(width 0.1016)
		(layer "In7.Cu")
		(net "PHY_DRV_A_TO_SCC_A_27_DP")
	)
	(segment
		(start 202.075288 -135.798052)
		(end 155.941268 -73.727564)
		(width 0.1016)
		(layer "In7.Cu")
		(net "PHY_DRV_A_TO_SCC_A_27_DP")
	)
	(segment
		(start 127.15875 -48.016668)
		(end 127.15875 -48.321468)
		(width 0.1016)
		(layer "In7.Cu")
		(net "PHY_DRV_A_TO_SCC_A_27_DP")
	)
	(segment
		(start 267.200126 -306.634134)
		(end 267.116306 -306.34051)
		(width 0.1016)
		(layer "In7.Cu")
		(net "PHY_DRV_A_TO_SCC_A_27_DP")
	)
	(segment
		(start 267.759942 -306.69865)
		(end 267.466318 -306.78247)
		(width 0.1016)
		(layer "In7.Cu")
		(net "PHY_DRV_A_TO_SCC_A_27_DP")
	)
	(segment
		(start 128.284732 -48.17618)
		(end 127.856234 -47.915068)
		(width 0.1016)
		(layer "In7.Cu")
		(net "PHY_DRV_A_TO_SCC_A_27_DP")
	)
	(segment
		(start 225.52025 -270.753586)
		(end 209.537808 -206.978758)
		(width 0.1016)
		(layer "In7.Cu")
		(net "PHY_DRV_A_TO_SCC_A_27_DP")
	)
	(segment
		(start 214.684356 -186.128152)
		(end 202.075288 -135.798052)
		(width 0.1016)
		(layer "In7.Cu")
		(net "PHY_DRV_A_TO_SCC_A_27_DP")
	)
	(segment
		(start 267.466318 -306.78247)
		(end 267.200126 -306.634134)
		(width 0.1016)
		(layer "In7.Cu")
		(net "PHY_DRV_A_TO_SCC_A_27_DP")
	)
	(segment
		(start 209.537808 -206.978758)
		(end 214.684356 -186.128152)
		(width 0.1016)
		(layer "In7.Cu")
		(net "PHY_DRV_A_TO_SCC_A_27_DP")
	)
	(arc
		(start 127.26035 -47.915068)
		(mid 127.188508 -47.944826)
		(end 127.15875 -48.016668)
		(width 0.1016)
		(layer "In7.Cu")
		(net "PHY_DRV_A_TO_SCC_A_27_DP")
	)
	(arc
		(start 285.846774 -309.105046)
		(mid 285.936577 -309.067849)
		(end 285.973774 -308.978046)
		(width 0.1016)
		(layer "In7.Cu")
		(net "PHY_DRV_A_TO_SCC_A_27_DP")
	)
	(arc
		(start 285.973774 -308.534816)
		(mid 285.925566 -308.418432)
		(end 285.809182 -308.370224)
		(width 0.1016)
		(layer "In7.Cu")
		(net "PHY_DRV_A_TO_SCC_A_27_DP")
	)
	(segment
		(start 126.1364 -47.241968)
		(end 126.0094 -47.114968)
		(width 0.127)
		(layer "F.Cu")
		(net "PHY_DRV_A_TO_SCC_A_27_DN")
	)
	(segment
		(start 126.1364 -47.476918)
		(end 126.1364 -47.241968)
		(width 0.127)
		(layer "F.Cu")
		(net "PHY_DRV_A_TO_SCC_A_27_DN")
	)
	(segment
		(start 127.03175 -47.603918)
		(end 126.2634 -47.603918)
		(width 0.127)
		(layer "F.Cu")
		(net "PHY_DRV_A_TO_SCC_A_27_DN")
	)
	(segment
		(start 127.15875 -47.178468)
		(end 127.15875 -47.476918)
		(width 0.127)
		(layer "F.Cu")
		(net "PHY_DRV_A_TO_SCC_A_27_DN")
	)
	(segment
		(start 126.2634 -47.603918)
		(end 126.1364 -47.476918)
		(width 0.127)
		(layer "F.Cu")
		(net "PHY_DRV_A_TO_SCC_A_27_DN")
	)
	(segment
		(start 126.0094 -47.114968)
		(end 124.674884 -47.114968)
		(width 0.127)
		(layer "F.Cu")
		(net "PHY_DRV_A_TO_SCC_A_27_DN")
	)
	(arc
		(start 127.15875 -47.476918)
		(mid 127.121553 -47.566721)
		(end 127.03175 -47.603918)
		(width 0.127)
		(layer "F.Cu")
		(net "PHY_DRV_A_TO_SCC_A_27_DN")
	)
	(segment
		(start 202.379834 -135.65378)
		(end 215.024716 -186.127644)
		(width 0.1016)
		(layer "In7.Cu")
		(net "PHY_DRV_A_TO_SCC_A_27_DN")
	)
	(segment
		(start 136.365488 -60.620402)
		(end 156.171138 -73.482708)
		(width 0.1016)
		(layer "In7.Cu")
		(net "PHY_DRV_A_TO_SCC_A_27_DN")
	)
	(segment
		(start 225.832162 -270.639794)
		(end 234.11688 -287.603692)
		(width 0.1016)
		(layer "In7.Cu")
		(net "PHY_DRV_A_TO_SCC_A_27_DN")
	)
	(segment
		(start 270.85036 -308.040024)
		(end 285.809182 -308.040024)
		(width 0.1016)
		(layer "In7.Cu")
		(net "PHY_DRV_A_TO_SCC_A_27_DN")
	)
	(segment
		(start 209.878168 -206.97825)
		(end 217.855292 -238.809022)
		(width 0.1016)
		(layer "In7.Cu")
		(net "PHY_DRV_A_TO_SCC_A_27_DN")
	)
	(segment
		(start 127.26035 -47.584868)
		(end 127.948944 -47.584868)
		(width 0.1016)
		(layer "In7.Cu")
		(net "PHY_DRV_A_TO_SCC_A_27_DN")
	)
	(segment
		(start 128.524254 -47.935134)
		(end 136.365488 -60.620402)
		(width 0.1016)
		(layer "In7.Cu")
		(net "PHY_DRV_A_TO_SCC_A_27_DN")
	)
	(segment
		(start 217.855292 -238.809022)
		(end 225.832162 -270.639794)
		(width 0.1016)
		(layer "In7.Cu")
		(net "PHY_DRV_A_TO_SCC_A_27_DN")
	)
	(segment
		(start 127.948944 -47.584868)
		(end 128.524254 -47.935134)
		(width 0.1016)
		(layer "In7.Cu")
		(net "PHY_DRV_A_TO_SCC_A_27_DN")
	)
	(segment
		(start 234.11688 -287.603692)
		(end 270.85036 -308.040024)
		(width 0.1016)
		(layer "In7.Cu")
		(net "PHY_DRV_A_TO_SCC_A_27_DN")
	)
	(segment
		(start 179.273454 -104.56545)
		(end 202.379834 -135.65378)
		(width 0.1016)
		(layer "In7.Cu")
		(net "PHY_DRV_A_TO_SCC_A_27_DN")
	)
	(segment
		(start 127.15875 -47.178468)
		(end 127.15875 -47.483268)
		(width 0.1016)
		(layer "In7.Cu")
		(net "PHY_DRV_A_TO_SCC_A_27_DN")
	)
	(segment
		(start 215.024716 -186.127644)
		(end 209.878168 -206.97825)
		(width 0.1016)
		(layer "In7.Cu")
		(net "PHY_DRV_A_TO_SCC_A_27_DN")
	)
	(segment
		(start 156.171138 -73.482708)
		(end 179.273454 -104.56545)
		(width 0.1016)
		(layer "In7.Cu")
		(net "PHY_DRV_A_TO_SCC_A_27_DN")
	)
	(segment
		(start 286.303974 -308.534816)
		(end 286.303974 -308.978046)
		(width 0.1016)
		(layer "In7.Cu")
		(net "PHY_DRV_A_TO_SCC_A_27_DN")
	)
	(segment
		(start 286.430974 -309.105046)
		(end 286.836612 -309.105046)
		(width 0.1016)
		(layer "In7.Cu")
		(net "PHY_DRV_A_TO_SCC_A_27_DN")
	)
	(arc
		(start 286.303974 -308.978046)
		(mid 286.341171 -309.067849)
		(end 286.430974 -309.105046)
		(width 0.1016)
		(layer "In7.Cu")
		(net "PHY_DRV_A_TO_SCC_A_27_DN")
	)
	(arc
		(start 127.15875 -47.483268)
		(mid 127.188508 -47.55511)
		(end 127.26035 -47.584868)
		(width 0.1016)
		(layer "In7.Cu")
		(net "PHY_DRV_A_TO_SCC_A_27_DN")
	)
	(arc
		(start 285.809182 -308.040024)
		(mid 286.159053 -308.184945)
		(end 286.303974 -308.534816)
		(width 0.1016)
		(layer "In7.Cu")
		(net "PHY_DRV_A_TO_SCC_A_27_DN")
	)
	(segment
		(start 95.481902 -47.896018)
		(end 94.713552 -47.896018)
		(width 0.127)
		(layer "F.Cu")
		(net "PHY_DRV_A_TO_SCC_A_26_DP")
	)
	(segment
		(start 94.586552 -48.257968)
		(end 94.459552 -48.384968)
		(width 0.127)
		(layer "F.Cu")
		(net "PHY_DRV_A_TO_SCC_A_26_DP")
	)
	(segment
		(start 94.713552 -47.896018)
		(end 94.586552 -48.023018)
		(width 0.127)
		(layer "F.Cu")
		(net "PHY_DRV_A_TO_SCC_A_26_DP")
	)
	(segment
		(start 95.608902 -48.321468)
		(end 95.608902 -48.023018)
		(width 0.127)
		(layer "F.Cu")
		(net "PHY_DRV_A_TO_SCC_A_26_DP")
	)
	(segment
		(start 94.459552 -48.384968)
		(end 93.125036 -48.384968)
		(width 0.127)
		(layer "F.Cu")
		(net "PHY_DRV_A_TO_SCC_A_26_DP")
	)
	(segment
		(start 94.586552 -48.023018)
		(end 94.586552 -48.257968)
		(width 0.127)
		(layer "F.Cu")
		(net "PHY_DRV_A_TO_SCC_A_26_DP")
	)
	(arc
		(start 95.608902 -48.023018)
		(mid 95.571705 -47.933215)
		(end 95.481902 -47.896018)
		(width 0.127)
		(layer "F.Cu")
		(net "PHY_DRV_A_TO_SCC_A_26_DP")
	)
	(segment
		(start 286.973772 -310.778144)
		(end 286.973772 -310.334914)
		(width 0.1016)
		(layer "In7.Cu")
		(net "PHY_DRV_A_TO_SCC_A_26_DP")
	)
	(segment
		(start 269.56639 -309.457344)
		(end 269.272766 -309.54091)
		(width 0.1016)
		(layer "In7.Cu")
		(net "PHY_DRV_A_TO_SCC_A_26_DP")
	)
	(segment
		(start 267.10259 -308.086506)
		(end 232.640886 -288.915856)
		(width 0.1016)
		(layer "In7.Cu")
		(net "PHY_DRV_A_TO_SCC_A_26_DP")
	)
	(segment
		(start 267.746226 -308.444646)
		(end 267.452602 -308.528466)
		(width 0.1016)
		(layer "In7.Cu")
		(net "PHY_DRV_A_TO_SCC_A_26_DP")
	)
	(segment
		(start 268.012672 -308.592982)
		(end 267.746226 -308.444646)
		(width 0.1016)
		(layer "In7.Cu")
		(net "PHY_DRV_A_TO_SCC_A_26_DP")
	)
	(segment
		(start 268.922754 -309.099204)
		(end 268.656308 -308.950868)
		(width 0.1016)
		(layer "In7.Cu")
		(net "PHY_DRV_A_TO_SCC_A_26_DP")
	)
	(segment
		(start 267.18641 -308.38013)
		(end 267.10259 -308.086506)
		(width 0.1016)
		(layer "In7.Cu")
		(net "PHY_DRV_A_TO_SCC_A_26_DP")
	)
	(segment
		(start 97.47504 -48.435514)
		(end 96.556068 -47.915068)
		(width 0.1016)
		(layer "In7.Cu")
		(net "PHY_DRV_A_TO_SCC_A_26_DP")
	)
	(segment
		(start 286.80918 -310.170322)
		(end 270.848328 -310.170322)
		(width 0.1016)
		(layer "In7.Cu")
		(net "PHY_DRV_A_TO_SCC_A_26_DP")
	)
	(segment
		(start 212.95741 -184.650634)
		(end 201.554842 -140.20292)
		(width 0.1016)
		(layer "In7.Cu")
		(net "PHY_DRV_A_TO_SCC_A_26_DP")
	)
	(segment
		(start 159.748474 -110.075472)
		(end 117.941344 -79.948024)
		(width 0.1016)
		(layer "In7.Cu")
		(net "PHY_DRV_A_TO_SCC_A_26_DP")
	)
	(segment
		(start 269.006574 -309.392828)
		(end 268.922754 -309.099204)
		(width 0.1016)
		(layer "In7.Cu")
		(net "PHY_DRV_A_TO_SCC_A_26_DP")
	)
	(segment
		(start 232.640886 -288.915856)
		(end 222.523304 -268.200632)
		(width 0.1016)
		(layer "In7.Cu")
		(net "PHY_DRV_A_TO_SCC_A_26_DP")
	)
	(segment
		(start 269.272766 -309.54091)
		(end 269.006574 -309.392828)
		(width 0.1016)
		(layer "In7.Cu")
		(net "PHY_DRV_A_TO_SCC_A_26_DP")
	)
	(segment
		(start 201.554842 -140.20292)
		(end 159.748474 -110.075472)
		(width 0.1016)
		(layer "In7.Cu")
		(net "PHY_DRV_A_TO_SCC_A_26_DP")
	)
	(segment
		(start 95.608902 -48.016668)
		(end 95.608902 -48.321468)
		(width 0.1016)
		(layer "In7.Cu")
		(net "PHY_DRV_A_TO_SCC_A_26_DP")
	)
	(segment
		(start 96.556068 -47.915068)
		(end 95.710502 -47.915068)
		(width 0.1016)
		(layer "In7.Cu")
		(net "PHY_DRV_A_TO_SCC_A_26_DP")
	)
	(segment
		(start 286.436562 -310.905144)
		(end 286.846772 -310.905144)
		(width 0.1016)
		(layer "In7.Cu")
		(net "PHY_DRV_A_TO_SCC_A_26_DP")
	)
	(segment
		(start 222.523304 -268.200632)
		(end 207.47355 -208.447386)
		(width 0.1016)
		(layer "In7.Cu")
		(net "PHY_DRV_A_TO_SCC_A_26_DP")
	)
	(segment
		(start 207.47355 -208.447386)
		(end 212.95741 -184.650634)
		(width 0.1016)
		(layer "In7.Cu")
		(net "PHY_DRV_A_TO_SCC_A_26_DP")
	)
	(segment
		(start 268.362684 -309.034688)
		(end 268.096492 -308.886606)
		(width 0.1016)
		(layer "In7.Cu")
		(net "PHY_DRV_A_TO_SCC_A_26_DP")
	)
	(segment
		(start 267.452602 -308.528466)
		(end 267.18641 -308.38013)
		(width 0.1016)
		(layer "In7.Cu")
		(net "PHY_DRV_A_TO_SCC_A_26_DP")
	)
	(segment
		(start 268.096492 -308.886606)
		(end 268.012672 -308.592982)
		(width 0.1016)
		(layer "In7.Cu")
		(net "PHY_DRV_A_TO_SCC_A_26_DP")
	)
	(segment
		(start 117.941344 -79.948024)
		(end 97.47504 -48.435514)
		(width 0.1016)
		(layer "In7.Cu")
		(net "PHY_DRV_A_TO_SCC_A_26_DP")
	)
	(segment
		(start 270.848328 -310.170322)
		(end 269.56639 -309.457344)
		(width 0.1016)
		(layer "In7.Cu")
		(net "PHY_DRV_A_TO_SCC_A_26_DP")
	)
	(segment
		(start 268.656308 -308.950868)
		(end 268.362684 -309.034688)
		(width 0.1016)
		(layer "In7.Cu")
		(net "PHY_DRV_A_TO_SCC_A_26_DP")
	)
	(arc
		(start 286.973772 -310.334914)
		(mid 286.925564 -310.21853)
		(end 286.80918 -310.170322)
		(width 0.1016)
		(layer "In7.Cu")
		(net "PHY_DRV_A_TO_SCC_A_26_DP")
	)
	(arc
		(start 95.710502 -47.915068)
		(mid 95.63866 -47.944826)
		(end 95.608902 -48.016668)
		(width 0.1016)
		(layer "In7.Cu")
		(net "PHY_DRV_A_TO_SCC_A_26_DP")
	)
	(arc
		(start 286.846772 -310.905144)
		(mid 286.936575 -310.867947)
		(end 286.973772 -310.778144)
		(width 0.1016)
		(layer "In7.Cu")
		(net "PHY_DRV_A_TO_SCC_A_26_DP")
	)
	(segment
		(start 94.459552 -47.114968)
		(end 93.125036 -47.114968)
		(width 0.127)
		(layer "F.Cu")
		(net "PHY_DRV_A_TO_SCC_A_26_DN")
	)
	(segment
		(start 94.586552 -47.476918)
		(end 94.586552 -47.241968)
		(width 0.127)
		(layer "F.Cu")
		(net "PHY_DRV_A_TO_SCC_A_26_DN")
	)
	(segment
		(start 94.713552 -47.603918)
		(end 94.586552 -47.476918)
		(width 0.127)
		(layer "F.Cu")
		(net "PHY_DRV_A_TO_SCC_A_26_DN")
	)
	(segment
		(start 95.481902 -47.603918)
		(end 94.713552 -47.603918)
		(width 0.127)
		(layer "F.Cu")
		(net "PHY_DRV_A_TO_SCC_A_26_DN")
	)
	(segment
		(start 95.608902 -47.178468)
		(end 95.608902 -47.476918)
		(width 0.127)
		(layer "F.Cu")
		(net "PHY_DRV_A_TO_SCC_A_26_DN")
	)
	(segment
		(start 94.586552 -47.241968)
		(end 94.459552 -47.114968)
		(width 0.127)
		(layer "F.Cu")
		(net "PHY_DRV_A_TO_SCC_A_26_DN")
	)
	(arc
		(start 95.608902 -47.476918)
		(mid 95.571705 -47.566721)
		(end 95.481902 -47.603918)
		(width 0.127)
		(layer "F.Cu")
		(net "PHY_DRV_A_TO_SCC_A_26_DN")
	)
	(segment
		(start 201.845164 -140.0048)
		(end 118.184676 -79.716122)
		(width 0.1016)
		(layer "In7.Cu")
		(net "PHY_DRV_A_TO_SCC_A_26_DN")
	)
	(segment
		(start 250.077732 -298.237656)
		(end 248.834402 -297.546014)
		(width 0.1016)
		(layer "In7.Cu")
		(net "PHY_DRV_A_TO_SCC_A_26_DN")
	)
	(segment
		(start 245.159276 -295.501568)
		(end 232.892092 -288.677604)
		(width 0.1016)
		(layer "In7.Cu")
		(net "PHY_DRV_A_TO_SCC_A_26_DN")
	)
	(segment
		(start 213.297262 -184.64657)
		(end 201.845164 -140.0048)
		(width 0.1016)
		(layer "In7.Cu")
		(net "PHY_DRV_A_TO_SCC_A_26_DN")
	)
	(segment
		(start 286.80918 -309.840122)
		(end 270.93418 -309.840122)
		(width 0.1016)
		(layer "In7.Cu")
		(net "PHY_DRV_A_TO_SCC_A_26_DN")
	)
	(segment
		(start 222.835216 -268.086586)
		(end 207.813402 -208.44383)
		(width 0.1016)
		(layer "In7.Cu")
		(net "PHY_DRV_A_TO_SCC_A_26_DN")
	)
	(segment
		(start 270.93418 -309.840122)
		(end 250.077732 -298.237656)
		(width 0.1016)
		(layer "In7.Cu")
		(net "PHY_DRV_A_TO_SCC_A_26_DN")
	)
	(segment
		(start 232.892092 -288.677604)
		(end 222.835216 -268.086586)
		(width 0.1016)
		(layer "In7.Cu")
		(net "PHY_DRV_A_TO_SCC_A_26_DN")
	)
	(segment
		(start 287.303972 -310.778144)
		(end 287.303972 -310.334914)
		(width 0.1016)
		(layer "In7.Cu")
		(net "PHY_DRV_A_TO_SCC_A_26_DN")
	)
	(segment
		(start 97.707958 -48.187864)
		(end 96.64319 -47.584868)
		(width 0.1016)
		(layer "In7.Cu")
		(net "PHY_DRV_A_TO_SCC_A_26_DN")
	)
	(segment
		(start 248.834402 -297.546014)
		(end 245.159276 -295.501568)
		(width 0.1016)
		(layer "In7.Cu")
		(net "PHY_DRV_A_TO_SCC_A_26_DN")
	)
	(segment
		(start 118.184676 -79.716122)
		(end 97.707958 -48.187864)
		(width 0.1016)
		(layer "In7.Cu")
		(net "PHY_DRV_A_TO_SCC_A_26_DN")
	)
	(segment
		(start 287.83661 -310.905144)
		(end 287.430972 -310.905144)
		(width 0.1016)
		(layer "In7.Cu")
		(net "PHY_DRV_A_TO_SCC_A_26_DN")
	)
	(segment
		(start 207.813402 -208.44383)
		(end 213.297262 -184.64657)
		(width 0.1016)
		(layer "In7.Cu")
		(net "PHY_DRV_A_TO_SCC_A_26_DN")
	)
	(segment
		(start 96.64319 -47.584868)
		(end 95.710502 -47.584868)
		(width 0.1016)
		(layer "In7.Cu")
		(net "PHY_DRV_A_TO_SCC_A_26_DN")
	)
	(segment
		(start 95.608902 -47.483268)
		(end 95.608902 -47.178468)
		(width 0.1016)
		(layer "In7.Cu")
		(net "PHY_DRV_A_TO_SCC_A_26_DN")
	)
	(arc
		(start 287.303972 -310.334914)
		(mid 287.159051 -309.985043)
		(end 286.80918 -309.840122)
		(width 0.1016)
		(layer "In7.Cu")
		(net "PHY_DRV_A_TO_SCC_A_26_DN")
	)
	(arc
		(start 287.430972 -310.905144)
		(mid 287.341169 -310.867947)
		(end 287.303972 -310.778144)
		(width 0.1016)
		(layer "In7.Cu")
		(net "PHY_DRV_A_TO_SCC_A_26_DN")
	)
	(arc
		(start 95.710502 -47.584868)
		(mid 95.63866 -47.55511)
		(end 95.608902 -47.483268)
		(width 0.1016)
		(layer "In7.Cu")
		(net "PHY_DRV_A_TO_SCC_A_26_DN")
	)
	(segment
		(start 63.03645 -48.257968)
		(end 62.90945 -48.384968)
		(width 0.127)
		(layer "F.Cu")
		(net "PHY_DRV_A_TO_SCC_A_25_DP")
	)
	(segment
		(start 63.03645 -48.05807)
		(end 63.03645 -48.257968)
		(width 0.127)
		(layer "F.Cu")
		(net "PHY_DRV_A_TO_SCC_A_25_DP")
	)
	(segment
		(start 63.9318 -47.896018)
		(end 63.198502 -47.896018)
		(width 0.127)
		(layer "F.Cu")
		(net "PHY_DRV_A_TO_SCC_A_25_DP")
	)
	(segment
		(start 64.0588 -48.321468)
		(end 64.0588 -48.023018)
		(width 0.127)
		(layer "F.Cu")
		(net "PHY_DRV_A_TO_SCC_A_25_DP")
	)
	(segment
		(start 63.198502 -47.896018)
		(end 63.03645 -48.05807)
		(width 0.127)
		(layer "F.Cu")
		(net "PHY_DRV_A_TO_SCC_A_25_DP")
	)
	(segment
		(start 62.90945 -48.384968)
		(end 61.574934 -48.384968)
		(width 0.127)
		(layer "F.Cu")
		(net "PHY_DRV_A_TO_SCC_A_25_DP")
	)
	(arc
		(start 64.0588 -48.023018)
		(mid 64.021603 -47.933215)
		(end 63.9318 -47.896018)
		(width 0.127)
		(layer "F.Cu")
		(net "PHY_DRV_A_TO_SCC_A_25_DP")
	)
	(segment
		(start 78.730348 -54.224682)
		(end 71.900034 -51.070002)
		(width 0.1016)
		(layer "In7.Cu")
		(net "PHY_DRV_A_TO_SCC_A_25_DP")
	)
	(segment
		(start 202.957176 -231.221026)
		(end 192.824354 -184.076848)
		(width 0.1016)
		(layer "In7.Cu")
		(net "PHY_DRV_A_TO_SCC_A_25_DP")
	)
	(segment
		(start 71.900034 -51.070002)
		(end 71.900034 -51.070256)
		(width 0.1016)
		(layer "In7.Cu")
		(net "PHY_DRV_A_TO_SCC_A_25_DP")
	)
	(segment
		(start 267.335508 -309.975758)
		(end 267.041884 -310.059324)
		(width 0.1016)
		(layer "In7.Cu")
		(net "PHY_DRV_A_TO_SCC_A_25_DP")
	)
	(segment
		(start 65.069466 -47.915068)
		(end 64.1604 -47.915068)
		(width 0.1016)
		(layer "In7.Cu")
		(net "PHY_DRV_A_TO_SCC_A_25_DP")
	)
	(segment
		(start 267.68552 -310.417464)
		(end 267.6017 -310.12384)
		(width 0.1016)
		(layer "In7.Cu")
		(net "PHY_DRV_A_TO_SCC_A_25_DP")
	)
	(segment
		(start 266.775438 -309.911242)
		(end 266.691618 -309.617618)
		(width 0.1016)
		(layer "In7.Cu")
		(net "PHY_DRV_A_TO_SCC_A_25_DP")
	)
	(segment
		(start 267.951966 -310.565546)
		(end 267.68552 -310.417464)
		(width 0.1016)
		(layer "In7.Cu")
		(net "PHY_DRV_A_TO_SCC_A_25_DP")
	)
	(segment
		(start 270.92148 -311.97042)
		(end 269.155672 -310.988202)
		(width 0.1016)
		(layer "In7.Cu")
		(net "PHY_DRV_A_TO_SCC_A_25_DP")
	)
	(segment
		(start 266.691618 -309.617618)
		(end 250.98883 -300.882558)
		(width 0.1016)
		(layer "In7.Cu")
		(net "PHY_DRV_A_TO_SCC_A_25_DP")
	)
	(segment
		(start 71.900034 -51.070256)
		(end 65.069466 -47.915068)
		(width 0.1016)
		(layer "In7.Cu")
		(net "PHY_DRV_A_TO_SCC_A_25_DP")
	)
	(segment
		(start 268.595602 -310.923686)
		(end 268.511782 -310.630062)
		(width 0.1016)
		(layer "In7.Cu")
		(net "PHY_DRV_A_TO_SCC_A_25_DP")
	)
	(segment
		(start 268.862048 -311.071768)
		(end 268.595602 -310.923686)
		(width 0.1016)
		(layer "In7.Cu")
		(net "PHY_DRV_A_TO_SCC_A_25_DP")
	)
	(segment
		(start 267.041884 -310.059324)
		(end 266.775438 -309.911242)
		(width 0.1016)
		(layer "In7.Cu")
		(net "PHY_DRV_A_TO_SCC_A_25_DP")
	)
	(segment
		(start 285.973774 -312.578242)
		(end 285.973774 -312.135012)
		(width 0.1016)
		(layer "In7.Cu")
		(net "PHY_DRV_A_TO_SCC_A_25_DP")
	)
	(segment
		(start 250.98883 -300.882558)
		(end 241.417094 -295.557956)
		(width 0.1016)
		(layer "In7.Cu")
		(net "PHY_DRV_A_TO_SCC_A_25_DP")
	)
	(segment
		(start 269.155672 -310.988202)
		(end 268.862048 -311.071768)
		(width 0.1016)
		(layer "In7.Cu")
		(net "PHY_DRV_A_TO_SCC_A_25_DP")
	)
	(segment
		(start 193.53784 -153.140664)
		(end 170.734736 -121.62155)
		(width 0.1016)
		(layer "In7.Cu")
		(net "PHY_DRV_A_TO_SCC_A_25_DP")
	)
	(segment
		(start 196.613018 -167.787828)
		(end 193.53784 -153.140664)
		(width 0.1016)
		(layer "In7.Cu")
		(net "PHY_DRV_A_TO_SCC_A_25_DP")
	)
	(segment
		(start 241.417094 -295.557956)
		(end 231.755188 -290.183316)
		(width 0.1016)
		(layer "In7.Cu")
		(net "PHY_DRV_A_TO_SCC_A_25_DP")
	)
	(segment
		(start 170.734736 -121.621804)
		(end 78.730348 -54.224682)
		(width 0.1016)
		(layer "In7.Cu")
		(net "PHY_DRV_A_TO_SCC_A_25_DP")
	)
	(segment
		(start 192.824354 -184.076848)
		(end 196.613018 -167.787828)
		(width 0.1016)
		(layer "In7.Cu")
		(net "PHY_DRV_A_TO_SCC_A_25_DP")
	)
	(segment
		(start 64.0588 -48.016668)
		(end 64.0588 -48.321468)
		(width 0.1016)
		(layer "In7.Cu")
		(net "PHY_DRV_A_TO_SCC_A_25_DP")
	)
	(segment
		(start 268.511782 -310.630062)
		(end 268.24559 -310.48198)
		(width 0.1016)
		(layer "In7.Cu")
		(net "PHY_DRV_A_TO_SCC_A_25_DP")
	)
	(segment
		(start 267.6017 -310.12384)
		(end 267.335508 -309.975758)
		(width 0.1016)
		(layer "In7.Cu")
		(net "PHY_DRV_A_TO_SCC_A_25_DP")
	)
	(segment
		(start 231.755188 -290.183316)
		(end 202.957176 -231.221026)
		(width 0.1016)
		(layer "In7.Cu")
		(net "PHY_DRV_A_TO_SCC_A_25_DP")
	)
	(segment
		(start 285.809182 -311.97042)
		(end 270.92148 -311.97042)
		(width 0.1016)
		(layer "In7.Cu")
		(net "PHY_DRV_A_TO_SCC_A_25_DP")
	)
	(segment
		(start 268.24559 -310.48198)
		(end 267.951966 -310.565546)
		(width 0.1016)
		(layer "In7.Cu")
		(net "PHY_DRV_A_TO_SCC_A_25_DP")
	)
	(segment
		(start 170.734736 -121.62155)
		(end 170.734736 -121.621804)
		(width 0.1016)
		(layer "In7.Cu")
		(net "PHY_DRV_A_TO_SCC_A_25_DP")
	)
	(segment
		(start 285.436564 -312.705242)
		(end 285.846774 -312.705242)
		(width 0.1016)
		(layer "In7.Cu")
		(net "PHY_DRV_A_TO_SCC_A_25_DP")
	)
	(arc
		(start 285.846774 -312.705242)
		(mid 285.936577 -312.668045)
		(end 285.973774 -312.578242)
		(width 0.1016)
		(layer "In7.Cu")
		(net "PHY_DRV_A_TO_SCC_A_25_DP")
	)
	(arc
		(start 285.973774 -312.135012)
		(mid 285.925566 -312.018628)
		(end 285.809182 -311.97042)
		(width 0.1016)
		(layer "In7.Cu")
		(net "PHY_DRV_A_TO_SCC_A_25_DP")
	)
	(arc
		(start 64.1604 -47.915068)
		(mid 64.088558 -47.944826)
		(end 64.0588 -48.016668)
		(width 0.1016)
		(layer "In7.Cu")
		(net "PHY_DRV_A_TO_SCC_A_25_DP")
	)
	(segment
		(start 63.9318 -47.603918)
		(end 63.16345 -47.603918)
		(width 0.127)
		(layer "F.Cu")
		(net "PHY_DRV_A_TO_SCC_A_25_DN")
	)
	(segment
		(start 63.16345 -47.603918)
		(end 63.03645 -47.476918)
		(width 0.127)
		(layer "F.Cu")
		(net "PHY_DRV_A_TO_SCC_A_25_DN")
	)
	(segment
		(start 62.90945 -47.114968)
		(end 61.574934 -47.114968)
		(width 0.127)
		(layer "F.Cu")
		(net "PHY_DRV_A_TO_SCC_A_25_DN")
	)
	(segment
		(start 63.03645 -47.476918)
		(end 63.03645 -47.241968)
		(width 0.127)
		(layer "F.Cu")
		(net "PHY_DRV_A_TO_SCC_A_25_DN")
	)
	(segment
		(start 64.0588 -47.178468)
		(end 64.0588 -47.476918)
		(width 0.127)
		(layer "F.Cu")
		(net "PHY_DRV_A_TO_SCC_A_25_DN")
	)
	(segment
		(start 63.03645 -47.241968)
		(end 62.90945 -47.114968)
		(width 0.127)
		(layer "F.Cu")
		(net "PHY_DRV_A_TO_SCC_A_25_DN")
	)
	(arc
		(start 64.0588 -47.476918)
		(mid 64.021603 -47.566721)
		(end 63.9318 -47.603918)
		(width 0.127)
		(layer "F.Cu")
		(net "PHY_DRV_A_TO_SCC_A_25_DN")
	)
	(segment
		(start 241.577368 -295.269158)
		(end 236.791754 -292.606984)
		(width 0.1016)
		(layer "In7.Cu")
		(net "PHY_DRV_A_TO_SCC_A_25_DN")
	)
	(segment
		(start 236.791754 -292.606984)
		(end 232.006394 -289.945064)
		(width 0.1016)
		(layer "In7.Cu")
		(net "PHY_DRV_A_TO_SCC_A_25_DN")
	)
	(segment
		(start 286.836612 -312.705242)
		(end 286.430974 -312.705242)
		(width 0.1016)
		(layer "In7.Cu")
		(net "PHY_DRV_A_TO_SCC_A_25_DN")
	)
	(segment
		(start 196.951346 -167.791384)
		(end 193.846704 -153.004012)
		(width 0.1016)
		(layer "In7.Cu")
		(net "PHY_DRV_A_TO_SCC_A_25_DN")
	)
	(segment
		(start 286.303974 -312.578242)
		(end 286.303974 -312.135012)
		(width 0.1016)
		(layer "In7.Cu")
		(net "PHY_DRV_A_TO_SCC_A_25_DN")
	)
	(segment
		(start 64.0588 -47.483268)
		(end 64.0588 -47.178468)
		(width 0.1016)
		(layer "In7.Cu")
		(net "PHY_DRV_A_TO_SCC_A_25_DN")
	)
	(segment
		(start 241.577622 -295.269158)
		(end 241.577368 -295.269158)
		(width 0.1016)
		(layer "In7.Cu")
		(net "PHY_DRV_A_TO_SCC_A_25_DN")
	)
	(segment
		(start 285.809182 -311.64022)
		(end 271.007332 -311.64022)
		(width 0.1016)
		(layer "In7.Cu")
		(net "PHY_DRV_A_TO_SCC_A_25_DN")
	)
	(segment
		(start 203.271628 -231.112314)
		(end 193.162936 -184.079642)
		(width 0.1016)
		(layer "In7.Cu")
		(net "PHY_DRV_A_TO_SCC_A_25_DN")
	)
	(segment
		(start 193.162936 -184.079642)
		(end 196.951346 -167.791384)
		(width 0.1016)
		(layer "In7.Cu")
		(net "PHY_DRV_A_TO_SCC_A_25_DN")
	)
	(segment
		(start 271.007332 -311.64022)
		(end 241.577622 -295.269158)
		(width 0.1016)
		(layer "In7.Cu")
		(net "PHY_DRV_A_TO_SCC_A_25_DN")
	)
	(segment
		(start 170.971972 -121.385838)
		(end 78.89875 -53.938678)
		(width 0.1016)
		(layer "In7.Cu")
		(net "PHY_DRV_A_TO_SCC_A_25_DN")
	)
	(segment
		(start 193.846704 -153.004012)
		(end 170.971972 -121.385838)
		(width 0.1016)
		(layer "In7.Cu")
		(net "PHY_DRV_A_TO_SCC_A_25_DN")
	)
	(segment
		(start 232.006394 -289.945064)
		(end 203.271628 -231.112314)
		(width 0.1016)
		(layer "In7.Cu")
		(net "PHY_DRV_A_TO_SCC_A_25_DN")
	)
	(segment
		(start 78.89875 -53.938678)
		(end 65.14211 -47.584868)
		(width 0.1016)
		(layer "In7.Cu")
		(net "PHY_DRV_A_TO_SCC_A_25_DN")
	)
	(segment
		(start 65.14211 -47.584868)
		(end 64.1604 -47.584868)
		(width 0.1016)
		(layer "In7.Cu")
		(net "PHY_DRV_A_TO_SCC_A_25_DN")
	)
	(arc
		(start 286.430974 -312.705242)
		(mid 286.341171 -312.668045)
		(end 286.303974 -312.578242)
		(width 0.1016)
		(layer "In7.Cu")
		(net "PHY_DRV_A_TO_SCC_A_25_DN")
	)
	(arc
		(start 286.303974 -312.135012)
		(mid 286.159053 -311.785141)
		(end 285.809182 -311.64022)
		(width 0.1016)
		(layer "In7.Cu")
		(net "PHY_DRV_A_TO_SCC_A_25_DN")
	)
	(arc
		(start 64.1604 -47.584868)
		(mid 64.088558 -47.55511)
		(end 64.0588 -47.483268)
		(width 0.1016)
		(layer "In7.Cu")
		(net "PHY_DRV_A_TO_SCC_A_25_DN")
	)
	(segment
		(start 31.329122 -48.384968)
		(end 30.025086 -48.384968)
		(width 0.127)
		(layer "F.Cu")
		(net "PHY_DRV_A_TO_SCC_A_24_DP")
	)
	(segment
		(start 32.381952 -47.896018)
		(end 31.613602 -47.896018)
		(width 0.127)
		(layer "F.Cu")
		(net "PHY_DRV_A_TO_SCC_A_24_DP")
	)
	(segment
		(start 32.508952 -48.321468)
		(end 32.508952 -48.023018)
		(width 0.127)
		(layer "F.Cu")
		(net "PHY_DRV_A_TO_SCC_A_24_DP")
	)
	(segment
		(start 31.486602 -48.227488)
		(end 31.329122 -48.384968)
		(width 0.127)
		(layer "F.Cu")
		(net "PHY_DRV_A_TO_SCC_A_24_DP")
	)
	(segment
		(start 31.613602 -47.896018)
		(end 31.486602 -48.023018)
		(width 0.127)
		(layer "F.Cu")
		(net "PHY_DRV_A_TO_SCC_A_24_DP")
	)
	(segment
		(start 31.486602 -48.023018)
		(end 31.486602 -48.227488)
		(width 0.127)
		(layer "F.Cu")
		(net "PHY_DRV_A_TO_SCC_A_24_DP")
	)
	(arc
		(start 32.508952 -48.023018)
		(mid 32.471755 -47.933215)
		(end 32.381952 -47.896018)
		(width 0.127)
		(layer "F.Cu")
		(net "PHY_DRV_A_TO_SCC_A_24_DP")
	)
	(segment
		(start 267.255752 -312.1152)
		(end 266.989306 -311.967118)
		(width 0.1016)
		(layer "In7.Cu")
		(net "PHY_DRV_A_TO_SCC_A_24_DP")
	)
	(segment
		(start 194.9577 -168.413176)
		(end 192.072768 -154.673808)
		(width 0.1016)
		(layer "In7.Cu")
		(net "PHY_DRV_A_TO_SCC_A_24_DP")
	)
	(segment
		(start 260.156452 -307.920136)
		(end 255.25857 -305.19624)
		(width 0.1016)
		(layer "In7.Cu")
		(net "PHY_DRV_A_TO_SCC_A_24_DP")
	)
	(segment
		(start 265.995404 -311.167272)
		(end 260.156452 -307.920136)
		(width 0.1016)
		(layer "In7.Cu")
		(net "PHY_DRV_A_TO_SCC_A_24_DP")
	)
	(segment
		(start 286.80918 -313.770264)
		(end 270.676116 -313.770264)
		(width 0.1016)
		(layer "In7.Cu")
		(net "PHY_DRV_A_TO_SCC_A_24_DP")
	)
	(segment
		(start 266.345416 -311.608978)
		(end 266.079224 -311.460896)
		(width 0.1016)
		(layer "In7.Cu")
		(net "PHY_DRV_A_TO_SCC_A_24_DP")
	)
	(segment
		(start 268.165834 -312.621422)
		(end 267.899388 -312.473086)
		(width 0.1016)
		(layer "In7.Cu")
		(net "PHY_DRV_A_TO_SCC_A_24_DP")
	)
	(segment
		(start 74.008742 -61.49848)
		(end 53.6448 -54.706774)
		(width 0.1016)
		(layer "In7.Cu")
		(net "PHY_DRV_A_TO_SCC_A_24_DP")
	)
	(segment
		(start 53.6448 -54.706774)
		(end 53.6448 -54.707028)
		(width 0.1016)
		(layer "In7.Cu")
		(net "PHY_DRV_A_TO_SCC_A_24_DP")
	)
	(segment
		(start 267.899388 -312.473086)
		(end 267.815568 -312.179462)
		(width 0.1016)
		(layer "In7.Cu")
		(net "PHY_DRV_A_TO_SCC_A_24_DP")
	)
	(segment
		(start 32.508952 -48.016668)
		(end 32.508952 -48.321468)
		(width 0.1016)
		(layer "In7.Cu")
		(net "PHY_DRV_A_TO_SCC_A_24_DP")
	)
	(segment
		(start 191.398906 -183.963564)
		(end 194.9577 -168.413176)
		(width 0.1016)
		(layer "In7.Cu")
		(net "PHY_DRV_A_TO_SCC_A_24_DP")
	)
	(segment
		(start 266.989306 -311.967118)
		(end 266.905486 -311.673494)
		(width 0.1016)
		(layer "In7.Cu")
		(net "PHY_DRV_A_TO_SCC_A_24_DP")
	)
	(segment
		(start 266.079224 -311.460896)
		(end 265.995404 -311.167272)
		(width 0.1016)
		(layer "In7.Cu")
		(net "PHY_DRV_A_TO_SCC_A_24_DP")
	)
	(segment
		(start 33.280858 -47.915068)
		(end 32.610552 -47.915068)
		(width 0.1016)
		(layer "In7.Cu")
		(net "PHY_DRV_A_TO_SCC_A_24_DP")
	)
	(segment
		(start 266.63904 -311.525412)
		(end 266.345416 -311.608978)
		(width 0.1016)
		(layer "In7.Cu")
		(net "PHY_DRV_A_TO_SCC_A_24_DP")
	)
	(segment
		(start 266.905486 -311.673494)
		(end 266.63904 -311.525412)
		(width 0.1016)
		(layer "In7.Cu")
		(net "PHY_DRV_A_TO_SCC_A_24_DP")
	)
	(segment
		(start 267.815568 -312.179462)
		(end 267.549376 -312.03138)
		(width 0.1016)
		(layer "In7.Cu")
		(net "PHY_DRV_A_TO_SCC_A_24_DP")
	)
	(segment
		(start 240.627408 -297.059096)
		(end 230.802942 -291.595302)
		(width 0.1016)
		(layer "In7.Cu")
		(net "PHY_DRV_A_TO_SCC_A_24_DP")
	)
	(segment
		(start 255.25857 -305.19624)
		(end 254.034036 -304.515266)
		(width 0.1016)
		(layer "In7.Cu")
		(net "PHY_DRV_A_TO_SCC_A_24_DP")
	)
	(segment
		(start 192.072768 -154.673808)
		(end 171.444158 -126.160022)
		(width 0.1016)
		(layer "In7.Cu")
		(net "PHY_DRV_A_TO_SCC_A_24_DP")
	)
	(segment
		(start 250.361196 -302.472598)
		(end 240.627408 -297.059096)
		(width 0.1016)
		(layer "In7.Cu")
		(net "PHY_DRV_A_TO_SCC_A_24_DP")
	)
	(segment
		(start 267.549376 -312.03138)
		(end 267.255752 -312.1152)
		(width 0.1016)
		(layer "In7.Cu")
		(net "PHY_DRV_A_TO_SCC_A_24_DP")
	)
	(segment
		(start 286.973772 -314.378086)
		(end 286.973772 -313.934856)
		(width 0.1016)
		(layer "In7.Cu")
		(net "PHY_DRV_A_TO_SCC_A_24_DP")
	)
	(segment
		(start 254.034036 -304.515266)
		(end 250.361196 -302.472598)
		(width 0.1016)
		(layer "In7.Cu")
		(net "PHY_DRV_A_TO_SCC_A_24_DP")
	)
	(segment
		(start 286.436562 -314.505086)
		(end 286.846772 -314.505086)
		(width 0.1016)
		(layer "In7.Cu")
		(net "PHY_DRV_A_TO_SCC_A_24_DP")
	)
	(segment
		(start 171.444158 -126.160022)
		(end 74.008742 -61.49848)
		(width 0.1016)
		(layer "In7.Cu")
		(net "PHY_DRV_A_TO_SCC_A_24_DP")
	)
	(segment
		(start 230.802942 -291.595302)
		(end 201.740008 -232.075482)
		(width 0.1016)
		(layer "In7.Cu")
		(net "PHY_DRV_A_TO_SCC_A_24_DP")
	)
	(segment
		(start 201.740008 -232.075482)
		(end 191.398906 -183.963564)
		(width 0.1016)
		(layer "In7.Cu")
		(net "PHY_DRV_A_TO_SCC_A_24_DP")
	)
	(segment
		(start 268.459458 -312.537602)
		(end 268.165834 -312.621422)
		(width 0.1016)
		(layer "In7.Cu")
		(net "PHY_DRV_A_TO_SCC_A_24_DP")
	)
	(segment
		(start 270.676116 -313.770264)
		(end 268.459458 -312.537602)
		(width 0.1016)
		(layer "In7.Cu")
		(net "PHY_DRV_A_TO_SCC_A_24_DP")
	)
	(segment
		(start 53.6448 -54.707028)
		(end 33.280858 -47.915068)
		(width 0.1016)
		(layer "In7.Cu")
		(net "PHY_DRV_A_TO_SCC_A_24_DP")
	)
	(arc
		(start 286.846772 -314.505086)
		(mid 286.936575 -314.467889)
		(end 286.973772 -314.378086)
		(width 0.1016)
		(layer "In7.Cu")
		(net "PHY_DRV_A_TO_SCC_A_24_DP")
	)
	(arc
		(start 286.973772 -313.934856)
		(mid 286.925564 -313.818472)
		(end 286.80918 -313.770264)
		(width 0.1016)
		(layer "In7.Cu")
		(net "PHY_DRV_A_TO_SCC_A_24_DP")
	)
	(arc
		(start 32.610552 -47.915068)
		(mid 32.53871 -47.944826)
		(end 32.508952 -48.016668)
		(width 0.1016)
		(layer "In7.Cu")
		(net "PHY_DRV_A_TO_SCC_A_24_DP")
	)
	(segment
		(start 31.486602 -47.241968)
		(end 31.359602 -47.114968)
		(width 0.127)
		(layer "F.Cu")
		(net "PHY_DRV_A_TO_SCC_A_24_DN")
	)
	(segment
		(start 31.486602 -47.476918)
		(end 31.486602 -47.241968)
		(width 0.127)
		(layer "F.Cu")
		(net "PHY_DRV_A_TO_SCC_A_24_DN")
	)
	(segment
		(start 32.508952 -47.178468)
		(end 32.508952 -47.476918)
		(width 0.127)
		(layer "F.Cu")
		(net "PHY_DRV_A_TO_SCC_A_24_DN")
	)
	(segment
		(start 31.359602 -47.114968)
		(end 30.025086 -47.114968)
		(width 0.127)
		(layer "F.Cu")
		(net "PHY_DRV_A_TO_SCC_A_24_DN")
	)
	(segment
		(start 31.613602 -47.603918)
		(end 31.486602 -47.476918)
		(width 0.127)
		(layer "F.Cu")
		(net "PHY_DRV_A_TO_SCC_A_24_DN")
	)
	(segment
		(start 32.381952 -47.603918)
		(end 31.613602 -47.603918)
		(width 0.127)
		(layer "F.Cu")
		(net "PHY_DRV_A_TO_SCC_A_24_DN")
	)
	(arc
		(start 32.508952 -47.476918)
		(mid 32.471755 -47.566721)
		(end 32.381952 -47.603918)
		(width 0.127)
		(layer "F.Cu")
		(net "PHY_DRV_A_TO_SCC_A_24_DN")
	)
	(segment
		(start 250.521724 -302.1838)
		(end 245.65483 -299.476922)
		(width 0.1016)
		(layer "In7.Cu")
		(net "PHY_DRV_A_TO_SCC_A_24_DN")
	)
	(segment
		(start 191.737234 -183.96585)
		(end 195.295774 -168.416224)
		(width 0.1016)
		(layer "In7.Cu")
		(net "PHY_DRV_A_TO_SCC_A_24_DN")
	)
	(segment
		(start 245.65483 -299.476922)
		(end 231.054148 -291.35705)
		(width 0.1016)
		(layer "In7.Cu")
		(net "PHY_DRV_A_TO_SCC_A_24_DN")
	)
	(segment
		(start 171.676822 -125.917706)
		(end 74.154792 -61.199014)
		(width 0.1016)
		(layer "In7.Cu")
		(net "PHY_DRV_A_TO_SCC_A_24_DN")
	)
	(segment
		(start 74.154792 -61.199014)
		(end 33.334706 -47.584868)
		(width 0.1016)
		(layer "In7.Cu")
		(net "PHY_DRV_A_TO_SCC_A_24_DN")
	)
	(segment
		(start 202.05446 -231.96677)
		(end 191.737234 -183.96585)
		(width 0.1016)
		(layer "In7.Cu")
		(net "PHY_DRV_A_TO_SCC_A_24_DN")
	)
	(segment
		(start 287.83661 -314.505086)
		(end 287.430972 -314.505086)
		(width 0.1016)
		(layer "In7.Cu")
		(net "PHY_DRV_A_TO_SCC_A_24_DN")
	)
	(segment
		(start 286.80918 -313.440064)
		(end 270.761968 -313.440064)
		(width 0.1016)
		(layer "In7.Cu")
		(net "PHY_DRV_A_TO_SCC_A_24_DN")
	)
	(segment
		(start 231.054148 -291.35705)
		(end 202.05446 -231.96677)
		(width 0.1016)
		(layer "In7.Cu")
		(net "PHY_DRV_A_TO_SCC_A_24_DN")
	)
	(segment
		(start 32.508952 -47.483268)
		(end 32.508952 -47.178468)
		(width 0.1016)
		(layer "In7.Cu")
		(net "PHY_DRV_A_TO_SCC_A_24_DN")
	)
	(segment
		(start 287.303972 -314.378086)
		(end 287.303972 -313.934856)
		(width 0.1016)
		(layer "In7.Cu")
		(net "PHY_DRV_A_TO_SCC_A_24_DN")
	)
	(segment
		(start 270.761968 -313.440064)
		(end 250.521724 -302.1838)
		(width 0.1016)
		(layer "In7.Cu")
		(net "PHY_DRV_A_TO_SCC_A_24_DN")
	)
	(segment
		(start 195.295774 -168.416224)
		(end 192.381632 -154.537156)
		(width 0.1016)
		(layer "In7.Cu")
		(net "PHY_DRV_A_TO_SCC_A_24_DN")
	)
	(segment
		(start 192.381632 -154.537156)
		(end 171.676822 -125.917706)
		(width 0.1016)
		(layer "In7.Cu")
		(net "PHY_DRV_A_TO_SCC_A_24_DN")
	)
	(segment
		(start 33.334706 -47.584868)
		(end 32.610552 -47.584868)
		(width 0.1016)
		(layer "In7.Cu")
		(net "PHY_DRV_A_TO_SCC_A_24_DN")
	)
	(arc
		(start 287.303972 -313.934856)
		(mid 287.159051 -313.584985)
		(end 286.80918 -313.440064)
		(width 0.1016)
		(layer "In7.Cu")
		(net "PHY_DRV_A_TO_SCC_A_24_DN")
	)
	(arc
		(start 287.430972 -314.505086)
		(mid 287.341169 -314.467889)
		(end 287.303972 -314.378086)
		(width 0.1016)
		(layer "In7.Cu")
		(net "PHY_DRV_A_TO_SCC_A_24_DN")
	)
	(arc
		(start 32.610552 -47.584868)
		(mid 32.53871 -47.55511)
		(end 32.508952 -47.483268)
		(width 0.1016)
		(layer "In7.Cu")
		(net "PHY_DRV_A_TO_SCC_A_24_DN")
	)
	(segment
		(start 483.663498 -163.224972)
		(end 483.823518 -163.384992)
		(width 0.127)
		(layer "F.Cu")
		(net "PHY_DRV_A_TO_SCC_A_23_DP")
	)
	(segment
		(start 482.658674 -162.896042)
		(end 483.501446 -162.896042)
		(width 0.127)
		(layer "F.Cu")
		(net "PHY_DRV_A_TO_SCC_A_23_DP")
	)
	(segment
		(start 483.823518 -163.384992)
		(end 485.125014 -163.384992)
		(width 0.127)
		(layer "F.Cu")
		(net "PHY_DRV_A_TO_SCC_A_23_DP")
	)
	(segment
		(start 482.489002 -163.321492)
		(end 482.489002 -163.065714)
		(width 0.127)
		(layer "F.Cu")
		(net "PHY_DRV_A_TO_SCC_A_23_DP")
	)
	(segment
		(start 483.663498 -163.058094)
		(end 483.663498 -163.224972)
		(width 0.127)
		(layer "F.Cu")
		(net "PHY_DRV_A_TO_SCC_A_23_DP")
	)
	(segment
		(start 483.501446 -162.896042)
		(end 483.663498 -163.058094)
		(width 0.127)
		(layer "F.Cu")
		(net "PHY_DRV_A_TO_SCC_A_23_DP")
	)
	(arc
		(start 482.489002 -163.065714)
		(mid 482.538698 -162.945738)
		(end 482.658674 -162.896042)
		(width 0.127)
		(layer "F.Cu")
		(net "PHY_DRV_A_TO_SCC_A_23_DP")
	)
	(segment
		(start 430.3014 -225.298508)
		(end 377.815094 -235.752894)
		(width 0.127)
		(layer "B.Cu")
		(net "PHY_DRV_A_TO_SCC_A_23_DP")
	)
	(segment
		(start 461.723994 -193.123566)
		(end 450.586094 -201.717148)
		(width 0.127)
		(layer "B.Cu")
		(net "PHY_DRV_A_TO_SCC_A_23_DP")
	)
	(segment
		(start 482.312218 -162.896042)
		(end 481.831396 -162.896042)
		(width 0.127)
		(layer "B.Cu")
		(net "PHY_DRV_A_TO_SCC_A_23_DP")
	)
	(segment
		(start 481.831396 -162.896042)
		(end 481.811838 -162.9156)
		(width 0.127)
		(layer "B.Cu")
		(net "PHY_DRV_A_TO_SCC_A_23_DP")
	)
	(segment
		(start 289.03422 -326.351138)
		(end 287.7439 -326.351138)
		(width 0.127)
		(layer "B.Cu")
		(net "PHY_DRV_A_TO_SCC_A_23_DP")
	)
	(segment
		(start 482.489002 -163.321492)
		(end 482.489002 -163.072826)
		(width 0.127)
		(layer "B.Cu")
		(net "PHY_DRV_A_TO_SCC_A_23_DP")
	)
	(segment
		(start 286.863536 -325.305166)
		(end 286.436562 -325.305166)
		(width 0.127)
		(layer "B.Cu")
		(net "PHY_DRV_A_TO_SCC_A_23_DP")
	)
	(segment
		(start 322.298822 -277.480014)
		(end 319.760854 -288.928048)
		(width 0.127)
		(layer "B.Cu")
		(net "PHY_DRV_A_TO_SCC_A_23_DP")
	)
	(segment
		(start 436.905146 -220.17355)
		(end 430.3014 -225.298508)
		(width 0.127)
		(layer "B.Cu")
		(net "PHY_DRV_A_TO_SCC_A_23_DP")
	)
	(segment
		(start 290.62045 -325.999348)
		(end 289.03422 -326.351138)
		(width 0.127)
		(layer "B.Cu")
		(net "PHY_DRV_A_TO_SCC_A_23_DP")
	)
	(segment
		(start 319.760854 -288.928048)
		(end 299.921168 -320.07429)
		(width 0.127)
		(layer "B.Cu")
		(net "PHY_DRV_A_TO_SCC_A_23_DP")
	)
	(segment
		(start 328.168762 -268.613382)
		(end 322.298822 -277.480014)
		(width 0.127)
		(layer "B.Cu")
		(net "PHY_DRV_A_TO_SCC_A_23_DP")
	)
	(segment
		(start 286.990536 -325.68261)
		(end 286.990536 -325.432166)
		(width 0.127)
		(layer "B.Cu")
		(net "PHY_DRV_A_TO_SCC_A_23_DP")
	)
	(segment
		(start 377.381516 -236.040168)
		(end 328.168762 -268.613382)
		(width 0.127)
		(layer "B.Cu")
		(net "PHY_DRV_A_TO_SCC_A_23_DP")
	)
	(segment
		(start 450.586094 -201.717148)
		(end 436.905146 -220.17355)
		(width 0.127)
		(layer "B.Cu")
		(net "PHY_DRV_A_TO_SCC_A_23_DP")
	)
	(segment
		(start 377.815094 -235.752894)
		(end 377.381516 -236.040168)
		(width 0.127)
		(layer "B.Cu")
		(net "PHY_DRV_A_TO_SCC_A_23_DP")
	)
	(segment
		(start 299.921168 -320.07429)
		(end 290.62045 -325.999348)
		(width 0.127)
		(layer "B.Cu")
		(net "PHY_DRV_A_TO_SCC_A_23_DP")
	)
	(segment
		(start 481.479098 -163.249102)
		(end 461.723994 -193.123566)
		(width 0.127)
		(layer "B.Cu")
		(net "PHY_DRV_A_TO_SCC_A_23_DP")
	)
	(segment
		(start 481.811838 -162.9156)
		(end 481.479098 -163.249102)
		(width 0.127)
		(layer "B.Cu")
		(net "PHY_DRV_A_TO_SCC_A_23_DP")
	)
	(arc
		(start 287.16859 -326.112886)
		(mid 287.03682 -325.915444)
		(end 286.990536 -325.68261)
		(width 0.127)
		(layer "B.Cu")
		(net "PHY_DRV_A_TO_SCC_A_23_DP")
	)
	(arc
		(start 286.990536 -325.432166)
		(mid 286.953339 -325.342363)
		(end 286.863536 -325.305166)
		(width 0.127)
		(layer "B.Cu")
		(net "PHY_DRV_A_TO_SCC_A_23_DP")
	)
	(arc
		(start 287.7439 -326.351138)
		(mid 287.432563 -326.289209)
		(end 287.16859 -326.112886)
		(width 0.127)
		(layer "B.Cu")
		(net "PHY_DRV_A_TO_SCC_A_23_DP")
	)
	(arc
		(start 482.489002 -163.072826)
		(mid 482.437223 -162.947821)
		(end 482.312218 -162.896042)
		(width 0.127)
		(layer "B.Cu")
		(net "PHY_DRV_A_TO_SCC_A_23_DP")
	)
	(segment
		(start 483.536498 -162.603942)
		(end 483.663498 -162.476942)
		(width 0.127)
		(layer "F.Cu")
		(net "PHY_DRV_A_TO_SCC_A_23_DN")
	)
	(segment
		(start 483.790498 -162.114992)
		(end 485.125014 -162.114992)
		(width 0.127)
		(layer "F.Cu")
		(net "PHY_DRV_A_TO_SCC_A_23_DN")
	)
	(segment
		(start 483.663498 -162.476942)
		(end 483.663498 -162.241992)
		(width 0.127)
		(layer "F.Cu")
		(net "PHY_DRV_A_TO_SCC_A_23_DN")
	)
	(segment
		(start 482.489002 -162.178492)
		(end 482.489002 -162.43427)
		(width 0.127)
		(layer "F.Cu")
		(net "PHY_DRV_A_TO_SCC_A_23_DN")
	)
	(segment
		(start 482.658674 -162.603942)
		(end 483.536498 -162.603942)
		(width 0.127)
		(layer "F.Cu")
		(net "PHY_DRV_A_TO_SCC_A_23_DN")
	)
	(segment
		(start 483.663498 -162.241992)
		(end 483.790498 -162.114992)
		(width 0.127)
		(layer "F.Cu")
		(net "PHY_DRV_A_TO_SCC_A_23_DN")
	)
	(arc
		(start 482.489002 -162.43427)
		(mid 482.538698 -162.554246)
		(end 482.658674 -162.603942)
		(width 0.127)
		(layer "F.Cu")
		(net "PHY_DRV_A_TO_SCC_A_23_DN")
	)
	(segment
		(start 303.203102 -314.075826)
		(end 302.998378 -314.397136)
		(width 0.127)
		(layer "B.Cu")
		(net "PHY_DRV_A_TO_SCC_A_23_DN")
	)
	(segment
		(start 450.375528 -201.510646)
		(end 443.522862 -210.75523)
		(width 0.127)
		(layer "B.Cu")
		(net "PHY_DRV_A_TO_SCC_A_23_DN")
	)
	(segment
		(start 481.709984 -162.603942)
		(end 481.690426 -162.6235)
		(width 0.127)
		(layer "B.Cu")
		(net "PHY_DRV_A_TO_SCC_A_23_DN")
	)
	(segment
		(start 481.690426 -162.6235)
		(end 481.604828 -162.709352)
		(width 0.127)
		(layer "B.Cu")
		(net "PHY_DRV_A_TO_SCC_A_23_DN")
	)
	(segment
		(start 301.880016 -316.455298)
		(end 299.709586 -319.862708)
		(width 0.127)
		(layer "B.Cu")
		(net "PHY_DRV_A_TO_SCC_A_23_DN")
	)
	(segment
		(start 436.694326 -219.967302)
		(end 430.176686 -225.025458)
		(width 0.127)
		(layer "B.Cu")
		(net "PHY_DRV_A_TO_SCC_A_23_DN")
	)
	(segment
		(start 377.220226 -235.796582)
		(end 327.957942 -268.402562)
		(width 0.127)
		(layer "B.Cu")
		(net "PHY_DRV_A_TO_SCC_A_23_DN")
	)
	(segment
		(start 327.957942 -268.402562)
		(end 322.025264 -277.363936)
		(width 0.127)
		(layer "B.Cu")
		(net "PHY_DRV_A_TO_SCC_A_23_DN")
	)
	(segment
		(start 290.506912 -325.725282)
		(end 289.002216 -326.059038)
		(width 0.127)
		(layer "B.Cu")
		(net "PHY_DRV_A_TO_SCC_A_23_DN")
	)
	(segment
		(start 482.489002 -162.178492)
		(end 482.489002 -162.427158)
		(width 0.127)
		(layer "B.Cu")
		(net "PHY_DRV_A_TO_SCC_A_23_DN")
	)
	(segment
		(start 303.048162 -314.621418)
		(end 302.843438 -314.942728)
		(width 0.127)
		(layer "B.Cu")
		(net "PHY_DRV_A_TO_SCC_A_23_DN")
	)
	(segment
		(start 302.463962 -315.538358)
		(end 302.259238 -315.859668)
		(width 0.127)
		(layer "B.Cu")
		(net "PHY_DRV_A_TO_SCC_A_23_DN")
	)
	(segment
		(start 481.438458 -162.875976)
		(end 481.251514 -163.063428)
		(width 0.127)
		(layer "B.Cu")
		(net "PHY_DRV_A_TO_SCC_A_23_DN")
	)
	(segment
		(start 482.312218 -162.603942)
		(end 481.709984 -162.603942)
		(width 0.127)
		(layer "B.Cu")
		(net "PHY_DRV_A_TO_SCC_A_23_DN")
	)
	(segment
		(start 319.486788 -288.81451)
		(end 303.427384 -314.026042)
		(width 0.127)
		(layer "B.Cu")
		(net "PHY_DRV_A_TO_SCC_A_23_DN")
	)
	(segment
		(start 377.699016 -235.479336)
		(end 377.220226 -235.796582)
		(width 0.127)
		(layer "B.Cu")
		(net "PHY_DRV_A_TO_SCC_A_23_DN")
	)
	(segment
		(start 302.843438 -314.942728)
		(end 302.618902 -314.992512)
		(width 0.127)
		(layer "B.Cu")
		(net "PHY_DRV_A_TO_SCC_A_23_DN")
	)
	(segment
		(start 481.604828 -162.709352)
		(end 481.438458 -162.875976)
		(width 0.127)
		(layer "B.Cu")
		(net "PHY_DRV_A_TO_SCC_A_23_DN")
	)
	(segment
		(start 289.002216 -326.059038)
		(end 287.7439 -326.059038)
		(width 0.127)
		(layer "B.Cu")
		(net "PHY_DRV_A_TO_SCC_A_23_DN")
	)
	(segment
		(start 322.025264 -277.363936)
		(end 319.486788 -288.81451)
		(width 0.127)
		(layer "B.Cu")
		(net "PHY_DRV_A_TO_SCC_A_23_DN")
	)
	(segment
		(start 302.259238 -315.859668)
		(end 302.034956 -315.909452)
		(width 0.127)
		(layer "B.Cu")
		(net "PHY_DRV_A_TO_SCC_A_23_DN")
	)
	(segment
		(start 299.709586 -319.862708)
		(end 290.506912 -325.725282)
		(width 0.127)
		(layer "B.Cu")
		(net "PHY_DRV_A_TO_SCC_A_23_DN")
	)
	(segment
		(start 461.507078 -192.92189)
		(end 450.375528 -201.510646)
		(width 0.127)
		(layer "B.Cu")
		(net "PHY_DRV_A_TO_SCC_A_23_DN")
	)
	(segment
		(start 287.409636 -325.305166)
		(end 287.83661 -325.305166)
		(width 0.127)
		(layer "B.Cu")
		(net "PHY_DRV_A_TO_SCC_A_23_DN")
	)
	(segment
		(start 287.282636 -325.68261)
		(end 287.282636 -325.432166)
		(width 0.127)
		(layer "B.Cu")
		(net "PHY_DRV_A_TO_SCC_A_23_DN")
	)
	(segment
		(start 303.427384 -314.026042)
		(end 303.203102 -314.075826)
		(width 0.127)
		(layer "B.Cu")
		(net "PHY_DRV_A_TO_SCC_A_23_DN")
	)
	(segment
		(start 301.830232 -316.230762)
		(end 301.880016 -316.455298)
		(width 0.127)
		(layer "B.Cu")
		(net "PHY_DRV_A_TO_SCC_A_23_DN")
	)
	(segment
		(start 430.176686 -225.025458)
		(end 377.70181 -235.477558)
		(width 0.127)
		(layer "B.Cu")
		(net "PHY_DRV_A_TO_SCC_A_23_DN")
	)
	(segment
		(start 302.414178 -315.314076)
		(end 302.463962 -315.538358)
		(width 0.127)
		(layer "B.Cu")
		(net "PHY_DRV_A_TO_SCC_A_23_DN")
	)
	(segment
		(start 302.618902 -314.992512)
		(end 302.414178 -315.314076)
		(width 0.127)
		(layer "B.Cu")
		(net "PHY_DRV_A_TO_SCC_A_23_DN")
	)
	(segment
		(start 302.034956 -315.909452)
		(end 301.830232 -316.230762)
		(width 0.127)
		(layer "B.Cu")
		(net "PHY_DRV_A_TO_SCC_A_23_DN")
	)
	(segment
		(start 377.70181 -235.477558)
		(end 377.699016 -235.479336)
		(width 0.127)
		(layer "B.Cu")
		(net "PHY_DRV_A_TO_SCC_A_23_DN")
	)
	(segment
		(start 443.522862 -210.75523)
		(end 436.694326 -219.967302)
		(width 0.127)
		(layer "B.Cu")
		(net "PHY_DRV_A_TO_SCC_A_23_DN")
	)
	(segment
		(start 302.998378 -314.397136)
		(end 303.048162 -314.621418)
		(width 0.127)
		(layer "B.Cu")
		(net "PHY_DRV_A_TO_SCC_A_23_DN")
	)
	(segment
		(start 481.251514 -163.063428)
		(end 461.507078 -192.92189)
		(width 0.127)
		(layer "B.Cu")
		(net "PHY_DRV_A_TO_SCC_A_23_DN")
	)
	(arc
		(start 482.489002 -162.427158)
		(mid 482.437223 -162.552163)
		(end 482.312218 -162.603942)
		(width 0.127)
		(layer "B.Cu")
		(net "PHY_DRV_A_TO_SCC_A_23_DN")
	)
	(arc
		(start 287.375346 -325.906384)
		(mid 287.306745 -325.803716)
		(end 287.282636 -325.68261)
		(width 0.127)
		(layer "B.Cu")
		(net "PHY_DRV_A_TO_SCC_A_23_DN")
	)
	(arc
		(start 287.7439 -326.059038)
		(mid 287.544442 -326.019363)
		(end 287.375346 -325.906384)
		(width 0.127)
		(layer "B.Cu")
		(net "PHY_DRV_A_TO_SCC_A_23_DN")
	)
	(arc
		(start 287.282636 -325.432166)
		(mid 287.319833 -325.342363)
		(end 287.409636 -325.305166)
		(width 0.127)
		(layer "B.Cu")
		(net "PHY_DRV_A_TO_SCC_A_23_DN")
	)
	(segment
		(start 451.969124 -162.896042)
		(end 438.387236 -162.896042)
		(width 0.127)
		(layer "F.Cu")
		(net "PHY_DRV_A_TO_SCC_A_22_DP")
	)
	(segment
		(start 452.271384 -163.384992)
		(end 452.113396 -163.227004)
		(width 0.127)
		(layer "F.Cu")
		(net "PHY_DRV_A_TO_SCC_A_22_DP")
	)
	(segment
		(start 452.113396 -163.227004)
		(end 452.113396 -163.040314)
		(width 0.127)
		(layer "F.Cu")
		(net "PHY_DRV_A_TO_SCC_A_22_DP")
	)
	(segment
		(start 452.113396 -163.040314)
		(end 451.969124 -162.896042)
		(width 0.127)
		(layer "F.Cu")
		(net "PHY_DRV_A_TO_SCC_A_22_DP")
	)
	(segment
		(start 438.2389 -163.044378)
		(end 438.2389 -163.321492)
		(width 0.127)
		(layer "F.Cu")
		(net "PHY_DRV_A_TO_SCC_A_22_DP")
	)
	(segment
		(start 453.574912 -163.384992)
		(end 452.271384 -163.384992)
		(width 0.127)
		(layer "F.Cu")
		(net "PHY_DRV_A_TO_SCC_A_22_DP")
	)
	(arc
		(start 438.387236 -162.896042)
		(mid 438.282347 -162.939489)
		(end 438.2389 -163.044378)
		(width 0.127)
		(layer "F.Cu")
		(net "PHY_DRV_A_TO_SCC_A_22_DP")
	)
	(segment
		(start 321.880484 -272.127472)
		(end 354.904548 -222.229426)
		(width 0.127)
		(layer "B.Cu")
		(net "PHY_DRV_A_TO_SCC_A_22_DP")
	)
	(segment
		(start 298.217082 -319.288922)
		(end 318.477138 -287.481518)
		(width 0.127)
		(layer "B.Cu")
		(net "PHY_DRV_A_TO_SCC_A_22_DP")
	)
	(segment
		(start 285.990538 -323.632068)
		(end 285.990538 -323.882512)
		(width 0.127)
		(layer "B.Cu")
		(net "PHY_DRV_A_TO_SCC_A_22_DP")
	)
	(segment
		(start 438.2389 -163.072826)
		(end 438.2389 -163.321492)
		(width 0.127)
		(layer "B.Cu")
		(net "PHY_DRV_A_TO_SCC_A_22_DP")
	)
	(segment
		(start 286.743902 -324.55104)
		(end 287.628584 -324.55104)
		(width 0.127)
		(layer "B.Cu")
		(net "PHY_DRV_A_TO_SCC_A_22_DP")
	)
	(segment
		(start 291.19703 -323.761608)
		(end 298.217082 -319.288922)
		(width 0.127)
		(layer "B.Cu")
		(net "PHY_DRV_A_TO_SCC_A_22_DP")
	)
	(segment
		(start 395.666468 -196.752972)
		(end 422.93159 -169.73804)
		(width 0.127)
		(layer "B.Cu")
		(net "PHY_DRV_A_TO_SCC_A_22_DP")
	)
	(segment
		(start 285.436564 -323.505068)
		(end 285.863538 -323.505068)
		(width 0.127)
		(layer "B.Cu")
		(net "PHY_DRV_A_TO_SCC_A_22_DP")
	)
	(segment
		(start 354.904548 -222.229426)
		(end 395.666468 -196.752972)
		(width 0.127)
		(layer "B.Cu")
		(net "PHY_DRV_A_TO_SCC_A_22_DP")
	)
	(segment
		(start 422.93159 -169.73804)
		(end 436.951628 -162.896042)
		(width 0.127)
		(layer "B.Cu")
		(net "PHY_DRV_A_TO_SCC_A_22_DP")
	)
	(segment
		(start 318.477138 -287.481518)
		(end 321.880484 -272.127472)
		(width 0.127)
		(layer "B.Cu")
		(net "PHY_DRV_A_TO_SCC_A_22_DP")
	)
	(segment
		(start 287.628584 -324.55104)
		(end 291.19703 -323.761608)
		(width 0.127)
		(layer "B.Cu")
		(net "PHY_DRV_A_TO_SCC_A_22_DP")
	)
	(segment
		(start 436.951628 -162.896042)
		(end 438.062116 -162.896042)
		(width 0.127)
		(layer "B.Cu")
		(net "PHY_DRV_A_TO_SCC_A_22_DP")
	)
	(arc
		(start 438.062116 -162.896042)
		(mid 438.187121 -162.947821)
		(end 438.2389 -163.072826)
		(width 0.127)
		(layer "B.Cu")
		(net "PHY_DRV_A_TO_SCC_A_22_DP")
	)
	(arc
		(start 285.863538 -323.505068)
		(mid 285.953341 -323.542265)
		(end 285.990538 -323.632068)
		(width 0.127)
		(layer "B.Cu")
		(net "PHY_DRV_A_TO_SCC_A_22_DP")
	)
	(arc
		(start 285.990538 -323.882512)
		(mid 286.036746 -324.115378)
		(end 286.168592 -324.312788)
		(width 0.127)
		(layer "B.Cu")
		(net "PHY_DRV_A_TO_SCC_A_22_DP")
	)
	(arc
		(start 286.168592 -324.312788)
		(mid 286.432546 -324.489157)
		(end 286.743902 -324.55104)
		(width 0.127)
		(layer "B.Cu")
		(net "PHY_DRV_A_TO_SCC_A_22_DP")
	)
	(segment
		(start 451.986396 -162.603942)
		(end 438.387236 -162.603942)
		(width 0.127)
		(layer "F.Cu")
		(net "PHY_DRV_A_TO_SCC_A_22_DN")
	)
	(segment
		(start 452.113396 -162.476942)
		(end 451.986396 -162.603942)
		(width 0.127)
		(layer "F.Cu")
		(net "PHY_DRV_A_TO_SCC_A_22_DN")
	)
	(segment
		(start 438.2389 -162.455606)
		(end 438.2389 -162.178492)
		(width 0.127)
		(layer "F.Cu")
		(net "PHY_DRV_A_TO_SCC_A_22_DN")
	)
	(segment
		(start 453.574912 -162.114992)
		(end 452.240396 -162.114992)
		(width 0.127)
		(layer "F.Cu")
		(net "PHY_DRV_A_TO_SCC_A_22_DN")
	)
	(segment
		(start 452.113396 -162.241992)
		(end 452.113396 -162.476942)
		(width 0.127)
		(layer "F.Cu")
		(net "PHY_DRV_A_TO_SCC_A_22_DN")
	)
	(segment
		(start 452.240396 -162.114992)
		(end 452.113396 -162.241992)
		(width 0.127)
		(layer "F.Cu")
		(net "PHY_DRV_A_TO_SCC_A_22_DN")
	)
	(arc
		(start 438.387236 -162.603942)
		(mid 438.282347 -162.560495)
		(end 438.2389 -162.455606)
		(width 0.127)
		(layer "F.Cu")
		(net "PHY_DRV_A_TO_SCC_A_22_DN")
	)
	(segment
		(start 436.884064 -162.603942)
		(end 438.062116 -162.603942)
		(width 0.127)
		(layer "B.Cu")
		(net "PHY_DRV_A_TO_SCC_A_22_DN")
	)
	(segment
		(start 302.210216 -312.173366)
		(end 302.434752 -312.123582)
		(width 0.127)
		(layer "B.Cu")
		(net "PHY_DRV_A_TO_SCC_A_22_DN")
	)
	(segment
		(start 302.794162 -311.256426)
		(end 303.018698 -311.206642)
		(width 0.127)
		(layer "B.Cu")
		(net "PHY_DRV_A_TO_SCC_A_22_DN")
	)
	(segment
		(start 310.610758 -299.287438)
		(end 318.203072 -287.36798)
		(width 0.127)
		(layer "B.Cu")
		(net "PHY_DRV_A_TO_SCC_A_22_DN")
	)
	(segment
		(start 302.055276 -312.719212)
		(end 302.005492 -312.494676)
		(width 0.127)
		(layer "B.Cu")
		(net "PHY_DRV_A_TO_SCC_A_22_DN")
	)
	(segment
		(start 287.59658 -324.25894)
		(end 291.083492 -323.487542)
		(width 0.127)
		(layer "B.Cu")
		(net "PHY_DRV_A_TO_SCC_A_22_DN")
	)
	(segment
		(start 286.743902 -324.25894)
		(end 287.59658 -324.25894)
		(width 0.127)
		(layer "B.Cu")
		(net "PHY_DRV_A_TO_SCC_A_22_DN")
	)
	(segment
		(start 301.47133 -313.636152)
		(end 301.421546 -313.411616)
		(width 0.127)
		(layer "B.Cu")
		(net "PHY_DRV_A_TO_SCC_A_22_DN")
	)
	(segment
		(start 321.606926 -272.011394)
		(end 354.69576 -222.01505)
		(width 0.127)
		(layer "B.Cu")
		(net "PHY_DRV_A_TO_SCC_A_22_DN")
	)
	(segment
		(start 301.62627 -313.090306)
		(end 301.850552 -313.040522)
		(width 0.127)
		(layer "B.Cu")
		(net "PHY_DRV_A_TO_SCC_A_22_DN")
	)
	(segment
		(start 291.083492 -323.487542)
		(end 298.0055 -319.07734)
		(width 0.127)
		(layer "B.Cu")
		(net "PHY_DRV_A_TO_SCC_A_22_DN")
	)
	(segment
		(start 301.850552 -313.040522)
		(end 302.055276 -312.719212)
		(width 0.127)
		(layer "B.Cu")
		(net "PHY_DRV_A_TO_SCC_A_22_DN")
	)
	(segment
		(start 286.836612 -323.505068)
		(end 286.409638 -323.505068)
		(width 0.127)
		(layer "B.Cu")
		(net "PHY_DRV_A_TO_SCC_A_22_DN")
	)
	(segment
		(start 302.639222 -311.802272)
		(end 302.589438 -311.577736)
		(width 0.127)
		(layer "B.Cu")
		(net "PHY_DRV_A_TO_SCC_A_22_DN")
	)
	(segment
		(start 302.589438 -311.577736)
		(end 302.794162 -311.256426)
		(width 0.127)
		(layer "B.Cu")
		(net "PHY_DRV_A_TO_SCC_A_22_DN")
	)
	(segment
		(start 318.203072 -287.36798)
		(end 321.606926 -272.011394)
		(width 0.127)
		(layer "B.Cu")
		(net "PHY_DRV_A_TO_SCC_A_22_DN")
	)
	(segment
		(start 298.0055 -319.07734)
		(end 301.47133 -313.636152)
		(width 0.127)
		(layer "B.Cu")
		(net "PHY_DRV_A_TO_SCC_A_22_DN")
	)
	(segment
		(start 302.005492 -312.494676)
		(end 302.210216 -312.173366)
		(width 0.127)
		(layer "B.Cu")
		(net "PHY_DRV_A_TO_SCC_A_22_DN")
	)
	(segment
		(start 303.018698 -311.206642)
		(end 310.610758 -299.287438)
		(width 0.127)
		(layer "B.Cu")
		(net "PHY_DRV_A_TO_SCC_A_22_DN")
	)
	(segment
		(start 422.76014 -169.496486)
		(end 436.884064 -162.603942)
		(width 0.127)
		(layer "B.Cu")
		(net "PHY_DRV_A_TO_SCC_A_22_DN")
	)
	(segment
		(start 395.483842 -196.52234)
		(end 422.76014 -169.496486)
		(width 0.127)
		(layer "B.Cu")
		(net "PHY_DRV_A_TO_SCC_A_22_DN")
	)
	(segment
		(start 302.434752 -312.123582)
		(end 302.639222 -311.802272)
		(width 0.127)
		(layer "B.Cu")
		(net "PHY_DRV_A_TO_SCC_A_22_DN")
	)
	(segment
		(start 438.2389 -162.427158)
		(end 438.2389 -162.178492)
		(width 0.127)
		(layer "B.Cu")
		(net "PHY_DRV_A_TO_SCC_A_22_DN")
	)
	(segment
		(start 286.282638 -323.632068)
		(end 286.282638 -323.882512)
		(width 0.127)
		(layer "B.Cu")
		(net "PHY_DRV_A_TO_SCC_A_22_DN")
	)
	(segment
		(start 301.421546 -313.411616)
		(end 301.62627 -313.090306)
		(width 0.127)
		(layer "B.Cu")
		(net "PHY_DRV_A_TO_SCC_A_22_DN")
	)
	(segment
		(start 354.69576 -222.01505)
		(end 395.483842 -196.52234)
		(width 0.127)
		(layer "B.Cu")
		(net "PHY_DRV_A_TO_SCC_A_22_DN")
	)
	(arc
		(start 286.409638 -323.505068)
		(mid 286.319835 -323.542265)
		(end 286.282638 -323.632068)
		(width 0.127)
		(layer "B.Cu")
		(net "PHY_DRV_A_TO_SCC_A_22_DN")
	)
	(arc
		(start 286.375348 -324.106286)
		(mid 286.544442 -324.219271)
		(end 286.743902 -324.25894)
		(width 0.127)
		(layer "B.Cu")
		(net "PHY_DRV_A_TO_SCC_A_22_DN")
	)
	(arc
		(start 286.282638 -323.882512)
		(mid 286.306729 -324.003625)
		(end 286.375348 -324.106286)
		(width 0.127)
		(layer "B.Cu")
		(net "PHY_DRV_A_TO_SCC_A_22_DN")
	)
	(arc
		(start 438.062116 -162.603942)
		(mid 438.187121 -162.552163)
		(end 438.2389 -162.427158)
		(width 0.127)
		(layer "B.Cu")
		(net "PHY_DRV_A_TO_SCC_A_22_DN")
	)
	(segment
		(start 420.563548 -163.242244)
		(end 420.706296 -163.384992)
		(width 0.127)
		(layer "F.Cu")
		(net "PHY_DRV_A_TO_SCC_A_21_DP")
	)
	(segment
		(start 419.516306 -162.896042)
		(end 420.395908 -162.896042)
		(width 0.127)
		(layer "F.Cu")
		(net "PHY_DRV_A_TO_SCC_A_21_DP")
	)
	(segment
		(start 420.563548 -163.063682)
		(end 420.563548 -163.242244)
		(width 0.127)
		(layer "F.Cu")
		(net "PHY_DRV_A_TO_SCC_A_21_DP")
	)
	(segment
		(start 419.389052 -163.321492)
		(end 419.389052 -163.023296)
		(width 0.127)
		(layer "F.Cu")
		(net "PHY_DRV_A_TO_SCC_A_21_DP")
	)
	(segment
		(start 420.706296 -163.384992)
		(end 422.025064 -163.384992)
		(width 0.127)
		(layer "F.Cu")
		(net "PHY_DRV_A_TO_SCC_A_21_DP")
	)
	(segment
		(start 420.395908 -162.896042)
		(end 420.563548 -163.063682)
		(width 0.127)
		(layer "F.Cu")
		(net "PHY_DRV_A_TO_SCC_A_21_DP")
	)
	(arc
		(start 419.389052 -163.023296)
		(mid 419.426324 -162.933314)
		(end 419.516306 -162.896042)
		(width 0.127)
		(layer "F.Cu")
		(net "PHY_DRV_A_TO_SCC_A_21_DP")
	)
	(segment
		(start 290.694872 -322.244974)
		(end 288.411666 -322.751196)
		(width 0.127)
		(layer "B.Cu")
		(net "PHY_DRV_A_TO_SCC_A_21_DP")
	)
	(segment
		(start 418.792914 -162.896042)
		(end 394.209524 -178.26101)
		(width 0.127)
		(layer "B.Cu")
		(net "PHY_DRV_A_TO_SCC_A_21_DP")
	)
	(segment
		(start 296.756074 -318.383412)
		(end 290.694872 -322.244974)
		(width 0.127)
		(layer "B.Cu")
		(net "PHY_DRV_A_TO_SCC_A_21_DP")
	)
	(segment
		(start 356.622858 -214.060278)
		(end 316.957202 -276.272498)
		(width 0.127)
		(layer "B.Cu")
		(net "PHY_DRV_A_TO_SCC_A_21_DP")
	)
	(segment
		(start 288.411666 -322.751196)
		(end 287.7439 -322.751196)
		(width 0.127)
		(layer "B.Cu")
		(net "PHY_DRV_A_TO_SCC_A_21_DP")
	)
	(segment
		(start 313.415934 -292.243002)
		(end 296.756074 -318.383412)
		(width 0.127)
		(layer "B.Cu")
		(net "PHY_DRV_A_TO_SCC_A_21_DP")
	)
	(segment
		(start 419.212268 -162.896042)
		(end 418.792914 -162.896042)
		(width 0.127)
		(layer "B.Cu")
		(net "PHY_DRV_A_TO_SCC_A_21_DP")
	)
	(segment
		(start 286.863536 -321.705224)
		(end 286.436562 -321.705224)
		(width 0.127)
		(layer "B.Cu")
		(net "PHY_DRV_A_TO_SCC_A_21_DP")
	)
	(segment
		(start 419.389052 -163.321492)
		(end 419.389052 -163.072826)
		(width 0.127)
		(layer "B.Cu")
		(net "PHY_DRV_A_TO_SCC_A_21_DP")
	)
	(segment
		(start 316.957202 -276.272498)
		(end 313.415934 -292.243002)
		(width 0.127)
		(layer "B.Cu")
		(net "PHY_DRV_A_TO_SCC_A_21_DP")
	)
	(segment
		(start 356.623112 -214.060278)
		(end 356.622858 -214.060278)
		(width 0.127)
		(layer "B.Cu")
		(net "PHY_DRV_A_TO_SCC_A_21_DP")
	)
	(segment
		(start 369.66906 -193.5988)
		(end 356.623112 -214.060278)
		(width 0.127)
		(layer "B.Cu")
		(net "PHY_DRV_A_TO_SCC_A_21_DP")
	)
	(segment
		(start 394.209524 -178.26101)
		(end 394.209524 -178.260756)
		(width 0.127)
		(layer "B.Cu")
		(net "PHY_DRV_A_TO_SCC_A_21_DP")
	)
	(segment
		(start 286.990536 -322.082668)
		(end 286.990536 -321.832224)
		(width 0.127)
		(layer "B.Cu")
		(net "PHY_DRV_A_TO_SCC_A_21_DP")
	)
	(segment
		(start 394.209524 -178.260756)
		(end 369.66906 -193.5988)
		(width 0.127)
		(layer "B.Cu")
		(net "PHY_DRV_A_TO_SCC_A_21_DP")
	)
	(arc
		(start 287.16859 -322.512944)
		(mid 287.03682 -322.315502)
		(end 286.990536 -322.082668)
		(width 0.127)
		(layer "B.Cu")
		(net "PHY_DRV_A_TO_SCC_A_21_DP")
	)
	(arc
		(start 287.7439 -322.751196)
		(mid 287.432563 -322.689267)
		(end 287.16859 -322.512944)
		(width 0.127)
		(layer "B.Cu")
		(net "PHY_DRV_A_TO_SCC_A_21_DP")
	)
	(arc
		(start 286.990536 -321.832224)
		(mid 286.953339 -321.742421)
		(end 286.863536 -321.705224)
		(width 0.127)
		(layer "B.Cu")
		(net "PHY_DRV_A_TO_SCC_A_21_DP")
	)
	(arc
		(start 419.389052 -163.072826)
		(mid 419.337273 -162.947821)
		(end 419.212268 -162.896042)
		(width 0.127)
		(layer "B.Cu")
		(net "PHY_DRV_A_TO_SCC_A_21_DP")
	)
	(segment
		(start 420.563548 -162.241992)
		(end 420.690548 -162.114992)
		(width 0.127)
		(layer "F.Cu")
		(net "PHY_DRV_A_TO_SCC_A_21_DN")
	)
	(segment
		(start 419.389052 -162.178492)
		(end 419.389052 -162.476688)
		(width 0.127)
		(layer "F.Cu")
		(net "PHY_DRV_A_TO_SCC_A_21_DN")
	)
	(segment
		(start 420.436548 -162.603942)
		(end 420.563548 -162.476942)
		(width 0.127)
		(layer "F.Cu")
		(net "PHY_DRV_A_TO_SCC_A_21_DN")
	)
	(segment
		(start 419.516306 -162.603942)
		(end 420.436548 -162.603942)
		(width 0.127)
		(layer "F.Cu")
		(net "PHY_DRV_A_TO_SCC_A_21_DN")
	)
	(segment
		(start 420.690548 -162.114992)
		(end 422.025064 -162.114992)
		(width 0.127)
		(layer "F.Cu")
		(net "PHY_DRV_A_TO_SCC_A_21_DN")
	)
	(segment
		(start 420.563548 -162.476942)
		(end 420.563548 -162.241992)
		(width 0.127)
		(layer "F.Cu")
		(net "PHY_DRV_A_TO_SCC_A_21_DN")
	)
	(arc
		(start 419.389052 -162.476688)
		(mid 419.426324 -162.56667)
		(end 419.516306 -162.603942)
		(width 0.127)
		(layer "F.Cu")
		(net "PHY_DRV_A_TO_SCC_A_21_DN")
	)
	(segment
		(start 288.379662 -322.459096)
		(end 287.7439 -322.459096)
		(width 0.127)
		(layer "B.Cu")
		(net "PHY_DRV_A_TO_SCC_A_21_DN")
	)
	(segment
		(start 300.661578 -311.40908)
		(end 300.456854 -311.73039)
		(width 0.127)
		(layer "B.Cu")
		(net "PHY_DRV_A_TO_SCC_A_21_DN")
	)
	(segment
		(start 299.922438 -312.871612)
		(end 296.544492 -318.17183)
		(width 0.127)
		(layer "B.Cu")
		(net "PHY_DRV_A_TO_SCC_A_21_DN")
	)
	(segment
		(start 301.246032 -310.492394)
		(end 301.041054 -310.813704)
		(width 0.127)
		(layer "B.Cu")
		(net "PHY_DRV_A_TO_SCC_A_21_DN")
	)
	(segment
		(start 290.581334 -321.970908)
		(end 288.379662 -322.459096)
		(width 0.127)
		(layer "B.Cu")
		(net "PHY_DRV_A_TO_SCC_A_21_DN")
	)
	(segment
		(start 287.282636 -322.082668)
		(end 287.282636 -321.832224)
		(width 0.127)
		(layer "B.Cu")
		(net "PHY_DRV_A_TO_SCC_A_21_DN")
	)
	(segment
		(start 300.456854 -311.73039)
		(end 300.506638 -311.954926)
		(width 0.127)
		(layer "B.Cu")
		(net "PHY_DRV_A_TO_SCC_A_21_DN")
	)
	(segment
		(start 301.041054 -310.813704)
		(end 301.090838 -311.03824)
		(width 0.127)
		(layer "B.Cu")
		(net "PHY_DRV_A_TO_SCC_A_21_DN")
	)
	(segment
		(start 419.389052 -162.178492)
		(end 419.389052 -162.427158)
		(width 0.127)
		(layer "B.Cu")
		(net "PHY_DRV_A_TO_SCC_A_21_DN")
	)
	(segment
		(start 419.212268 -162.603942)
		(end 418.709094 -162.603942)
		(width 0.127)
		(layer "B.Cu")
		(net "PHY_DRV_A_TO_SCC_A_21_DN")
	)
	(segment
		(start 299.872654 -312.64733)
		(end 299.922438 -312.871612)
		(width 0.127)
		(layer "B.Cu")
		(net "PHY_DRV_A_TO_SCC_A_21_DN")
	)
	(segment
		(start 316.683136 -276.15896)
		(end 313.141868 -292.129464)
		(width 0.127)
		(layer "B.Cu")
		(net "PHY_DRV_A_TO_SCC_A_21_DN")
	)
	(segment
		(start 300.077378 -312.32602)
		(end 299.872654 -312.64733)
		(width 0.127)
		(layer "B.Cu")
		(net "PHY_DRV_A_TO_SCC_A_21_DN")
	)
	(segment
		(start 301.090838 -311.03824)
		(end 300.886114 -311.35955)
		(width 0.127)
		(layer "B.Cu")
		(net "PHY_DRV_A_TO_SCC_A_21_DN")
	)
	(segment
		(start 418.709094 -162.603942)
		(end 369.457986 -193.385948)
		(width 0.127)
		(layer "B.Cu")
		(net "PHY_DRV_A_TO_SCC_A_21_DN")
	)
	(segment
		(start 300.886114 -311.35955)
		(end 300.661578 -311.40908)
		(width 0.127)
		(layer "B.Cu")
		(net "PHY_DRV_A_TO_SCC_A_21_DN")
	)
	(segment
		(start 296.544492 -318.17183)
		(end 290.581334 -321.970908)
		(width 0.127)
		(layer "B.Cu")
		(net "PHY_DRV_A_TO_SCC_A_21_DN")
	)
	(segment
		(start 300.301914 -312.276236)
		(end 300.077378 -312.32602)
		(width 0.127)
		(layer "B.Cu")
		(net "PHY_DRV_A_TO_SCC_A_21_DN")
	)
	(segment
		(start 287.409636 -321.705224)
		(end 287.83661 -321.705224)
		(width 0.127)
		(layer "B.Cu")
		(net "PHY_DRV_A_TO_SCC_A_21_DN")
	)
	(segment
		(start 369.457986 -193.385948)
		(end 356.462584 -213.768178)
		(width 0.127)
		(layer "B.Cu")
		(net "PHY_DRV_A_TO_SCC_A_21_DN")
	)
	(segment
		(start 301.470314 -310.44261)
		(end 301.246032 -310.492394)
		(width 0.127)
		(layer "B.Cu")
		(net "PHY_DRV_A_TO_SCC_A_21_DN")
	)
	(segment
		(start 300.506638 -311.954926)
		(end 300.301914 -312.276236)
		(width 0.127)
		(layer "B.Cu")
		(net "PHY_DRV_A_TO_SCC_A_21_DN")
	)
	(segment
		(start 356.462584 -213.768178)
		(end 316.683136 -276.15896)
		(width 0.127)
		(layer "B.Cu")
		(net "PHY_DRV_A_TO_SCC_A_21_DN")
	)
	(segment
		(start 313.141868 -292.129464)
		(end 301.470314 -310.44261)
		(width 0.127)
		(layer "B.Cu")
		(net "PHY_DRV_A_TO_SCC_A_21_DN")
	)
	(arc
		(start 287.282636 -321.832224)
		(mid 287.319833 -321.742421)
		(end 287.409636 -321.705224)
		(width 0.127)
		(layer "B.Cu")
		(net "PHY_DRV_A_TO_SCC_A_21_DN")
	)
	(arc
		(start 419.389052 -162.427158)
		(mid 419.337273 -162.552163)
		(end 419.212268 -162.603942)
		(width 0.127)
		(layer "B.Cu")
		(net "PHY_DRV_A_TO_SCC_A_21_DN")
	)
	(arc
		(start 287.375346 -322.306442)
		(mid 287.306745 -322.203774)
		(end 287.282636 -322.082668)
		(width 0.127)
		(layer "B.Cu")
		(net "PHY_DRV_A_TO_SCC_A_21_DN")
	)
	(arc
		(start 287.7439 -322.459096)
		(mid 287.544442 -322.419421)
		(end 287.375346 -322.306442)
		(width 0.127)
		(layer "B.Cu")
		(net "PHY_DRV_A_TO_SCC_A_21_DN")
	)
	(segment
		(start 387.966204 -162.896042)
		(end 388.86003 -162.896042)
		(width 0.127)
		(layer "F.Cu")
		(net "PHY_DRV_A_TO_SCC_A_20_DP")
	)
	(segment
		(start 387.83895 -163.321492)
		(end 387.83895 -163.023296)
		(width 0.127)
		(layer "F.Cu")
		(net "PHY_DRV_A_TO_SCC_A_20_DP")
	)
	(segment
		(start 389.013446 -163.212272)
		(end 389.186166 -163.384992)
		(width 0.127)
		(layer "F.Cu")
		(net "PHY_DRV_A_TO_SCC_A_20_DP")
	)
	(segment
		(start 389.186166 -163.384992)
		(end 390.474962 -163.384992)
		(width 0.127)
		(layer "F.Cu")
		(net "PHY_DRV_A_TO_SCC_A_20_DP")
	)
	(segment
		(start 389.013446 -163.049458)
		(end 389.013446 -163.212272)
		(width 0.127)
		(layer "F.Cu")
		(net "PHY_DRV_A_TO_SCC_A_20_DP")
	)
	(segment
		(start 388.86003 -162.896042)
		(end 389.013446 -163.049458)
		(width 0.127)
		(layer "F.Cu")
		(net "PHY_DRV_A_TO_SCC_A_20_DP")
	)
	(arc
		(start 387.83895 -163.023296)
		(mid 387.876222 -162.933314)
		(end 387.966204 -162.896042)
		(width 0.127)
		(layer "F.Cu")
		(net "PHY_DRV_A_TO_SCC_A_20_DP")
	)
	(segment
		(start 350.741488 -219.272104)
		(end 314.817252 -275.647658)
		(width 0.127)
		(layer "B.Cu")
		(net "PHY_DRV_A_TO_SCC_A_20_DP")
	)
	(segment
		(start 387.83895 -163.321492)
		(end 387.83895 -163.072826)
		(width 0.127)
		(layer "B.Cu")
		(net "PHY_DRV_A_TO_SCC_A_20_DP")
	)
	(segment
		(start 295.289986 -317.469012)
		(end 290.701222 -320.393822)
		(width 0.127)
		(layer "B.Cu")
		(net "PHY_DRV_A_TO_SCC_A_20_DP")
	)
	(segment
		(start 314.817252 -275.647658)
		(end 310.98617 -292.927278)
		(width 0.127)
		(layer "B.Cu")
		(net "PHY_DRV_A_TO_SCC_A_20_DP")
	)
	(segment
		(start 290.701222 -320.393822)
		(end 288.184336 -320.951352)
		(width 0.127)
		(layer "B.Cu")
		(net "PHY_DRV_A_TO_SCC_A_20_DP")
	)
	(segment
		(start 310.98617 -292.927278)
		(end 295.289986 -317.469012)
		(width 0.127)
		(layer "B.Cu")
		(net "PHY_DRV_A_TO_SCC_A_20_DP")
	)
	(segment
		(start 287.575752 -320.951352)
		(end 287.575498 -320.951098)
		(width 0.127)
		(layer "B.Cu")
		(net "PHY_DRV_A_TO_SCC_A_20_DP")
	)
	(segment
		(start 285.863538 -319.905126)
		(end 285.436564 -319.905126)
		(width 0.127)
		(layer "B.Cu")
		(net "PHY_DRV_A_TO_SCC_A_20_DP")
	)
	(segment
		(start 386.50164 -163.154106)
		(end 350.741488 -219.272104)
		(width 0.127)
		(layer "B.Cu")
		(net "PHY_DRV_A_TO_SCC_A_20_DP")
	)
	(segment
		(start 287.575498 -320.951098)
		(end 286.743902 -320.951098)
		(width 0.127)
		(layer "B.Cu")
		(net "PHY_DRV_A_TO_SCC_A_20_DP")
	)
	(segment
		(start 285.990538 -320.28257)
		(end 285.990538 -320.032126)
		(width 0.127)
		(layer "B.Cu")
		(net "PHY_DRV_A_TO_SCC_A_20_DP")
	)
	(segment
		(start 288.184336 -320.951352)
		(end 287.575752 -320.951352)
		(width 0.127)
		(layer "B.Cu")
		(net "PHY_DRV_A_TO_SCC_A_20_DP")
	)
	(segment
		(start 387.662166 -162.896042)
		(end 386.912866 -162.896042)
		(width 0.127)
		(layer "B.Cu")
		(net "PHY_DRV_A_TO_SCC_A_20_DP")
	)
	(segment
		(start 386.912866 -162.896042)
		(end 386.50164 -163.154106)
		(width 0.127)
		(layer "B.Cu")
		(net "PHY_DRV_A_TO_SCC_A_20_DP")
	)
	(arc
		(start 285.990538 -320.032126)
		(mid 285.953341 -319.942323)
		(end 285.863538 -319.905126)
		(width 0.127)
		(layer "B.Cu")
		(net "PHY_DRV_A_TO_SCC_A_20_DP")
	)
	(arc
		(start 286.743902 -320.951098)
		(mid 286.432565 -320.889169)
		(end 286.168592 -320.712846)
		(width 0.127)
		(layer "B.Cu")
		(net "PHY_DRV_A_TO_SCC_A_20_DP")
	)
	(arc
		(start 286.168592 -320.712846)
		(mid 286.036822 -320.515404)
		(end 285.990538 -320.28257)
		(width 0.127)
		(layer "B.Cu")
		(net "PHY_DRV_A_TO_SCC_A_20_DP")
	)
	(arc
		(start 387.83895 -163.072826)
		(mid 387.787171 -162.947821)
		(end 387.662166 -162.896042)
		(width 0.127)
		(layer "B.Cu")
		(net "PHY_DRV_A_TO_SCC_A_20_DP")
	)
	(segment
		(start 387.83895 -162.178492)
		(end 387.83895 -162.476688)
		(width 0.127)
		(layer "F.Cu")
		(net "PHY_DRV_A_TO_SCC_A_20_DN")
	)
	(segment
		(start 388.886446 -162.603942)
		(end 389.013446 -162.476942)
		(width 0.127)
		(layer "F.Cu")
		(net "PHY_DRV_A_TO_SCC_A_20_DN")
	)
	(segment
		(start 387.966204 -162.603942)
		(end 388.886446 -162.603942)
		(width 0.127)
		(layer "F.Cu")
		(net "PHY_DRV_A_TO_SCC_A_20_DN")
	)
	(segment
		(start 389.140446 -162.114992)
		(end 390.474962 -162.114992)
		(width 0.127)
		(layer "F.Cu")
		(net "PHY_DRV_A_TO_SCC_A_20_DN")
	)
	(segment
		(start 389.013446 -162.476942)
		(end 389.013446 -162.241992)
		(width 0.127)
		(layer "F.Cu")
		(net "PHY_DRV_A_TO_SCC_A_20_DN")
	)
	(segment
		(start 389.013446 -162.241992)
		(end 389.140446 -162.114992)
		(width 0.127)
		(layer "F.Cu")
		(net "PHY_DRV_A_TO_SCC_A_20_DN")
	)
	(arc
		(start 387.83895 -162.476688)
		(mid 387.876222 -162.56667)
		(end 387.966204 -162.603942)
		(width 0.127)
		(layer "F.Cu")
		(net "PHY_DRV_A_TO_SCC_A_20_DN")
	)
	(segment
		(start 314.543186 -275.53412)
		(end 350.495108 -219.115132)
		(width 0.127)
		(layer "B.Cu")
		(net "PHY_DRV_A_TO_SCC_A_20_DN")
	)
	(segment
		(start 350.495108 -219.115132)
		(end 386.290566 -162.941508)
		(width 0.127)
		(layer "B.Cu")
		(net "PHY_DRV_A_TO_SCC_A_20_DN")
	)
	(segment
		(start 290.587684 -320.119756)
		(end 295.078404 -317.257176)
		(width 0.127)
		(layer "B.Cu")
		(net "PHY_DRV_A_TO_SCC_A_20_DN")
	)
	(segment
		(start 299.786294 -309.594504)
		(end 300.01083 -309.545228)
		(width 0.127)
		(layer "B.Cu")
		(net "PHY_DRV_A_TO_SCC_A_20_DN")
	)
	(segment
		(start 387.83895 -162.427158)
		(end 387.83895 -162.178492)
		(width 0.127)
		(layer "B.Cu")
		(net "PHY_DRV_A_TO_SCC_A_20_DN")
	)
	(segment
		(start 298.995338 -310.831484)
		(end 299.20057 -310.510428)
		(width 0.127)
		(layer "B.Cu")
		(net "PHY_DRV_A_TO_SCC_A_20_DN")
	)
	(segment
		(start 286.836612 -319.905126)
		(end 286.409638 -319.905126)
		(width 0.127)
		(layer "B.Cu")
		(net "PHY_DRV_A_TO_SCC_A_20_DN")
	)
	(segment
		(start 299.425106 -310.461152)
		(end 299.630338 -310.140096)
		(width 0.127)
		(layer "B.Cu")
		(net "PHY_DRV_A_TO_SCC_A_20_DN")
	)
	(segment
		(start 300.01083 -309.545228)
		(end 310.712104 -292.813486)
		(width 0.127)
		(layer "B.Cu")
		(net "PHY_DRV_A_TO_SCC_A_20_DN")
	)
	(segment
		(start 299.044614 -311.05602)
		(end 298.995338 -310.831484)
		(width 0.127)
		(layer "B.Cu")
		(net "PHY_DRV_A_TO_SCC_A_20_DN")
	)
	(segment
		(start 298.45889 -311.97169)
		(end 298.40936 -311.747154)
		(width 0.127)
		(layer "B.Cu")
		(net "PHY_DRV_A_TO_SCC_A_20_DN")
	)
	(segment
		(start 298.614846 -311.426352)
		(end 298.839382 -311.376822)
		(width 0.127)
		(layer "B.Cu")
		(net "PHY_DRV_A_TO_SCC_A_20_DN")
	)
	(segment
		(start 299.581062 -309.91556)
		(end 299.786294 -309.594504)
		(width 0.127)
		(layer "B.Cu")
		(net "PHY_DRV_A_TO_SCC_A_20_DN")
	)
	(segment
		(start 286.743902 -320.658998)
		(end 287.477962 -320.658998)
		(width 0.127)
		(layer "B.Cu")
		(net "PHY_DRV_A_TO_SCC_A_20_DN")
	)
	(segment
		(start 299.20057 -310.510428)
		(end 299.425106 -310.461152)
		(width 0.127)
		(layer "B.Cu")
		(net "PHY_DRV_A_TO_SCC_A_20_DN")
	)
	(segment
		(start 299.630338 -310.140096)
		(end 299.581062 -309.91556)
		(width 0.127)
		(layer "B.Cu")
		(net "PHY_DRV_A_TO_SCC_A_20_DN")
	)
	(segment
		(start 287.478216 -320.659252)
		(end 288.152332 -320.659252)
		(width 0.127)
		(layer "B.Cu")
		(net "PHY_DRV_A_TO_SCC_A_20_DN")
	)
	(segment
		(start 287.477962 -320.658998)
		(end 287.478216 -320.659252)
		(width 0.127)
		(layer "B.Cu")
		(net "PHY_DRV_A_TO_SCC_A_20_DN")
	)
	(segment
		(start 310.712104 -292.813486)
		(end 314.543186 -275.53412)
		(width 0.127)
		(layer "B.Cu")
		(net "PHY_DRV_A_TO_SCC_A_20_DN")
	)
	(segment
		(start 286.282638 -320.032126)
		(end 286.282638 -320.28257)
		(width 0.127)
		(layer "B.Cu")
		(net "PHY_DRV_A_TO_SCC_A_20_DN")
	)
	(segment
		(start 295.078404 -317.257176)
		(end 298.45889 -311.97169)
		(width 0.127)
		(layer "B.Cu")
		(net "PHY_DRV_A_TO_SCC_A_20_DN")
	)
	(segment
		(start 288.152332 -320.659252)
		(end 290.587684 -320.119756)
		(width 0.127)
		(layer "B.Cu")
		(net "PHY_DRV_A_TO_SCC_A_20_DN")
	)
	(segment
		(start 386.290566 -162.941508)
		(end 386.828792 -162.603942)
		(width 0.127)
		(layer "B.Cu")
		(net "PHY_DRV_A_TO_SCC_A_20_DN")
	)
	(segment
		(start 298.40936 -311.747154)
		(end 298.614846 -311.426352)
		(width 0.127)
		(layer "B.Cu")
		(net "PHY_DRV_A_TO_SCC_A_20_DN")
	)
	(segment
		(start 386.828792 -162.603942)
		(end 387.662166 -162.603942)
		(width 0.127)
		(layer "B.Cu")
		(net "PHY_DRV_A_TO_SCC_A_20_DN")
	)
	(segment
		(start 298.839382 -311.376822)
		(end 299.044614 -311.05602)
		(width 0.127)
		(layer "B.Cu")
		(net "PHY_DRV_A_TO_SCC_A_20_DN")
	)
	(arc
		(start 286.282638 -320.28257)
		(mid 286.306729 -320.403683)
		(end 286.375348 -320.506344)
		(width 0.127)
		(layer "B.Cu")
		(net "PHY_DRV_A_TO_SCC_A_20_DN")
	)
	(arc
		(start 286.409638 -319.905126)
		(mid 286.319835 -319.942323)
		(end 286.282638 -320.032126)
		(width 0.127)
		(layer "B.Cu")
		(net "PHY_DRV_A_TO_SCC_A_20_DN")
	)
	(arc
		(start 387.662166 -162.603942)
		(mid 387.787171 -162.552163)
		(end 387.83895 -162.427158)
		(width 0.127)
		(layer "B.Cu")
		(net "PHY_DRV_A_TO_SCC_A_20_DN")
	)
	(arc
		(start 286.375348 -320.506344)
		(mid 286.544442 -320.619329)
		(end 286.743902 -320.658998)
		(width 0.127)
		(layer "B.Cu")
		(net "PHY_DRV_A_TO_SCC_A_20_DN")
	)
	(segment
		(start 94.586552 -278.023066)
		(end 94.713552 -277.896066)
		(width 0.127)
		(layer "F.Cu")
		(net "PHY_DRV_A_TO_SCC_A_2_DP")
	)
	(segment
		(start 95.608902 -278.023066)
		(end 95.608902 -278.321516)
		(width 0.127)
		(layer "F.Cu")
		(net "PHY_DRV_A_TO_SCC_A_2_DP")
	)
	(segment
		(start 93.125036 -278.385016)
		(end 94.459552 -278.385016)
		(width 0.127)
		(layer "F.Cu")
		(net "PHY_DRV_A_TO_SCC_A_2_DP")
	)
	(segment
		(start 94.586552 -278.258016)
		(end 94.586552 -278.023066)
		(width 0.127)
		(layer "F.Cu")
		(net "PHY_DRV_A_TO_SCC_A_2_DP")
	)
	(segment
		(start 94.713552 -277.896066)
		(end 95.481902 -277.896066)
		(width 0.127)
		(layer "F.Cu")
		(net "PHY_DRV_A_TO_SCC_A_2_DP")
	)
	(segment
		(start 94.459552 -278.385016)
		(end 94.586552 -278.258016)
		(width 0.127)
		(layer "F.Cu")
		(net "PHY_DRV_A_TO_SCC_A_2_DP")
	)
	(arc
		(start 95.481902 -277.896066)
		(mid 95.571705 -277.933263)
		(end 95.608902 -278.023066)
		(width 0.127)
		(layer "F.Cu")
		(net "PHY_DRV_A_TO_SCC_A_2_DP")
	)
	(segment
		(start 266.219178 -351.761552)
		(end 266.505436 -351.8662)
		(width 0.1016)
		(layer "In7.Cu")
		(net "PHY_DRV_A_TO_SCC_A_2_DP")
	)
	(segment
		(start 267.068554 -351.842324)
		(end 267.197078 -352.119184)
		(width 0.1016)
		(layer "In7.Cu")
		(net "PHY_DRV_A_TO_SCC_A_2_DP")
	)
	(segment
		(start 268.46149 -352.581718)
		(end 268.73835 -352.45294)
		(width 0.1016)
		(layer "In7.Cu")
		(net "PHY_DRV_A_TO_SCC_A_2_DP")
	)
	(segment
		(start 266.782296 -351.737676)
		(end 267.068554 -351.842324)
		(width 0.1016)
		(layer "In7.Cu")
		(net "PHY_DRV_A_TO_SCC_A_2_DP")
	)
	(segment
		(start 262.06831 -350.013524)
		(end 266.090654 -351.484692)
		(width 0.1016)
		(layer "In7.Cu")
		(net "PHY_DRV_A_TO_SCC_A_2_DP")
	)
	(segment
		(start 168.994328 -312.295032)
		(end 220.943678 -323.812916)
		(width 0.1016)
		(layer "In7.Cu")
		(net "PHY_DRV_A_TO_SCC_A_2_DP")
	)
	(segment
		(start 220.943678 -323.812916)
		(end 262.06831 -350.013524)
		(width 0.1016)
		(layer "In7.Cu")
		(net "PHY_DRV_A_TO_SCC_A_2_DP")
	)
	(segment
		(start 267.76045 -352.095308)
		(end 268.046708 -352.199956)
		(width 0.1016)
		(layer "In7.Cu")
		(net "PHY_DRV_A_TO_SCC_A_2_DP")
	)
	(segment
		(start 117.973856 -279.790652)
		(end 168.994328 -312.295032)
		(width 0.1016)
		(layer "In7.Cu")
		(net "PHY_DRV_A_TO_SCC_A_2_DP")
	)
	(segment
		(start 95.608902 -278.321516)
		(end 95.608902 -278.016716)
		(width 0.1016)
		(layer "In7.Cu")
		(net "PHY_DRV_A_TO_SCC_A_2_DP")
	)
	(segment
		(start 266.090654 -351.484692)
		(end 266.219178 -351.761552)
		(width 0.1016)
		(layer "In7.Cu")
		(net "PHY_DRV_A_TO_SCC_A_2_DP")
	)
	(segment
		(start 95.710502 -277.915116)
		(end 109.512862 -277.915116)
		(width 0.1016)
		(layer "In7.Cu")
		(net "PHY_DRV_A_TO_SCC_A_2_DP")
	)
	(segment
		(start 268.175232 -352.47707)
		(end 268.46149 -352.581718)
		(width 0.1016)
		(layer "In7.Cu")
		(net "PHY_DRV_A_TO_SCC_A_2_DP")
	)
	(segment
		(start 268.046708 -352.199956)
		(end 268.175232 -352.47707)
		(width 0.1016)
		(layer "In7.Cu")
		(net "PHY_DRV_A_TO_SCC_A_2_DP")
	)
	(segment
		(start 268.73835 -352.45294)
		(end 271.2466 -353.370388)
		(width 0.1016)
		(layer "In7.Cu")
		(net "PHY_DRV_A_TO_SCC_A_2_DP")
	)
	(segment
		(start 267.197078 -352.119184)
		(end 267.483336 -352.224086)
		(width 0.1016)
		(layer "In7.Cu")
		(net "PHY_DRV_A_TO_SCC_A_2_DP")
	)
	(segment
		(start 109.512862 -277.915116)
		(end 117.973856 -279.790652)
		(width 0.1016)
		(layer "In7.Cu")
		(net "PHY_DRV_A_TO_SCC_A_2_DP")
	)
	(segment
		(start 271.2466 -353.370388)
		(end 286.80918 -353.370388)
		(width 0.1016)
		(layer "In7.Cu")
		(net "PHY_DRV_A_TO_SCC_A_2_DP")
	)
	(segment
		(start 266.505436 -351.8662)
		(end 266.782296 -351.737676)
		(width 0.1016)
		(layer "In7.Cu")
		(net "PHY_DRV_A_TO_SCC_A_2_DP")
	)
	(segment
		(start 267.483336 -352.224086)
		(end 267.76045 -352.095308)
		(width 0.1016)
		(layer "In7.Cu")
		(net "PHY_DRV_A_TO_SCC_A_2_DP")
	)
	(segment
		(start 286.846772 -354.10521)
		(end 286.436562 -354.10521)
		(width 0.1016)
		(layer "In7.Cu")
		(net "PHY_DRV_A_TO_SCC_A_2_DP")
	)
	(segment
		(start 286.973772 -353.53498)
		(end 286.973772 -353.97821)
		(width 0.1016)
		(layer "In7.Cu")
		(net "PHY_DRV_A_TO_SCC_A_2_DP")
	)
	(arc
		(start 95.608902 -278.016716)
		(mid 95.63866 -277.944874)
		(end 95.710502 -277.915116)
		(width 0.1016)
		(layer "In7.Cu")
		(net "PHY_DRV_A_TO_SCC_A_2_DP")
	)
	(arc
		(start 286.80918 -353.370388)
		(mid 286.925564 -353.418596)
		(end 286.973772 -353.53498)
		(width 0.1016)
		(layer "In7.Cu")
		(net "PHY_DRV_A_TO_SCC_A_2_DP")
	)
	(arc
		(start 286.973772 -353.97821)
		(mid 286.936575 -354.068013)
		(end 286.846772 -354.10521)
		(width 0.1016)
		(layer "In7.Cu")
		(net "PHY_DRV_A_TO_SCC_A_2_DP")
	)
	(segment
		(start 94.586552 -277.476966)
		(end 94.586552 -277.242016)
		(width 0.127)
		(layer "F.Cu")
		(net "PHY_DRV_A_TO_SCC_A_2_DN")
	)
	(segment
		(start 94.586552 -277.242016)
		(end 94.459552 -277.115016)
		(width 0.127)
		(layer "F.Cu")
		(net "PHY_DRV_A_TO_SCC_A_2_DN")
	)
	(segment
		(start 95.608902 -277.178516)
		(end 95.608902 -277.476966)
		(width 0.127)
		(layer "F.Cu")
		(net "PHY_DRV_A_TO_SCC_A_2_DN")
	)
	(segment
		(start 94.459552 -277.115016)
		(end 93.125036 -277.115016)
		(width 0.127)
		(layer "F.Cu")
		(net "PHY_DRV_A_TO_SCC_A_2_DN")
	)
	(segment
		(start 94.713552 -277.603966)
		(end 94.586552 -277.476966)
		(width 0.127)
		(layer "F.Cu")
		(net "PHY_DRV_A_TO_SCC_A_2_DN")
	)
	(segment
		(start 95.481902 -277.603966)
		(end 94.713552 -277.603966)
		(width 0.127)
		(layer "F.Cu")
		(net "PHY_DRV_A_TO_SCC_A_2_DN")
	)
	(arc
		(start 95.608902 -277.476966)
		(mid 95.571705 -277.566769)
		(end 95.481902 -277.603966)
		(width 0.127)
		(layer "F.Cu")
		(net "PHY_DRV_A_TO_SCC_A_2_DN")
	)
	(segment
		(start 169.122598 -311.985152)
		(end 195.04025 -317.73114)
		(width 0.1016)
		(layer "In7.Cu")
		(net "PHY_DRV_A_TO_SCC_A_2_DN")
	)
	(segment
		(start 195.04025 -317.73114)
		(end 195.04025 -317.731394)
		(width 0.1016)
		(layer "In7.Cu")
		(net "PHY_DRV_A_TO_SCC_A_2_DN")
	)
	(segment
		(start 95.608902 -277.178516)
		(end 95.608902 -277.483316)
		(width 0.1016)
		(layer "In7.Cu")
		(net "PHY_DRV_A_TO_SCC_A_2_DN")
	)
	(segment
		(start 262.21563 -349.715582)
		(end 271.305274 -353.040188)
		(width 0.1016)
		(layer "In7.Cu")
		(net "PHY_DRV_A_TO_SCC_A_2_DN")
	)
	(segment
		(start 95.710502 -277.584916)
		(end 109.549184 -277.584916)
		(width 0.1016)
		(layer "In7.Cu")
		(net "PHY_DRV_A_TO_SCC_A_2_DN")
	)
	(segment
		(start 287.303972 -353.53498)
		(end 287.303972 -353.97821)
		(width 0.1016)
		(layer "In7.Cu")
		(net "PHY_DRV_A_TO_SCC_A_2_DN")
	)
	(segment
		(start 287.430972 -354.10521)
		(end 287.83661 -354.10521)
		(width 0.1016)
		(layer "In7.Cu")
		(net "PHY_DRV_A_TO_SCC_A_2_DN")
	)
	(segment
		(start 109.549184 -277.584916)
		(end 118.102126 -279.480772)
		(width 0.1016)
		(layer "In7.Cu")
		(net "PHY_DRV_A_TO_SCC_A_2_DN")
	)
	(segment
		(start 118.102126 -279.480772)
		(end 169.122598 -311.985152)
		(width 0.1016)
		(layer "In7.Cu")
		(net "PHY_DRV_A_TO_SCC_A_2_DN")
	)
	(segment
		(start 221.071948 -323.503036)
		(end 262.21563 -349.715582)
		(width 0.1016)
		(layer "In7.Cu")
		(net "PHY_DRV_A_TO_SCC_A_2_DN")
	)
	(segment
		(start 195.04025 -317.731394)
		(end 221.071948 -323.503036)
		(width 0.1016)
		(layer "In7.Cu")
		(net "PHY_DRV_A_TO_SCC_A_2_DN")
	)
	(segment
		(start 271.305274 -353.040188)
		(end 286.80918 -353.040188)
		(width 0.1016)
		(layer "In7.Cu")
		(net "PHY_DRV_A_TO_SCC_A_2_DN")
	)
	(arc
		(start 95.608902 -277.483316)
		(mid 95.63866 -277.555158)
		(end 95.710502 -277.584916)
		(width 0.1016)
		(layer "In7.Cu")
		(net "PHY_DRV_A_TO_SCC_A_2_DN")
	)
	(arc
		(start 287.303972 -353.97821)
		(mid 287.341169 -354.068013)
		(end 287.430972 -354.10521)
		(width 0.1016)
		(layer "In7.Cu")
		(net "PHY_DRV_A_TO_SCC_A_2_DN")
	)
	(arc
		(start 286.80918 -353.040188)
		(mid 287.159051 -353.185109)
		(end 287.303972 -353.53498)
		(width 0.1016)
		(layer "In7.Cu")
		(net "PHY_DRV_A_TO_SCC_A_2_DN")
	)
	(segment
		(start 357.463598 -163.211764)
		(end 357.636826 -163.384992)
		(width 0.127)
		(layer "F.Cu")
		(net "PHY_DRV_A_TO_SCC_A_19_DP")
	)
	(segment
		(start 357.463598 -163.040822)
		(end 357.463598 -163.211764)
		(width 0.127)
		(layer "F.Cu")
		(net "PHY_DRV_A_TO_SCC_A_19_DP")
	)
	(segment
		(start 356.416356 -162.896042)
		(end 357.318818 -162.896042)
		(width 0.127)
		(layer "F.Cu")
		(net "PHY_DRV_A_TO_SCC_A_19_DP")
	)
	(segment
		(start 357.636826 -163.384992)
		(end 358.925114 -163.384992)
		(width 0.127)
		(layer "F.Cu")
		(net "PHY_DRV_A_TO_SCC_A_19_DP")
	)
	(segment
		(start 357.318818 -162.896042)
		(end 357.463598 -163.040822)
		(width 0.127)
		(layer "F.Cu")
		(net "PHY_DRV_A_TO_SCC_A_19_DP")
	)
	(segment
		(start 356.289102 -163.321492)
		(end 356.289102 -163.023296)
		(width 0.127)
		(layer "F.Cu")
		(net "PHY_DRV_A_TO_SCC_A_19_DP")
	)
	(arc
		(start 356.289102 -163.023296)
		(mid 356.326374 -162.933314)
		(end 356.416356 -162.896042)
		(width 0.127)
		(layer "F.Cu")
		(net "PHY_DRV_A_TO_SCC_A_19_DP")
	)
	(segment
		(start 354.345494 -164.470588)
		(end 354.37191 -164.431472)
		(width 0.127)
		(layer "B.Cu")
		(net "PHY_DRV_A_TO_SCC_A_19_DP")
	)
	(segment
		(start 312.656982 -274.28825)
		(end 338.969858 -232.986326)
		(width 0.127)
		(layer "B.Cu")
		(net "PHY_DRV_A_TO_SCC_A_19_DP")
	)
	(segment
		(start 355.792532 -162.896042)
		(end 356.112318 -162.896042)
		(width 0.127)
		(layer "B.Cu")
		(net "PHY_DRV_A_TO_SCC_A_19_DP")
	)
	(segment
		(start 287.7439 -319.151)
		(end 288.863024 -319.151)
		(width 0.127)
		(layer "B.Cu")
		(net "PHY_DRV_A_TO_SCC_A_19_DP")
	)
	(segment
		(start 355.269038 -163.100512)
		(end 355.482652 -162.966146)
		(width 0.127)
		(layer "B.Cu")
		(net "PHY_DRV_A_TO_SCC_A_19_DP")
	)
	(segment
		(start 354.37191 -164.431472)
		(end 355.269038 -163.100512)
		(width 0.127)
		(layer "B.Cu")
		(net "PHY_DRV_A_TO_SCC_A_19_DP")
	)
	(segment
		(start 354.072952 -164.874448)
		(end 354.345494 -164.470588)
		(width 0.127)
		(layer "B.Cu")
		(net "PHY_DRV_A_TO_SCC_A_19_DP")
	)
	(segment
		(start 288.863024 -319.151)
		(end 290.226496 -318.84747)
		(width 0.127)
		(layer "B.Cu")
		(net "PHY_DRV_A_TO_SCC_A_19_DP")
	)
	(segment
		(start 338.969858 -232.986326)
		(end 354.072952 -164.874448)
		(width 0.127)
		(layer "B.Cu")
		(net "PHY_DRV_A_TO_SCC_A_19_DP")
	)
	(segment
		(start 286.436562 -318.105028)
		(end 286.863536 -318.105028)
		(width 0.127)
		(layer "B.Cu")
		(net "PHY_DRV_A_TO_SCC_A_19_DP")
	)
	(segment
		(start 355.482652 -162.966146)
		(end 355.792532 -162.896042)
		(width 0.127)
		(layer "B.Cu")
		(net "PHY_DRV_A_TO_SCC_A_19_DP")
	)
	(segment
		(start 356.289102 -163.072826)
		(end 356.289102 -163.321492)
		(width 0.127)
		(layer "B.Cu")
		(net "PHY_DRV_A_TO_SCC_A_19_DP")
	)
	(segment
		(start 308.364128 -293.65194)
		(end 312.656982 -274.28825)
		(width 0.127)
		(layer "B.Cu")
		(net "PHY_DRV_A_TO_SCC_A_19_DP")
	)
	(segment
		(start 293.75227 -316.602618)
		(end 308.364128 -293.65194)
		(width 0.127)
		(layer "B.Cu")
		(net "PHY_DRV_A_TO_SCC_A_19_DP")
	)
	(segment
		(start 286.990536 -318.232028)
		(end 286.990536 -318.482472)
		(width 0.127)
		(layer "B.Cu")
		(net "PHY_DRV_A_TO_SCC_A_19_DP")
	)
	(segment
		(start 290.226496 -318.84747)
		(end 293.75227 -316.602618)
		(width 0.127)
		(layer "B.Cu")
		(net "PHY_DRV_A_TO_SCC_A_19_DP")
	)
	(arc
		(start 287.16859 -318.912748)
		(mid 287.432544 -319.089117)
		(end 287.7439 -319.151)
		(width 0.127)
		(layer "B.Cu")
		(net "PHY_DRV_A_TO_SCC_A_19_DP")
	)
	(arc
		(start 286.863536 -318.105028)
		(mid 286.953339 -318.142225)
		(end 286.990536 -318.232028)
		(width 0.127)
		(layer "B.Cu")
		(net "PHY_DRV_A_TO_SCC_A_19_DP")
	)
	(arc
		(start 286.990536 -318.482472)
		(mid 287.036744 -318.715338)
		(end 287.16859 -318.912748)
		(width 0.127)
		(layer "B.Cu")
		(net "PHY_DRV_A_TO_SCC_A_19_DP")
	)
	(arc
		(start 356.112318 -162.896042)
		(mid 356.237323 -162.947821)
		(end 356.289102 -163.072826)
		(width 0.127)
		(layer "B.Cu")
		(net "PHY_DRV_A_TO_SCC_A_19_DP")
	)
	(segment
		(start 357.463598 -162.241992)
		(end 357.590598 -162.114992)
		(width 0.127)
		(layer "F.Cu")
		(net "PHY_DRV_A_TO_SCC_A_19_DN")
	)
	(segment
		(start 357.590598 -162.114992)
		(end 358.925114 -162.114992)
		(width 0.127)
		(layer "F.Cu")
		(net "PHY_DRV_A_TO_SCC_A_19_DN")
	)
	(segment
		(start 357.336598 -162.603942)
		(end 357.463598 -162.476942)
		(width 0.127)
		(layer "F.Cu")
		(net "PHY_DRV_A_TO_SCC_A_19_DN")
	)
	(segment
		(start 356.416356 -162.603942)
		(end 357.336598 -162.603942)
		(width 0.127)
		(layer "F.Cu")
		(net "PHY_DRV_A_TO_SCC_A_19_DN")
	)
	(segment
		(start 357.463598 -162.476942)
		(end 357.463598 -162.241992)
		(width 0.127)
		(layer "F.Cu")
		(net "PHY_DRV_A_TO_SCC_A_19_DN")
	)
	(segment
		(start 356.289102 -162.178492)
		(end 356.289102 -162.476688)
		(width 0.127)
		(layer "F.Cu")
		(net "PHY_DRV_A_TO_SCC_A_19_DN")
	)
	(arc
		(start 356.289102 -162.476688)
		(mid 356.326374 -162.56667)
		(end 356.416356 -162.603942)
		(width 0.127)
		(layer "F.Cu")
		(net "PHY_DRV_A_TO_SCC_A_19_DN")
	)
	(segment
		(start 287.282636 -318.482472)
		(end 287.282636 -318.232028)
		(width 0.127)
		(layer "B.Cu")
		(net "PHY_DRV_A_TO_SCC_A_19_DN")
	)
	(segment
		(start 297.567096 -309.764176)
		(end 297.61688 -309.988458)
		(width 0.127)
		(layer "B.Cu")
		(net "PHY_DRV_A_TO_SCC_A_19_DN")
	)
	(segment
		(start 297.032934 -310.905652)
		(end 293.540688 -316.391036)
		(width 0.127)
		(layer "B.Cu")
		(net "PHY_DRV_A_TO_SCC_A_19_DN")
	)
	(segment
		(start 353.799648 -164.7571)
		(end 350.070928 -181.57317)
		(width 0.127)
		(layer "B.Cu")
		(net "PHY_DRV_A_TO_SCC_A_19_DN")
	)
	(segment
		(start 297.412156 -310.310022)
		(end 297.187874 -310.359806)
		(width 0.127)
		(layer "B.Cu")
		(net "PHY_DRV_A_TO_SCC_A_19_DN")
	)
	(segment
		(start 298.150788 -308.846982)
		(end 298.200572 -309.071518)
		(width 0.127)
		(layer "B.Cu")
		(net "PHY_DRV_A_TO_SCC_A_19_DN")
	)
	(segment
		(start 298.200572 -309.071518)
		(end 297.996102 -309.392828)
		(width 0.127)
		(layer "B.Cu")
		(net "PHY_DRV_A_TO_SCC_A_19_DN")
	)
	(segment
		(start 298.579794 -308.475888)
		(end 298.355512 -308.525672)
		(width 0.127)
		(layer "B.Cu")
		(net "PHY_DRV_A_TO_SCC_A_19_DN")
	)
	(segment
		(start 290.112958 -318.573404)
		(end 288.830766 -318.8589)
		(width 0.127)
		(layer "B.Cu")
		(net "PHY_DRV_A_TO_SCC_A_19_DN")
	)
	(segment
		(start 293.540688 -316.391036)
		(end 290.112958 -318.573404)
		(width 0.127)
		(layer "B.Cu")
		(net "PHY_DRV_A_TO_SCC_A_19_DN")
	)
	(segment
		(start 312.382916 -274.174712)
		(end 308.090062 -293.538402)
		(width 0.127)
		(layer "B.Cu")
		(net "PHY_DRV_A_TO_SCC_A_19_DN")
	)
	(segment
		(start 355.061266 -162.886136)
		(end 354.129594 -164.267896)
		(width 0.127)
		(layer "B.Cu")
		(net "PHY_DRV_A_TO_SCC_A_19_DN")
	)
	(segment
		(start 350.070928 -181.57317)
		(end 338.695792 -232.872788)
		(width 0.127)
		(layer "B.Cu")
		(net "PHY_DRV_A_TO_SCC_A_19_DN")
	)
	(segment
		(start 296.98315 -310.681116)
		(end 297.032934 -310.905652)
		(width 0.127)
		(layer "B.Cu")
		(net "PHY_DRV_A_TO_SCC_A_19_DN")
	)
	(segment
		(start 298.355512 -308.525672)
		(end 298.150788 -308.846982)
		(width 0.127)
		(layer "B.Cu")
		(net "PHY_DRV_A_TO_SCC_A_19_DN")
	)
	(segment
		(start 297.61688 -309.988458)
		(end 297.412156 -310.310022)
		(width 0.127)
		(layer "B.Cu")
		(net "PHY_DRV_A_TO_SCC_A_19_DN")
	)
	(segment
		(start 355.760274 -162.603942)
		(end 355.369368 -162.69208)
		(width 0.127)
		(layer "B.Cu")
		(net "PHY_DRV_A_TO_SCC_A_19_DN")
	)
	(segment
		(start 288.830766 -318.8589)
		(end 287.7439 -318.8589)
		(width 0.127)
		(layer "B.Cu")
		(net "PHY_DRV_A_TO_SCC_A_19_DN")
	)
	(segment
		(start 354.129594 -164.267896)
		(end 353.799648 -164.7571)
		(width 0.127)
		(layer "B.Cu")
		(net "PHY_DRV_A_TO_SCC_A_19_DN")
	)
	(segment
		(start 297.187874 -310.359806)
		(end 296.98315 -310.681116)
		(width 0.127)
		(layer "B.Cu")
		(net "PHY_DRV_A_TO_SCC_A_19_DN")
	)
	(segment
		(start 356.112318 -162.603942)
		(end 355.760274 -162.603942)
		(width 0.127)
		(layer "B.Cu")
		(net "PHY_DRV_A_TO_SCC_A_19_DN")
	)
	(segment
		(start 308.090062 -293.538402)
		(end 298.579794 -308.475888)
		(width 0.127)
		(layer "B.Cu")
		(net "PHY_DRV_A_TO_SCC_A_19_DN")
	)
	(segment
		(start 297.996102 -309.392828)
		(end 297.771566 -309.442612)
		(width 0.127)
		(layer "B.Cu")
		(net "PHY_DRV_A_TO_SCC_A_19_DN")
	)
	(segment
		(start 287.409636 -318.105028)
		(end 287.83661 -318.105028)
		(width 0.127)
		(layer "B.Cu")
		(net "PHY_DRV_A_TO_SCC_A_19_DN")
	)
	(segment
		(start 356.289102 -162.178492)
		(end 356.289102 -162.427158)
		(width 0.127)
		(layer "B.Cu")
		(net "PHY_DRV_A_TO_SCC_A_19_DN")
	)
	(segment
		(start 297.771566 -309.442612)
		(end 297.567096 -309.764176)
		(width 0.127)
		(layer "B.Cu")
		(net "PHY_DRV_A_TO_SCC_A_19_DN")
	)
	(segment
		(start 338.695792 -232.872788)
		(end 312.382916 -274.174712)
		(width 0.127)
		(layer "B.Cu")
		(net "PHY_DRV_A_TO_SCC_A_19_DN")
	)
	(segment
		(start 355.369368 -162.69208)
		(end 355.061266 -162.886136)
		(width 0.127)
		(layer "B.Cu")
		(net "PHY_DRV_A_TO_SCC_A_19_DN")
	)
	(arc
		(start 287.282636 -318.232028)
		(mid 287.319833 -318.142225)
		(end 287.409636 -318.105028)
		(width 0.127)
		(layer "B.Cu")
		(net "PHY_DRV_A_TO_SCC_A_19_DN")
	)
	(arc
		(start 287.375346 -318.706246)
		(mid 287.306745 -318.603578)
		(end 287.282636 -318.482472)
		(width 0.127)
		(layer "B.Cu")
		(net "PHY_DRV_A_TO_SCC_A_19_DN")
	)
	(arc
		(start 287.7439 -318.8589)
		(mid 287.544442 -318.819225)
		(end 287.375346 -318.706246)
		(width 0.127)
		(layer "B.Cu")
		(net "PHY_DRV_A_TO_SCC_A_19_DN")
	)
	(arc
		(start 356.289102 -162.427158)
		(mid 356.237323 -162.552163)
		(end 356.112318 -162.603942)
		(width 0.127)
		(layer "B.Cu")
		(net "PHY_DRV_A_TO_SCC_A_19_DN")
	)
	(segment
		(start 325.759064 -162.896042)
		(end 325.913496 -163.050474)
		(width 0.127)
		(layer "F.Cu")
		(net "PHY_DRV_A_TO_SCC_A_18_DP")
	)
	(segment
		(start 326.096884 -163.384992)
		(end 327.375012 -163.384992)
		(width 0.127)
		(layer "F.Cu")
		(net "PHY_DRV_A_TO_SCC_A_18_DP")
	)
	(segment
		(start 324.866254 -162.896042)
		(end 325.759064 -162.896042)
		(width 0.127)
		(layer "F.Cu")
		(net "PHY_DRV_A_TO_SCC_A_18_DP")
	)
	(segment
		(start 324.739 -163.321492)
		(end 324.739 -163.023296)
		(width 0.127)
		(layer "F.Cu")
		(net "PHY_DRV_A_TO_SCC_A_18_DP")
	)
	(segment
		(start 325.913496 -163.201604)
		(end 326.096884 -163.384992)
		(width 0.127)
		(layer "F.Cu")
		(net "PHY_DRV_A_TO_SCC_A_18_DP")
	)
	(segment
		(start 325.913496 -163.050474)
		(end 325.913496 -163.201604)
		(width 0.127)
		(layer "F.Cu")
		(net "PHY_DRV_A_TO_SCC_A_18_DP")
	)
	(arc
		(start 324.739 -163.023296)
		(mid 324.776272 -162.933314)
		(end 324.866254 -162.896042)
		(width 0.127)
		(layer "F.Cu")
		(net "PHY_DRV_A_TO_SCC_A_18_DP")
	)
	(segment
		(start 313.51982 -261.238238)
		(end 316.768734 -246.519954)
		(width 0.127)
		(layer "B.Cu")
		(net "PHY_DRV_A_TO_SCC_A_18_DP")
	)
	(segment
		(start 285.436564 -316.305184)
		(end 285.863538 -316.305184)
		(width 0.127)
		(layer "B.Cu")
		(net "PHY_DRV_A_TO_SCC_A_18_DP")
	)
	(segment
		(start 323.36486 -163.206938)
		(end 323.67601 -163.001198)
		(width 0.127)
		(layer "B.Cu")
		(net "PHY_DRV_A_TO_SCC_A_18_DP")
	)
	(segment
		(start 323.67601 -163.001198)
		(end 324.1929 -162.896042)
		(width 0.127)
		(layer "B.Cu")
		(net "PHY_DRV_A_TO_SCC_A_18_DP")
	)
	(segment
		(start 316.768734 -246.519954)
		(end 310.59374 -218.664028)
		(width 0.127)
		(layer "B.Cu")
		(net "PHY_DRV_A_TO_SCC_A_18_DP")
	)
	(segment
		(start 288.107628 -317.351156)
		(end 289.53968 -317.033402)
		(width 0.127)
		(layer "B.Cu")
		(net "PHY_DRV_A_TO_SCC_A_18_DP")
	)
	(segment
		(start 324.1929 -162.896042)
		(end 324.562216 -162.896042)
		(width 0.127)
		(layer "B.Cu")
		(net "PHY_DRV_A_TO_SCC_A_18_DP")
	)
	(segment
		(start 285.990538 -316.432184)
		(end 285.990538 -316.682628)
		(width 0.127)
		(layer "B.Cu")
		(net "PHY_DRV_A_TO_SCC_A_18_DP")
	)
	(segment
		(start 292.71976 -315.007752)
		(end 306.39131 -293.531544)
		(width 0.127)
		(layer "B.Cu")
		(net "PHY_DRV_A_TO_SCC_A_18_DP")
	)
	(segment
		(start 324.739 -163.072826)
		(end 324.739 -163.321492)
		(width 0.127)
		(layer "B.Cu")
		(net "PHY_DRV_A_TO_SCC_A_18_DP")
	)
	(segment
		(start 289.53968 -317.033402)
		(end 292.71976 -315.007752)
		(width 0.127)
		(layer "B.Cu")
		(net "PHY_DRV_A_TO_SCC_A_18_DP")
	)
	(segment
		(start 322.669916 -164.25672)
		(end 323.36486 -163.206938)
		(width 0.127)
		(layer "B.Cu")
		(net "PHY_DRV_A_TO_SCC_A_18_DP")
	)
	(segment
		(start 306.39131 -293.531544)
		(end 313.51982 -261.238238)
		(width 0.127)
		(layer "B.Cu")
		(net "PHY_DRV_A_TO_SCC_A_18_DP")
	)
	(segment
		(start 310.59374 -218.664028)
		(end 322.669916 -164.25672)
		(width 0.127)
		(layer "B.Cu")
		(net "PHY_DRV_A_TO_SCC_A_18_DP")
	)
	(segment
		(start 286.743902 -317.351156)
		(end 288.107628 -317.351156)
		(width 0.127)
		(layer "B.Cu")
		(net "PHY_DRV_A_TO_SCC_A_18_DP")
	)
	(arc
		(start 285.863538 -316.305184)
		(mid 285.953341 -316.342381)
		(end 285.990538 -316.432184)
		(width 0.127)
		(layer "B.Cu")
		(net "PHY_DRV_A_TO_SCC_A_18_DP")
	)
	(arc
		(start 286.168592 -317.112904)
		(mid 286.432546 -317.289273)
		(end 286.743902 -317.351156)
		(width 0.127)
		(layer "B.Cu")
		(net "PHY_DRV_A_TO_SCC_A_18_DP")
	)
	(arc
		(start 285.990538 -316.682628)
		(mid 286.036746 -316.915494)
		(end 286.168592 -317.112904)
		(width 0.127)
		(layer "B.Cu")
		(net "PHY_DRV_A_TO_SCC_A_18_DP")
	)
	(arc
		(start 324.562216 -162.896042)
		(mid 324.687221 -162.947821)
		(end 324.739 -163.072826)
		(width 0.127)
		(layer "B.Cu")
		(net "PHY_DRV_A_TO_SCC_A_18_DP")
	)
	(segment
		(start 324.866254 -162.603942)
		(end 325.786496 -162.603942)
		(width 0.127)
		(layer "F.Cu")
		(net "PHY_DRV_A_TO_SCC_A_18_DN")
	)
	(segment
		(start 325.913496 -162.476942)
		(end 325.913496 -162.241992)
		(width 0.127)
		(layer "F.Cu")
		(net "PHY_DRV_A_TO_SCC_A_18_DN")
	)
	(segment
		(start 325.786496 -162.603942)
		(end 325.913496 -162.476942)
		(width 0.127)
		(layer "F.Cu")
		(net "PHY_DRV_A_TO_SCC_A_18_DN")
	)
	(segment
		(start 326.040496 -162.114992)
		(end 327.375012 -162.114992)
		(width 0.127)
		(layer "F.Cu")
		(net "PHY_DRV_A_TO_SCC_A_18_DN")
	)
	(segment
		(start 324.739 -162.178492)
		(end 324.739 -162.476688)
		(width 0.127)
		(layer "F.Cu")
		(net "PHY_DRV_A_TO_SCC_A_18_DN")
	)
	(segment
		(start 325.913496 -162.241992)
		(end 326.040496 -162.114992)
		(width 0.127)
		(layer "F.Cu")
		(net "PHY_DRV_A_TO_SCC_A_18_DN")
	)
	(arc
		(start 324.739 -162.476688)
		(mid 324.776272 -162.56667)
		(end 324.866254 -162.603942)
		(width 0.127)
		(layer "F.Cu")
		(net "PHY_DRV_A_TO_SCC_A_18_DN")
	)
	(segment
		(start 316.469522 -246.520208)
		(end 313.234578 -261.175246)
		(width 0.127)
		(layer "B.Cu")
		(net "PHY_DRV_A_TO_SCC_A_18_DN")
	)
	(segment
		(start 288.07537 -317.059056)
		(end 286.743902 -317.059056)
		(width 0.127)
		(layer "B.Cu")
		(net "PHY_DRV_A_TO_SCC_A_18_DN")
	)
	(segment
		(start 324.562216 -162.603942)
		(end 324.163944 -162.603942)
		(width 0.127)
		(layer "B.Cu")
		(net "PHY_DRV_A_TO_SCC_A_18_DN")
	)
	(segment
		(start 295.179242 -310.60009)
		(end 292.508178 -314.79617)
		(width 0.127)
		(layer "B.Cu")
		(net "PHY_DRV_A_TO_SCC_A_18_DN")
	)
	(segment
		(start 295.334182 -310.054244)
		(end 295.129458 -310.375554)
		(width 0.127)
		(layer "B.Cu")
		(net "PHY_DRV_A_TO_SCC_A_18_DN")
	)
	(segment
		(start 324.163944 -162.603942)
		(end 323.562218 -162.726116)
		(width 0.127)
		(layer "B.Cu")
		(net "PHY_DRV_A_TO_SCC_A_18_DN")
	)
	(segment
		(start 295.558464 -310.00446)
		(end 295.334182 -310.054244)
		(width 0.127)
		(layer "B.Cu")
		(net "PHY_DRV_A_TO_SCC_A_18_DN")
	)
	(segment
		(start 310.294528 -218.664028)
		(end 316.469522 -246.520208)
		(width 0.127)
		(layer "B.Cu")
		(net "PHY_DRV_A_TO_SCC_A_18_DN")
	)
	(segment
		(start 296.34688 -308.765956)
		(end 296.14241 -309.087266)
		(width 0.127)
		(layer "B.Cu")
		(net "PHY_DRV_A_TO_SCC_A_18_DN")
	)
	(segment
		(start 296.297096 -308.54142)
		(end 296.34688 -308.765956)
		(width 0.127)
		(layer "B.Cu")
		(net "PHY_DRV_A_TO_SCC_A_18_DN")
	)
	(segment
		(start 296.501566 -308.22011)
		(end 296.297096 -308.54142)
		(width 0.127)
		(layer "B.Cu")
		(net "PHY_DRV_A_TO_SCC_A_18_DN")
	)
	(segment
		(start 295.763188 -309.682896)
		(end 295.558464 -310.00446)
		(width 0.127)
		(layer "B.Cu")
		(net "PHY_DRV_A_TO_SCC_A_18_DN")
	)
	(segment
		(start 296.726102 -308.170326)
		(end 296.501566 -308.22011)
		(width 0.127)
		(layer "B.Cu")
		(net "PHY_DRV_A_TO_SCC_A_18_DN")
	)
	(segment
		(start 295.71315 -309.458614)
		(end 295.763188 -309.682896)
		(width 0.127)
		(layer "B.Cu")
		(net "PHY_DRV_A_TO_SCC_A_18_DN")
	)
	(segment
		(start 295.129458 -310.375554)
		(end 295.179242 -310.60009)
		(width 0.127)
		(layer "B.Cu")
		(net "PHY_DRV_A_TO_SCC_A_18_DN")
	)
	(segment
		(start 295.917874 -309.13705)
		(end 295.71315 -309.458614)
		(width 0.127)
		(layer "B.Cu")
		(net "PHY_DRV_A_TO_SCC_A_18_DN")
	)
	(segment
		(start 286.282638 -316.682628)
		(end 286.282638 -316.432184)
		(width 0.127)
		(layer "B.Cu")
		(net "PHY_DRV_A_TO_SCC_A_18_DN")
	)
	(segment
		(start 289.426142 -316.759336)
		(end 288.07537 -317.059056)
		(width 0.127)
		(layer "B.Cu")
		(net "PHY_DRV_A_TO_SCC_A_18_DN")
	)
	(segment
		(start 324.739 -162.178492)
		(end 324.739 -162.427158)
		(width 0.127)
		(layer "B.Cu")
		(net "PHY_DRV_A_TO_SCC_A_18_DN")
	)
	(segment
		(start 313.234578 -261.175246)
		(end 306.11699 -293.418006)
		(width 0.127)
		(layer "B.Cu")
		(net "PHY_DRV_A_TO_SCC_A_18_DN")
	)
	(segment
		(start 323.562218 -162.726116)
		(end 323.15404 -162.996118)
		(width 0.127)
		(layer "B.Cu")
		(net "PHY_DRV_A_TO_SCC_A_18_DN")
	)
	(segment
		(start 306.11699 -293.418006)
		(end 296.726102 -308.170326)
		(width 0.127)
		(layer "B.Cu")
		(net "PHY_DRV_A_TO_SCC_A_18_DN")
	)
	(segment
		(start 286.409638 -316.305184)
		(end 286.836612 -316.305184)
		(width 0.127)
		(layer "B.Cu")
		(net "PHY_DRV_A_TO_SCC_A_18_DN")
	)
	(segment
		(start 296.14241 -309.087266)
		(end 295.917874 -309.13705)
		(width 0.127)
		(layer "B.Cu")
		(net "PHY_DRV_A_TO_SCC_A_18_DN")
	)
	(segment
		(start 322.396358 -164.140642)
		(end 310.294528 -218.664028)
		(width 0.127)
		(layer "B.Cu")
		(net "PHY_DRV_A_TO_SCC_A_18_DN")
	)
	(segment
		(start 323.15404 -162.996118)
		(end 322.396358 -164.140642)
		(width 0.127)
		(layer "B.Cu")
		(net "PHY_DRV_A_TO_SCC_A_18_DN")
	)
	(segment
		(start 292.508178 -314.79617)
		(end 289.426142 -316.759336)
		(width 0.127)
		(layer "B.Cu")
		(net "PHY_DRV_A_TO_SCC_A_18_DN")
	)
	(arc
		(start 286.375348 -316.906402)
		(mid 286.306747 -316.803734)
		(end 286.282638 -316.682628)
		(width 0.127)
		(layer "B.Cu")
		(net "PHY_DRV_A_TO_SCC_A_18_DN")
	)
	(arc
		(start 286.282638 -316.432184)
		(mid 286.319835 -316.342381)
		(end 286.409638 -316.305184)
		(width 0.127)
		(layer "B.Cu")
		(net "PHY_DRV_A_TO_SCC_A_18_DN")
	)
	(arc
		(start 324.739 -162.427158)
		(mid 324.687221 -162.552163)
		(end 324.562216 -162.603942)
		(width 0.127)
		(layer "B.Cu")
		(net "PHY_DRV_A_TO_SCC_A_18_DN")
	)
	(arc
		(start 286.743902 -317.059056)
		(mid 286.544444 -317.019381)
		(end 286.375348 -316.906402)
		(width 0.127)
		(layer "B.Cu")
		(net "PHY_DRV_A_TO_SCC_A_18_DN")
	)
	(segment
		(start 189.236604 -163.257992)
		(end 189.109604 -163.384992)
		(width 0.127)
		(layer "F.Cu")
		(net "PHY_DRV_A_TO_SCC_A_17_DP")
	)
	(segment
		(start 189.236604 -163.023042)
		(end 189.236604 -163.257992)
		(width 0.127)
		(layer "F.Cu")
		(net "PHY_DRV_A_TO_SCC_A_17_DP")
	)
	(segment
		(start 189.363604 -162.896042)
		(end 189.236604 -163.023042)
		(width 0.127)
		(layer "F.Cu")
		(net "PHY_DRV_A_TO_SCC_A_17_DP")
	)
	(segment
		(start 190.258954 -163.321492)
		(end 190.258954 -163.023042)
		(width 0.127)
		(layer "F.Cu")
		(net "PHY_DRV_A_TO_SCC_A_17_DP")
	)
	(segment
		(start 189.109604 -163.384992)
		(end 187.775088 -163.384992)
		(width 0.127)
		(layer "F.Cu")
		(net "PHY_DRV_A_TO_SCC_A_17_DP")
	)
	(segment
		(start 190.131954 -162.896042)
		(end 189.363604 -162.896042)
		(width 0.127)
		(layer "F.Cu")
		(net "PHY_DRV_A_TO_SCC_A_17_DP")
	)
	(arc
		(start 190.258954 -163.023042)
		(mid 190.221757 -162.933239)
		(end 190.131954 -162.896042)
		(width 0.127)
		(layer "F.Cu")
		(net "PHY_DRV_A_TO_SCC_A_17_DP")
	)
	(segment
		(start 268.630908 -323.41947)
		(end 268.344904 -323.314568)
		(width 0.1016)
		(layer "In7.Cu")
		(net "PHY_DRV_A_TO_SCC_A_17_DP")
	)
	(segment
		(start 285.973774 -326.978264)
		(end 285.973774 -326.535034)
		(width 0.1016)
		(layer "In7.Cu")
		(net "PHY_DRV_A_TO_SCC_A_17_DP")
	)
	(segment
		(start 200.20407 -231.720644)
		(end 188.548264 -177.489104)
		(width 0.1016)
		(layer "In7.Cu")
		(net "PHY_DRV_A_TO_SCC_A_17_DP")
	)
	(segment
		(start 269.045944 -323.800978)
		(end 268.759686 -323.69633)
		(width 0.1016)
		(layer "In7.Cu")
		(net "PHY_DRV_A_TO_SCC_A_17_DP")
	)
	(segment
		(start 191.216026 -163.037266)
		(end 191.21628 -163.037266)
		(width 0.1016)
		(layer "In7.Cu")
		(net "PHY_DRV_A_TO_SCC_A_17_DP")
	)
	(segment
		(start 270.300958 -324.030086)
		(end 270.023844 -324.15861)
		(width 0.1016)
		(layer "In7.Cu")
		(net "PHY_DRV_A_TO_SCC_A_17_DP")
	)
	(segment
		(start 190.964312 -162.915092)
		(end 190.360554 -162.915092)
		(width 0.1016)
		(layer "In7.Cu")
		(net "PHY_DRV_A_TO_SCC_A_17_DP")
	)
	(segment
		(start 190.258954 -163.016692)
		(end 190.258954 -163.321492)
		(width 0.1016)
		(layer "In7.Cu")
		(net "PHY_DRV_A_TO_SCC_A_17_DP")
	)
	(segment
		(start 268.344904 -323.314568)
		(end 268.06779 -323.443346)
		(width 0.1016)
		(layer "In7.Cu")
		(net "PHY_DRV_A_TO_SCC_A_17_DP")
	)
	(segment
		(start 268.759686 -323.69633)
		(end 268.630908 -323.41947)
		(width 0.1016)
		(layer "In7.Cu")
		(net "PHY_DRV_A_TO_SCC_A_17_DP")
	)
	(segment
		(start 285.809182 -326.370442)
		(end 276.699218 -326.370442)
		(width 0.1016)
		(layer "In7.Cu")
		(net "PHY_DRV_A_TO_SCC_A_17_DP")
	)
	(segment
		(start 191.21628 -163.037266)
		(end 190.964312 -162.915092)
		(width 0.1016)
		(layer "In7.Cu")
		(net "PHY_DRV_A_TO_SCC_A_17_DP")
	)
	(segment
		(start 276.699218 -326.370442)
		(end 270.300958 -324.030086)
		(width 0.1016)
		(layer "In7.Cu")
		(net "PHY_DRV_A_TO_SCC_A_17_DP")
	)
	(segment
		(start 270.023844 -324.15861)
		(end 269.737586 -324.053962)
		(width 0.1016)
		(layer "In7.Cu")
		(net "PHY_DRV_A_TO_SCC_A_17_DP")
	)
	(segment
		(start 285.436564 -327.105264)
		(end 285.846774 -327.105264)
		(width 0.1016)
		(layer "In7.Cu")
		(net "PHY_DRV_A_TO_SCC_A_17_DP")
	)
	(segment
		(start 269.609062 -323.777102)
		(end 269.322804 -323.672454)
		(width 0.1016)
		(layer "In7.Cu")
		(net "PHY_DRV_A_TO_SCC_A_17_DP")
	)
	(segment
		(start 188.548264 -177.489104)
		(end 191.636904 -163.66871)
		(width 0.1016)
		(layer "In7.Cu")
		(net "PHY_DRV_A_TO_SCC_A_17_DP")
	)
	(segment
		(start 267.653008 -323.061584)
		(end 267.36675 -322.956936)
		(width 0.1016)
		(layer "In7.Cu")
		(net "PHY_DRV_A_TO_SCC_A_17_DP")
	)
	(segment
		(start 268.06779 -323.443346)
		(end 267.781532 -323.338444)
		(width 0.1016)
		(layer "In7.Cu")
		(net "PHY_DRV_A_TO_SCC_A_17_DP")
	)
	(segment
		(start 267.781532 -323.338444)
		(end 267.653008 -323.061584)
		(width 0.1016)
		(layer "In7.Cu")
		(net "PHY_DRV_A_TO_SCC_A_17_DP")
	)
	(segment
		(start 267.36675 -322.956936)
		(end 233.813096 -300.535086)
		(width 0.1016)
		(layer "In7.Cu")
		(net "PHY_DRV_A_TO_SCC_A_17_DP")
	)
	(segment
		(start 269.322804 -323.672454)
		(end 269.045944 -323.800978)
		(width 0.1016)
		(layer "In7.Cu")
		(net "PHY_DRV_A_TO_SCC_A_17_DP")
	)
	(segment
		(start 191.46774 -163.159186)
		(end 191.216026 -163.037266)
		(width 0.1016)
		(layer "In7.Cu")
		(net "PHY_DRV_A_TO_SCC_A_17_DP")
	)
	(segment
		(start 191.636904 -163.66871)
		(end 191.46774 -163.159186)
		(width 0.1016)
		(layer "In7.Cu")
		(net "PHY_DRV_A_TO_SCC_A_17_DP")
	)
	(segment
		(start 233.813096 -300.535086)
		(end 200.20407 -231.720644)
		(width 0.1016)
		(layer "In7.Cu")
		(net "PHY_DRV_A_TO_SCC_A_17_DP")
	)
	(segment
		(start 269.737586 -324.053962)
		(end 269.609062 -323.777102)
		(width 0.1016)
		(layer "In7.Cu")
		(net "PHY_DRV_A_TO_SCC_A_17_DP")
	)
	(arc
		(start 190.360554 -162.915092)
		(mid 190.288712 -162.94485)
		(end 190.258954 -163.016692)
		(width 0.1016)
		(layer "In7.Cu")
		(net "PHY_DRV_A_TO_SCC_A_17_DP")
	)
	(arc
		(start 285.846774 -327.105264)
		(mid 285.936577 -327.068067)
		(end 285.973774 -326.978264)
		(width 0.1016)
		(layer "In7.Cu")
		(net "PHY_DRV_A_TO_SCC_A_17_DP")
	)
	(arc
		(start 285.973774 -326.535034)
		(mid 285.925566 -326.41865)
		(end 285.809182 -326.370442)
		(width 0.1016)
		(layer "In7.Cu")
		(net "PHY_DRV_A_TO_SCC_A_17_DP")
	)
	(segment
		(start 189.109604 -162.114992)
		(end 187.775088 -162.114992)
		(width 0.127)
		(layer "F.Cu")
		(net "PHY_DRV_A_TO_SCC_A_17_DN")
	)
	(segment
		(start 189.236604 -162.476942)
		(end 189.236604 -162.241992)
		(width 0.127)
		(layer "F.Cu")
		(net "PHY_DRV_A_TO_SCC_A_17_DN")
	)
	(segment
		(start 190.258954 -162.178492)
		(end 190.258954 -162.476942)
		(width 0.127)
		(layer "F.Cu")
		(net "PHY_DRV_A_TO_SCC_A_17_DN")
	)
	(segment
		(start 189.363604 -162.603942)
		(end 189.236604 -162.476942)
		(width 0.127)
		(layer "F.Cu")
		(net "PHY_DRV_A_TO_SCC_A_17_DN")
	)
	(segment
		(start 189.236604 -162.241992)
		(end 189.109604 -162.114992)
		(width 0.127)
		(layer "F.Cu")
		(net "PHY_DRV_A_TO_SCC_A_17_DN")
	)
	(segment
		(start 190.131954 -162.603942)
		(end 189.363604 -162.603942)
		(width 0.127)
		(layer "F.Cu")
		(net "PHY_DRV_A_TO_SCC_A_17_DN")
	)
	(arc
		(start 190.258954 -162.476942)
		(mid 190.221757 -162.566745)
		(end 190.131954 -162.603942)
		(width 0.127)
		(layer "F.Cu")
		(net "PHY_DRV_A_TO_SCC_A_17_DN")
	)
	(segment
		(start 200.518522 -231.611932)
		(end 234.070906 -300.309788)
		(width 0.1016)
		(layer "In7.Cu")
		(net "PHY_DRV_A_TO_SCC_A_17_DN")
	)
	(segment
		(start 286.430974 -327.105264)
		(end 286.836612 -327.105264)
		(width 0.1016)
		(layer "In7.Cu")
		(net "PHY_DRV_A_TO_SCC_A_17_DN")
	)
	(segment
		(start 276.757892 -326.040242)
		(end 285.809182 -326.040242)
		(width 0.1016)
		(layer "In7.Cu")
		(net "PHY_DRV_A_TO_SCC_A_17_DN")
	)
	(segment
		(start 267.517372 -322.660264)
		(end 276.757892 -326.040242)
		(width 0.1016)
		(layer "In7.Cu")
		(net "PHY_DRV_A_TO_SCC_A_17_DN")
	)
	(segment
		(start 190.360554 -162.584892)
		(end 191.040258 -162.584892)
		(width 0.1016)
		(layer "In7.Cu")
		(net "PHY_DRV_A_TO_SCC_A_17_DN")
	)
	(segment
		(start 191.040258 -162.584892)
		(end 191.737488 -162.922458)
		(width 0.1016)
		(layer "In7.Cu")
		(net "PHY_DRV_A_TO_SCC_A_17_DN")
	)
	(segment
		(start 191.737488 -162.922458)
		(end 191.979296 -163.651438)
		(width 0.1016)
		(layer "In7.Cu")
		(net "PHY_DRV_A_TO_SCC_A_17_DN")
	)
	(segment
		(start 190.258954 -162.178492)
		(end 190.258954 -162.483292)
		(width 0.1016)
		(layer "In7.Cu")
		(net "PHY_DRV_A_TO_SCC_A_17_DN")
	)
	(segment
		(start 286.303974 -326.535034)
		(end 286.303974 -326.978264)
		(width 0.1016)
		(layer "In7.Cu")
		(net "PHY_DRV_A_TO_SCC_A_17_DN")
	)
	(segment
		(start 234.070906 -300.309788)
		(end 267.517372 -322.660264)
		(width 0.1016)
		(layer "In7.Cu")
		(net "PHY_DRV_A_TO_SCC_A_17_DN")
	)
	(segment
		(start 188.886592 -177.490628)
		(end 200.518522 -231.611932)
		(width 0.1016)
		(layer "In7.Cu")
		(net "PHY_DRV_A_TO_SCC_A_17_DN")
	)
	(segment
		(start 191.979296 -163.651438)
		(end 188.886592 -177.490628)
		(width 0.1016)
		(layer "In7.Cu")
		(net "PHY_DRV_A_TO_SCC_A_17_DN")
	)
	(arc
		(start 286.303974 -326.978264)
		(mid 286.341171 -327.068067)
		(end 286.430974 -327.105264)
		(width 0.1016)
		(layer "In7.Cu")
		(net "PHY_DRV_A_TO_SCC_A_17_DN")
	)
	(arc
		(start 190.258954 -162.483292)
		(mid 190.288712 -162.555134)
		(end 190.360554 -162.584892)
		(width 0.1016)
		(layer "In7.Cu")
		(net "PHY_DRV_A_TO_SCC_A_17_DN")
	)
	(arc
		(start 285.809182 -326.040242)
		(mid 286.159053 -326.185163)
		(end 286.303974 -326.535034)
		(width 0.1016)
		(layer "In7.Cu")
		(net "PHY_DRV_A_TO_SCC_A_17_DN")
	)
	(segment
		(start 157.686502 -163.257992)
		(end 157.686502 -163.044632)
		(width 0.127)
		(layer "F.Cu")
		(net "PHY_DRV_A_TO_SCC_A_16_DP")
	)
	(segment
		(start 158.708852 -163.023042)
		(end 158.708852 -163.321492)
		(width 0.127)
		(layer "F.Cu")
		(net "PHY_DRV_A_TO_SCC_A_16_DP")
	)
	(segment
		(start 157.686502 -163.044632)
		(end 157.835092 -162.896042)
		(width 0.127)
		(layer "F.Cu")
		(net "PHY_DRV_A_TO_SCC_A_16_DP")
	)
	(segment
		(start 156.224986 -163.384992)
		(end 157.559502 -163.384992)
		(width 0.127)
		(layer "F.Cu")
		(net "PHY_DRV_A_TO_SCC_A_16_DP")
	)
	(segment
		(start 157.835092 -162.896042)
		(end 158.581852 -162.896042)
		(width 0.127)
		(layer "F.Cu")
		(net "PHY_DRV_A_TO_SCC_A_16_DP")
	)
	(segment
		(start 157.559502 -163.384992)
		(end 157.686502 -163.257992)
		(width 0.127)
		(layer "F.Cu")
		(net "PHY_DRV_A_TO_SCC_A_16_DP")
	)
	(arc
		(start 158.581852 -162.896042)
		(mid 158.671655 -162.933239)
		(end 158.708852 -163.023042)
		(width 0.127)
		(layer "F.Cu")
		(net "PHY_DRV_A_TO_SCC_A_16_DP")
	)
	(segment
		(start 286.436562 -328.905108)
		(end 286.846772 -328.905108)
		(width 0.1016)
		(layer "In7.Cu")
		(net "PHY_DRV_A_TO_SCC_A_16_DP")
	)
	(segment
		(start 158.708852 -163.016692)
		(end 158.708852 -163.321492)
		(width 0.1016)
		(layer "In7.Cu")
		(net "PHY_DRV_A_TO_SCC_A_16_DP")
	)
	(segment
		(start 269.288006 -325.734426)
		(end 269.159482 -325.457566)
		(width 0.1016)
		(layer "In7.Cu")
		(net "PHY_DRV_A_TO_SCC_A_16_DP")
	)
	(segment
		(start 160.231074 -163.071048)
		(end 159.529018 -162.915092)
		(width 0.1016)
		(layer "In7.Cu")
		(net "PHY_DRV_A_TO_SCC_A_16_DP")
	)
	(segment
		(start 266.848336 -324.612)
		(end 232.775252 -301.843186)
		(width 0.1016)
		(layer "In7.Cu")
		(net "PHY_DRV_A_TO_SCC_A_16_DP")
	)
	(segment
		(start 269.159482 -325.457566)
		(end 268.873224 -325.352918)
		(width 0.1016)
		(layer "In7.Cu")
		(net "PHY_DRV_A_TO_SCC_A_16_DP")
	)
	(segment
		(start 286.973772 -328.778108)
		(end 286.973772 -328.334878)
		(width 0.1016)
		(layer "In7.Cu")
		(net "PHY_DRV_A_TO_SCC_A_16_DP")
	)
	(segment
		(start 267.61821 -325.12381)
		(end 267.331952 -325.018908)
		(width 0.1016)
		(layer "In7.Cu")
		(net "PHY_DRV_A_TO_SCC_A_16_DP")
	)
	(segment
		(start 160.231074 -163.070794)
		(end 160.231074 -163.071048)
		(width 0.1016)
		(layer "In7.Cu")
		(net "PHY_DRV_A_TO_SCC_A_16_DP")
	)
	(segment
		(start 286.80918 -328.170286)
		(end 276.576536 -328.170286)
		(width 0.1016)
		(layer "In7.Cu")
		(net "PHY_DRV_A_TO_SCC_A_16_DP")
	)
	(segment
		(start 267.331952 -325.018908)
		(end 267.203428 -324.742048)
		(width 0.1016)
		(layer "In7.Cu")
		(net "PHY_DRV_A_TO_SCC_A_16_DP")
	)
	(segment
		(start 268.873224 -325.352918)
		(end 268.59611 -325.481442)
		(width 0.1016)
		(layer "In7.Cu")
		(net "PHY_DRV_A_TO_SCC_A_16_DP")
	)
	(segment
		(start 268.59611 -325.481442)
		(end 268.310106 -325.376794)
		(width 0.1016)
		(layer "In7.Cu")
		(net "PHY_DRV_A_TO_SCC_A_16_DP")
	)
	(segment
		(start 232.775252 -301.843186)
		(end 199.13473 -232.773474)
		(width 0.1016)
		(layer "In7.Cu")
		(net "PHY_DRV_A_TO_SCC_A_16_DP")
	)
	(segment
		(start 199.13473 -232.773474)
		(end 195.335144 -215.475312)
		(width 0.1016)
		(layer "In7.Cu")
		(net "PHY_DRV_A_TO_SCC_A_16_DP")
	)
	(segment
		(start 195.335144 -215.475312)
		(end 161.74847 -164.036756)
		(width 0.1016)
		(layer "In7.Cu")
		(net "PHY_DRV_A_TO_SCC_A_16_DP")
	)
	(segment
		(start 159.529018 -162.915092)
		(end 158.810452 -162.915092)
		(width 0.1016)
		(layer "In7.Cu")
		(net "PHY_DRV_A_TO_SCC_A_16_DP")
	)
	(segment
		(start 276.576536 -328.170286)
		(end 269.851124 -325.71055)
		(width 0.1016)
		(layer "In7.Cu")
		(net "PHY_DRV_A_TO_SCC_A_16_DP")
	)
	(segment
		(start 267.89507 -324.995032)
		(end 267.61821 -325.12381)
		(width 0.1016)
		(layer "In7.Cu")
		(net "PHY_DRV_A_TO_SCC_A_16_DP")
	)
	(segment
		(start 269.574264 -325.839074)
		(end 269.288006 -325.734426)
		(width 0.1016)
		(layer "In7.Cu")
		(net "PHY_DRV_A_TO_SCC_A_16_DP")
	)
	(segment
		(start 268.181328 -325.099934)
		(end 267.89507 -324.995032)
		(width 0.1016)
		(layer "In7.Cu")
		(net "PHY_DRV_A_TO_SCC_A_16_DP")
	)
	(segment
		(start 268.310106 -325.376794)
		(end 268.181328 -325.099934)
		(width 0.1016)
		(layer "In7.Cu")
		(net "PHY_DRV_A_TO_SCC_A_16_DP")
	)
	(segment
		(start 266.848336 -324.612254)
		(end 266.848336 -324.612)
		(width 0.1016)
		(layer "In7.Cu")
		(net "PHY_DRV_A_TO_SCC_A_16_DP")
	)
	(segment
		(start 267.203428 -324.742048)
		(end 266.848336 -324.612254)
		(width 0.1016)
		(layer "In7.Cu")
		(net "PHY_DRV_A_TO_SCC_A_16_DP")
	)
	(segment
		(start 161.74847 -164.036756)
		(end 160.231074 -163.070794)
		(width 0.1016)
		(layer "In7.Cu")
		(net "PHY_DRV_A_TO_SCC_A_16_DP")
	)
	(segment
		(start 269.851124 -325.71055)
		(end 269.574264 -325.839074)
		(width 0.1016)
		(layer "In7.Cu")
		(net "PHY_DRV_A_TO_SCC_A_16_DP")
	)
	(arc
		(start 158.810452 -162.915092)
		(mid 158.73861 -162.94485)
		(end 158.708852 -163.016692)
		(width 0.1016)
		(layer "In7.Cu")
		(net "PHY_DRV_A_TO_SCC_A_16_DP")
	)
	(arc
		(start 286.973772 -328.334878)
		(mid 286.925564 -328.218494)
		(end 286.80918 -328.170286)
		(width 0.1016)
		(layer "In7.Cu")
		(net "PHY_DRV_A_TO_SCC_A_16_DP")
	)
	(arc
		(start 286.846772 -328.905108)
		(mid 286.936575 -328.867911)
		(end 286.973772 -328.778108)
		(width 0.1016)
		(layer "In7.Cu")
		(net "PHY_DRV_A_TO_SCC_A_16_DP")
	)
	(segment
		(start 157.559502 -162.114992)
		(end 157.686502 -162.241992)
		(width 0.127)
		(layer "F.Cu")
		(net "PHY_DRV_A_TO_SCC_A_16_DN")
	)
	(segment
		(start 157.813502 -162.603942)
		(end 158.581852 -162.603942)
		(width 0.127)
		(layer "F.Cu")
		(net "PHY_DRV_A_TO_SCC_A_16_DN")
	)
	(segment
		(start 158.708852 -162.476942)
		(end 158.708852 -162.178492)
		(width 0.127)
		(layer "F.Cu")
		(net "PHY_DRV_A_TO_SCC_A_16_DN")
	)
	(segment
		(start 157.686502 -162.476942)
		(end 157.813502 -162.603942)
		(width 0.127)
		(layer "F.Cu")
		(net "PHY_DRV_A_TO_SCC_A_16_DN")
	)
	(segment
		(start 157.686502 -162.241992)
		(end 157.686502 -162.476942)
		(width 0.127)
		(layer "F.Cu")
		(net "PHY_DRV_A_TO_SCC_A_16_DN")
	)
	(segment
		(start 156.224986 -162.114992)
		(end 157.559502 -162.114992)
		(width 0.127)
		(layer "F.Cu")
		(net "PHY_DRV_A_TO_SCC_A_16_DN")
	)
	(arc
		(start 158.581852 -162.603942)
		(mid 158.671655 -162.566745)
		(end 158.708852 -162.476942)
		(width 0.127)
		(layer "F.Cu")
		(net "PHY_DRV_A_TO_SCC_A_16_DN")
	)
	(segment
		(start 287.303972 -328.334878)
		(end 287.303972 -328.778108)
		(width 0.1016)
		(layer "In7.Cu")
		(net "PHY_DRV_A_TO_SCC_A_16_DN")
	)
	(segment
		(start 266.99972 -324.315836)
		(end 276.63521 -327.840086)
		(width 0.1016)
		(layer "In7.Cu")
		(net "PHY_DRV_A_TO_SCC_A_16_DN")
	)
	(segment
		(start 233.033062 -301.618142)
		(end 266.99972 -324.315836)
		(width 0.1016)
		(layer "In7.Cu")
		(net "PHY_DRV_A_TO_SCC_A_16_DN")
	)
	(segment
		(start 199.448928 -232.664254)
		(end 233.033062 -301.618142)
		(width 0.1016)
		(layer "In7.Cu")
		(net "PHY_DRV_A_TO_SCC_A_16_DN")
	)
	(segment
		(start 276.63521 -327.840086)
		(end 286.80918 -327.840086)
		(width 0.1016)
		(layer "In7.Cu")
		(net "PHY_DRV_A_TO_SCC_A_16_DN")
	)
	(segment
		(start 195.64477 -215.345518)
		(end 199.448928 -232.664254)
		(width 0.1016)
		(layer "In7.Cu")
		(net "PHY_DRV_A_TO_SCC_A_16_DN")
	)
	(segment
		(start 161.98596 -163.796472)
		(end 195.64477 -215.345518)
		(width 0.1016)
		(layer "In7.Cu")
		(net "PHY_DRV_A_TO_SCC_A_16_DN")
	)
	(segment
		(start 287.430972 -328.905108)
		(end 287.83661 -328.905108)
		(width 0.1016)
		(layer "In7.Cu")
		(net "PHY_DRV_A_TO_SCC_A_16_DN")
	)
	(segment
		(start 158.810452 -162.584892)
		(end 159.56534 -162.584892)
		(width 0.1016)
		(layer "In7.Cu")
		(net "PHY_DRV_A_TO_SCC_A_16_DN")
	)
	(segment
		(start 160.359344 -162.760914)
		(end 161.98596 -163.796472)
		(width 0.1016)
		(layer "In7.Cu")
		(net "PHY_DRV_A_TO_SCC_A_16_DN")
	)
	(segment
		(start 158.708852 -162.178492)
		(end 158.708852 -162.483292)
		(width 0.1016)
		(layer "In7.Cu")
		(net "PHY_DRV_A_TO_SCC_A_16_DN")
	)
	(segment
		(start 159.56534 -162.584892)
		(end 160.359344 -162.760914)
		(width 0.1016)
		(layer "In7.Cu")
		(net "PHY_DRV_A_TO_SCC_A_16_DN")
	)
	(arc
		(start 286.80918 -327.840086)
		(mid 287.159051 -327.985007)
		(end 287.303972 -328.334878)
		(width 0.1016)
		(layer "In7.Cu")
		(net "PHY_DRV_A_TO_SCC_A_16_DN")
	)
	(arc
		(start 158.791402 -162.58286)
		(mid 158.800879 -162.584332)
		(end 158.810452 -162.584892)
		(width 0.1016)
		(layer "In7.Cu")
		(net "PHY_DRV_A_TO_SCC_A_16_DN")
	)
	(arc
		(start 287.303972 -328.778108)
		(mid 287.341169 -328.867911)
		(end 287.430972 -328.905108)
		(width 0.1016)
		(layer "In7.Cu")
		(net "PHY_DRV_A_TO_SCC_A_16_DN")
	)
	(arc
		(start 158.708852 -162.483292)
		(mid 158.732171 -162.547967)
		(end 158.791402 -162.58286)
		(width 0.1016)
		(layer "In7.Cu")
		(net "PHY_DRV_A_TO_SCC_A_16_DN")
	)
	(segment
		(start 126.2634 -162.896042)
		(end 126.1364 -163.023042)
		(width 0.127)
		(layer "F.Cu")
		(net "PHY_DRV_A_TO_SCC_A_15_DP")
	)
	(segment
		(start 126.0094 -163.384992)
		(end 124.674884 -163.384992)
		(width 0.127)
		(layer "F.Cu")
		(net "PHY_DRV_A_TO_SCC_A_15_DP")
	)
	(segment
		(start 127.03175 -162.896042)
		(end 126.2634 -162.896042)
		(width 0.127)
		(layer "F.Cu")
		(net "PHY_DRV_A_TO_SCC_A_15_DP")
	)
	(segment
		(start 126.1364 -163.257992)
		(end 126.0094 -163.384992)
		(width 0.127)
		(layer "F.Cu")
		(net "PHY_DRV_A_TO_SCC_A_15_DP")
	)
	(segment
		(start 127.15875 -163.321492)
		(end 127.15875 -163.023042)
		(width 0.127)
		(layer "F.Cu")
		(net "PHY_DRV_A_TO_SCC_A_15_DP")
	)
	(segment
		(start 126.1364 -163.023042)
		(end 126.1364 -163.257992)
		(width 0.127)
		(layer "F.Cu")
		(net "PHY_DRV_A_TO_SCC_A_15_DP")
	)
	(arc
		(start 127.15875 -163.023042)
		(mid 127.121553 -162.933239)
		(end 127.03175 -162.896042)
		(width 0.127)
		(layer "F.Cu")
		(net "PHY_DRV_A_TO_SCC_A_15_DP")
	)
	(segment
		(start 128.123188 -162.915092)
		(end 127.26035 -162.915092)
		(width 0.1016)
		(layer "In7.Cu")
		(net "PHY_DRV_A_TO_SCC_A_15_DP")
	)
	(segment
		(start 267.29944 -328.087482)
		(end 266.999974 -328.146918)
		(width 0.1016)
		(layer "In7.Cu")
		(net "PHY_DRV_A_TO_SCC_A_15_DP")
	)
	(segment
		(start 265.82116 -327.099422)
		(end 230.490776 -303.490122)
		(width 0.1016)
		(layer "In7.Cu")
		(net "PHY_DRV_A_TO_SCC_A_15_DP")
	)
	(segment
		(start 285.809182 -329.970384)
		(end 271.21866 -329.970384)
		(width 0.1016)
		(layer "In7.Cu")
		(net "PHY_DRV_A_TO_SCC_A_15_DP")
	)
	(segment
		(start 265.880596 -327.398888)
		(end 265.82116 -327.099422)
		(width 0.1016)
		(layer "In7.Cu")
		(net "PHY_DRV_A_TO_SCC_A_15_DP")
	)
	(segment
		(start 135.067548 -172.716698)
		(end 129.167128 -163.457636)
		(width 0.1016)
		(layer "In7.Cu")
		(net "PHY_DRV_A_TO_SCC_A_15_DP")
	)
	(segment
		(start 267.86586 -328.72553)
		(end 267.612368 -328.556112)
		(width 0.1016)
		(layer "In7.Cu")
		(net "PHY_DRV_A_TO_SCC_A_15_DP")
	)
	(segment
		(start 266.433554 -327.50887)
		(end 266.134088 -327.568306)
		(width 0.1016)
		(layer "In7.Cu")
		(net "PHY_DRV_A_TO_SCC_A_15_DP")
	)
	(segment
		(start 128.418082 -162.980624)
		(end 128.123188 -162.915092)
		(width 0.1016)
		(layer "In7.Cu")
		(net "PHY_DRV_A_TO_SCC_A_15_DP")
	)
	(segment
		(start 266.746482 -327.9775)
		(end 266.687046 -327.678034)
		(width 0.1016)
		(layer "In7.Cu")
		(net "PHY_DRV_A_TO_SCC_A_15_DP")
	)
	(segment
		(start 285.973774 -330.578206)
		(end 285.973774 -330.134976)
		(width 0.1016)
		(layer "In7.Cu")
		(net "PHY_DRV_A_TO_SCC_A_15_DP")
	)
	(segment
		(start 203.487782 -261.910068)
		(end 164.746178 -240.168176)
		(width 0.1016)
		(layer "In7.Cu")
		(net "PHY_DRV_A_TO_SCC_A_15_DP")
	)
	(segment
		(start 127.15875 -163.016692)
		(end 127.15875 -163.321492)
		(width 0.1016)
		(layer "In7.Cu")
		(net "PHY_DRV_A_TO_SCC_A_15_DP")
	)
	(segment
		(start 271.21866 -329.970384)
		(end 268.786864 -329.081384)
		(width 0.1016)
		(layer "In7.Cu")
		(net "PHY_DRV_A_TO_SCC_A_15_DP")
	)
	(segment
		(start 142.16253 -204.716888)
		(end 135.067548 -172.716698)
		(width 0.1016)
		(layer "In7.Cu")
		(net "PHY_DRV_A_TO_SCC_A_15_DP")
	)
	(segment
		(start 266.687046 -327.678034)
		(end 266.433554 -327.50887)
		(width 0.1016)
		(layer "In7.Cu")
		(net "PHY_DRV_A_TO_SCC_A_15_DP")
	)
	(segment
		(start 267.552932 -328.256646)
		(end 267.29944 -328.087482)
		(width 0.1016)
		(layer "In7.Cu")
		(net "PHY_DRV_A_TO_SCC_A_15_DP")
	)
	(segment
		(start 230.490776 -303.490122)
		(end 216.989406 -282.700222)
		(width 0.1016)
		(layer "In7.Cu")
		(net "PHY_DRV_A_TO_SCC_A_15_DP")
	)
	(segment
		(start 128.418082 -162.98037)
		(end 128.418082 -162.980624)
		(width 0.1016)
		(layer "In7.Cu")
		(net "PHY_DRV_A_TO_SCC_A_15_DP")
	)
	(segment
		(start 129.167128 -163.457636)
		(end 128.418082 -162.98037)
		(width 0.1016)
		(layer "In7.Cu")
		(net "PHY_DRV_A_TO_SCC_A_15_DP")
	)
	(segment
		(start 285.436564 -330.705206)
		(end 285.846774 -330.705206)
		(width 0.1016)
		(layer "In7.Cu")
		(net "PHY_DRV_A_TO_SCC_A_15_DP")
	)
	(segment
		(start 266.999974 -328.146918)
		(end 266.746482 -327.9775)
		(width 0.1016)
		(layer "In7.Cu")
		(net "PHY_DRV_A_TO_SCC_A_15_DP")
	)
	(segment
		(start 164.746178 -240.168176)
		(end 142.16253 -204.716888)
		(width 0.1016)
		(layer "In7.Cu")
		(net "PHY_DRV_A_TO_SCC_A_15_DP")
	)
	(segment
		(start 268.165326 -328.666094)
		(end 267.86586 -328.72553)
		(width 0.1016)
		(layer "In7.Cu")
		(net "PHY_DRV_A_TO_SCC_A_15_DP")
	)
	(segment
		(start 267.612368 -328.556112)
		(end 267.552932 -328.256646)
		(width 0.1016)
		(layer "In7.Cu")
		(net "PHY_DRV_A_TO_SCC_A_15_DP")
	)
	(segment
		(start 268.786864 -329.081384)
		(end 268.165326 -328.666094)
		(width 0.1016)
		(layer "In7.Cu")
		(net "PHY_DRV_A_TO_SCC_A_15_DP")
	)
	(segment
		(start 216.989406 -282.700222)
		(end 203.487782 -261.910068)
		(width 0.1016)
		(layer "In7.Cu")
		(net "PHY_DRV_A_TO_SCC_A_15_DP")
	)
	(segment
		(start 266.134088 -327.568306)
		(end 265.880596 -327.398888)
		(width 0.1016)
		(layer "In7.Cu")
		(net "PHY_DRV_A_TO_SCC_A_15_DP")
	)
	(arc
		(start 285.973774 -330.134976)
		(mid 285.925566 -330.018592)
		(end 285.809182 -329.970384)
		(width 0.1016)
		(layer "In7.Cu")
		(net "PHY_DRV_A_TO_SCC_A_15_DP")
	)
	(arc
		(start 127.26035 -162.915092)
		(mid 127.188508 -162.94485)
		(end 127.15875 -163.016692)
		(width 0.1016)
		(layer "In7.Cu")
		(net "PHY_DRV_A_TO_SCC_A_15_DP")
	)
	(arc
		(start 285.846774 -330.705206)
		(mid 285.936577 -330.668009)
		(end 285.973774 -330.578206)
		(width 0.1016)
		(layer "In7.Cu")
		(net "PHY_DRV_A_TO_SCC_A_15_DP")
	)
	(segment
		(start 126.1364 -162.476942)
		(end 126.1364 -162.241992)
		(width 0.127)
		(layer "F.Cu")
		(net "PHY_DRV_A_TO_SCC_A_15_DN")
	)
	(segment
		(start 126.0094 -162.114992)
		(end 124.674884 -162.114992)
		(width 0.127)
		(layer "F.Cu")
		(net "PHY_DRV_A_TO_SCC_A_15_DN")
	)
	(segment
		(start 127.03175 -162.603942)
		(end 126.2634 -162.603942)
		(width 0.127)
		(layer "F.Cu")
		(net "PHY_DRV_A_TO_SCC_A_15_DN")
	)
	(segment
		(start 126.2634 -162.603942)
		(end 126.1364 -162.476942)
		(width 0.127)
		(layer "F.Cu")
		(net "PHY_DRV_A_TO_SCC_A_15_DN")
	)
	(segment
		(start 126.1364 -162.241992)
		(end 126.0094 -162.114992)
		(width 0.127)
		(layer "F.Cu")
		(net "PHY_DRV_A_TO_SCC_A_15_DN")
	)
	(segment
		(start 127.15875 -162.178492)
		(end 127.15875 -162.476942)
		(width 0.127)
		(layer "F.Cu")
		(net "PHY_DRV_A_TO_SCC_A_15_DN")
	)
	(arc
		(start 127.15875 -162.476942)
		(mid 127.121553 -162.566745)
		(end 127.03175 -162.603942)
		(width 0.127)
		(layer "F.Cu")
		(net "PHY_DRV_A_TO_SCC_A_15_DN")
	)
	(segment
		(start 159.35325 -231.087422)
		(end 164.980112 -239.92078)
		(width 0.1016)
		(layer "In7.Cu")
		(net "PHY_DRV_A_TO_SCC_A_15_DN")
	)
	(segment
		(start 271.277334 -329.640184)
		(end 285.809182 -329.640184)
		(width 0.1016)
		(layer "In7.Cu")
		(net "PHY_DRV_A_TO_SCC_A_15_DN")
	)
	(segment
		(start 128.546352 -162.67049)
		(end 129.406396 -163.218368)
		(width 0.1016)
		(layer "In7.Cu")
		(net "PHY_DRV_A_TO_SCC_A_15_DN")
	)
	(segment
		(start 164.980112 -239.92078)
		(end 184.350406 -250.791472)
		(width 0.1016)
		(layer "In7.Cu")
		(net "PHY_DRV_A_TO_SCC_A_15_DN")
	)
	(segment
		(start 286.303974 -330.134976)
		(end 286.303974 -330.578206)
		(width 0.1016)
		(layer "In7.Cu")
		(net "PHY_DRV_A_TO_SCC_A_15_DN")
	)
	(segment
		(start 230.730806 -303.25314)
		(end 268.937486 -328.784712)
		(width 0.1016)
		(layer "In7.Cu")
		(net "PHY_DRV_A_TO_SCC_A_15_DN")
	)
	(segment
		(start 127.26035 -162.584892)
		(end 128.15951 -162.584892)
		(width 0.1016)
		(layer "In7.Cu")
		(net "PHY_DRV_A_TO_SCC_A_15_DN")
	)
	(segment
		(start 129.406396 -163.218368)
		(end 135.377428 -172.588428)
		(width 0.1016)
		(layer "In7.Cu")
		(net "PHY_DRV_A_TO_SCC_A_15_DN")
	)
	(segment
		(start 128.15951 -162.584892)
		(end 128.546352 -162.67049)
		(width 0.1016)
		(layer "In7.Cu")
		(net "PHY_DRV_A_TO_SCC_A_15_DN")
	)
	(segment
		(start 142.47241 -204.588618)
		(end 159.35325 -231.087422)
		(width 0.1016)
		(layer "In7.Cu")
		(net "PHY_DRV_A_TO_SCC_A_15_DN")
	)
	(segment
		(start 268.937486 -328.784712)
		(end 271.277334 -329.640184)
		(width 0.1016)
		(layer "In7.Cu")
		(net "PHY_DRV_A_TO_SCC_A_15_DN")
	)
	(segment
		(start 135.377428 -172.588428)
		(end 142.47241 -204.588618)
		(width 0.1016)
		(layer "In7.Cu")
		(net "PHY_DRV_A_TO_SCC_A_15_DN")
	)
	(segment
		(start 286.430974 -330.705206)
		(end 286.836612 -330.705206)
		(width 0.1016)
		(layer "In7.Cu")
		(net "PHY_DRV_A_TO_SCC_A_15_DN")
	)
	(segment
		(start 127.15875 -162.178492)
		(end 127.15875 -162.483292)
		(width 0.1016)
		(layer "In7.Cu")
		(net "PHY_DRV_A_TO_SCC_A_15_DN")
	)
	(segment
		(start 203.720446 -261.66191)
		(end 230.730806 -303.25314)
		(width 0.1016)
		(layer "In7.Cu")
		(net "PHY_DRV_A_TO_SCC_A_15_DN")
	)
	(segment
		(start 184.350406 -250.791472)
		(end 203.720446 -261.66191)
		(width 0.1016)
		(layer "In7.Cu")
		(net "PHY_DRV_A_TO_SCC_A_15_DN")
	)
	(arc
		(start 286.303974 -330.578206)
		(mid 286.341171 -330.668009)
		(end 286.430974 -330.705206)
		(width 0.1016)
		(layer "In7.Cu")
		(net "PHY_DRV_A_TO_SCC_A_15_DN")
	)
	(arc
		(start 127.15875 -162.483292)
		(mid 127.188508 -162.555134)
		(end 127.26035 -162.584892)
		(width 0.1016)
		(layer "In7.Cu")
		(net "PHY_DRV_A_TO_SCC_A_15_DN")
	)
	(arc
		(start 285.809182 -329.640184)
		(mid 286.159053 -329.785105)
		(end 286.303974 -330.134976)
		(width 0.1016)
		(layer "In7.Cu")
		(net "PHY_DRV_A_TO_SCC_A_15_DN")
	)
	(segment
		(start 93.125036 -163.384992)
		(end 94.459552 -163.384992)
		(width 0.127)
		(layer "F.Cu")
		(net "PHY_DRV_A_TO_SCC_A_14_DP")
	)
	(segment
		(start 95.608902 -163.023042)
		(end 95.608902 -163.321492)
		(width 0.127)
		(layer "F.Cu")
		(net "PHY_DRV_A_TO_SCC_A_14_DP")
	)
	(segment
		(start 94.586552 -163.257992)
		(end 94.586552 -163.023042)
		(width 0.127)
		(layer "F.Cu")
		(net "PHY_DRV_A_TO_SCC_A_14_DP")
	)
	(segment
		(start 94.586552 -163.023042)
		(end 94.713552 -162.896042)
		(width 0.127)
		(layer "F.Cu")
		(net "PHY_DRV_A_TO_SCC_A_14_DP")
	)
	(segment
		(start 94.713552 -162.896042)
		(end 95.481902 -162.896042)
		(width 0.127)
		(layer "F.Cu")
		(net "PHY_DRV_A_TO_SCC_A_14_DP")
	)
	(segment
		(start 94.459552 -163.384992)
		(end 94.586552 -163.257992)
		(width 0.127)
		(layer "F.Cu")
		(net "PHY_DRV_A_TO_SCC_A_14_DP")
	)
	(arc
		(start 95.481902 -162.896042)
		(mid 95.571705 -162.933239)
		(end 95.608902 -163.023042)
		(width 0.127)
		(layer "F.Cu")
		(net "PHY_DRV_A_TO_SCC_A_14_DP")
	)
	(segment
		(start 103.668322 -180.702712)
		(end 100.91547 -168.249092)
		(width 0.1016)
		(layer "In7.Cu")
		(net "PHY_DRV_A_TO_SCC_A_14_DP")
	)
	(segment
		(start 267.260832 -330.487528)
		(end 267.201142 -330.188062)
		(width 0.1016)
		(layer "In7.Cu")
		(net "PHY_DRV_A_TO_SCC_A_14_DP")
	)
	(segment
		(start 202.494388 -263.75614)
		(end 146.100292 -232.108248)
		(width 0.1016)
		(layer "In7.Cu")
		(net "PHY_DRV_A_TO_SCC_A_14_DP")
	)
	(segment
		(start 146.100292 -232.108248)
		(end 145.637758 -231.828848)
		(width 0.1016)
		(layer "In7.Cu")
		(net "PHY_DRV_A_TO_SCC_A_14_DP")
	)
	(segment
		(start 229.102412 -304.72888)
		(end 202.494388 -263.75614)
		(width 0.1016)
		(layer "In7.Cu")
		(net "PHY_DRV_A_TO_SCC_A_14_DP")
	)
	(segment
		(start 266.648184 -330.078334)
		(end 266.394946 -329.908916)
		(width 0.1016)
		(layer "In7.Cu")
		(net "PHY_DRV_A_TO_SCC_A_14_DP")
	)
	(segment
		(start 97.228914 -163.057078)
		(end 96.590104 -162.915092)
		(width 0.1016)
		(layer "In7.Cu")
		(net "PHY_DRV_A_TO_SCC_A_14_DP")
	)
	(segment
		(start 266.394946 -329.908916)
		(end 266.335256 -329.60945)
		(width 0.1016)
		(layer "In7.Cu")
		(net "PHY_DRV_A_TO_SCC_A_14_DP")
	)
	(segment
		(start 97.882202 -163.473384)
		(end 97.228914 -163.057078)
		(width 0.1016)
		(layer "In7.Cu")
		(net "PHY_DRV_A_TO_SCC_A_14_DP")
	)
	(segment
		(start 286.80918 -331.770228)
		(end 270.81226 -331.770228)
		(width 0.1016)
		(layer "In7.Cu")
		(net "PHY_DRV_A_TO_SCC_A_14_DP")
	)
	(segment
		(start 266.081764 -329.440032)
		(end 265.782298 -329.499722)
		(width 0.1016)
		(layer "In7.Cu")
		(net "PHY_DRV_A_TO_SCC_A_14_DP")
	)
	(segment
		(start 95.608902 -163.016692)
		(end 95.608902 -163.321492)
		(width 0.1016)
		(layer "In7.Cu")
		(net "PHY_DRV_A_TO_SCC_A_14_DP")
	)
	(segment
		(start 145.637758 -231.828848)
		(end 123.101862 -227.06838)
		(width 0.1016)
		(layer "In7.Cu")
		(net "PHY_DRV_A_TO_SCC_A_14_DP")
	)
	(segment
		(start 267.813536 -330.597256)
		(end 267.51407 -330.656946)
		(width 0.1016)
		(layer "In7.Cu")
		(net "PHY_DRV_A_TO_SCC_A_14_DP")
	)
	(segment
		(start 286.436562 -332.50505)
		(end 286.846772 -332.50505)
		(width 0.1016)
		(layer "In7.Cu")
		(net "PHY_DRV_A_TO_SCC_A_14_DP")
	)
	(segment
		(start 265.52906 -329.330304)
		(end 265.46937 -329.030838)
		(width 0.1016)
		(layer "In7.Cu")
		(net "PHY_DRV_A_TO_SCC_A_14_DP")
	)
	(segment
		(start 268.067028 -330.766674)
		(end 267.813536 -330.597256)
		(width 0.1016)
		(layer "In7.Cu")
		(net "PHY_DRV_A_TO_SCC_A_14_DP")
	)
	(segment
		(start 265.46937 -329.030838)
		(end 229.102412 -304.72888)
		(width 0.1016)
		(layer "In7.Cu")
		(net "PHY_DRV_A_TO_SCC_A_14_DP")
	)
	(segment
		(start 267.51407 -330.656946)
		(end 267.260832 -330.487528)
		(width 0.1016)
		(layer "In7.Cu")
		(net "PHY_DRV_A_TO_SCC_A_14_DP")
	)
	(segment
		(start 111.814864 -217.555318)
		(end 103.668322 -180.702712)
		(width 0.1016)
		(layer "In7.Cu")
		(net "PHY_DRV_A_TO_SCC_A_14_DP")
	)
	(segment
		(start 270.81226 -331.770228)
		(end 268.067028 -330.766674)
		(width 0.1016)
		(layer "In7.Cu")
		(net "PHY_DRV_A_TO_SCC_A_14_DP")
	)
	(segment
		(start 123.101862 -227.06838)
		(end 111.814864 -217.555318)
		(width 0.1016)
		(layer "In7.Cu")
		(net "PHY_DRV_A_TO_SCC_A_14_DP")
	)
	(segment
		(start 100.91547 -168.249092)
		(end 97.882202 -163.473384)
		(width 0.1016)
		(layer "In7.Cu")
		(net "PHY_DRV_A_TO_SCC_A_14_DP")
	)
	(segment
		(start 266.94765 -330.018644)
		(end 266.648184 -330.078334)
		(width 0.1016)
		(layer "In7.Cu")
		(net "PHY_DRV_A_TO_SCC_A_14_DP")
	)
	(segment
		(start 286.973772 -332.37805)
		(end 286.973772 -331.93482)
		(width 0.1016)
		(layer "In7.Cu")
		(net "PHY_DRV_A_TO_SCC_A_14_DP")
	)
	(segment
		(start 267.201142 -330.188062)
		(end 266.94765 -330.018644)
		(width 0.1016)
		(layer "In7.Cu")
		(net "PHY_DRV_A_TO_SCC_A_14_DP")
	)
	(segment
		(start 265.782298 -329.499722)
		(end 265.52906 -329.330304)
		(width 0.1016)
		(layer "In7.Cu")
		(net "PHY_DRV_A_TO_SCC_A_14_DP")
	)
	(segment
		(start 96.590104 -162.915092)
		(end 95.710502 -162.915092)
		(width 0.1016)
		(layer "In7.Cu")
		(net "PHY_DRV_A_TO_SCC_A_14_DP")
	)
	(segment
		(start 266.335256 -329.60945)
		(end 266.081764 -329.440032)
		(width 0.1016)
		(layer "In7.Cu")
		(net "PHY_DRV_A_TO_SCC_A_14_DP")
	)
	(arc
		(start 286.973772 -331.93482)
		(mid 286.925564 -331.818436)
		(end 286.80918 -331.770228)
		(width 0.1016)
		(layer "In7.Cu")
		(net "PHY_DRV_A_TO_SCC_A_14_DP")
	)
	(arc
		(start 95.710502 -162.915092)
		(mid 95.63866 -162.94485)
		(end 95.608902 -163.016692)
		(width 0.1016)
		(layer "In7.Cu")
		(net "PHY_DRV_A_TO_SCC_A_14_DP")
	)
	(arc
		(start 286.846772 -332.50505)
		(mid 286.936575 -332.467853)
		(end 286.973772 -332.37805)
		(width 0.1016)
		(layer "In7.Cu")
		(net "PHY_DRV_A_TO_SCC_A_14_DP")
	)
	(segment
		(start 94.586552 -162.241992)
		(end 94.459552 -162.114992)
		(width 0.127)
		(layer "F.Cu")
		(net "PHY_DRV_A_TO_SCC_A_14_DN")
	)
	(segment
		(start 94.713552 -162.603942)
		(end 94.586552 -162.476942)
		(width 0.127)
		(layer "F.Cu")
		(net "PHY_DRV_A_TO_SCC_A_14_DN")
	)
	(segment
		(start 95.481902 -162.603942)
		(end 94.713552 -162.603942)
		(width 0.127)
		(layer "F.Cu")
		(net "PHY_DRV_A_TO_SCC_A_14_DN")
	)
	(segment
		(start 95.608902 -162.178492)
		(end 95.608902 -162.476942)
		(width 0.127)
		(layer "F.Cu")
		(net "PHY_DRV_A_TO_SCC_A_14_DN")
	)
	(segment
		(start 94.459552 -162.114992)
		(end 93.125036 -162.114992)
		(width 0.127)
		(layer "F.Cu")
		(net "PHY_DRV_A_TO_SCC_A_14_DN")
	)
	(segment
		(start 94.586552 -162.476942)
		(end 94.586552 -162.241992)
		(width 0.127)
		(layer "F.Cu")
		(net "PHY_DRV_A_TO_SCC_A_14_DN")
	)
	(arc
		(start 95.608902 -162.476942)
		(mid 95.571705 -162.566745)
		(end 95.481902 -162.603942)
		(width 0.127)
		(layer "F.Cu")
		(net "PHY_DRV_A_TO_SCC_A_14_DN")
	)
	(segment
		(start 96.626426 -162.584892)
		(end 95.710502 -162.584892)
		(width 0.1016)
		(layer "In7.Cu")
		(net "PHY_DRV_A_TO_SCC_A_14_DN")
	)
	(segment
		(start 202.727052 -263.507982)
		(end 146.266662 -231.822752)
		(width 0.1016)
		(layer "In7.Cu")
		(net "PHY_DRV_A_TO_SCC_A_14_DN")
	)
	(segment
		(start 103.990902 -180.631338)
		(end 101.22535 -168.121076)
		(width 0.1016)
		(layer "In7.Cu")
		(net "PHY_DRV_A_TO_SCC_A_14_DN")
	)
	(segment
		(start 287.83661 -332.50505)
		(end 287.430972 -332.50505)
		(width 0.1016)
		(layer "In7.Cu")
		(net "PHY_DRV_A_TO_SCC_A_14_DN")
	)
	(segment
		(start 123.251468 -226.76231)
		(end 112.113314 -217.374724)
		(width 0.1016)
		(layer "In7.Cu")
		(net "PHY_DRV_A_TO_SCC_A_14_DN")
	)
	(segment
		(start 270.870934 -331.440028)
		(end 268.21765 -330.470002)
		(width 0.1016)
		(layer "In7.Cu")
		(net "PHY_DRV_A_TO_SCC_A_14_DN")
	)
	(segment
		(start 286.80918 -331.440028)
		(end 270.870934 -331.440028)
		(width 0.1016)
		(layer "In7.Cu")
		(net "PHY_DRV_A_TO_SCC_A_14_DN")
	)
	(segment
		(start 247.497854 -316.624208)
		(end 229.342442 -304.491898)
		(width 0.1016)
		(layer "In7.Cu")
		(net "PHY_DRV_A_TO_SCC_A_14_DN")
	)
	(segment
		(start 268.21765 -330.470002)
		(end 247.497854 -316.624208)
		(width 0.1016)
		(layer "In7.Cu")
		(net "PHY_DRV_A_TO_SCC_A_14_DN")
	)
	(segment
		(start 229.342442 -304.491898)
		(end 202.727052 -263.507982)
		(width 0.1016)
		(layer "In7.Cu")
		(net "PHY_DRV_A_TO_SCC_A_14_DN")
	)
	(segment
		(start 97.357184 -162.747198)
		(end 96.626426 -162.584892)
		(width 0.1016)
		(layer "In7.Cu")
		(net "PHY_DRV_A_TO_SCC_A_14_DN")
	)
	(segment
		(start 145.760694 -231.51719)
		(end 123.251468 -226.76231)
		(width 0.1016)
		(layer "In7.Cu")
		(net "PHY_DRV_A_TO_SCC_A_14_DN")
	)
	(segment
		(start 98.121724 -163.234116)
		(end 97.357184 -162.747198)
		(width 0.1016)
		(layer "In7.Cu")
		(net "PHY_DRV_A_TO_SCC_A_14_DN")
	)
	(segment
		(start 112.113314 -217.374724)
		(end 103.990902 -180.631338)
		(width 0.1016)
		(layer "In7.Cu")
		(net "PHY_DRV_A_TO_SCC_A_14_DN")
	)
	(segment
		(start 101.22535 -168.121076)
		(end 98.121724 -163.234116)
		(width 0.1016)
		(layer "In7.Cu")
		(net "PHY_DRV_A_TO_SCC_A_14_DN")
	)
	(segment
		(start 146.266662 -231.822752)
		(end 145.760694 -231.51719)
		(width 0.1016)
		(layer "In7.Cu")
		(net "PHY_DRV_A_TO_SCC_A_14_DN")
	)
	(segment
		(start 95.608902 -162.483292)
		(end 95.608902 -162.178492)
		(width 0.1016)
		(layer "In7.Cu")
		(net "PHY_DRV_A_TO_SCC_A_14_DN")
	)
	(segment
		(start 287.303972 -332.37805)
		(end 287.303972 -331.93482)
		(width 0.1016)
		(layer "In7.Cu")
		(net "PHY_DRV_A_TO_SCC_A_14_DN")
	)
	(arc
		(start 287.303972 -331.93482)
		(mid 287.159051 -331.584949)
		(end 286.80918 -331.440028)
		(width 0.1016)
		(layer "In7.Cu")
		(net "PHY_DRV_A_TO_SCC_A_14_DN")
	)
	(arc
		(start 95.710502 -162.584892)
		(mid 95.63866 -162.555134)
		(end 95.608902 -162.483292)
		(width 0.1016)
		(layer "In7.Cu")
		(net "PHY_DRV_A_TO_SCC_A_14_DN")
	)
	(arc
		(start 287.430972 -332.50505)
		(mid 287.341169 -332.467853)
		(end 287.303972 -332.37805)
		(width 0.1016)
		(layer "In7.Cu")
		(net "PHY_DRV_A_TO_SCC_A_14_DN")
	)
	(segment
		(start 63.16345 -162.896042)
		(end 63.03645 -163.023042)
		(width 0.127)
		(layer "F.Cu")
		(net "PHY_DRV_A_TO_SCC_A_13_DP")
	)
	(segment
		(start 63.9318 -162.896042)
		(end 63.16345 -162.896042)
		(width 0.127)
		(layer "F.Cu")
		(net "PHY_DRV_A_TO_SCC_A_13_DP")
	)
	(segment
		(start 63.03645 -163.257992)
		(end 62.90945 -163.384992)
		(width 0.127)
		(layer "F.Cu")
		(net "PHY_DRV_A_TO_SCC_A_13_DP")
	)
	(segment
		(start 62.90945 -163.384992)
		(end 61.574934 -163.384992)
		(width 0.127)
		(layer "F.Cu")
		(net "PHY_DRV_A_TO_SCC_A_13_DP")
	)
	(segment
		(start 63.03645 -163.023042)
		(end 63.03645 -163.257992)
		(width 0.127)
		(layer "F.Cu")
		(net "PHY_DRV_A_TO_SCC_A_13_DP")
	)
	(segment
		(start 64.0588 -163.321492)
		(end 64.0588 -163.023042)
		(width 0.127)
		(layer "F.Cu")
		(net "PHY_DRV_A_TO_SCC_A_13_DP")
	)
	(arc
		(start 64.0588 -163.023042)
		(mid 64.021603 -162.933239)
		(end 63.9318 -162.896042)
		(width 0.127)
		(layer "F.Cu")
		(net "PHY_DRV_A_TO_SCC_A_13_DP")
	)
	(segment
		(start 64.991488 -162.915092)
		(end 64.1604 -162.915092)
		(width 0.1016)
		(layer "In7.Cu")
		(net "PHY_DRV_A_TO_SCC_A_13_DP")
	)
	(segment
		(start 285.973774 -334.178148)
		(end 285.973774 -333.734918)
		(width 0.1016)
		(layer "In7.Cu")
		(net "PHY_DRV_A_TO_SCC_A_13_DP")
	)
	(segment
		(start 265.015726 -330.727812)
		(end 264.71626 -330.787248)
		(width 0.1016)
		(layer "In7.Cu")
		(net "PHY_DRV_A_TO_SCC_A_13_DP")
	)
	(segment
		(start 76.115164 -200.773792)
		(end 68.643754 -167.680894)
		(width 0.1016)
		(layer "In7.Cu")
		(net "PHY_DRV_A_TO_SCC_A_13_DP")
	)
	(segment
		(start 266.747498 -331.885036)
		(end 266.448032 -331.944472)
		(width 0.1016)
		(layer "In7.Cu")
		(net "PHY_DRV_A_TO_SCC_A_13_DP")
	)
	(segment
		(start 265.881612 -331.306424)
		(end 265.582146 -331.36586)
		(width 0.1016)
		(layer "In7.Cu")
		(net "PHY_DRV_A_TO_SCC_A_13_DP")
	)
	(segment
		(start 266.448032 -331.944472)
		(end 266.19454 -331.775054)
		(width 0.1016)
		(layer "In7.Cu")
		(net "PHY_DRV_A_TO_SCC_A_13_DP")
	)
	(segment
		(start 266.13485 -331.475588)
		(end 265.881612 -331.306424)
		(width 0.1016)
		(layer "In7.Cu")
		(net "PHY_DRV_A_TO_SCC_A_13_DP")
	)
	(segment
		(start 144.309338 -233.69524)
		(end 93.302836 -223.485202)
		(width 0.1016)
		(layer "In7.Cu")
		(net "PHY_DRV_A_TO_SCC_A_13_DP")
	)
	(segment
		(start 265.268964 -330.896976)
		(end 265.015726 -330.727812)
		(width 0.1016)
		(layer "In7.Cu")
		(net "PHY_DRV_A_TO_SCC_A_13_DP")
	)
	(segment
		(start 266.19454 -331.775054)
		(end 266.13485 -331.475588)
		(width 0.1016)
		(layer "In7.Cu")
		(net "PHY_DRV_A_TO_SCC_A_13_DP")
	)
	(segment
		(start 265.328654 -331.196442)
		(end 265.268964 -330.896976)
		(width 0.1016)
		(layer "In7.Cu")
		(net "PHY_DRV_A_TO_SCC_A_13_DP")
	)
	(segment
		(start 68.643754 -167.680894)
		(end 66.026284 -163.574222)
		(width 0.1016)
		(layer "In7.Cu")
		(net "PHY_DRV_A_TO_SCC_A_13_DP")
	)
	(segment
		(start 93.302836 -223.485202)
		(end 88.720676 -220.56217)
		(width 0.1016)
		(layer "In7.Cu")
		(net "PHY_DRV_A_TO_SCC_A_13_DP")
	)
	(segment
		(start 285.809182 -333.570326)
		(end 270.617442 -333.570326)
		(width 0.1016)
		(layer "In7.Cu")
		(net "PHY_DRV_A_TO_SCC_A_13_DP")
	)
	(segment
		(start 285.436564 -334.305148)
		(end 285.846774 -334.305148)
		(width 0.1016)
		(layer "In7.Cu")
		(net "PHY_DRV_A_TO_SCC_A_13_DP")
	)
	(segment
		(start 88.720676 -220.56217)
		(end 85.547708 -215.580722)
		(width 0.1016)
		(layer "In7.Cu")
		(net "PHY_DRV_A_TO_SCC_A_13_DP")
	)
	(segment
		(start 201.146664 -265.59256)
		(end 144.309338 -233.69524)
		(width 0.1016)
		(layer "In7.Cu")
		(net "PHY_DRV_A_TO_SCC_A_13_DP")
	)
	(segment
		(start 226.910138 -305.264058)
		(end 201.146664 -265.59256)
		(width 0.1016)
		(layer "In7.Cu")
		(net "PHY_DRV_A_TO_SCC_A_13_DP")
	)
	(segment
		(start 264.462768 -330.61783)
		(end 264.403078 -330.318364)
		(width 0.1016)
		(layer "In7.Cu")
		(net "PHY_DRV_A_TO_SCC_A_13_DP")
	)
	(segment
		(start 267.641578 -332.482444)
		(end 266.747498 -331.885036)
		(width 0.1016)
		(layer "In7.Cu")
		(net "PHY_DRV_A_TO_SCC_A_13_DP")
	)
	(segment
		(start 265.582146 -331.36586)
		(end 265.328654 -331.196442)
		(width 0.1016)
		(layer "In7.Cu")
		(net "PHY_DRV_A_TO_SCC_A_13_DP")
	)
	(segment
		(start 64.0588 -163.016692)
		(end 64.0588 -163.321492)
		(width 0.1016)
		(layer "In7.Cu")
		(net "PHY_DRV_A_TO_SCC_A_13_DP")
	)
	(segment
		(start 66.026284 -163.574222)
		(end 64.991488 -162.915092)
		(width 0.1016)
		(layer "In7.Cu")
		(net "PHY_DRV_A_TO_SCC_A_13_DP")
	)
	(segment
		(start 264.71626 -330.787248)
		(end 264.462768 -330.61783)
		(width 0.1016)
		(layer "In7.Cu")
		(net "PHY_DRV_A_TO_SCC_A_13_DP")
	)
	(segment
		(start 85.547708 -215.580722)
		(end 76.115164 -200.773792)
		(width 0.1016)
		(layer "In7.Cu")
		(net "PHY_DRV_A_TO_SCC_A_13_DP")
	)
	(segment
		(start 264.403078 -330.318364)
		(end 226.910138 -305.264058)
		(width 0.1016)
		(layer "In7.Cu")
		(net "PHY_DRV_A_TO_SCC_A_13_DP")
	)
	(segment
		(start 270.617442 -333.570326)
		(end 267.641578 -332.482444)
		(width 0.1016)
		(layer "In7.Cu")
		(net "PHY_DRV_A_TO_SCC_A_13_DP")
	)
	(arc
		(start 64.1604 -162.915092)
		(mid 64.088558 -162.94485)
		(end 64.0588 -163.016692)
		(width 0.1016)
		(layer "In7.Cu")
		(net "PHY_DRV_A_TO_SCC_A_13_DP")
	)
	(arc
		(start 285.973774 -333.734918)
		(mid 285.925566 -333.618534)
		(end 285.809182 -333.570326)
		(width 0.1016)
		(layer "In7.Cu")
		(net "PHY_DRV_A_TO_SCC_A_13_DP")
	)
	(arc
		(start 285.846774 -334.305148)
		(mid 285.936577 -334.267951)
		(end 285.973774 -334.178148)
		(width 0.1016)
		(layer "In7.Cu")
		(net "PHY_DRV_A_TO_SCC_A_13_DP")
	)
	(segment
		(start 64.0588 -162.178492)
		(end 64.0588 -162.476942)
		(width 0.127)
		(layer "F.Cu")
		(net "PHY_DRV_A_TO_SCC_A_13_DN")
	)
	(segment
		(start 63.03645 -162.241992)
		(end 62.90945 -162.114992)
		(width 0.127)
		(layer "F.Cu")
		(net "PHY_DRV_A_TO_SCC_A_13_DN")
	)
	(segment
		(start 63.16345 -162.603942)
		(end 63.03645 -162.476942)
		(width 0.127)
		(layer "F.Cu")
		(net "PHY_DRV_A_TO_SCC_A_13_DN")
	)
	(segment
		(start 63.03645 -162.476942)
		(end 63.03645 -162.241992)
		(width 0.127)
		(layer "F.Cu")
		(net "PHY_DRV_A_TO_SCC_A_13_DN")
	)
	(segment
		(start 62.90945 -162.114992)
		(end 61.574934 -162.114992)
		(width 0.127)
		(layer "F.Cu")
		(net "PHY_DRV_A_TO_SCC_A_13_DN")
	)
	(segment
		(start 63.9318 -162.603942)
		(end 63.16345 -162.603942)
		(width 0.127)
		(layer "F.Cu")
		(net "PHY_DRV_A_TO_SCC_A_13_DN")
	)
	(arc
		(start 64.0588 -162.476942)
		(mid 64.021603 -162.566745)
		(end 63.9318 -162.603942)
		(width 0.127)
		(layer "F.Cu")
		(net "PHY_DRV_A_TO_SCC_A_13_DN")
	)
	(segment
		(start 64.1604 -162.584892)
		(end 65.088008 -162.584892)
		(width 0.1016)
		(layer "In7.Cu")
		(net "PHY_DRV_A_TO_SCC_A_13_DN")
	)
	(segment
		(start 144.425416 -233.38155)
		(end 201.379328 -265.344402)
		(width 0.1016)
		(layer "In7.Cu")
		(net "PHY_DRV_A_TO_SCC_A_13_DN")
	)
	(segment
		(start 270.676116 -333.240126)
		(end 285.809182 -333.240126)
		(width 0.1016)
		(layer "In7.Cu")
		(net "PHY_DRV_A_TO_SCC_A_13_DN")
	)
	(segment
		(start 76.42479 -200.64476)
		(end 88.960198 -220.322902)
		(width 0.1016)
		(layer "In7.Cu")
		(net "PHY_DRV_A_TO_SCC_A_13_DN")
	)
	(segment
		(start 267.7922 -332.185772)
		(end 270.676116 -333.240126)
		(width 0.1016)
		(layer "In7.Cu")
		(net "PHY_DRV_A_TO_SCC_A_13_DN")
	)
	(segment
		(start 88.960198 -220.322902)
		(end 91.194382 -221.74835)
		(width 0.1016)
		(layer "In7.Cu")
		(net "PHY_DRV_A_TO_SCC_A_13_DN")
	)
	(segment
		(start 64.0588 -162.178492)
		(end 64.0588 -162.483292)
		(width 0.1016)
		(layer "In7.Cu")
		(net "PHY_DRV_A_TO_SCC_A_13_DN")
	)
	(segment
		(start 227.150168 -305.027076)
		(end 267.7922 -332.185772)
		(width 0.1016)
		(layer "In7.Cu")
		(net "PHY_DRV_A_TO_SCC_A_13_DN")
	)
	(segment
		(start 286.303974 -333.734918)
		(end 286.303974 -334.178148)
		(width 0.1016)
		(layer "In7.Cu")
		(net "PHY_DRV_A_TO_SCC_A_13_DN")
	)
	(segment
		(start 66.265552 -163.334954)
		(end 68.95338 -167.551862)
		(width 0.1016)
		(layer "In7.Cu")
		(net "PHY_DRV_A_TO_SCC_A_13_DN")
	)
	(segment
		(start 91.194382 -221.74835)
		(end 93.428312 -223.173544)
		(width 0.1016)
		(layer "In7.Cu")
		(net "PHY_DRV_A_TO_SCC_A_13_DN")
	)
	(segment
		(start 68.95338 -167.551862)
		(end 76.42479 -200.64476)
		(width 0.1016)
		(layer "In7.Cu")
		(net "PHY_DRV_A_TO_SCC_A_13_DN")
	)
	(segment
		(start 65.088008 -162.584892)
		(end 66.265552 -163.334954)
		(width 0.1016)
		(layer "In7.Cu")
		(net "PHY_DRV_A_TO_SCC_A_13_DN")
	)
	(segment
		(start 201.379328 -265.344402)
		(end 227.150168 -305.027076)
		(width 0.1016)
		(layer "In7.Cu")
		(net "PHY_DRV_A_TO_SCC_A_13_DN")
	)
	(segment
		(start 286.430974 -334.305148)
		(end 286.836612 -334.305148)
		(width 0.1016)
		(layer "In7.Cu")
		(net "PHY_DRV_A_TO_SCC_A_13_DN")
	)
	(segment
		(start 93.428312 -223.173544)
		(end 144.425416 -233.38155)
		(width 0.1016)
		(layer "In7.Cu")
		(net "PHY_DRV_A_TO_SCC_A_13_DN")
	)
	(arc
		(start 285.809182 -333.240126)
		(mid 286.159053 -333.385047)
		(end 286.303974 -333.734918)
		(width 0.1016)
		(layer "In7.Cu")
		(net "PHY_DRV_A_TO_SCC_A_13_DN")
	)
	(arc
		(start 286.303974 -334.178148)
		(mid 286.341171 -334.267951)
		(end 286.430974 -334.305148)
		(width 0.1016)
		(layer "In7.Cu")
		(net "PHY_DRV_A_TO_SCC_A_13_DN")
	)
	(arc
		(start 64.0588 -162.483292)
		(mid 64.088558 -162.555134)
		(end 64.1604 -162.584892)
		(width 0.1016)
		(layer "In7.Cu")
		(net "PHY_DRV_A_TO_SCC_A_13_DN")
	)
	(segment
		(start 31.613602 -162.896042)
		(end 31.486602 -163.023042)
		(width 0.127)
		(layer "F.Cu")
		(net "PHY_DRV_A_TO_SCC_A_12_DP")
	)
	(segment
		(start 31.486602 -163.023042)
		(end 31.486602 -163.257992)
		(width 0.127)
		(layer "F.Cu")
		(net "PHY_DRV_A_TO_SCC_A_12_DP")
	)
	(segment
		(start 31.486602 -163.257992)
		(end 31.359602 -163.384992)
		(width 0.127)
		(layer "F.Cu")
		(net "PHY_DRV_A_TO_SCC_A_12_DP")
	)
	(segment
		(start 31.359602 -163.384992)
		(end 30.025086 -163.384992)
		(width 0.127)
		(layer "F.Cu")
		(net "PHY_DRV_A_TO_SCC_A_12_DP")
	)
	(segment
		(start 32.508952 -163.321492)
		(end 32.508952 -163.023042)
		(width 0.127)
		(layer "F.Cu")
		(net "PHY_DRV_A_TO_SCC_A_12_DP")
	)
	(segment
		(start 32.381952 -162.896042)
		(end 31.613602 -162.896042)
		(width 0.127)
		(layer "F.Cu")
		(net "PHY_DRV_A_TO_SCC_A_12_DP")
	)
	(arc
		(start 32.508952 -163.023042)
		(mid 32.471755 -162.933239)
		(end 32.381952 -162.896042)
		(width 0.127)
		(layer "F.Cu")
		(net "PHY_DRV_A_TO_SCC_A_12_DP")
	)
	(segment
		(start 270.893286 -335.370424)
		(end 267.570712 -334.155796)
		(width 0.1016)
		(layer "In7.Cu")
		(net "PHY_DRV_A_TO_SCC_A_12_DP")
	)
	(segment
		(start 264.088118 -332.088236)
		(end 264.028428 -331.78877)
		(width 0.1016)
		(layer "In7.Cu")
		(net "PHY_DRV_A_TO_SCC_A_12_DP")
	)
	(segment
		(start 265.7602 -332.945994)
		(end 265.506708 -332.776576)
		(width 0.1016)
		(layer "In7.Cu")
		(net "PHY_DRV_A_TO_SCC_A_12_DP")
	)
	(segment
		(start 33.658556 -162.915092)
		(end 32.610552 -162.915092)
		(width 0.1016)
		(layer "In7.Cu")
		(net "PHY_DRV_A_TO_SCC_A_12_DP")
	)
	(segment
		(start 286.80918 -335.370424)
		(end 270.893286 -335.370424)
		(width 0.1016)
		(layer "In7.Cu")
		(net "PHY_DRV_A_TO_SCC_A_12_DP")
	)
	(segment
		(start 286.436562 -336.105246)
		(end 286.846772 -336.105246)
		(width 0.1016)
		(layer "In7.Cu")
		(net "PHY_DRV_A_TO_SCC_A_12_DP")
	)
	(segment
		(start 266.372594 -333.355188)
		(end 266.073128 -333.414624)
		(width 0.1016)
		(layer "In7.Cu")
		(net "PHY_DRV_A_TO_SCC_A_12_DP")
	)
	(segment
		(start 265.207242 -332.836012)
		(end 264.95375 -332.666848)
		(width 0.1016)
		(layer "In7.Cu")
		(net "PHY_DRV_A_TO_SCC_A_12_DP")
	)
	(segment
		(start 265.506708 -332.776576)
		(end 265.207242 -332.836012)
		(width 0.1016)
		(layer "In7.Cu")
		(net "PHY_DRV_A_TO_SCC_A_12_DP")
	)
	(segment
		(start 143.521938 -235.274104)
		(end 92.506546 -225.063304)
		(width 0.1016)
		(layer "In7.Cu")
		(net "PHY_DRV_A_TO_SCC_A_12_DP")
	)
	(segment
		(start 264.028428 -331.78877)
		(end 226.129088 -306.462684)
		(width 0.1016)
		(layer "In7.Cu")
		(net "PHY_DRV_A_TO_SCC_A_12_DP")
	)
	(segment
		(start 200.6981 -267.36167)
		(end 143.521938 -235.274104)
		(width 0.1016)
		(layer "In7.Cu")
		(net "PHY_DRV_A_TO_SCC_A_12_DP")
	)
	(segment
		(start 92.506546 -225.063304)
		(end 62.907926 -206.186532)
		(width 0.1016)
		(layer "In7.Cu")
		(net "PHY_DRV_A_TO_SCC_A_12_DP")
	)
	(segment
		(start 62.907926 -206.186532)
		(end 36.290504 -164.405056)
		(width 0.1016)
		(layer "In7.Cu")
		(net "PHY_DRV_A_TO_SCC_A_12_DP")
	)
	(segment
		(start 265.819636 -333.24546)
		(end 265.7602 -332.945994)
		(width 0.1016)
		(layer "In7.Cu")
		(net "PHY_DRV_A_TO_SCC_A_12_DP")
	)
	(segment
		(start 264.894314 -332.367382)
		(end 264.640822 -332.197964)
		(width 0.1016)
		(layer "In7.Cu")
		(net "PHY_DRV_A_TO_SCC_A_12_DP")
	)
	(segment
		(start 36.290504 -164.405056)
		(end 33.658556 -162.915092)
		(width 0.1016)
		(layer "In7.Cu")
		(net "PHY_DRV_A_TO_SCC_A_12_DP")
	)
	(segment
		(start 267.570712 -334.155796)
		(end 266.372594 -333.355188)
		(width 0.1016)
		(layer "In7.Cu")
		(net "PHY_DRV_A_TO_SCC_A_12_DP")
	)
	(segment
		(start 32.508952 -163.016692)
		(end 32.508952 -163.321492)
		(width 0.1016)
		(layer "In7.Cu")
		(net "PHY_DRV_A_TO_SCC_A_12_DP")
	)
	(segment
		(start 286.973772 -335.978246)
		(end 286.973772 -335.535016)
		(width 0.1016)
		(layer "In7.Cu")
		(net "PHY_DRV_A_TO_SCC_A_12_DP")
	)
	(segment
		(start 266.073128 -333.414624)
		(end 265.819636 -333.24546)
		(width 0.1016)
		(layer "In7.Cu")
		(net "PHY_DRV_A_TO_SCC_A_12_DP")
	)
	(segment
		(start 264.640822 -332.197964)
		(end 264.341356 -332.2574)
		(width 0.1016)
		(layer "In7.Cu")
		(net "PHY_DRV_A_TO_SCC_A_12_DP")
	)
	(segment
		(start 264.95375 -332.666848)
		(end 264.894314 -332.367382)
		(width 0.1016)
		(layer "In7.Cu")
		(net "PHY_DRV_A_TO_SCC_A_12_DP")
	)
	(segment
		(start 264.341356 -332.2574)
		(end 264.088118 -332.088236)
		(width 0.1016)
		(layer "In7.Cu")
		(net "PHY_DRV_A_TO_SCC_A_12_DP")
	)
	(segment
		(start 226.129088 -306.462684)
		(end 200.6981 -267.36167)
		(width 0.1016)
		(layer "In7.Cu")
		(net "PHY_DRV_A_TO_SCC_A_12_DP")
	)
	(arc
		(start 286.846772 -336.105246)
		(mid 286.936575 -336.068049)
		(end 286.973772 -335.978246)
		(width 0.1016)
		(layer "In7.Cu")
		(net "PHY_DRV_A_TO_SCC_A_12_DP")
	)
	(arc
		(start 32.610552 -162.915092)
		(mid 32.53871 -162.94485)
		(end 32.508952 -163.016692)
		(width 0.1016)
		(layer "In7.Cu")
		(net "PHY_DRV_A_TO_SCC_A_12_DP")
	)
	(arc
		(start 286.973772 -335.535016)
		(mid 286.925564 -335.418632)
		(end 286.80918 -335.370424)
		(width 0.1016)
		(layer "In7.Cu")
		(net "PHY_DRV_A_TO_SCC_A_12_DP")
	)
	(segment
		(start 31.613602 -162.603942)
		(end 31.486602 -162.476942)
		(width 0.127)
		(layer "F.Cu")
		(net "PHY_DRV_A_TO_SCC_A_12_DN")
	)
	(segment
		(start 32.508952 -162.178492)
		(end 32.508952 -162.476942)
		(width 0.127)
		(layer "F.Cu")
		(net "PHY_DRV_A_TO_SCC_A_12_DN")
	)
	(segment
		(start 32.381952 -162.603942)
		(end 31.613602 -162.603942)
		(width 0.127)
		(layer "F.Cu")
		(net "PHY_DRV_A_TO_SCC_A_12_DN")
	)
	(segment
		(start 31.486602 -162.476942)
		(end 31.486602 -162.241992)
		(width 0.127)
		(layer "F.Cu")
		(net "PHY_DRV_A_TO_SCC_A_12_DN")
	)
	(segment
		(start 31.486602 -162.241992)
		(end 31.359602 -162.114992)
		(width 0.127)
		(layer "F.Cu")
		(net "PHY_DRV_A_TO_SCC_A_12_DN")
	)
	(segment
		(start 31.359602 -162.114992)
		(end 30.025086 -162.114992)
		(width 0.127)
		(layer "F.Cu")
		(net "PHY_DRV_A_TO_SCC_A_12_DN")
	)
	(arc
		(start 32.508952 -162.476942)
		(mid 32.471755 -162.566745)
		(end 32.381952 -162.603942)
		(width 0.127)
		(layer "F.Cu")
		(net "PHY_DRV_A_TO_SCC_A_12_DN")
	)
	(segment
		(start 36.524946 -164.158168)
		(end 63.147194 -205.947264)
		(width 0.1016)
		(layer "In7.Cu")
		(net "PHY_DRV_A_TO_SCC_A_12_DN")
	)
	(segment
		(start 92.632022 -224.751646)
		(end 143.638016 -234.960414)
		(width 0.1016)
		(layer "In7.Cu")
		(net "PHY_DRV_A_TO_SCC_A_12_DN")
	)
	(segment
		(start 33.745678 -162.584892)
		(end 36.524946 -164.158168)
		(width 0.1016)
		(layer "In7.Cu")
		(net "PHY_DRV_A_TO_SCC_A_12_DN")
	)
	(segment
		(start 226.368864 -306.225702)
		(end 267.721334 -333.859124)
		(width 0.1016)
		(layer "In7.Cu")
		(net "PHY_DRV_A_TO_SCC_A_12_DN")
	)
	(segment
		(start 287.430972 -336.105246)
		(end 287.83661 -336.105246)
		(width 0.1016)
		(layer "In7.Cu")
		(net "PHY_DRV_A_TO_SCC_A_12_DN")
	)
	(segment
		(start 143.638016 -234.960414)
		(end 200.930764 -267.113258)
		(width 0.1016)
		(layer "In7.Cu")
		(net "PHY_DRV_A_TO_SCC_A_12_DN")
	)
	(segment
		(start 270.95196 -335.040224)
		(end 286.80918 -335.040224)
		(width 0.1016)
		(layer "In7.Cu")
		(net "PHY_DRV_A_TO_SCC_A_12_DN")
	)
	(segment
		(start 267.721334 -333.859124)
		(end 270.95196 -335.040224)
		(width 0.1016)
		(layer "In7.Cu")
		(net "PHY_DRV_A_TO_SCC_A_12_DN")
	)
	(segment
		(start 63.147194 -205.947264)
		(end 92.632022 -224.751646)
		(width 0.1016)
		(layer "In7.Cu")
		(net "PHY_DRV_A_TO_SCC_A_12_DN")
	)
	(segment
		(start 200.930764 -267.113258)
		(end 226.368864 -306.225702)
		(width 0.1016)
		(layer "In7.Cu")
		(net "PHY_DRV_A_TO_SCC_A_12_DN")
	)
	(segment
		(start 287.303972 -335.535016)
		(end 287.303972 -335.978246)
		(width 0.1016)
		(layer "In7.Cu")
		(net "PHY_DRV_A_TO_SCC_A_12_DN")
	)
	(segment
		(start 32.610552 -162.584892)
		(end 33.745678 -162.584892)
		(width 0.1016)
		(layer "In7.Cu")
		(net "PHY_DRV_A_TO_SCC_A_12_DN")
	)
	(segment
		(start 32.508952 -162.178492)
		(end 32.508952 -162.483292)
		(width 0.1016)
		(layer "In7.Cu")
		(net "PHY_DRV_A_TO_SCC_A_12_DN")
	)
	(arc
		(start 286.80918 -335.040224)
		(mid 287.159051 -335.185145)
		(end 287.303972 -335.535016)
		(width 0.1016)
		(layer "In7.Cu")
		(net "PHY_DRV_A_TO_SCC_A_12_DN")
	)
	(arc
		(start 32.508952 -162.483292)
		(mid 32.53871 -162.555134)
		(end 32.610552 -162.584892)
		(width 0.1016)
		(layer "In7.Cu")
		(net "PHY_DRV_A_TO_SCC_A_12_DN")
	)
	(arc
		(start 287.303972 -335.978246)
		(mid 287.341169 -336.068049)
		(end 287.430972 -336.105246)
		(width 0.1016)
		(layer "In7.Cu")
		(net "PHY_DRV_A_TO_SCC_A_12_DN")
	)
	(segment
		(start 483.663498 -278.046434)
		(end 483.663498 -278.20112)
		(width 0.127)
		(layer "F.Cu")
		(net "PHY_DRV_A_TO_SCC_A_11_DP")
	)
	(segment
		(start 483.663498 -278.20112)
		(end 483.847394 -278.385016)
		(width 0.127)
		(layer "F.Cu")
		(net "PHY_DRV_A_TO_SCC_A_11_DP")
	)
	(segment
		(start 483.847394 -278.385016)
		(end 485.125014 -278.385016)
		(width 0.127)
		(layer "F.Cu")
		(net "PHY_DRV_A_TO_SCC_A_11_DP")
	)
	(segment
		(start 482.489002 -278.321516)
		(end 482.489002 -278.02332)
		(width 0.127)
		(layer "F.Cu")
		(net "PHY_DRV_A_TO_SCC_A_11_DP")
	)
	(segment
		(start 482.616256 -277.896066)
		(end 483.51313 -277.896066)
		(width 0.127)
		(layer "F.Cu")
		(net "PHY_DRV_A_TO_SCC_A_11_DP")
	)
	(segment
		(start 483.51313 -277.896066)
		(end 483.663498 -278.046434)
		(width 0.127)
		(layer "F.Cu")
		(net "PHY_DRV_A_TO_SCC_A_11_DP")
	)
	(arc
		(start 482.489002 -278.02332)
		(mid 482.526274 -277.933338)
		(end 482.616256 -277.896066)
		(width 0.127)
		(layer "F.Cu")
		(net "PHY_DRV_A_TO_SCC_A_11_DP")
	)
	(segment
		(start 481.725732 -277.896066)
		(end 481.169218 -278.028654)
		(width 0.127)
		(layer "B.Cu")
		(net "PHY_DRV_A_TO_SCC_A_11_DP")
	)
	(segment
		(start 290.841684 -347.951044)
		(end 287.7439 -347.951044)
		(width 0.127)
		(layer "B.Cu")
		(net "PHY_DRV_A_TO_SCC_A_11_DP")
	)
	(segment
		(start 372.493032 -315.020198)
		(end 372.492778 -315.020198)
		(width 0.127)
		(layer "B.Cu")
		(net "PHY_DRV_A_TO_SCC_A_11_DP")
	)
	(segment
		(start 482.489002 -278.321516)
		(end 482.489002 -278.07285)
		(width 0.127)
		(layer "B.Cu")
		(net "PHY_DRV_A_TO_SCC_A_11_DP")
	)
	(segment
		(start 372.492778 -315.020198)
		(end 336.799682 -337.762596)
		(width 0.127)
		(layer "B.Cu")
		(net "PHY_DRV_A_TO_SCC_A_11_DP")
	)
	(segment
		(start 286.990536 -347.282516)
		(end 286.990536 -347.032072)
		(width 0.127)
		(layer "B.Cu")
		(net "PHY_DRV_A_TO_SCC_A_11_DP")
	)
	(segment
		(start 481.169218 -278.028654)
		(end 479.902012 -278.867362)
		(width 0.127)
		(layer "B.Cu")
		(net "PHY_DRV_A_TO_SCC_A_11_DP")
	)
	(segment
		(start 451.530466 -298.93895)
		(end 372.493032 -315.020198)
		(width 0.127)
		(layer "B.Cu")
		(net "PHY_DRV_A_TO_SCC_A_11_DP")
	)
	(segment
		(start 286.863536 -346.905072)
		(end 286.436562 -346.905072)
		(width 0.127)
		(layer "B.Cu")
		(net "PHY_DRV_A_TO_SCC_A_11_DP")
	)
	(segment
		(start 482.312218 -277.896066)
		(end 481.725732 -277.896066)
		(width 0.127)
		(layer "B.Cu")
		(net "PHY_DRV_A_TO_SCC_A_11_DP")
	)
	(segment
		(start 478.378266 -281.168348)
		(end 451.530466 -298.93895)
		(width 0.127)
		(layer "B.Cu")
		(net "PHY_DRV_A_TO_SCC_A_11_DP")
	)
	(segment
		(start 479.902012 -278.867362)
		(end 478.378266 -281.168348)
		(width 0.127)
		(layer "B.Cu")
		(net "PHY_DRV_A_TO_SCC_A_11_DP")
	)
	(segment
		(start 336.799682 -337.762596)
		(end 290.841684 -347.951044)
		(width 0.127)
		(layer "B.Cu")
		(net "PHY_DRV_A_TO_SCC_A_11_DP")
	)
	(arc
		(start 286.990536 -347.032072)
		(mid 286.953339 -346.942269)
		(end 286.863536 -346.905072)
		(width 0.127)
		(layer "B.Cu")
		(net "PHY_DRV_A_TO_SCC_A_11_DP")
	)
	(arc
		(start 287.16859 -347.712792)
		(mid 287.03682 -347.51535)
		(end 286.990536 -347.282516)
		(width 0.127)
		(layer "B.Cu")
		(net "PHY_DRV_A_TO_SCC_A_11_DP")
	)
	(arc
		(start 482.489002 -278.07285)
		(mid 482.437223 -277.947845)
		(end 482.312218 -277.896066)
		(width 0.127)
		(layer "B.Cu")
		(net "PHY_DRV_A_TO_SCC_A_11_DP")
	)
	(arc
		(start 287.7439 -347.951044)
		(mid 287.432563 -347.889115)
		(end 287.16859 -347.712792)
		(width 0.127)
		(layer "B.Cu")
		(net "PHY_DRV_A_TO_SCC_A_11_DP")
	)
	(segment
		(start 483.663498 -277.476966)
		(end 483.663498 -277.242016)
		(width 0.127)
		(layer "F.Cu")
		(net "PHY_DRV_A_TO_SCC_A_11_DN")
	)
	(segment
		(start 482.616256 -277.603966)
		(end 483.536498 -277.603966)
		(width 0.127)
		(layer "F.Cu")
		(net "PHY_DRV_A_TO_SCC_A_11_DN")
	)
	(segment
		(start 483.790498 -277.115016)
		(end 485.125014 -277.115016)
		(width 0.127)
		(layer "F.Cu")
		(net "PHY_DRV_A_TO_SCC_A_11_DN")
	)
	(segment
		(start 483.536498 -277.603966)
		(end 483.663498 -277.476966)
		(width 0.127)
		(layer "F.Cu")
		(net "PHY_DRV_A_TO_SCC_A_11_DN")
	)
	(segment
		(start 483.663498 -277.242016)
		(end 483.790498 -277.115016)
		(width 0.127)
		(layer "F.Cu")
		(net "PHY_DRV_A_TO_SCC_A_11_DN")
	)
	(segment
		(start 482.489002 -277.178516)
		(end 482.489002 -277.476712)
		(width 0.127)
		(layer "F.Cu")
		(net "PHY_DRV_A_TO_SCC_A_11_DN")
	)
	(arc
		(start 482.489002 -277.476712)
		(mid 482.526274 -277.566694)
		(end 482.616256 -277.603966)
		(width 0.127)
		(layer "F.Cu")
		(net "PHY_DRV_A_TO_SCC_A_11_DN")
	)
	(segment
		(start 287.7439 -347.658944)
		(end 290.80968 -347.658944)
		(width 0.127)
		(layer "B.Cu")
		(net "PHY_DRV_A_TO_SCC_A_11_DN")
	)
	(segment
		(start 465.627212 -289.257994)
		(end 478.167446 -280.957528)
		(width 0.127)
		(layer "B.Cu")
		(net "PHY_DRV_A_TO_SCC_A_11_DN")
	)
	(segment
		(start 372.881398 -314.476892)
		(end 373.254778 -314.400946)
		(width 0.127)
		(layer "B.Cu")
		(net "PHY_DRV_A_TO_SCC_A_11_DN")
	)
	(segment
		(start 478.167446 -280.957528)
		(end 479.691192 -278.656542)
		(width 0.127)
		(layer "B.Cu")
		(net "PHY_DRV_A_TO_SCC_A_11_DN")
	)
	(segment
		(start 373.446548 -314.527946)
		(end 373.819928 -314.452)
		(width 0.127)
		(layer "B.Cu")
		(net "PHY_DRV_A_TO_SCC_A_11_DN")
	)
	(segment
		(start 373.819928 -314.452)
		(end 373.946928 -314.26023)
		(width 0.127)
		(layer "B.Cu")
		(net "PHY_DRV_A_TO_SCC_A_11_DN")
	)
	(segment
		(start 372.754652 -314.668662)
		(end 372.881398 -314.476892)
		(width 0.127)
		(layer "B.Cu")
		(net "PHY_DRV_A_TO_SCC_A_11_DN")
	)
	(segment
		(start 411.899608 -306.704238)
		(end 451.41642 -298.663868)
		(width 0.127)
		(layer "B.Cu")
		(net "PHY_DRV_A_TO_SCC_A_11_DN")
	)
	(segment
		(start 372.381272 -314.744608)
		(end 372.754652 -314.668662)
		(width 0.127)
		(layer "B.Cu")
		(net "PHY_DRV_A_TO_SCC_A_11_DN")
	)
	(segment
		(start 451.41642 -298.663868)
		(end 453.086978 -297.558206)
		(width 0.127)
		(layer "B.Cu")
		(net "PHY_DRV_A_TO_SCC_A_11_DN")
	)
	(segment
		(start 374.320054 -314.184284)
		(end 374.511824 -314.31103)
		(width 0.127)
		(layer "B.Cu")
		(net "PHY_DRV_A_TO_SCC_A_11_DN")
	)
	(segment
		(start 374.511824 -314.31103)
		(end 374.885204 -314.235084)
		(width 0.127)
		(layer "B.Cu")
		(net "PHY_DRV_A_TO_SCC_A_11_DN")
	)
	(segment
		(start 453.086978 -297.558206)
		(end 453.087232 -297.558206)
		(width 0.127)
		(layer "B.Cu")
		(net "PHY_DRV_A_TO_SCC_A_11_DN")
	)
	(segment
		(start 481.101654 -277.744428)
		(end 481.691188 -277.603966)
		(width 0.127)
		(layer "B.Cu")
		(net "PHY_DRV_A_TO_SCC_A_11_DN")
	)
	(segment
		(start 479.691192 -278.656542)
		(end 481.055172 -277.753572)
		(width 0.127)
		(layer "B.Cu")
		(net "PHY_DRV_A_TO_SCC_A_11_DN")
	)
	(segment
		(start 375.38533 -313.967622)
		(end 375.5771 -314.094368)
		(width 0.127)
		(layer "B.Cu")
		(net "PHY_DRV_A_TO_SCC_A_11_DN")
	)
	(segment
		(start 481.055172 -277.753572)
		(end 481.101654 -277.744428)
		(width 0.127)
		(layer "B.Cu")
		(net "PHY_DRV_A_TO_SCC_A_11_DN")
	)
	(segment
		(start 373.254778 -314.400946)
		(end 373.446548 -314.527946)
		(width 0.127)
		(layer "B.Cu")
		(net "PHY_DRV_A_TO_SCC_A_11_DN")
	)
	(segment
		(start 336.686144 -337.48853)
		(end 372.381272 -314.744608)
		(width 0.127)
		(layer "B.Cu")
		(net "PHY_DRV_A_TO_SCC_A_11_DN")
	)
	(segment
		(start 373.946928 -314.26023)
		(end 374.320054 -314.184284)
		(width 0.127)
		(layer "B.Cu")
		(net "PHY_DRV_A_TO_SCC_A_11_DN")
	)
	(segment
		(start 290.80968 -347.658944)
		(end 336.686144 -337.48853)
		(width 0.127)
		(layer "B.Cu")
		(net "PHY_DRV_A_TO_SCC_A_11_DN")
	)
	(segment
		(start 482.489002 -277.427182)
		(end 482.489002 -277.178516)
		(width 0.127)
		(layer "B.Cu")
		(net "PHY_DRV_A_TO_SCC_A_11_DN")
	)
	(segment
		(start 287.83661 -346.905072)
		(end 287.409636 -346.905072)
		(width 0.127)
		(layer "B.Cu")
		(net "PHY_DRV_A_TO_SCC_A_11_DN")
	)
	(segment
		(start 287.282636 -347.032072)
		(end 287.282636 -347.282516)
		(width 0.127)
		(layer "B.Cu")
		(net "PHY_DRV_A_TO_SCC_A_11_DN")
	)
	(segment
		(start 375.012204 -314.043568)
		(end 375.38533 -313.967622)
		(width 0.127)
		(layer "B.Cu")
		(net "PHY_DRV_A_TO_SCC_A_11_DN")
	)
	(segment
		(start 453.087232 -297.558206)
		(end 465.627212 -289.257994)
		(width 0.127)
		(layer "B.Cu")
		(net "PHY_DRV_A_TO_SCC_A_11_DN")
	)
	(segment
		(start 481.691188 -277.603966)
		(end 482.312218 -277.603966)
		(width 0.127)
		(layer "B.Cu")
		(net "PHY_DRV_A_TO_SCC_A_11_DN")
	)
	(segment
		(start 375.5771 -314.094368)
		(end 411.899608 -306.704238)
		(width 0.127)
		(layer "B.Cu")
		(net "PHY_DRV_A_TO_SCC_A_11_DN")
	)
	(segment
		(start 374.885204 -314.235084)
		(end 375.012204 -314.043568)
		(width 0.127)
		(layer "B.Cu")
		(net "PHY_DRV_A_TO_SCC_A_11_DN")
	)
	(arc
		(start 287.282636 -347.282516)
		(mid 287.306727 -347.403629)
		(end 287.375346 -347.50629)
		(width 0.127)
		(layer "B.Cu")
		(net "PHY_DRV_A_TO_SCC_A_11_DN")
	)
	(arc
		(start 287.375346 -347.50629)
		(mid 287.54444 -347.619275)
		(end 287.7439 -347.658944)
		(width 0.127)
		(layer "B.Cu")
		(net "PHY_DRV_A_TO_SCC_A_11_DN")
	)
	(arc
		(start 482.312218 -277.603966)
		(mid 482.437223 -277.552187)
		(end 482.489002 -277.427182)
		(width 0.127)
		(layer "B.Cu")
		(net "PHY_DRV_A_TO_SCC_A_11_DN")
	)
	(arc
		(start 287.409636 -346.905072)
		(mid 287.319833 -346.942269)
		(end 287.282636 -347.032072)
		(width 0.127)
		(layer "B.Cu")
		(net "PHY_DRV_A_TO_SCC_A_11_DN")
	)
	(segment
		(start 452.113396 -278.189436)
		(end 452.308976 -278.385016)
		(width 0.127)
		(layer "F.Cu")
		(net "PHY_DRV_A_TO_SCC_A_10_DP")
	)
	(segment
		(start 451.951344 -277.896066)
		(end 452.113396 -278.058118)
		(width 0.127)
		(layer "F.Cu")
		(net "PHY_DRV_A_TO_SCC_A_10_DP")
	)
	(segment
		(start 452.113396 -278.058118)
		(end 452.113396 -278.189436)
		(width 0.127)
		(layer "F.Cu")
		(net "PHY_DRV_A_TO_SCC_A_10_DP")
	)
	(segment
		(start 450.9389 -278.321516)
		(end 450.9389 -278.05634)
		(width 0.127)
		(layer "F.Cu")
		(net "PHY_DRV_A_TO_SCC_A_10_DP")
	)
	(segment
		(start 451.099174 -277.896066)
		(end 451.951344 -277.896066)
		(width 0.127)
		(layer "F.Cu")
		(net "PHY_DRV_A_TO_SCC_A_10_DP")
	)
	(segment
		(start 452.308976 -278.385016)
		(end 453.574912 -278.385016)
		(width 0.127)
		(layer "F.Cu")
		(net "PHY_DRV_A_TO_SCC_A_10_DP")
	)
	(arc
		(start 450.9389 -278.05634)
		(mid 450.985843 -277.943009)
		(end 451.099174 -277.896066)
		(width 0.127)
		(layer "F.Cu")
		(net "PHY_DRV_A_TO_SCC_A_10_DP")
	)
	(segment
		(start 285.863538 -345.105228)
		(end 285.436564 -345.105228)
		(width 0.127)
		(layer "B.Cu")
		(net "PHY_DRV_A_TO_SCC_A_10_DP")
	)
	(segment
		(start 408.509216 -305.34229)
		(end 371.45087 -312.881772)
		(width 0.127)
		(layer "B.Cu")
		(net "PHY_DRV_A_TO_SCC_A_10_DP")
	)
	(segment
		(start 291.73932 -346.1512)
		(end 286.743902 -346.1512)
		(width 0.127)
		(layer "B.Cu")
		(net "PHY_DRV_A_TO_SCC_A_10_DP")
	)
	(segment
		(start 449.974716 -277.896066)
		(end 408.509216 -305.34229)
		(width 0.127)
		(layer "B.Cu")
		(net "PHY_DRV_A_TO_SCC_A_10_DP")
	)
	(segment
		(start 450.9389 -278.321516)
		(end 450.9389 -278.07285)
		(width 0.127)
		(layer "B.Cu")
		(net "PHY_DRV_A_TO_SCC_A_10_DP")
	)
	(segment
		(start 334.486758 -336.675222)
		(end 291.73932 -346.1512)
		(width 0.127)
		(layer "B.Cu")
		(net "PHY_DRV_A_TO_SCC_A_10_DP")
	)
	(segment
		(start 450.762116 -277.896066)
		(end 449.974716 -277.896066)
		(width 0.127)
		(layer "B.Cu")
		(net "PHY_DRV_A_TO_SCC_A_10_DP")
	)
	(segment
		(start 285.990538 -345.482672)
		(end 285.990538 -345.232228)
		(width 0.127)
		(layer "B.Cu")
		(net "PHY_DRV_A_TO_SCC_A_10_DP")
	)
	(segment
		(start 371.45087 -312.881772)
		(end 334.486758 -336.675222)
		(width 0.127)
		(layer "B.Cu")
		(net "PHY_DRV_A_TO_SCC_A_10_DP")
	)
	(arc
		(start 285.990538 -345.232228)
		(mid 285.953341 -345.142425)
		(end 285.863538 -345.105228)
		(width 0.127)
		(layer "B.Cu")
		(net "PHY_DRV_A_TO_SCC_A_10_DP")
	)
	(arc
		(start 286.743902 -346.1512)
		(mid 286.432565 -346.089271)
		(end 286.168592 -345.912948)
		(width 0.127)
		(layer "B.Cu")
		(net "PHY_DRV_A_TO_SCC_A_10_DP")
	)
	(arc
		(start 450.9389 -278.07285)
		(mid 450.887121 -277.947845)
		(end 450.762116 -277.896066)
		(width 0.127)
		(layer "B.Cu")
		(net "PHY_DRV_A_TO_SCC_A_10_DP")
	)
	(arc
		(start 286.168592 -345.912948)
		(mid 286.036822 -345.715506)
		(end 285.990538 -345.482672)
		(width 0.127)
		(layer "B.Cu")
		(net "PHY_DRV_A_TO_SCC_A_10_DP")
	)
	(segment
		(start 451.099174 -277.603966)
		(end 451.986396 -277.603966)
		(width 0.127)
		(layer "F.Cu")
		(net "PHY_DRV_A_TO_SCC_A_10_DN")
	)
	(segment
		(start 451.986396 -277.603966)
		(end 452.113396 -277.476966)
		(width 0.127)
		(layer "F.Cu")
		(net "PHY_DRV_A_TO_SCC_A_10_DN")
	)
	(segment
		(start 452.113396 -277.476966)
		(end 452.113396 -277.242016)
		(width 0.127)
		(layer "F.Cu")
		(net "PHY_DRV_A_TO_SCC_A_10_DN")
	)
	(segment
		(start 452.240396 -277.115016)
		(end 453.574912 -277.115016)
		(width 0.127)
		(layer "F.Cu")
		(net "PHY_DRV_A_TO_SCC_A_10_DN")
	)
	(segment
		(start 450.9389 -277.178516)
		(end 450.9389 -277.443692)
		(width 0.127)
		(layer "F.Cu")
		(net "PHY_DRV_A_TO_SCC_A_10_DN")
	)
	(segment
		(start 452.113396 -277.242016)
		(end 452.240396 -277.115016)
		(width 0.127)
		(layer "F.Cu")
		(net "PHY_DRV_A_TO_SCC_A_10_DN")
	)
	(arc
		(start 450.9389 -277.443692)
		(mid 450.985843 -277.557023)
		(end 451.099174 -277.603966)
		(width 0.127)
		(layer "F.Cu")
		(net "PHY_DRV_A_TO_SCC_A_10_DN")
	)
	(segment
		(start 350.116648 -326.26681)
		(end 349.905828 -326.22109)
		(width 0.127)
		(layer "B.Cu")
		(net "PHY_DRV_A_TO_SCC_A_10_DN")
	)
	(segment
		(start 349.905828 -326.22109)
		(end 349.585534 -326.427338)
		(width 0.127)
		(layer "B.Cu")
		(net "PHY_DRV_A_TO_SCC_A_10_DN")
	)
	(segment
		(start 348.64294 -327.2155)
		(end 348.322646 -327.421748)
		(width 0.127)
		(layer "B.Cu")
		(net "PHY_DRV_A_TO_SCC_A_10_DN")
	)
	(segment
		(start 347.791532 -327.582276)
		(end 347.745812 -327.792842)
		(width 0.127)
		(layer "B.Cu")
		(net "PHY_DRV_A_TO_SCC_A_10_DN")
	)
	(segment
		(start 347.745812 -327.792842)
		(end 334.372458 -336.401156)
		(width 0.127)
		(layer "B.Cu")
		(net "PHY_DRV_A_TO_SCC_A_10_DN")
	)
	(segment
		(start 334.372458 -336.401156)
		(end 291.707316 -345.8591)
		(width 0.127)
		(layer "B.Cu")
		(net "PHY_DRV_A_TO_SCC_A_10_DN")
	)
	(segment
		(start 349.008954 -326.798686)
		(end 348.68866 -327.00468)
		(width 0.127)
		(layer "B.Cu")
		(net "PHY_DRV_A_TO_SCC_A_10_DN")
	)
	(segment
		(start 286.282638 -345.482672)
		(end 286.282638 -345.232228)
		(width 0.127)
		(layer "B.Cu")
		(net "PHY_DRV_A_TO_SCC_A_10_DN")
	)
	(segment
		(start 408.39517 -305.067208)
		(end 371.338856 -312.606436)
		(width 0.127)
		(layer "B.Cu")
		(net "PHY_DRV_A_TO_SCC_A_10_DN")
	)
	(segment
		(start 349.585534 -326.427338)
		(end 349.539814 -326.637904)
		(width 0.127)
		(layer "B.Cu")
		(net "PHY_DRV_A_TO_SCC_A_10_DN")
	)
	(segment
		(start 371.338856 -312.606436)
		(end 350.116648 -326.26681)
		(width 0.127)
		(layer "B.Cu")
		(net "PHY_DRV_A_TO_SCC_A_10_DN")
	)
	(segment
		(start 349.539814 -326.637904)
		(end 349.21952 -326.844152)
		(width 0.127)
		(layer "B.Cu")
		(net "PHY_DRV_A_TO_SCC_A_10_DN")
	)
	(segment
		(start 348.68866 -327.00468)
		(end 348.64294 -327.2155)
		(width 0.127)
		(layer "B.Cu")
		(net "PHY_DRV_A_TO_SCC_A_10_DN")
	)
	(segment
		(start 349.21952 -326.844152)
		(end 349.008954 -326.798686)
		(width 0.127)
		(layer "B.Cu")
		(net "PHY_DRV_A_TO_SCC_A_10_DN")
	)
	(segment
		(start 286.409638 -345.105228)
		(end 286.836612 -345.105228)
		(width 0.127)
		(layer "B.Cu")
		(net "PHY_DRV_A_TO_SCC_A_10_DN")
	)
	(segment
		(start 348.111826 -327.376028)
		(end 347.791532 -327.582276)
		(width 0.127)
		(layer "B.Cu")
		(net "PHY_DRV_A_TO_SCC_A_10_DN")
	)
	(segment
		(start 449.886578 -277.603966)
		(end 408.39517 -305.067208)
		(width 0.127)
		(layer "B.Cu")
		(net "PHY_DRV_A_TO_SCC_A_10_DN")
	)
	(segment
		(start 348.322646 -327.421748)
		(end 348.111826 -327.376028)
		(width 0.127)
		(layer "B.Cu")
		(net "PHY_DRV_A_TO_SCC_A_10_DN")
	)
	(segment
		(start 450.762116 -277.603966)
		(end 449.886578 -277.603966)
		(width 0.127)
		(layer "B.Cu")
		(net "PHY_DRV_A_TO_SCC_A_10_DN")
	)
	(segment
		(start 291.707316 -345.8591)
		(end 286.743902 -345.8591)
		(width 0.127)
		(layer "B.Cu")
		(net "PHY_DRV_A_TO_SCC_A_10_DN")
	)
	(segment
		(start 450.9389 -277.178516)
		(end 450.9389 -277.427182)
		(width 0.127)
		(layer "B.Cu")
		(net "PHY_DRV_A_TO_SCC_A_10_DN")
	)
	(arc
		(start 286.375348 -345.706446)
		(mid 286.306747 -345.603778)
		(end 286.282638 -345.482672)
		(width 0.127)
		(layer "B.Cu")
		(net "PHY_DRV_A_TO_SCC_A_10_DN")
	)
	(arc
		(start 286.743902 -345.8591)
		(mid 286.544444 -345.819425)
		(end 286.375348 -345.706446)
		(width 0.127)
		(layer "B.Cu")
		(net "PHY_DRV_A_TO_SCC_A_10_DN")
	)
	(arc
		(start 286.282638 -345.232228)
		(mid 286.319835 -345.142425)
		(end 286.409638 -345.105228)
		(width 0.127)
		(layer "B.Cu")
		(net "PHY_DRV_A_TO_SCC_A_10_DN")
	)
	(arc
		(start 450.9389 -277.427182)
		(mid 450.887121 -277.552187)
		(end 450.762116 -277.603966)
		(width 0.127)
		(layer "B.Cu")
		(net "PHY_DRV_A_TO_SCC_A_10_DN")
	)
	(segment
		(start 63.16345 -277.896066)
		(end 63.03645 -278.023066)
		(width 0.127)
		(layer "F.Cu")
		(net "PHY_DRV_A_TO_SCC_A_1_DP")
	)
	(segment
		(start 63.9318 -277.896066)
		(end 63.16345 -277.896066)
		(width 0.127)
		(layer "F.Cu")
		(net "PHY_DRV_A_TO_SCC_A_1_DP")
	)
	(segment
		(start 64.0588 -278.321516)
		(end 64.0588 -278.023066)
		(width 0.127)
		(layer "F.Cu")
		(net "PHY_DRV_A_TO_SCC_A_1_DP")
	)
	(segment
		(start 63.03645 -278.258016)
		(end 62.90945 -278.385016)
		(width 0.127)
		(layer "F.Cu")
		(net "PHY_DRV_A_TO_SCC_A_1_DP")
	)
	(segment
		(start 63.03645 -278.023066)
		(end 63.03645 -278.258016)
		(width 0.127)
		(layer "F.Cu")
		(net "PHY_DRV_A_TO_SCC_A_1_DP")
	)
	(segment
		(start 62.90945 -278.385016)
		(end 61.574934 -278.385016)
		(width 0.127)
		(layer "F.Cu")
		(net "PHY_DRV_A_TO_SCC_A_1_DP")
	)
	(arc
		(start 64.0588 -278.023066)
		(mid 64.021603 -277.933263)
		(end 63.9318 -277.896066)
		(width 0.127)
		(layer "F.Cu")
		(net "PHY_DRV_A_TO_SCC_A_1_DP")
	)
	(segment
		(start 69.498464 -278.841454)
		(end 69.498464 -278.841708)
		(width 0.1016)
		(layer "In7.Cu")
		(net "PHY_DRV_A_TO_SCC_A_1_DP")
	)
	(segment
		(start 266.168124 -353.493578)
		(end 266.039346 -353.216718)
		(width 0.1016)
		(layer "In7.Cu")
		(net "PHY_DRV_A_TO_SCC_A_1_DP")
	)
	(segment
		(start 73.855072 -279.767792)
		(end 69.498464 -278.841454)
		(width 0.1016)
		(layer "In7.Cu")
		(net "PHY_DRV_A_TO_SCC_A_1_DP")
	)
	(segment
		(start 64.0588 -278.016716)
		(end 64.0588 -278.321516)
		(width 0.1016)
		(layer "In7.Cu")
		(net "PHY_DRV_A_TO_SCC_A_1_DP")
	)
	(segment
		(start 265.476228 -353.240594)
		(end 265.18997 -353.135946)
		(width 0.1016)
		(layer "In7.Cu")
		(net "PHY_DRV_A_TO_SCC_A_1_DP")
	)
	(segment
		(start 265.061446 -352.859086)
		(end 261.250176 -351.465134)
		(width 0.1016)
		(layer "In7.Cu")
		(net "PHY_DRV_A_TO_SCC_A_1_DP")
	)
	(segment
		(start 267.0175 -353.574604)
		(end 266.731242 -353.469702)
		(width 0.1016)
		(layer "In7.Cu")
		(net "PHY_DRV_A_TO_SCC_A_1_DP")
	)
	(segment
		(start 265.753342 -353.11207)
		(end 265.476228 -353.240594)
		(width 0.1016)
		(layer "In7.Cu")
		(net "PHY_DRV_A_TO_SCC_A_1_DP")
	)
	(segment
		(start 285.809182 -355.170232)
		(end 271.380712 -355.170232)
		(width 0.1016)
		(layer "In7.Cu")
		(net "PHY_DRV_A_TO_SCC_A_1_DP")
	)
	(segment
		(start 65.141856 -277.915116)
		(end 64.1604 -277.915116)
		(width 0.1016)
		(layer "In7.Cu")
		(net "PHY_DRV_A_TO_SCC_A_1_DP")
	)
	(segment
		(start 267.709396 -353.827588)
		(end 267.432282 -353.956112)
		(width 0.1016)
		(layer "In7.Cu")
		(net "PHY_DRV_A_TO_SCC_A_1_DP")
	)
	(segment
		(start 271.380712 -355.170232)
		(end 267.709396 -353.827588)
		(width 0.1016)
		(layer "In7.Cu")
		(net "PHY_DRV_A_TO_SCC_A_1_DP")
	)
	(segment
		(start 105.086912 -300.050454)
		(end 73.855072 -279.767792)
		(width 0.1016)
		(layer "In7.Cu")
		(net "PHY_DRV_A_TO_SCC_A_1_DP")
	)
	(segment
		(start 267.432282 -353.956112)
		(end 267.146024 -353.851464)
		(width 0.1016)
		(layer "In7.Cu")
		(net "PHY_DRV_A_TO_SCC_A_1_DP")
	)
	(segment
		(start 261.250176 -351.465134)
		(end 220.81744 -325.706232)
		(width 0.1016)
		(layer "In7.Cu")
		(net "PHY_DRV_A_TO_SCC_A_1_DP")
	)
	(segment
		(start 285.973774 -355.778054)
		(end 285.973774 -355.334824)
		(width 0.1016)
		(layer "In7.Cu")
		(net "PHY_DRV_A_TO_SCC_A_1_DP")
	)
	(segment
		(start 266.454382 -353.59848)
		(end 266.168124 -353.493578)
		(width 0.1016)
		(layer "In7.Cu")
		(net "PHY_DRV_A_TO_SCC_A_1_DP")
	)
	(segment
		(start 285.436564 -355.905054)
		(end 285.846774 -355.905054)
		(width 0.1016)
		(layer "In7.Cu")
		(net "PHY_DRV_A_TO_SCC_A_1_DP")
	)
	(segment
		(start 220.81744 -325.706232)
		(end 105.086912 -300.050454)
		(width 0.1016)
		(layer "In7.Cu")
		(net "PHY_DRV_A_TO_SCC_A_1_DP")
	)
	(segment
		(start 266.039346 -353.216718)
		(end 265.753342 -353.11207)
		(width 0.1016)
		(layer "In7.Cu")
		(net "PHY_DRV_A_TO_SCC_A_1_DP")
	)
	(segment
		(start 267.146024 -353.851464)
		(end 267.0175 -353.574604)
		(width 0.1016)
		(layer "In7.Cu")
		(net "PHY_DRV_A_TO_SCC_A_1_DP")
	)
	(segment
		(start 266.731242 -353.469702)
		(end 266.454382 -353.59848)
		(width 0.1016)
		(layer "In7.Cu")
		(net "PHY_DRV_A_TO_SCC_A_1_DP")
	)
	(segment
		(start 69.498464 -278.841708)
		(end 65.141856 -277.915116)
		(width 0.1016)
		(layer "In7.Cu")
		(net "PHY_DRV_A_TO_SCC_A_1_DP")
	)
	(segment
		(start 265.18997 -353.135946)
		(end 265.061446 -352.859086)
		(width 0.1016)
		(layer "In7.Cu")
		(net "PHY_DRV_A_TO_SCC_A_1_DP")
	)
	(arc
		(start 285.973774 -355.334824)
		(mid 285.925566 -355.21844)
		(end 285.809182 -355.170232)
		(width 0.1016)
		(layer "In7.Cu")
		(net "PHY_DRV_A_TO_SCC_A_1_DP")
	)
	(arc
		(start 285.846774 -355.905054)
		(mid 285.936577 -355.867857)
		(end 285.973774 -355.778054)
		(width 0.1016)
		(layer "In7.Cu")
		(net "PHY_DRV_A_TO_SCC_A_1_DP")
	)
	(arc
		(start 64.1604 -277.915116)
		(mid 64.088558 -277.944874)
		(end 64.0588 -278.016716)
		(width 0.1016)
		(layer "In7.Cu")
		(net "PHY_DRV_A_TO_SCC_A_1_DP")
	)
	(segment
		(start 63.9318 -277.603966)
		(end 63.16345 -277.603966)
		(width 0.127)
		(layer "F.Cu")
		(net "PHY_DRV_A_TO_SCC_A_1_DN")
	)
	(segment
		(start 63.16345 -277.603966)
		(end 63.03645 -277.476966)
		(width 0.127)
		(layer "F.Cu")
		(net "PHY_DRV_A_TO_SCC_A_1_DN")
	)
	(segment
		(start 62.90945 -277.115016)
		(end 61.574934 -277.115016)
		(width 0.127)
		(layer "F.Cu")
		(net "PHY_DRV_A_TO_SCC_A_1_DN")
	)
	(segment
		(start 64.0588 -277.178516)
		(end 64.0588 -277.476966)
		(width 0.127)
		(layer "F.Cu")
		(net "PHY_DRV_A_TO_SCC_A_1_DN")
	)
	(segment
		(start 63.03645 -277.242016)
		(end 62.90945 -277.115016)
		(width 0.127)
		(layer "F.Cu")
		(net "PHY_DRV_A_TO_SCC_A_1_DN")
	)
	(segment
		(start 63.03645 -277.476966)
		(end 63.03645 -277.242016)
		(width 0.127)
		(layer "F.Cu")
		(net "PHY_DRV_A_TO_SCC_A_1_DN")
	)
	(arc
		(start 64.0588 -277.476966)
		(mid 64.021603 -277.566769)
		(end 63.9318 -277.603966)
		(width 0.127)
		(layer "F.Cu")
		(net "PHY_DRV_A_TO_SCC_A_1_DN")
	)
	(segment
		(start 65.176654 -277.584916)
		(end 73.983596 -279.457404)
		(width 0.1016)
		(layer "In7.Cu")
		(net "PHY_DRV_A_TO_SCC_A_1_DN")
	)
	(segment
		(start 64.1604 -277.584916)
		(end 65.176654 -277.584916)
		(width 0.1016)
		(layer "In7.Cu")
		(net "PHY_DRV_A_TO_SCC_A_1_DN")
	)
	(segment
		(start 271.439132 -354.839778)
		(end 271.439386 -354.840032)
		(width 0.1016)
		(layer "In7.Cu")
		(net "PHY_DRV_A_TO_SCC_A_1_DN")
	)
	(segment
		(start 64.0588 -277.178516)
		(end 64.0588 -277.483316)
		(width 0.1016)
		(layer "In7.Cu")
		(net "PHY_DRV_A_TO_SCC_A_1_DN")
	)
	(segment
		(start 105.216706 -299.740828)
		(end 220.94571 -325.396352)
		(width 0.1016)
		(layer "In7.Cu")
		(net "PHY_DRV_A_TO_SCC_A_1_DN")
	)
	(segment
		(start 261.397496 -351.167192)
		(end 271.439132 -354.839778)
		(width 0.1016)
		(layer "In7.Cu")
		(net "PHY_DRV_A_TO_SCC_A_1_DN")
	)
	(segment
		(start 286.430974 -355.905054)
		(end 286.836612 -355.905054)
		(width 0.1016)
		(layer "In7.Cu")
		(net "PHY_DRV_A_TO_SCC_A_1_DN")
	)
	(segment
		(start 271.439386 -354.840032)
		(end 285.809182 -354.840032)
		(width 0.1016)
		(layer "In7.Cu")
		(net "PHY_DRV_A_TO_SCC_A_1_DN")
	)
	(segment
		(start 220.94571 -325.396352)
		(end 261.397496 -351.167192)
		(width 0.1016)
		(layer "In7.Cu")
		(net "PHY_DRV_A_TO_SCC_A_1_DN")
	)
	(segment
		(start 73.983596 -279.457404)
		(end 105.216706 -299.740828)
		(width 0.1016)
		(layer "In7.Cu")
		(net "PHY_DRV_A_TO_SCC_A_1_DN")
	)
	(segment
		(start 286.303974 -355.334824)
		(end 286.303974 -355.778054)
		(width 0.1016)
		(layer "In7.Cu")
		(net "PHY_DRV_A_TO_SCC_A_1_DN")
	)
	(arc
		(start 286.303974 -355.778054)
		(mid 286.341171 -355.867857)
		(end 286.430974 -355.905054)
		(width 0.1016)
		(layer "In7.Cu")
		(net "PHY_DRV_A_TO_SCC_A_1_DN")
	)
	(arc
		(start 64.0588 -277.483316)
		(mid 64.088558 -277.555158)
		(end 64.1604 -277.584916)
		(width 0.1016)
		(layer "In7.Cu")
		(net "PHY_DRV_A_TO_SCC_A_1_DN")
	)
	(arc
		(start 285.809182 -354.840032)
		(mid 286.159053 -354.984953)
		(end 286.303974 -355.334824)
		(width 0.1016)
		(layer "In7.Cu")
		(net "PHY_DRV_A_TO_SCC_A_1_DN")
	)
	(segment
		(start 31.359602 -278.385016)
		(end 30.025086 -278.385016)
		(width 0.127)
		(layer "F.Cu")
		(net "PHY_DRV_A_TO_SCC_A_0_DP")
	)
	(segment
		(start 32.508952 -278.321516)
		(end 32.508952 -278.023066)
		(width 0.127)
		(layer "F.Cu")
		(net "PHY_DRV_A_TO_SCC_A_0_DP")
	)
	(segment
		(start 31.613602 -277.896066)
		(end 31.486602 -278.023066)
		(width 0.127)
		(layer "F.Cu")
		(net "PHY_DRV_A_TO_SCC_A_0_DP")
	)
	(segment
		(start 31.486602 -278.023066)
		(end 31.486602 -278.258016)
		(width 0.127)
		(layer "F.Cu")
		(net "PHY_DRV_A_TO_SCC_A_0_DP")
	)
	(segment
		(start 32.381952 -277.896066)
		(end 31.613602 -277.896066)
		(width 0.127)
		(layer "F.Cu")
		(net "PHY_DRV_A_TO_SCC_A_0_DP")
	)
	(segment
		(start 31.486602 -278.258016)
		(end 31.359602 -278.385016)
		(width 0.127)
		(layer "F.Cu")
		(net "PHY_DRV_A_TO_SCC_A_0_DP")
	)
	(arc
		(start 32.508952 -278.023066)
		(mid 32.471755 -277.933263)
		(end 32.381952 -277.896066)
		(width 0.127)
		(layer "F.Cu")
		(net "PHY_DRV_A_TO_SCC_A_0_DP")
	)
	(segment
		(start 264.616946 -354.651056)
		(end 264.340086 -354.779834)
		(width 0.1016)
		(layer "In7.Cu")
		(net "PHY_DRV_A_TO_SCC_A_0_DP")
	)
	(segment
		(start 265.31824 -355.137466)
		(end 265.031982 -355.032818)
		(width 0.1016)
		(layer "In7.Cu")
		(net "PHY_DRV_A_TO_SCC_A_0_DP")
	)
	(segment
		(start 32.508952 -278.016716)
		(end 32.508952 -278.321516)
		(width 0.1016)
		(layer "In7.Cu")
		(net "PHY_DRV_A_TO_SCC_A_0_DP")
	)
	(segment
		(start 265.881358 -355.11359)
		(end 265.5951 -355.008942)
		(width 0.1016)
		(layer "In7.Cu")
		(net "PHY_DRV_A_TO_SCC_A_0_DP")
	)
	(segment
		(start 35.74161 -279.440894)
		(end 33.433258 -277.970996)
		(width 0.1016)
		(layer "In7.Cu")
		(net "PHY_DRV_A_TO_SCC_A_0_DP")
	)
	(segment
		(start 264.053828 -354.675186)
		(end 263.925304 -354.398072)
		(width 0.1016)
		(layer "In7.Cu")
		(net "PHY_DRV_A_TO_SCC_A_0_DP")
	)
	(segment
		(start 286.973772 -357.578152)
		(end 286.973772 -357.25862)
		(width 0.1016)
		(layer "In7.Cu")
		(net "PHY_DRV_A_TO_SCC_A_0_DP")
	)
	(segment
		(start 265.031982 -355.032818)
		(end 264.903204 -354.755958)
		(width 0.1016)
		(layer "In7.Cu")
		(net "PHY_DRV_A_TO_SCC_A_0_DP")
	)
	(segment
		(start 33.433258 -277.97125)
		(end 33.18129 -277.915116)
		(width 0.1016)
		(layer "In7.Cu")
		(net "PHY_DRV_A_TO_SCC_A_0_DP")
	)
	(segment
		(start 39.290244 -285.010606)
		(end 35.74161 -279.440894)
		(width 0.1016)
		(layer "In7.Cu")
		(net "PHY_DRV_A_TO_SCC_A_0_DP")
	)
	(segment
		(start 264.340086 -354.779834)
		(end 264.053828 -354.675186)
		(width 0.1016)
		(layer "In7.Cu")
		(net "PHY_DRV_A_TO_SCC_A_0_DP")
	)
	(segment
		(start 33.433258 -277.970996)
		(end 33.433258 -277.97125)
		(width 0.1016)
		(layer "In7.Cu")
		(net "PHY_DRV_A_TO_SCC_A_0_DP")
	)
	(segment
		(start 270.958056 -356.97033)
		(end 266.573254 -355.366574)
		(width 0.1016)
		(layer "In7.Cu")
		(net "PHY_DRV_A_TO_SCC_A_0_DP")
	)
	(segment
		(start 43.884342 -287.937448)
		(end 39.290244 -285.010606)
		(width 0.1016)
		(layer "In7.Cu")
		(net "PHY_DRV_A_TO_SCC_A_0_DP")
	)
	(segment
		(start 261.486396 -353.506024)
		(end 220.099128 -326.99833)
		(width 0.1016)
		(layer "In7.Cu")
		(net "PHY_DRV_A_TO_SCC_A_0_DP")
	)
	(segment
		(start 286.436562 -357.705152)
		(end 286.846772 -357.705152)
		(width 0.1016)
		(layer "In7.Cu")
		(net "PHY_DRV_A_TO_SCC_A_0_DP")
	)
	(segment
		(start 266.009882 -355.39045)
		(end 265.881358 -355.11359)
		(width 0.1016)
		(layer "In7.Cu")
		(net "PHY_DRV_A_TO_SCC_A_0_DP")
	)
	(segment
		(start 264.903204 -354.755958)
		(end 264.616946 -354.651056)
		(width 0.1016)
		(layer "In7.Cu")
		(net "PHY_DRV_A_TO_SCC_A_0_DP")
	)
	(segment
		(start 266.573254 -355.366574)
		(end 266.29614 -355.495098)
		(width 0.1016)
		(layer "In7.Cu")
		(net "PHY_DRV_A_TO_SCC_A_0_DP")
	)
	(segment
		(start 286.685482 -356.97033)
		(end 270.958056 -356.97033)
		(width 0.1016)
		(layer "In7.Cu")
		(net "PHY_DRV_A_TO_SCC_A_0_DP")
	)
	(segment
		(start 265.5951 -355.008942)
		(end 265.31824 -355.137466)
		(width 0.1016)
		(layer "In7.Cu")
		(net "PHY_DRV_A_TO_SCC_A_0_DP")
	)
	(segment
		(start 220.099128 -326.99833)
		(end 43.884342 -287.937448)
		(width 0.1016)
		(layer "In7.Cu")
		(net "PHY_DRV_A_TO_SCC_A_0_DP")
	)
	(segment
		(start 266.29614 -355.495098)
		(end 266.009882 -355.39045)
		(width 0.1016)
		(layer "In7.Cu")
		(net "PHY_DRV_A_TO_SCC_A_0_DP")
	)
	(segment
		(start 33.18129 -277.915116)
		(end 32.610552 -277.915116)
		(width 0.1016)
		(layer "In7.Cu")
		(net "PHY_DRV_A_TO_SCC_A_0_DP")
	)
	(segment
		(start 263.925304 -354.398072)
		(end 261.486396 -353.506024)
		(width 0.1016)
		(layer "In7.Cu")
		(net "PHY_DRV_A_TO_SCC_A_0_DP")
	)
	(arc
		(start 286.846772 -357.705152)
		(mid 286.936575 -357.667955)
		(end 286.973772 -357.578152)
		(width 0.1016)
		(layer "In7.Cu")
		(net "PHY_DRV_A_TO_SCC_A_0_DP")
	)
	(arc
		(start 32.610552 -277.915116)
		(mid 32.53871 -277.944874)
		(end 32.508952 -278.016716)
		(width 0.1016)
		(layer "In7.Cu")
		(net "PHY_DRV_A_TO_SCC_A_0_DP")
	)
	(arc
		(start 286.973772 -357.25862)
		(mid 286.889334 -357.054768)
		(end 286.685482 -356.97033)
		(width 0.1016)
		(layer "In7.Cu")
		(net "PHY_DRV_A_TO_SCC_A_0_DP")
	)
	(segment
		(start 32.381952 -277.603966)
		(end 31.613602 -277.603966)
		(width 0.127)
		(layer "F.Cu")
		(net "PHY_DRV_A_TO_SCC_A_0_DN")
	)
	(segment
		(start 31.613602 -277.603966)
		(end 31.486602 -277.476966)
		(width 0.127)
		(layer "F.Cu")
		(net "PHY_DRV_A_TO_SCC_A_0_DN")
	)
	(segment
		(start 31.359602 -277.115016)
		(end 30.025086 -277.115016)
		(width 0.127)
		(layer "F.Cu")
		(net "PHY_DRV_A_TO_SCC_A_0_DN")
	)
	(segment
		(start 31.486602 -277.476966)
		(end 31.486602 -277.242016)
		(width 0.127)
		(layer "F.Cu")
		(net "PHY_DRV_A_TO_SCC_A_0_DN")
	)
	(segment
		(start 32.508952 -277.178516)
		(end 32.508952 -277.476966)
		(width 0.127)
		(layer "F.Cu")
		(net "PHY_DRV_A_TO_SCC_A_0_DN")
	)
	(segment
		(start 31.486602 -277.242016)
		(end 31.359602 -277.115016)
		(width 0.127)
		(layer "F.Cu")
		(net "PHY_DRV_A_TO_SCC_A_0_DN")
	)
	(arc
		(start 32.508952 -277.476966)
		(mid 32.471755 -277.566769)
		(end 32.381952 -277.603966)
		(width 0.127)
		(layer "F.Cu")
		(net "PHY_DRV_A_TO_SCC_A_0_DN")
	)
	(segment
		(start 44.012612 -287.627568)
		(end 220.227906 -326.68845)
		(width 0.1016)
		(layer "In7.Cu")
		(net "PHY_DRV_A_TO_SCC_A_0_DN")
	)
	(segment
		(start 220.227906 -326.68845)
		(end 261.63397 -353.208336)
		(width 0.1016)
		(layer "In7.Cu")
		(net "PHY_DRV_A_TO_SCC_A_0_DN")
	)
	(segment
		(start 39.529512 -284.771338)
		(end 44.012612 -287.627568)
		(width 0.1016)
		(layer "In7.Cu")
		(net "PHY_DRV_A_TO_SCC_A_0_DN")
	)
	(segment
		(start 264.038842 -354.087938)
		(end 266.558268 -355.009196)
		(width 0.1016)
		(layer "In7.Cu")
		(net "PHY_DRV_A_TO_SCC_A_0_DN")
	)
	(segment
		(start 287.303972 -357.25862)
		(end 287.303972 -357.578152)
		(width 0.1016)
		(layer "In7.Cu")
		(net "PHY_DRV_A_TO_SCC_A_0_DN")
	)
	(segment
		(start 266.558268 -355.00945)
		(end 271.01673 -356.64013)
		(width 0.1016)
		(layer "In7.Cu")
		(net "PHY_DRV_A_TO_SCC_A_0_DN")
	)
	(segment
		(start 35.980878 -279.201626)
		(end 39.529512 -284.771338)
		(width 0.1016)
		(layer "In7.Cu")
		(net "PHY_DRV_A_TO_SCC_A_0_DN")
	)
	(segment
		(start 33.561528 -277.661116)
		(end 34.764726 -278.42718)
		(width 0.1016)
		(layer "In7.Cu")
		(net "PHY_DRV_A_TO_SCC_A_0_DN")
	)
	(segment
		(start 33.217612 -277.584916)
		(end 33.561528 -277.661116)
		(width 0.1016)
		(layer "In7.Cu")
		(net "PHY_DRV_A_TO_SCC_A_0_DN")
	)
	(segment
		(start 287.430972 -357.705152)
		(end 287.83661 -357.705152)
		(width 0.1016)
		(layer "In7.Cu")
		(net "PHY_DRV_A_TO_SCC_A_0_DN")
	)
	(segment
		(start 271.01673 -356.64013)
		(end 286.685482 -356.64013)
		(width 0.1016)
		(layer "In7.Cu")
		(net "PHY_DRV_A_TO_SCC_A_0_DN")
	)
	(segment
		(start 34.764726 -278.42718)
		(end 35.980878 -279.201626)
		(width 0.1016)
		(layer "In7.Cu")
		(net "PHY_DRV_A_TO_SCC_A_0_DN")
	)
	(segment
		(start 266.558268 -355.009196)
		(end 266.558268 -355.00945)
		(width 0.1016)
		(layer "In7.Cu")
		(net "PHY_DRV_A_TO_SCC_A_0_DN")
	)
	(segment
		(start 263.437624 -353.867974)
		(end 264.038842 -354.087938)
		(width 0.1016)
		(layer "In7.Cu")
		(net "PHY_DRV_A_TO_SCC_A_0_DN")
	)
	(segment
		(start 261.63397 -353.208336)
		(end 263.437624 -353.867974)
		(width 0.1016)
		(layer "In7.Cu")
		(net "PHY_DRV_A_TO_SCC_A_0_DN")
	)
	(segment
		(start 32.610552 -277.584916)
		(end 33.217612 -277.584916)
		(width 0.1016)
		(layer "In7.Cu")
		(net "PHY_DRV_A_TO_SCC_A_0_DN")
	)
	(segment
		(start 32.508952 -277.178516)
		(end 32.508952 -277.483316)
		(width 0.1016)
		(layer "In7.Cu")
		(net "PHY_DRV_A_TO_SCC_A_0_DN")
	)
	(arc
		(start 286.685482 -356.64013)
		(mid 287.12282 -356.821282)
		(end 287.303972 -357.25862)
		(width 0.1016)
		(layer "In7.Cu")
		(net "PHY_DRV_A_TO_SCC_A_0_DN")
	)
	(arc
		(start 287.303972 -357.578152)
		(mid 287.341169 -357.667955)
		(end 287.430972 -357.705152)
		(width 0.1016)
		(layer "In7.Cu")
		(net "PHY_DRV_A_TO_SCC_A_0_DN")
	)
	(arc
		(start 32.508952 -277.483316)
		(mid 32.53871 -277.555158)
		(end 32.610552 -277.584916)
		(width 0.1016)
		(layer "In7.Cu")
		(net "PHY_DRV_A_TO_SCC_A_0_DN")
	)
	(segment
		(start 264.143236 -179.17033)
		(end 273.62785 -164.564314)
		(width 0.1651)
		(layer "B.Cu")
		(net "PCIE_SCC_B_TO_COMP_B_7_DP")
	)
	(segment
		(start 273.62785 -164.564314)
		(end 277.619714 -161.354008)
		(width 0.1651)
		(layer "B.Cu")
		(net "PCIE_SCC_B_TO_COMP_B_7_DP")
	)
	(segment
		(start 263.06907 -182.710328)
		(end 263.069324 -182.709566)
		(width 0.1651)
		(layer "B.Cu")
		(net "PCIE_SCC_B_TO_COMP_B_7_DP")
	)
	(segment
		(start 263.069324 -182.709566)
		(end 263.423146 -181.543452)
		(width 0.1651)
		(layer "B.Cu")
		(net "PCIE_SCC_B_TO_COMP_B_7_DP")
	)
	(segment
		(start 277.619714 -161.354008)
		(end 279.17394 -161.354008)
		(width 0.1651)
		(layer "B.Cu")
		(net "PCIE_SCC_B_TO_COMP_B_7_DP")
	)
	(segment
		(start 219.754704 -396.842488)
		(end 221.649036 -388.287768)
		(width 0.1651)
		(layer "B.Cu")
		(net "PCIE_SCC_B_TO_COMP_B_7_DP")
	)
	(segment
		(start 261.030212 -189.430152)
		(end 263.06907 -182.710328)
		(width 0.1651)
		(layer "B.Cu")
		(net "PCIE_SCC_B_TO_COMP_B_7_DP")
	)
	(segment
		(start 221.649036 -388.287768)
		(end 214.764874 -357.876094)
		(width 0.1651)
		(layer "B.Cu")
		(net "PCIE_SCC_B_TO_COMP_B_7_DP")
	)
	(segment
		(start 263.423146 -181.543452)
		(end 263.4234 -181.54269)
		(width 0.1651)
		(layer "B.Cu")
		(net "PCIE_SCC_B_TO_COMP_B_7_DP")
	)
	(segment
		(start 221.55404 -404.797514)
		(end 219.754704 -396.842488)
		(width 0.1651)
		(layer "B.Cu")
		(net "PCIE_SCC_B_TO_COMP_B_7_DP")
	)
	(segment
		(start 214.190834 -343.811098)
		(end 261.029958 -189.430914)
		(width 0.1651)
		(layer "B.Cu")
		(net "PCIE_SCC_B_TO_COMP_B_7_DP")
	)
	(segment
		(start 279.764744 -161.701988)
		(end 279.807162 -161.786824)
		(width 0.1651)
		(layer "B.Cu")
		(net "PCIE_SCC_B_TO_COMP_B_7_DP")
	)
	(segment
		(start 261.029958 -189.430914)
		(end 261.030212 -189.430152)
		(width 0.1651)
		(layer "B.Cu")
		(net "PCIE_SCC_B_TO_COMP_B_7_DP")
	)
	(segment
		(start 215.98255 -351.7392)
		(end 214.190834 -343.811098)
		(width 0.1651)
		(layer "B.Cu")
		(net "PCIE_SCC_B_TO_COMP_B_7_DP")
	)
	(segment
		(start 263.4234 -181.54269)
		(end 263.987534 -179.68341)
		(width 0.1651)
		(layer "B.Cu")
		(net "PCIE_SCC_B_TO_COMP_B_7_DP")
	)
	(segment
		(start 279.714452 -161.601912)
		(end 279.764744 -161.701988)
		(width 0.1651)
		(layer "B.Cu")
		(net "PCIE_SCC_B_TO_COMP_B_7_DP")
	)
	(segment
		(start 222.600012 -407.399998)
		(end 222.600012 -407.030682)
		(width 0.1651)
		(layer "B.Cu")
		(net "PCIE_SCC_B_TO_COMP_B_7_DP")
	)
	(segment
		(start 263.987788 -179.682648)
		(end 264.143236 -179.17033)
		(width 0.1651)
		(layer "B.Cu")
		(net "PCIE_SCC_B_TO_COMP_B_7_DP")
	)
	(segment
		(start 280.02865 -161.860738)
		(end 280.75001 -161.499804)
		(width 0.1651)
		(layer "B.Cu")
		(net "PCIE_SCC_B_TO_COMP_B_7_DP")
	)
	(segment
		(start 263.987534 -179.68341)
		(end 263.987788 -179.682648)
		(width 0.1651)
		(layer "B.Cu")
		(net "PCIE_SCC_B_TO_COMP_B_7_DP")
	)
	(segment
		(start 222.415354 -406.846024)
		(end 222.045784 -406.846024)
		(width 0.1651)
		(layer "B.Cu")
		(net "PCIE_SCC_B_TO_COMP_B_7_DP")
	)
	(segment
		(start 221.55404 -406.35428)
		(end 221.55404 -404.797514)
		(width 0.1651)
		(layer "B.Cu")
		(net "PCIE_SCC_B_TO_COMP_B_7_DP")
	)
	(segment
		(start 214.764874 -357.876094)
		(end 215.98255 -351.7392)
		(width 0.1651)
		(layer "B.Cu")
		(net "PCIE_SCC_B_TO_COMP_B_7_DP")
	)
	(arc
		(start 222.045784 -406.846024)
		(mid 221.848279 -406.804594)
		(end 221.684088 -406.687274)
		(width 0.1651)
		(layer "B.Cu")
		(net "PCIE_SCC_B_TO_COMP_B_7_DP")
	)
	(arc
		(start 221.684088 -406.687274)
		(mid 221.587701 -406.533019)
		(end 221.55404 -406.35428)
		(width 0.1651)
		(layer "B.Cu")
		(net "PCIE_SCC_B_TO_COMP_B_7_DP")
	)
	(arc
		(start 279.17394 -161.354008)
		(mid 279.471223 -161.419008)
		(end 279.714452 -161.601912)
		(width 0.1651)
		(layer "B.Cu")
		(net "PCIE_SCC_B_TO_COMP_B_7_DP")
	)
	(arc
		(start 279.807162 -161.786824)
		(mid 279.902579 -161.869636)
		(end 280.02865 -161.860738)
		(width 0.1651)
		(layer "B.Cu")
		(net "PCIE_SCC_B_TO_COMP_B_7_DP")
	)
	(arc
		(start 222.600012 -407.030682)
		(mid 222.545927 -406.900109)
		(end 222.415354 -406.846024)
		(width 0.1651)
		(layer "B.Cu")
		(net "PCIE_SCC_B_TO_COMP_B_7_DP")
	)
	(segment
		(start 267.79474 -174.294038)
		(end 267.760958 -174.135796)
		(width 0.1651)
		(layer "B.Cu")
		(net "PCIE_SCC_B_TO_COMP_B_7_DN")
	)
	(segment
		(start 266.196826 -176.754536)
		(end 266.466574 -176.338992)
		(width 0.1651)
		(layer "B.Cu")
		(net "PCIE_SCC_B_TO_COMP_B_7_DN")
	)
	(segment
		(start 261.166102 -189.98946)
		(end 261.309866 -189.515496)
		(width 0.1651)
		(layer "B.Cu")
		(net "PCIE_SCC_B_TO_COMP_B_7_DN")
	)
	(segment
		(start 261.098538 -190.605918)
		(end 261.242302 -190.131954)
		(width 0.1651)
		(layer "B.Cu")
		(net "PCIE_SCC_B_TO_COMP_B_7_DN")
	)
	(segment
		(start 263.845548 -181.552088)
		(end 263.989312 -181.078124)
		(width 0.1651)
		(layer "B.Cu")
		(net "PCIE_SCC_B_TO_COMP_B_7_DN")
	)
	(segment
		(start 263.559544 -182.101236)
		(end 263.703054 -181.628034)
		(width 0.1651)
		(layer "B.Cu")
		(net "PCIE_SCC_B_TO_COMP_B_7_DN")
	)
	(segment
		(start 263.703054 -181.628034)
		(end 263.845548 -181.552088)
		(width 0.1651)
		(layer "B.Cu")
		(net "PCIE_SCC_B_TO_COMP_B_7_DN")
	)
	(segment
		(start 272.034762 -167.554402)
		(end 272.206974 -167.517826)
		(width 0.1651)
		(layer "B.Cu")
		(net "PCIE_SCC_B_TO_COMP_B_7_DN")
	)
	(segment
		(start 268.030706 -173.720506)
		(end 268.188948 -173.686978)
		(width 0.1651)
		(layer "B.Cu")
		(net "PCIE_SCC_B_TO_COMP_B_7_DN")
	)
	(segment
		(start 266.038838 -176.788064)
		(end 266.196826 -176.754536)
		(width 0.1651)
		(layer "B.Cu")
		(net "PCIE_SCC_B_TO_COMP_B_7_DN")
	)
	(segment
		(start 273.115024 -165.890702)
		(end 273.84756 -164.762688)
		(width 0.1651)
		(layer "B.Cu")
		(net "PCIE_SCC_B_TO_COMP_B_7_DN")
	)
	(segment
		(start 261.242302 -190.131954)
		(end 261.166102 -189.98946)
		(width 0.1651)
		(layer "B.Cu")
		(net "PCIE_SCC_B_TO_COMP_B_7_DN")
	)
	(segment
		(start 221.948502 -388.287006)
		(end 215.063578 -357.87203)
		(width 0.1651)
		(layer "B.Cu")
		(net "PCIE_SCC_B_TO_COMP_B_7_DN")
	)
	(segment
		(start 268.458696 -173.271434)
		(end 268.424914 -173.113446)
		(width 0.1651)
		(layer "B.Cu")
		(net "PCIE_SCC_B_TO_COMP_B_7_DN")
	)
	(segment
		(start 260.956044 -190.682118)
		(end 261.098538 -190.605918)
		(width 0.1651)
		(layer "B.Cu")
		(net "PCIE_SCC_B_TO_COMP_B_7_DN")
	)
	(segment
		(start 279.545542 -161.916872)
		(end 279.545542 -161.917126)
		(width 0.1651)
		(layer "B.Cu")
		(net "PCIE_SCC_B_TO_COMP_B_7_DN")
	)
	(segment
		(start 272.476722 -167.102282)
		(end 272.440146 -166.930324)
		(width 0.1651)
		(layer "B.Cu")
		(net "PCIE_SCC_B_TO_COMP_B_7_DN")
	)
	(segment
		(start 266.466574 -176.338992)
		(end 266.433046 -176.181004)
		(width 0.1651)
		(layer "B.Cu")
		(net "PCIE_SCC_B_TO_COMP_B_7_DN")
	)
	(segment
		(start 267.097002 -175.1584)
		(end 267.36675 -174.74311)
		(width 0.1651)
		(layer "B.Cu")
		(net "PCIE_SCC_B_TO_COMP_B_7_DN")
	)
	(segment
		(start 267.13053 -175.316642)
		(end 267.097002 -175.1584)
		(width 0.1651)
		(layer "B.Cu")
		(net "PCIE_SCC_B_TO_COMP_B_7_DN")
	)
	(segment
		(start 272.881852 -166.478204)
		(end 273.1516 -166.062914)
		(width 0.1651)
		(layer "B.Cu")
		(net "PCIE_SCC_B_TO_COMP_B_7_DN")
	)
	(segment
		(start 261.452614 -189.439296)
		(end 261.596378 -188.965332)
		(width 0.1651)
		(layer "B.Cu")
		(net "PCIE_SCC_B_TO_COMP_B_7_DN")
	)
	(segment
		(start 261.520178 -188.822584)
		(end 262.995156 -183.961532)
		(width 0.1651)
		(layer "B.Cu")
		(net "PCIE_SCC_B_TO_COMP_B_7_DN")
	)
	(segment
		(start 264.267188 -179.768754)
		(end 264.267696 -179.76723)
		(width 0.1651)
		(layer "B.Cu")
		(net "PCIE_SCC_B_TO_COMP_B_7_DN")
	)
	(segment
		(start 272.206974 -167.517826)
		(end 272.476722 -167.102282)
		(width 0.1651)
		(layer "B.Cu")
		(net "PCIE_SCC_B_TO_COMP_B_7_DN")
	)
	(segment
		(start 267.760958 -174.135796)
		(end 268.030706 -173.720506)
		(width 0.1651)
		(layer "B.Cu")
		(net "PCIE_SCC_B_TO_COMP_B_7_DN")
	)
	(segment
		(start 261.309866 -189.515496)
		(end 261.452614 -189.439296)
		(width 0.1651)
		(layer "B.Cu")
		(net "PCIE_SCC_B_TO_COMP_B_7_DN")
	)
	(segment
		(start 222.600012 -405.99995)
		(end 222.600012 -406.36952)
		(width 0.1651)
		(layer "B.Cu")
		(net "PCIE_SCC_B_TO_COMP_B_7_DN")
	)
	(segment
		(start 272.440146 -166.930324)
		(end 272.709894 -166.51478)
		(width 0.1651)
		(layer "B.Cu")
		(net "PCIE_SCC_B_TO_COMP_B_7_DN")
	)
	(segment
		(start 272.709894 -166.51478)
		(end 272.881852 -166.478204)
		(width 0.1651)
		(layer "B.Cu")
		(net "PCIE_SCC_B_TO_COMP_B_7_DN")
	)
	(segment
		(start 263.205214 -183.268874)
		(end 263.348978 -182.79491)
		(width 0.1651)
		(layer "B.Cu")
		(net "PCIE_SCC_B_TO_COMP_B_7_DN")
	)
	(segment
		(start 262.995156 -183.961532)
		(end 263.13765 -183.885332)
		(width 0.1651)
		(layer "B.Cu")
		(net "PCIE_SCC_B_TO_COMP_B_7_DN")
	)
	(segment
		(start 271.35963 -168.594024)
		(end 271.531842 -168.557448)
		(width 0.1651)
		(layer "B.Cu")
		(net "PCIE_SCC_B_TO_COMP_B_7_DN")
	)
	(segment
		(start 263.63549 -182.244746)
		(end 263.55929 -182.101998)
		(width 0.1651)
		(layer "B.Cu")
		(net "PCIE_SCC_B_TO_COMP_B_7_DN")
	)
	(segment
		(start 268.424914 -173.113446)
		(end 271.35963 -168.594024)
		(width 0.1651)
		(layer "B.Cu")
		(net "PCIE_SCC_B_TO_COMP_B_7_DN")
	)
	(segment
		(start 271.80159 -168.141904)
		(end 271.765014 -167.969692)
		(width 0.1651)
		(layer "B.Cu")
		(net "PCIE_SCC_B_TO_COMP_B_7_DN")
	)
	(segment
		(start 215.063578 -357.87203)
		(end 216.281254 -351.735136)
		(width 0.1651)
		(layer "B.Cu")
		(net "PCIE_SCC_B_TO_COMP_B_7_DN")
	)
	(segment
		(start 220.05417 -396.841726)
		(end 221.948502 -388.287006)
		(width 0.1651)
		(layer "B.Cu")
		(net "PCIE_SCC_B_TO_COMP_B_7_DN")
	)
	(segment
		(start 273.84756 -164.762688)
		(end 277.722838 -161.646108)
		(width 0.1651)
		(layer "B.Cu")
		(net "PCIE_SCC_B_TO_COMP_B_7_DN")
	)
	(segment
		(start 277.722838 -161.646108)
		(end 279.173686 -161.646108)
		(width 0.1651)
		(layer "B.Cu")
		(net "PCIE_SCC_B_TO_COMP_B_7_DN")
	)
	(segment
		(start 222.41764 -406.553924)
		(end 222.045784 -406.553924)
		(width 0.1651)
		(layer "B.Cu")
		(net "PCIE_SCC_B_TO_COMP_B_7_DN")
	)
	(segment
		(start 264.056876 -180.461412)
		(end 264.199624 -180.385212)
		(width 0.1651)
		(layer "B.Cu")
		(net "PCIE_SCC_B_TO_COMP_B_7_DN")
	)
	(segment
		(start 268.188948 -173.686978)
		(end 268.458696 -173.271434)
		(width 0.1651)
		(layer "B.Cu")
		(net "PCIE_SCC_B_TO_COMP_B_7_DN")
	)
	(segment
		(start 214.49284 -343.82202)
		(end 260.956044 -190.682118)
		(width 0.1651)
		(layer "B.Cu")
		(net "PCIE_SCC_B_TO_COMP_B_7_DN")
	)
	(segment
		(start 266.702794 -175.76546)
		(end 266.860782 -175.731932)
		(width 0.1651)
		(layer "B.Cu")
		(net "PCIE_SCC_B_TO_COMP_B_7_DN")
	)
	(segment
		(start 264.343388 -179.911248)
		(end 264.267188 -179.768754)
		(width 0.1651)
		(layer "B.Cu")
		(net "PCIE_SCC_B_TO_COMP_B_7_DN")
	)
	(segment
		(start 271.765014 -167.969692)
		(end 272.034762 -167.554402)
		(width 0.1651)
		(layer "B.Cu")
		(net "PCIE_SCC_B_TO_COMP_B_7_DN")
	)
	(segment
		(start 267.36675 -174.74311)
		(end 267.524992 -174.709328)
		(width 0.1651)
		(layer "B.Cu")
		(net "PCIE_SCC_B_TO_COMP_B_7_DN")
	)
	(segment
		(start 216.281254 -351.735136)
		(end 214.49284 -343.82202)
		(width 0.1651)
		(layer "B.Cu")
		(net "PCIE_SCC_B_TO_COMP_B_7_DN")
	)
	(segment
		(start 263.281414 -183.411368)
		(end 263.205214 -183.268874)
		(width 0.1651)
		(layer "B.Cu")
		(net "PCIE_SCC_B_TO_COMP_B_7_DN")
	)
	(segment
		(start 263.491472 -182.71871)
		(end 263.63549 -182.244746)
		(width 0.1651)
		(layer "B.Cu")
		(net "PCIE_SCC_B_TO_COMP_B_7_DN")
	)
	(segment
		(start 263.913112 -180.935376)
		(end 264.056876 -180.461412)
		(width 0.1651)
		(layer "B.Cu")
		(net "PCIE_SCC_B_TO_COMP_B_7_DN")
	)
	(segment
		(start 271.531842 -168.557448)
		(end 271.80159 -168.141904)
		(width 0.1651)
		(layer "B.Cu")
		(net "PCIE_SCC_B_TO_COMP_B_7_DN")
	)
	(segment
		(start 279.471882 -162.138614)
		(end 278.750014 -162.499802)
		(width 0.1651)
		(layer "B.Cu")
		(net "PCIE_SCC_B_TO_COMP_B_7_DN")
	)
	(segment
		(start 264.199624 -180.385212)
		(end 264.343388 -179.911248)
		(width 0.1651)
		(layer "B.Cu")
		(net "PCIE_SCC_B_TO_COMP_B_7_DN")
	)
	(segment
		(start 279.471628 -161.769552)
		(end 279.545542 -161.916872)
		(width 0.1651)
		(layer "B.Cu")
		(net "PCIE_SCC_B_TO_COMP_B_7_DN")
	)
	(segment
		(start 263.989312 -181.078124)
		(end 263.913112 -180.935376)
		(width 0.1651)
		(layer "B.Cu")
		(net "PCIE_SCC_B_TO_COMP_B_7_DN")
	)
	(segment
		(start 264.410952 -179.29479)
		(end 266.038838 -176.788064)
		(width 0.1651)
		(layer "B.Cu")
		(net "PCIE_SCC_B_TO_COMP_B_7_DN")
	)
	(segment
		(start 263.55929 -182.101998)
		(end 263.559544 -182.101236)
		(width 0.1651)
		(layer "B.Cu")
		(net "PCIE_SCC_B_TO_COMP_B_7_DN")
	)
	(segment
		(start 266.860782 -175.731932)
		(end 267.13053 -175.316642)
		(width 0.1651)
		(layer "B.Cu")
		(net "PCIE_SCC_B_TO_COMP_B_7_DN")
	)
	(segment
		(start 221.84614 -406.35428)
		(end 221.84614 -404.764748)
		(width 0.1651)
		(layer "B.Cu")
		(net "PCIE_SCC_B_TO_COMP_B_7_DN")
	)
	(segment
		(start 267.524992 -174.709328)
		(end 267.79474 -174.294038)
		(width 0.1651)
		(layer "B.Cu")
		(net "PCIE_SCC_B_TO_COMP_B_7_DN")
	)
	(segment
		(start 261.596378 -188.965332)
		(end 261.520178 -188.822584)
		(width 0.1651)
		(layer "B.Cu")
		(net "PCIE_SCC_B_TO_COMP_B_7_DN")
	)
	(segment
		(start 266.433046 -176.181004)
		(end 266.702794 -175.76546)
		(width 0.1651)
		(layer "B.Cu")
		(net "PCIE_SCC_B_TO_COMP_B_7_DN")
	)
	(segment
		(start 221.84614 -404.764748)
		(end 220.05417 -396.841726)
		(width 0.1651)
		(layer "B.Cu")
		(net "PCIE_SCC_B_TO_COMP_B_7_DN")
	)
	(segment
		(start 273.1516 -166.062914)
		(end 273.115024 -165.890702)
		(width 0.1651)
		(layer "B.Cu")
		(net "PCIE_SCC_B_TO_COMP_B_7_DN")
	)
	(segment
		(start 264.267696 -179.76723)
		(end 264.410952 -179.29479)
		(width 0.1651)
		(layer "B.Cu")
		(net "PCIE_SCC_B_TO_COMP_B_7_DN")
	)
	(segment
		(start 263.13765 -183.885332)
		(end 263.281414 -183.411368)
		(width 0.1651)
		(layer "B.Cu")
		(net "PCIE_SCC_B_TO_COMP_B_7_DN")
	)
	(segment
		(start 263.348978 -182.79491)
		(end 263.491472 -182.71871)
		(width 0.1651)
		(layer "B.Cu")
		(net "PCIE_SCC_B_TO_COMP_B_7_DN")
	)
	(arc
		(start 222.480378 -406.542494)
		(mid 222.449527 -406.55106)
		(end 222.41764 -406.553924)
		(width 0.1651)
		(layer "B.Cu")
		(net "PCIE_SCC_B_TO_COMP_B_7_DN")
	)
	(arc
		(start 222.045784 -406.553924)
		(mid 221.965597 -406.537089)
		(end 221.898972 -406.489408)
		(width 0.1651)
		(layer "B.Cu")
		(net "PCIE_SCC_B_TO_COMP_B_7_DN")
	)
	(arc
		(start 279.173686 -161.646108)
		(mid 279.334943 -161.678184)
		(end 279.471628 -161.769552)
		(width 0.1651)
		(layer "B.Cu")
		(net "PCIE_SCC_B_TO_COMP_B_7_DN")
	)
	(arc
		(start 279.545542 -161.917126)
		(mid 279.554584 -162.043125)
		(end 279.471882 -162.138614)
		(width 0.1651)
		(layer "B.Cu")
		(net "PCIE_SCC_B_TO_COMP_B_7_DN")
	)
	(arc
		(start 222.600012 -406.36952)
		(mid 222.567194 -406.474686)
		(end 222.480378 -406.542494)
		(width 0.1651)
		(layer "B.Cu")
		(net "PCIE_SCC_B_TO_COMP_B_7_DN")
	)
	(arc
		(start 221.898972 -406.489408)
		(mid 221.859818 -406.426818)
		(end 221.84614 -406.35428)
		(width 0.1651)
		(layer "B.Cu")
		(net "PCIE_SCC_B_TO_COMP_B_7_DN")
	)
	(segment
		(start 273.152362 -161.520124)
		(end 278.3332 -157.354016)
		(width 0.1651)
		(layer "B.Cu")
		(net "PCIE_SCC_B_TO_COMP_B_6_DP")
	)
	(segment
		(start 262.260334 -179.556664)
		(end 262.260588 -179.555902)
		(width 0.1651)
		(layer "B.Cu")
		(net "PCIE_SCC_B_TO_COMP_B_6_DP")
	)
	(segment
		(start 220.800168 -408.399996)
		(end 220.800168 -408.03068)
		(width 0.1651)
		(layer "B.Cu")
		(net "PCIE_SCC_B_TO_COMP_B_6_DP")
	)
	(segment
		(start 262.980424 -177.183542)
		(end 273.152362 -161.520124)
		(width 0.1651)
		(layer "B.Cu")
		(net "PCIE_SCC_B_TO_COMP_B_6_DP")
	)
	(segment
		(start 220.61551 -407.846022)
		(end 220.24594 -407.846022)
		(width 0.1651)
		(layer "B.Cu")
		(net "PCIE_SCC_B_TO_COMP_B_6_DP")
	)
	(segment
		(start 219.754196 -407.354278)
		(end 219.754196 -404.209504)
		(width 0.1651)
		(layer "B.Cu")
		(net "PCIE_SCC_B_TO_COMP_B_6_DP")
	)
	(segment
		(start 280.02865 -157.860746)
		(end 280.75001 -157.499812)
		(width 0.1651)
		(layer "B.Cu")
		(net "PCIE_SCC_B_TO_COMP_B_6_DP")
	)
	(segment
		(start 262.824976 -177.69586)
		(end 262.980424 -177.183542)
		(width 0.1651)
		(layer "B.Cu")
		(net "PCIE_SCC_B_TO_COMP_B_6_DP")
	)
	(segment
		(start 214.291672 -351.524316)
		(end 212.495892 -343.577418)
		(width 0.1651)
		(layer "B.Cu")
		(net "PCIE_SCC_B_TO_COMP_B_6_DP")
	)
	(segment
		(start 262.824722 -177.696622)
		(end 262.824976 -177.69586)
		(width 0.1651)
		(layer "B.Cu")
		(net "PCIE_SCC_B_TO_COMP_B_6_DP")
	)
	(segment
		(start 212.495892 -343.577418)
		(end 262.260334 -179.556664)
		(width 0.1651)
		(layer "B.Cu")
		(net "PCIE_SCC_B_TO_COMP_B_6_DP")
	)
	(segment
		(start 219.89161 -388.743698)
		(end 212.894672 -357.830882)
		(width 0.1651)
		(layer "B.Cu")
		(net "PCIE_SCC_B_TO_COMP_B_6_DP")
	)
	(segment
		(start 262.260588 -179.555902)
		(end 262.824722 -177.696622)
		(width 0.1651)
		(layer "B.Cu")
		(net "PCIE_SCC_B_TO_COMP_B_6_DP")
	)
	(segment
		(start 278.3332 -157.354016)
		(end 279.17394 -157.354016)
		(width 0.1651)
		(layer "B.Cu")
		(net "PCIE_SCC_B_TO_COMP_B_6_DP")
	)
	(segment
		(start 279.714452 -157.60192)
		(end 279.764744 -157.701996)
		(width 0.1651)
		(layer "B.Cu")
		(net "PCIE_SCC_B_TO_COMP_B_6_DP")
	)
	(segment
		(start 212.894672 -357.830882)
		(end 214.291672 -351.524316)
		(width 0.1651)
		(layer "B.Cu")
		(net "PCIE_SCC_B_TO_COMP_B_6_DP")
	)
	(segment
		(start 218.078812 -396.923768)
		(end 219.89161 -388.743698)
		(width 0.1651)
		(layer "B.Cu")
		(net "PCIE_SCC_B_TO_COMP_B_6_DP")
	)
	(segment
		(start 279.764744 -157.701996)
		(end 279.807162 -157.786832)
		(width 0.1651)
		(layer "B.Cu")
		(net "PCIE_SCC_B_TO_COMP_B_6_DP")
	)
	(segment
		(start 219.754196 -404.209504)
		(end 218.078812 -396.923768)
		(width 0.1651)
		(layer "B.Cu")
		(net "PCIE_SCC_B_TO_COMP_B_6_DP")
	)
	(arc
		(start 220.24594 -407.846022)
		(mid 220.048435 -407.804592)
		(end 219.884244 -407.687272)
		(width 0.1651)
		(layer "B.Cu")
		(net "PCIE_SCC_B_TO_COMP_B_6_DP")
	)
	(arc
		(start 220.800168 -408.03068)
		(mid 220.746083 -407.900107)
		(end 220.61551 -407.846022)
		(width 0.1651)
		(layer "B.Cu")
		(net "PCIE_SCC_B_TO_COMP_B_6_DP")
	)
	(arc
		(start 279.807162 -157.786832)
		(mid 279.902579 -157.869644)
		(end 280.02865 -157.860746)
		(width 0.1651)
		(layer "B.Cu")
		(net "PCIE_SCC_B_TO_COMP_B_6_DP")
	)
	(arc
		(start 279.17394 -157.354016)
		(mid 279.471223 -157.419016)
		(end 279.714452 -157.60192)
		(width 0.1651)
		(layer "B.Cu")
		(net "PCIE_SCC_B_TO_COMP_B_6_DP")
	)
	(arc
		(start 219.884244 -407.687272)
		(mid 219.787857 -407.533017)
		(end 219.754196 -407.354278)
		(width 0.1651)
		(layer "B.Cu")
		(net "PCIE_SCC_B_TO_COMP_B_6_DP")
	)
	(segment
		(start 276.250908 -159.563308)
		(end 276.269958 -159.388302)
		(width 0.1651)
		(layer "B.Cu")
		(net "PCIE_SCC_B_TO_COMP_B_6_DN")
	)
	(segment
		(start 272.708116 -162.741102)
		(end 272.866104 -162.70732)
		(width 0.1651)
		(layer "B.Cu")
		(net "PCIE_SCC_B_TO_COMP_B_6_DN")
	)
	(segment
		(start 263.036812 -178.398424)
		(end 263.180576 -177.92446)
		(width 0.1651)
		(layer "B.Cu")
		(net "PCIE_SCC_B_TO_COMP_B_6_DN")
	)
	(segment
		(start 271.37995 -164.786056)
		(end 271.538192 -164.752528)
		(width 0.1651)
		(layer "B.Cu")
		(net "PCIE_SCC_B_TO_COMP_B_6_DN")
	)
	(segment
		(start 272.043906 -163.763452)
		(end 272.202148 -163.729924)
		(width 0.1651)
		(layer "B.Cu")
		(net "PCIE_SCC_B_TO_COMP_B_6_DN")
	)
	(segment
		(start 275.284946 -160.34004)
		(end 275.303996 -160.165034)
		(width 0.1651)
		(layer "B.Cu")
		(net "PCIE_SCC_B_TO_COMP_B_6_DN")
	)
	(segment
		(start 272.438368 -163.156392)
		(end 272.708116 -162.741102)
		(width 0.1651)
		(layer "B.Cu")
		(net "PCIE_SCC_B_TO_COMP_B_6_DN")
	)
	(segment
		(start 214.591138 -351.523554)
		(end 212.797898 -343.58834)
		(width 0.1651)
		(layer "B.Cu")
		(net "PCIE_SCC_B_TO_COMP_B_6_DN")
	)
	(segment
		(start 272.202148 -163.729924)
		(end 272.471896 -163.314634)
		(width 0.1651)
		(layer "B.Cu")
		(net "PCIE_SCC_B_TO_COMP_B_6_DN")
	)
	(segment
		(start 275.303996 -160.165034)
		(end 275.690076 -159.854646)
		(width 0.1651)
		(layer "B.Cu")
		(net "PCIE_SCC_B_TO_COMP_B_6_DN")
	)
	(segment
		(start 271.774158 -164.178996)
		(end 272.043906 -163.763452)
		(width 0.1651)
		(layer "B.Cu")
		(net "PCIE_SCC_B_TO_COMP_B_6_DN")
	)
	(segment
		(start 262.682736 -179.5653)
		(end 262.8265 -179.091336)
		(width 0.1651)
		(layer "B.Cu")
		(net "PCIE_SCC_B_TO_COMP_B_6_DN")
	)
	(segment
		(start 273.102324 -162.133788)
		(end 273.372072 -161.718498)
		(width 0.1651)
		(layer "B.Cu")
		(net "PCIE_SCC_B_TO_COMP_B_6_DN")
	)
	(segment
		(start 278.436324 -157.646116)
		(end 279.173686 -157.646116)
		(width 0.1651)
		(layer "B.Cu")
		(net "PCIE_SCC_B_TO_COMP_B_6_DN")
	)
	(segment
		(start 262.894064 -178.474624)
		(end 263.036812 -178.398424)
		(width 0.1651)
		(layer "B.Cu")
		(net "PCIE_SCC_B_TO_COMP_B_6_DN")
	)
	(segment
		(start 274.338034 -160.941766)
		(end 274.724114 -160.631378)
		(width 0.1651)
		(layer "B.Cu")
		(net "PCIE_SCC_B_TO_COMP_B_6_DN")
	)
	(segment
		(start 263.104376 -177.781966)
		(end 263.104884 -177.780442)
		(width 0.1651)
		(layer "B.Cu")
		(net "PCIE_SCC_B_TO_COMP_B_6_DN")
	)
	(segment
		(start 265.95705 -173.13656)
		(end 266.226798 -172.721016)
		(width 0.1651)
		(layer "B.Cu")
		(net "PCIE_SCC_B_TO_COMP_B_6_DN")
	)
	(segment
		(start 220.800168 -407.000202)
		(end 220.800168 -407.369518)
		(width 0.1651)
		(layer "B.Cu")
		(net "PCIE_SCC_B_TO_COMP_B_6_DN")
	)
	(segment
		(start 266.654788 -172.272198)
		(end 266.62126 -172.113956)
		(width 0.1651)
		(layer "B.Cu")
		(net "PCIE_SCC_B_TO_COMP_B_6_DN")
	)
	(segment
		(start 273.758152 -161.40811)
		(end 273.933158 -161.42716)
		(width 0.1651)
		(layer "B.Cu")
		(net "PCIE_SCC_B_TO_COMP_B_6_DN")
	)
	(segment
		(start 213.194138 -357.83012)
		(end 214.591138 -351.523554)
		(width 0.1651)
		(layer "B.Cu")
		(net "PCIE_SCC_B_TO_COMP_B_6_DN")
	)
	(segment
		(start 274.898866 -160.650428)
		(end 275.284946 -160.34004)
		(width 0.1651)
		(layer "B.Cu")
		(net "PCIE_SCC_B_TO_COMP_B_6_DN")
	)
	(segment
		(start 271.80794 -164.336984)
		(end 271.774158 -164.178996)
		(width 0.1651)
		(layer "B.Cu")
		(net "PCIE_SCC_B_TO_COMP_B_6_DN")
	)
	(segment
		(start 265.562842 -173.74362)
		(end 265.721084 -173.710092)
		(width 0.1651)
		(layer "B.Cu")
		(net "PCIE_SCC_B_TO_COMP_B_6_DN")
	)
	(segment
		(start 220.046296 -407.354278)
		(end 220.046296 -404.17623)
		(width 0.1651)
		(layer "B.Cu")
		(net "PCIE_SCC_B_TO_COMP_B_6_DN")
	)
	(segment
		(start 263.104884 -177.780442)
		(end 263.24814 -177.308002)
		(width 0.1651)
		(layer "B.Cu")
		(net "PCIE_SCC_B_TO_COMP_B_6_DN")
	)
	(segment
		(start 267.712952 -170.642534)
		(end 267.9827 -170.22699)
		(width 0.1651)
		(layer "B.Cu")
		(net "PCIE_SCC_B_TO_COMP_B_6_DN")
	)
	(segment
		(start 275.690076 -159.854646)
		(end 275.864828 -159.873696)
		(width 0.1651)
		(layer "B.Cu")
		(net "PCIE_SCC_B_TO_COMP_B_6_DN")
	)
	(segment
		(start 273.933158 -161.42716)
		(end 274.318984 -161.116772)
		(width 0.1651)
		(layer "B.Cu")
		(net "PCIE_SCC_B_TO_COMP_B_6_DN")
	)
	(segment
		(start 274.318984 -161.116772)
		(end 274.338034 -160.941766)
		(width 0.1651)
		(layer "B.Cu")
		(net "PCIE_SCC_B_TO_COMP_B_6_DN")
	)
	(segment
		(start 266.38504 -172.687488)
		(end 266.654788 -172.272198)
		(width 0.1651)
		(layer "B.Cu")
		(net "PCIE_SCC_B_TO_COMP_B_6_DN")
	)
	(segment
		(start 267.949172 -170.069002)
		(end 270.715994 -165.808406)
		(width 0.1651)
		(layer "B.Cu")
		(net "PCIE_SCC_B_TO_COMP_B_6_DN")
	)
	(segment
		(start 220.046296 -404.17623)
		(end 218.378532 -396.922498)
		(width 0.1651)
		(layer "B.Cu")
		(net "PCIE_SCC_B_TO_COMP_B_6_DN")
	)
	(segment
		(start 212.797898 -343.58834)
		(end 262.540242 -179.641246)
		(width 0.1651)
		(layer "B.Cu")
		(net "PCIE_SCC_B_TO_COMP_B_6_DN")
	)
	(segment
		(start 270.715994 -165.808406)
		(end 270.873982 -165.774878)
		(width 0.1651)
		(layer "B.Cu")
		(net "PCIE_SCC_B_TO_COMP_B_6_DN")
	)
	(segment
		(start 275.864828 -159.873696)
		(end 276.250908 -159.563308)
		(width 0.1651)
		(layer "B.Cu")
		(net "PCIE_SCC_B_TO_COMP_B_6_DN")
	)
	(segment
		(start 271.110202 -165.201346)
		(end 271.37995 -164.786056)
		(width 0.1651)
		(layer "B.Cu")
		(net "PCIE_SCC_B_TO_COMP_B_6_DN")
	)
	(segment
		(start 267.9827 -170.22699)
		(end 267.949172 -170.069002)
		(width 0.1651)
		(layer "B.Cu")
		(net "PCIE_SCC_B_TO_COMP_B_6_DN")
	)
	(segment
		(start 271.538192 -164.752528)
		(end 271.80794 -164.336984)
		(width 0.1651)
		(layer "B.Cu")
		(net "PCIE_SCC_B_TO_COMP_B_6_DN")
	)
	(segment
		(start 262.540242 -179.641246)
		(end 262.682736 -179.5653)
		(width 0.1651)
		(layer "B.Cu")
		(net "PCIE_SCC_B_TO_COMP_B_6_DN")
	)
	(segment
		(start 262.8265 -179.091336)
		(end 262.7503 -178.948588)
		(width 0.1651)
		(layer "B.Cu")
		(net "PCIE_SCC_B_TO_COMP_B_6_DN")
	)
	(segment
		(start 267.554964 -170.676062)
		(end 267.712952 -170.642534)
		(width 0.1651)
		(layer "B.Cu")
		(net "PCIE_SCC_B_TO_COMP_B_6_DN")
	)
	(segment
		(start 270.873982 -165.774878)
		(end 271.14373 -165.359588)
		(width 0.1651)
		(layer "B.Cu")
		(net "PCIE_SCC_B_TO_COMP_B_6_DN")
	)
	(segment
		(start 273.135852 -162.29203)
		(end 273.102324 -162.133788)
		(width 0.1651)
		(layer "B.Cu")
		(net "PCIE_SCC_B_TO_COMP_B_6_DN")
	)
	(segment
		(start 267.285216 -171.091606)
		(end 267.554964 -170.676062)
		(width 0.1651)
		(layer "B.Cu")
		(net "PCIE_SCC_B_TO_COMP_B_6_DN")
	)
	(segment
		(start 262.7503 -178.948588)
		(end 262.894064 -178.474624)
		(width 0.1651)
		(layer "B.Cu")
		(net "PCIE_SCC_B_TO_COMP_B_6_DN")
	)
	(segment
		(start 266.226798 -172.721016)
		(end 266.38504 -172.687488)
		(width 0.1651)
		(layer "B.Cu")
		(net "PCIE_SCC_B_TO_COMP_B_6_DN")
	)
	(segment
		(start 263.24814 -177.308002)
		(end 265.562842 -173.74362)
		(width 0.1651)
		(layer "B.Cu")
		(net "PCIE_SCC_B_TO_COMP_B_6_DN")
	)
	(segment
		(start 274.724114 -160.631378)
		(end 274.898866 -160.650428)
		(width 0.1651)
		(layer "B.Cu")
		(net "PCIE_SCC_B_TO_COMP_B_6_DN")
	)
	(segment
		(start 266.891008 -171.698666)
		(end 267.048996 -171.664884)
		(width 0.1651)
		(layer "B.Cu")
		(net "PCIE_SCC_B_TO_COMP_B_6_DN")
	)
	(segment
		(start 265.990832 -173.294548)
		(end 265.95705 -173.13656)
		(width 0.1651)
		(layer "B.Cu")
		(net "PCIE_SCC_B_TO_COMP_B_6_DN")
	)
	(segment
		(start 220.617796 -407.553922)
		(end 220.24594 -407.553922)
		(width 0.1651)
		(layer "B.Cu")
		(net "PCIE_SCC_B_TO_COMP_B_6_DN")
	)
	(segment
		(start 218.378532 -396.922498)
		(end 220.191076 -388.742936)
		(width 0.1651)
		(layer "B.Cu")
		(net "PCIE_SCC_B_TO_COMP_B_6_DN")
	)
	(segment
		(start 220.191076 -388.742936)
		(end 213.194138 -357.83012)
		(width 0.1651)
		(layer "B.Cu")
		(net "PCIE_SCC_B_TO_COMP_B_6_DN")
	)
	(segment
		(start 276.269958 -159.388302)
		(end 278.436324 -157.646116)
		(width 0.1651)
		(layer "B.Cu")
		(net "PCIE_SCC_B_TO_COMP_B_6_DN")
	)
	(segment
		(start 266.62126 -172.113956)
		(end 266.891008 -171.698666)
		(width 0.1651)
		(layer "B.Cu")
		(net "PCIE_SCC_B_TO_COMP_B_6_DN")
	)
	(segment
		(start 272.866104 -162.70732)
		(end 273.135852 -162.29203)
		(width 0.1651)
		(layer "B.Cu")
		(net "PCIE_SCC_B_TO_COMP_B_6_DN")
	)
	(segment
		(start 279.471628 -157.76956)
		(end 279.545542 -157.91688)
		(width 0.1651)
		(layer "B.Cu")
		(net "PCIE_SCC_B_TO_COMP_B_6_DN")
	)
	(segment
		(start 267.048996 -171.664884)
		(end 267.318744 -171.249594)
		(width 0.1651)
		(layer "B.Cu")
		(net "PCIE_SCC_B_TO_COMP_B_6_DN")
	)
	(segment
		(start 273.372072 -161.718498)
		(end 273.758152 -161.40811)
		(width 0.1651)
		(layer "B.Cu")
		(net "PCIE_SCC_B_TO_COMP_B_6_DN")
	)
	(segment
		(start 263.180576 -177.92446)
		(end 263.104376 -177.781966)
		(width 0.1651)
		(layer "B.Cu")
		(net "PCIE_SCC_B_TO_COMP_B_6_DN")
	)
	(segment
		(start 272.471896 -163.314634)
		(end 272.438368 -163.156392)
		(width 0.1651)
		(layer "B.Cu")
		(net "PCIE_SCC_B_TO_COMP_B_6_DN")
	)
	(segment
		(start 279.545542 -157.91688)
		(end 279.545542 -157.917134)
		(width 0.1651)
		(layer "B.Cu")
		(net "PCIE_SCC_B_TO_COMP_B_6_DN")
	)
	(segment
		(start 271.14373 -165.359588)
		(end 271.110202 -165.201346)
		(width 0.1651)
		(layer "B.Cu")
		(net "PCIE_SCC_B_TO_COMP_B_6_DN")
	)
	(segment
		(start 279.471882 -158.138622)
		(end 278.750014 -158.49981)
		(width 0.1651)
		(layer "B.Cu")
		(net "PCIE_SCC_B_TO_COMP_B_6_DN")
	)
	(segment
		(start 265.721084 -173.710092)
		(end 265.990832 -173.294548)
		(width 0.1651)
		(layer "B.Cu")
		(net "PCIE_SCC_B_TO_COMP_B_6_DN")
	)
	(segment
		(start 267.318744 -171.249594)
		(end 267.285216 -171.091606)
		(width 0.1651)
		(layer "B.Cu")
		(net "PCIE_SCC_B_TO_COMP_B_6_DN")
	)
	(arc
		(start 220.099128 -407.489406)
		(mid 220.059974 -407.426816)
		(end 220.046296 -407.354278)
		(width 0.1651)
		(layer "B.Cu")
		(net "PCIE_SCC_B_TO_COMP_B_6_DN")
	)
	(arc
		(start 220.680534 -407.542492)
		(mid 220.649683 -407.551058)
		(end 220.617796 -407.553922)
		(width 0.1651)
		(layer "B.Cu")
		(net "PCIE_SCC_B_TO_COMP_B_6_DN")
	)
	(arc
		(start 220.800168 -407.369518)
		(mid 220.76735 -407.474684)
		(end 220.680534 -407.542492)
		(width 0.1651)
		(layer "B.Cu")
		(net "PCIE_SCC_B_TO_COMP_B_6_DN")
	)
	(arc
		(start 279.545542 -157.917134)
		(mid 279.554584 -158.043133)
		(end 279.471882 -158.138622)
		(width 0.1651)
		(layer "B.Cu")
		(net "PCIE_SCC_B_TO_COMP_B_6_DN")
	)
	(arc
		(start 279.173686 -157.646116)
		(mid 279.334943 -157.678192)
		(end 279.471628 -157.76956)
		(width 0.1651)
		(layer "B.Cu")
		(net "PCIE_SCC_B_TO_COMP_B_6_DN")
	)
	(arc
		(start 220.24594 -407.553922)
		(mid 220.165753 -407.537087)
		(end 220.099128 -407.489406)
		(width 0.1651)
		(layer "B.Cu")
		(net "PCIE_SCC_B_TO_COMP_B_6_DN")
	)
	(segment
		(start 218.815412 -406.846024)
		(end 218.445842 -406.846024)
		(width 0.1651)
		(layer "B.Cu")
		(net "PCIE_SCC_B_TO_COMP_B_5_DP")
	)
	(segment
		(start 236.200188 -259.632196)
		(end 261.57301 -176.00422)
		(width 0.1651)
		(layer "B.Cu")
		(net "PCIE_SCC_B_TO_COMP_B_5_DP")
	)
	(segment
		(start 216.315798 -397.500856)
		(end 218.160092 -389.174736)
		(width 0.1651)
		(layer "B.Cu")
		(net "PCIE_SCC_B_TO_COMP_B_5_DP")
	)
	(segment
		(start 211.915248 -354.746306)
		(end 212.652102 -351.418398)
		(width 0.1651)
		(layer "B.Cu")
		(net "PCIE_SCC_B_TO_COMP_B_5_DP")
	)
	(segment
		(start 219.00007 -407.399998)
		(end 219.00007 -407.030682)
		(width 0.1651)
		(layer "B.Cu")
		(net "PCIE_SCC_B_TO_COMP_B_5_DP")
	)
	(segment
		(start 279.714452 -153.601928)
		(end 279.764744 -153.702004)
		(width 0.1651)
		(layer "B.Cu")
		(net "PCIE_SCC_B_TO_COMP_B_5_DP")
	)
	(segment
		(start 280.02865 -153.860754)
		(end 280.75001 -153.49982)
		(width 0.1651)
		(layer "B.Cu")
		(net "PCIE_SCC_B_TO_COMP_B_5_DP")
	)
	(segment
		(start 211.150454 -358.201976)
		(end 211.915502 -354.746306)
		(width 0.1651)
		(layer "B.Cu")
		(net "PCIE_SCC_B_TO_COMP_B_5_DP")
	)
	(segment
		(start 217.954098 -406.35428)
		(end 217.954098 -404.737824)
		(width 0.1651)
		(layer "B.Cu")
		(net "PCIE_SCC_B_TO_COMP_B_5_DP")
	)
	(segment
		(start 217.954098 -404.737824)
		(end 216.315798 -397.500856)
		(width 0.1651)
		(layer "B.Cu")
		(net "PCIE_SCC_B_TO_COMP_B_5_DP")
	)
	(segment
		(start 274.03806 -156.808424)
		(end 278.3332 -153.354024)
		(width 0.1651)
		(layer "B.Cu")
		(net "PCIE_SCC_B_TO_COMP_B_5_DP")
	)
	(segment
		(start 212.652102 -351.418398)
		(end 210.816444 -343.295224)
		(width 0.1651)
		(layer "B.Cu")
		(net "PCIE_SCC_B_TO_COMP_B_5_DP")
	)
	(segment
		(start 236.199934 -259.632704)
		(end 236.200188 -259.632196)
		(width 0.1651)
		(layer "B.Cu")
		(net "PCIE_SCC_B_TO_COMP_B_5_DP")
	)
	(segment
		(start 211.915502 -354.746306)
		(end 211.915248 -354.746306)
		(width 0.1651)
		(layer "B.Cu")
		(net "PCIE_SCC_B_TO_COMP_B_5_DP")
	)
	(segment
		(start 279.764744 -153.702004)
		(end 279.807162 -153.78684)
		(width 0.1651)
		(layer "B.Cu")
		(net "PCIE_SCC_B_TO_COMP_B_5_DP")
	)
	(segment
		(start 210.816444 -343.295224)
		(end 236.199934 -259.632704)
		(width 0.1651)
		(layer "B.Cu")
		(net "PCIE_SCC_B_TO_COMP_B_5_DP")
	)
	(segment
		(start 218.160092 -389.174736)
		(end 211.150454 -358.201976)
		(width 0.1651)
		(layer "B.Cu")
		(net "PCIE_SCC_B_TO_COMP_B_5_DP")
	)
	(segment
		(start 261.57301 -176.00422)
		(end 274.03806 -156.808424)
		(width 0.1651)
		(layer "B.Cu")
		(net "PCIE_SCC_B_TO_COMP_B_5_DP")
	)
	(segment
		(start 278.3332 -153.354024)
		(end 279.17394 -153.354024)
		(width 0.1651)
		(layer "B.Cu")
		(net "PCIE_SCC_B_TO_COMP_B_5_DP")
	)
	(arc
		(start 279.17394 -153.354024)
		(mid 279.471223 -153.419024)
		(end 279.714452 -153.601928)
		(width 0.1651)
		(layer "B.Cu")
		(net "PCIE_SCC_B_TO_COMP_B_5_DP")
	)
	(arc
		(start 279.807162 -153.78684)
		(mid 279.902579 -153.869652)
		(end 280.02865 -153.860754)
		(width 0.1651)
		(layer "B.Cu")
		(net "PCIE_SCC_B_TO_COMP_B_5_DP")
	)
	(arc
		(start 218.445842 -406.846024)
		(mid 218.098126 -406.701996)
		(end 217.954098 -406.35428)
		(width 0.1651)
		(layer "B.Cu")
		(net "PCIE_SCC_B_TO_COMP_B_5_DP")
	)
	(arc
		(start 219.00007 -407.030682)
		(mid 218.945985 -406.900109)
		(end 218.815412 -406.846024)
		(width 0.1651)
		(layer "B.Cu")
		(net "PCIE_SCC_B_TO_COMP_B_5_DP")
	)
	(segment
		(start 268.868906 -165.515544)
		(end 268.835124 -165.357556)
		(width 0.1651)
		(layer "B.Cu")
		(net "PCIE_SCC_B_TO_COMP_B_5_DN")
	)
	(segment
		(start 271.996154 -160.4899)
		(end 272.265902 -160.074356)
		(width 0.1651)
		(layer "B.Cu")
		(net "PCIE_SCC_B_TO_COMP_B_5_DN")
	)
	(segment
		(start 275.609558 -155.919424)
		(end 275.784564 -155.938474)
		(width 0.1651)
		(layer "B.Cu")
		(net "PCIE_SCC_B_TO_COMP_B_5_DN")
	)
	(segment
		(start 272.693638 -159.625284)
		(end 272.66011 -159.467296)
		(width 0.1651)
		(layer "B.Cu")
		(net "PCIE_SCC_B_TO_COMP_B_5_DN")
	)
	(segment
		(start 268.599158 -165.931088)
		(end 268.868906 -165.515544)
		(width 0.1651)
		(layer "B.Cu")
		(net "PCIE_SCC_B_TO_COMP_B_5_DN")
	)
	(segment
		(start 267.935202 -166.953438)
		(end 268.20495 -166.538148)
		(width 0.1651)
		(layer "B.Cu")
		(net "PCIE_SCC_B_TO_COMP_B_5_DN")
	)
	(segment
		(start 212.951568 -351.417636)
		(end 211.11845 -343.306146)
		(width 0.1651)
		(layer "B.Cu")
		(net "PCIE_SCC_B_TO_COMP_B_5_DN")
	)
	(segment
		(start 267.507212 -167.40251)
		(end 267.77696 -166.98722)
		(width 0.1651)
		(layer "B.Cu")
		(net "PCIE_SCC_B_TO_COMP_B_5_DN")
	)
	(segment
		(start 273.357594 -158.602934)
		(end 273.324066 -158.444692)
		(width 0.1651)
		(layer "B.Cu")
		(net "PCIE_SCC_B_TO_COMP_B_5_DN")
	)
	(segment
		(start 267.54074 -167.560752)
		(end 267.507212 -167.40251)
		(width 0.1651)
		(layer "B.Cu")
		(net "PCIE_SCC_B_TO_COMP_B_5_DN")
	)
	(segment
		(start 276.57552 -155.142692)
		(end 276.750526 -155.161742)
		(width 0.1651)
		(layer "B.Cu")
		(net "PCIE_SCC_B_TO_COMP_B_5_DN")
	)
	(segment
		(start 211.44992 -358.201214)
		(end 212.951568 -351.417636)
		(width 0.1651)
		(layer "B.Cu")
		(net "PCIE_SCC_B_TO_COMP_B_5_DN")
	)
	(segment
		(start 218.246198 -406.35428)
		(end 218.246198 -404.705058)
		(width 0.1651)
		(layer "B.Cu")
		(net "PCIE_SCC_B_TO_COMP_B_5_DN")
	)
	(segment
		(start 274.818602 -156.71546)
		(end 275.204682 -156.404818)
		(width 0.1651)
		(layer "B.Cu")
		(net "PCIE_SCC_B_TO_COMP_B_5_DN")
	)
	(segment
		(start 236.479588 -259.71754)
		(end 236.479842 -259.716778)
		(width 0.1651)
		(layer "B.Cu")
		(net "PCIE_SCC_B_TO_COMP_B_5_DN")
	)
	(segment
		(start 273.593814 -158.029402)
		(end 273.751802 -157.99562)
		(width 0.1651)
		(layer "B.Cu")
		(net "PCIE_SCC_B_TO_COMP_B_5_DN")
	)
	(segment
		(start 274.64385 -156.69641)
		(end 274.818602 -156.71546)
		(width 0.1651)
		(layer "B.Cu")
		(net "PCIE_SCC_B_TO_COMP_B_5_DN")
	)
	(segment
		(start 277.136352 -154.851354)
		(end 277.155402 -154.676348)
		(width 0.1651)
		(layer "B.Cu")
		(net "PCIE_SCC_B_TO_COMP_B_5_DN")
	)
	(segment
		(start 276.750526 -155.161742)
		(end 277.136352 -154.851354)
		(width 0.1651)
		(layer "B.Cu")
		(net "PCIE_SCC_B_TO_COMP_B_5_DN")
	)
	(segment
		(start 271.759934 -161.063432)
		(end 272.029682 -160.647888)
		(width 0.1651)
		(layer "B.Cu")
		(net "PCIE_SCC_B_TO_COMP_B_5_DN")
	)
	(segment
		(start 218.459558 -389.173974)
		(end 211.44992 -358.201214)
		(width 0.1651)
		(layer "B.Cu")
		(net "PCIE_SCC_B_TO_COMP_B_5_DN")
	)
	(segment
		(start 263.01827 -174.315374)
		(end 263.288018 -173.89983)
		(width 0.1651)
		(layer "B.Cu")
		(net "PCIE_SCC_B_TO_COMP_B_5_DN")
	)
	(segment
		(start 261.840726 -176.12868)
		(end 262.624062 -174.922434)
		(width 0.1651)
		(layer "B.Cu")
		(net "PCIE_SCC_B_TO_COMP_B_5_DN")
	)
	(segment
		(start 268.20495 -166.538148)
		(end 268.171168 -166.379906)
		(width 0.1651)
		(layer "B.Cu")
		(net "PCIE_SCC_B_TO_COMP_B_5_DN")
	)
	(segment
		(start 275.784564 -155.938474)
		(end 276.170644 -155.628086)
		(width 0.1651)
		(layer "B.Cu")
		(net "PCIE_SCC_B_TO_COMP_B_5_DN")
	)
	(segment
		(start 276.18944 -155.45308)
		(end 276.57552 -155.142692)
		(width 0.1651)
		(layer "B.Cu")
		(net "PCIE_SCC_B_TO_COMP_B_5_DN")
	)
	(segment
		(start 263.716008 -173.450758)
		(end 263.68248 -173.29277)
		(width 0.1651)
		(layer "B.Cu")
		(net "PCIE_SCC_B_TO_COMP_B_5_DN")
	)
	(segment
		(start 218.246198 -404.705058)
		(end 216.615264 -397.500094)
		(width 0.1651)
		(layer "B.Cu")
		(net "PCIE_SCC_B_TO_COMP_B_5_DN")
	)
	(segment
		(start 263.44626 -173.866302)
		(end 263.716008 -173.450758)
		(width 0.1651)
		(layer "B.Cu")
		(net "PCIE_SCC_B_TO_COMP_B_5_DN")
	)
	(segment
		(start 272.265902 -160.074356)
		(end 272.42389 -160.040828)
		(width 0.1651)
		(layer "B.Cu")
		(net "PCIE_SCC_B_TO_COMP_B_5_DN")
	)
	(segment
		(start 279.471882 -154.13863)
		(end 278.750014 -154.499818)
		(width 0.1651)
		(layer "B.Cu")
		(net "PCIE_SCC_B_TO_COMP_B_5_DN")
	)
	(segment
		(start 272.929858 -159.051752)
		(end 273.087846 -159.018224)
		(width 0.1651)
		(layer "B.Cu")
		(net "PCIE_SCC_B_TO_COMP_B_5_DN")
	)
	(segment
		(start 272.42389 -160.040828)
		(end 272.693638 -159.625284)
		(width 0.1651)
		(layer "B.Cu")
		(net "PCIE_SCC_B_TO_COMP_B_5_DN")
	)
	(segment
		(start 273.751802 -157.99562)
		(end 274.02155 -157.58033)
		(width 0.1651)
		(layer "B.Cu")
		(net "PCIE_SCC_B_TO_COMP_B_5_DN")
	)
	(segment
		(start 263.68248 -173.29277)
		(end 266.449048 -169.032174)
		(width 0.1651)
		(layer "B.Cu")
		(net "PCIE_SCC_B_TO_COMP_B_5_DN")
	)
	(segment
		(start 268.171168 -166.379906)
		(end 268.440916 -165.964616)
		(width 0.1651)
		(layer "B.Cu")
		(net "PCIE_SCC_B_TO_COMP_B_5_DN")
	)
	(segment
		(start 279.471628 -153.769568)
		(end 279.545542 -153.916888)
		(width 0.1651)
		(layer "B.Cu")
		(net "PCIE_SCC_B_TO_COMP_B_5_DN")
	)
	(segment
		(start 263.052052 -174.473362)
		(end 263.01827 -174.315374)
		(width 0.1651)
		(layer "B.Cu")
		(net "PCIE_SCC_B_TO_COMP_B_5_DN")
	)
	(segment
		(start 266.449048 -169.032174)
		(end 266.607036 -168.998646)
		(width 0.1651)
		(layer "B.Cu")
		(net "PCIE_SCC_B_TO_COMP_B_5_DN")
	)
	(segment
		(start 272.029682 -160.647888)
		(end 271.996154 -160.4899)
		(width 0.1651)
		(layer "B.Cu")
		(net "PCIE_SCC_B_TO_COMP_B_5_DN")
	)
	(segment
		(start 267.270992 -167.976042)
		(end 267.54074 -167.560752)
		(width 0.1651)
		(layer "B.Cu")
		(net "PCIE_SCC_B_TO_COMP_B_5_DN")
	)
	(segment
		(start 274.25777 -157.006798)
		(end 274.64385 -156.69641)
		(width 0.1651)
		(layer "B.Cu")
		(net "PCIE_SCC_B_TO_COMP_B_5_DN")
	)
	(segment
		(start 216.615264 -397.500094)
		(end 218.459558 -389.173974)
		(width 0.1651)
		(layer "B.Cu")
		(net "PCIE_SCC_B_TO_COMP_B_5_DN")
	)
	(segment
		(start 266.607036 -168.998646)
		(end 266.876784 -168.583102)
		(width 0.1651)
		(layer "B.Cu")
		(net "PCIE_SCC_B_TO_COMP_B_5_DN")
	)
	(segment
		(start 218.817698 -406.553924)
		(end 218.445842 -406.553924)
		(width 0.1651)
		(layer "B.Cu")
		(net "PCIE_SCC_B_TO_COMP_B_5_DN")
	)
	(segment
		(start 262.624062 -174.922434)
		(end 262.782304 -174.888652)
		(width 0.1651)
		(layer "B.Cu")
		(net "PCIE_SCC_B_TO_COMP_B_5_DN")
	)
	(segment
		(start 273.988022 -157.422088)
		(end 274.25777 -157.006798)
		(width 0.1651)
		(layer "B.Cu")
		(net "PCIE_SCC_B_TO_COMP_B_5_DN")
	)
	(segment
		(start 278.436324 -153.646124)
		(end 279.173686 -153.646124)
		(width 0.1651)
		(layer "B.Cu")
		(net "PCIE_SCC_B_TO_COMP_B_5_DN")
	)
	(segment
		(start 273.324066 -158.444692)
		(end 273.593814 -158.029402)
		(width 0.1651)
		(layer "B.Cu")
		(net "PCIE_SCC_B_TO_COMP_B_5_DN")
	)
	(segment
		(start 279.545542 -153.916888)
		(end 279.545542 -153.917142)
		(width 0.1651)
		(layer "B.Cu")
		(net "PCIE_SCC_B_TO_COMP_B_5_DN")
	)
	(segment
		(start 263.288018 -173.89983)
		(end 263.44626 -173.866302)
		(width 0.1651)
		(layer "B.Cu")
		(net "PCIE_SCC_B_TO_COMP_B_5_DN")
	)
	(segment
		(start 271.601692 -161.09696)
		(end 271.759934 -161.063432)
		(width 0.1651)
		(layer "B.Cu")
		(net "PCIE_SCC_B_TO_COMP_B_5_DN")
	)
	(segment
		(start 267.77696 -166.98722)
		(end 267.935202 -166.953438)
		(width 0.1651)
		(layer "B.Cu")
		(net "PCIE_SCC_B_TO_COMP_B_5_DN")
	)
	(segment
		(start 277.155402 -154.676348)
		(end 278.436324 -153.646124)
		(width 0.1651)
		(layer "B.Cu")
		(net "PCIE_SCC_B_TO_COMP_B_5_DN")
	)
	(segment
		(start 268.440916 -165.964616)
		(end 268.599158 -165.931088)
		(width 0.1651)
		(layer "B.Cu")
		(net "PCIE_SCC_B_TO_COMP_B_5_DN")
	)
	(segment
		(start 275.223732 -156.230066)
		(end 275.609558 -155.919424)
		(width 0.1651)
		(layer "B.Cu")
		(net "PCIE_SCC_B_TO_COMP_B_5_DN")
	)
	(segment
		(start 236.479842 -259.716778)
		(end 261.840726 -176.12868)
		(width 0.1651)
		(layer "B.Cu")
		(net "PCIE_SCC_B_TO_COMP_B_5_DN")
	)
	(segment
		(start 276.170644 -155.628086)
		(end 276.18944 -155.45308)
		(width 0.1651)
		(layer "B.Cu")
		(net "PCIE_SCC_B_TO_COMP_B_5_DN")
	)
	(segment
		(start 211.11845 -343.306146)
		(end 236.479588 -259.71754)
		(width 0.1651)
		(layer "B.Cu")
		(net "PCIE_SCC_B_TO_COMP_B_5_DN")
	)
	(segment
		(start 267.113004 -168.00957)
		(end 267.270992 -167.976042)
		(width 0.1651)
		(layer "B.Cu")
		(net "PCIE_SCC_B_TO_COMP_B_5_DN")
	)
	(segment
		(start 262.782304 -174.888652)
		(end 263.052052 -174.473362)
		(width 0.1651)
		(layer "B.Cu")
		(net "PCIE_SCC_B_TO_COMP_B_5_DN")
	)
	(segment
		(start 273.087846 -159.018224)
		(end 273.357594 -158.602934)
		(width 0.1651)
		(layer "B.Cu")
		(net "PCIE_SCC_B_TO_COMP_B_5_DN")
	)
	(segment
		(start 274.02155 -157.58033)
		(end 273.988022 -157.422088)
		(width 0.1651)
		(layer "B.Cu")
		(net "PCIE_SCC_B_TO_COMP_B_5_DN")
	)
	(segment
		(start 266.876784 -168.583102)
		(end 266.843256 -168.425114)
		(width 0.1651)
		(layer "B.Cu")
		(net "PCIE_SCC_B_TO_COMP_B_5_DN")
	)
	(segment
		(start 219.00007 -405.99995)
		(end 219.00007 -406.36952)
		(width 0.1651)
		(layer "B.Cu")
		(net "PCIE_SCC_B_TO_COMP_B_5_DN")
	)
	(segment
		(start 275.204682 -156.404818)
		(end 275.223732 -156.230066)
		(width 0.1651)
		(layer "B.Cu")
		(net "PCIE_SCC_B_TO_COMP_B_5_DN")
	)
	(segment
		(start 266.843256 -168.425114)
		(end 267.113004 -168.00957)
		(width 0.1651)
		(layer "B.Cu")
		(net "PCIE_SCC_B_TO_COMP_B_5_DN")
	)
	(segment
		(start 268.835124 -165.357556)
		(end 271.601692 -161.09696)
		(width 0.1651)
		(layer "B.Cu")
		(net "PCIE_SCC_B_TO_COMP_B_5_DN")
	)
	(segment
		(start 272.66011 -159.467296)
		(end 272.929858 -159.051752)
		(width 0.1651)
		(layer "B.Cu")
		(net "PCIE_SCC_B_TO_COMP_B_5_DN")
	)
	(arc
		(start 218.880436 -406.542494)
		(mid 218.849585 -406.55106)
		(end 218.817698 -406.553924)
		(width 0.1651)
		(layer "B.Cu")
		(net "PCIE_SCC_B_TO_COMP_B_5_DN")
	)
	(arc
		(start 218.445842 -406.553924)
		(mid 218.365655 -406.537089)
		(end 218.29903 -406.489408)
		(width 0.1651)
		(layer "B.Cu")
		(net "PCIE_SCC_B_TO_COMP_B_5_DN")
	)
	(arc
		(start 279.545542 -153.917142)
		(mid 279.554584 -154.043141)
		(end 279.471882 -154.13863)
		(width 0.1651)
		(layer "B.Cu")
		(net "PCIE_SCC_B_TO_COMP_B_5_DN")
	)
	(arc
		(start 279.173686 -153.646124)
		(mid 279.334943 -153.6782)
		(end 279.471628 -153.769568)
		(width 0.1651)
		(layer "B.Cu")
		(net "PCIE_SCC_B_TO_COMP_B_5_DN")
	)
	(arc
		(start 218.29903 -406.489408)
		(mid 218.259876 -406.426818)
		(end 218.246198 -406.35428)
		(width 0.1651)
		(layer "B.Cu")
		(net "PCIE_SCC_B_TO_COMP_B_5_DN")
	)
	(arc
		(start 219.00007 -406.36952)
		(mid 218.967252 -406.474686)
		(end 218.880436 -406.542494)
		(width 0.1651)
		(layer "B.Cu")
		(net "PCIE_SCC_B_TO_COMP_B_5_DN")
	)
	(segment
		(start 209.466942 -358.431592)
		(end 211.02574 -351.392998)
		(width 0.1651)
		(layer "B.Cu")
		(net "PCIE_SCC_B_TO_COMP_B_4_DP")
	)
	(segment
		(start 216.154 -404.602442)
		(end 213.835488 -394.350494)
		(width 0.1651)
		(layer "B.Cu")
		(net "PCIE_SCC_B_TO_COMP_B_4_DP")
	)
	(segment
		(start 211.02574 -351.392998)
		(end 209.185002 -343.246964)
		(width 0.1651)
		(layer "B.Cu")
		(net "PCIE_SCC_B_TO_COMP_B_4_DP")
	)
	(segment
		(start 234.749086 -258.893564)
		(end 260.302756 -174.574454)
		(width 0.1651)
		(layer "B.Cu")
		(net "PCIE_SCC_B_TO_COMP_B_4_DP")
	)
	(segment
		(start 217.199972 -408.399996)
		(end 217.199972 -408.03068)
		(width 0.1651)
		(layer "B.Cu")
		(net "PCIE_SCC_B_TO_COMP_B_4_DP")
	)
	(segment
		(start 279.764744 -149.702012)
		(end 279.807162 -149.786848)
		(width 0.1651)
		(layer "B.Cu")
		(net "PCIE_SCC_B_TO_COMP_B_4_DP")
	)
	(segment
		(start 209.185002 -343.246964)
		(end 234.749086 -258.893818)
		(width 0.1651)
		(layer "B.Cu")
		(net "PCIE_SCC_B_TO_COMP_B_4_DP")
	)
	(segment
		(start 217.015314 -407.846022)
		(end 216.645744 -407.846022)
		(width 0.1651)
		(layer "B.Cu")
		(net "PCIE_SCC_B_TO_COMP_B_4_DP")
	)
	(segment
		(start 234.749086 -258.893818)
		(end 234.749086 -258.893564)
		(width 0.1651)
		(layer "B.Cu")
		(net "PCIE_SCC_B_TO_COMP_B_4_DP")
	)
	(segment
		(start 280.02865 -149.860762)
		(end 280.75001 -149.499828)
		(width 0.1651)
		(layer "B.Cu")
		(net "PCIE_SCC_B_TO_COMP_B_4_DP")
	)
	(segment
		(start 260.302756 -174.574454)
		(end 275.115782 -151.762968)
		(width 0.1651)
		(layer "B.Cu")
		(net "PCIE_SCC_B_TO_COMP_B_4_DP")
	)
	(segment
		(start 216.154 -407.354278)
		(end 216.154 -404.602442)
		(width 0.1651)
		(layer "B.Cu")
		(net "PCIE_SCC_B_TO_COMP_B_4_DP")
	)
	(segment
		(start 278.11095 -149.354032)
		(end 279.17394 -149.354032)
		(width 0.1651)
		(layer "B.Cu")
		(net "PCIE_SCC_B_TO_COMP_B_4_DP")
	)
	(segment
		(start 275.115782 -151.762968)
		(end 278.11095 -149.354032)
		(width 0.1651)
		(layer "B.Cu")
		(net "PCIE_SCC_B_TO_COMP_B_4_DP")
	)
	(segment
		(start 279.714452 -149.601936)
		(end 279.764744 -149.702012)
		(width 0.1651)
		(layer "B.Cu")
		(net "PCIE_SCC_B_TO_COMP_B_4_DP")
	)
	(segment
		(start 215.697816 -385.941824)
		(end 209.466942 -358.431592)
		(width 0.1651)
		(layer "B.Cu")
		(net "PCIE_SCC_B_TO_COMP_B_4_DP")
	)
	(segment
		(start 213.835488 -394.350494)
		(end 215.697816 -385.941824)
		(width 0.1651)
		(layer "B.Cu")
		(net "PCIE_SCC_B_TO_COMP_B_4_DP")
	)
	(arc
		(start 217.199972 -408.03068)
		(mid 217.145887 -407.900107)
		(end 217.015314 -407.846022)
		(width 0.1651)
		(layer "B.Cu")
		(net "PCIE_SCC_B_TO_COMP_B_4_DP")
	)
	(arc
		(start 216.284048 -407.687272)
		(mid 216.187661 -407.533017)
		(end 216.154 -407.354278)
		(width 0.1651)
		(layer "B.Cu")
		(net "PCIE_SCC_B_TO_COMP_B_4_DP")
	)
	(arc
		(start 216.645744 -407.846022)
		(mid 216.448239 -407.804592)
		(end 216.284048 -407.687272)
		(width 0.1651)
		(layer "B.Cu")
		(net "PCIE_SCC_B_TO_COMP_B_4_DP")
	)
	(arc
		(start 279.807162 -149.786848)
		(mid 279.902579 -149.86966)
		(end 280.02865 -149.860762)
		(width 0.1651)
		(layer "B.Cu")
		(net "PCIE_SCC_B_TO_COMP_B_4_DP")
	)
	(arc
		(start 279.17394 -149.354032)
		(mid 279.471223 -149.419032)
		(end 279.714452 -149.601936)
		(width 0.1651)
		(layer "B.Cu")
		(net "PCIE_SCC_B_TO_COMP_B_4_DP")
	)
	(segment
		(start 263.860026 -169.843196)
		(end 264.129774 -169.427906)
		(width 0.1651)
		(layer "B.Cu")
		(net "PCIE_SCC_B_TO_COMP_B_4_DN")
	)
	(segment
		(start 260.570472 -174.698914)
		(end 262.373872 -171.921932)
		(width 0.1651)
		(layer "B.Cu")
		(net "PCIE_SCC_B_TO_COMP_B_4_DN")
	)
	(segment
		(start 217.0176 -407.553922)
		(end 216.645744 -407.553922)
		(width 0.1651)
		(layer "B.Cu")
		(net "PCIE_SCC_B_TO_COMP_B_4_DN")
	)
	(segment
		(start 264.523982 -168.820846)
		(end 264.79373 -168.405302)
		(width 0.1651)
		(layer "B.Cu")
		(net "PCIE_SCC_B_TO_COMP_B_4_DN")
	)
	(segment
		(start 276.26818 -151.357838)
		(end 276.285452 -151.19731)
		(width 0.1651)
		(layer "B.Cu")
		(net "PCIE_SCC_B_TO_COMP_B_4_DN")
	)
	(segment
		(start 269.282672 -161.492692)
		(end 269.24889 -161.33445)
		(width 0.1651)
		(layer "B.Cu")
		(net "PCIE_SCC_B_TO_COMP_B_4_DN")
	)
	(segment
		(start 274.765262 -153.06802)
		(end 275.03501 -152.652476)
		(width 0.1651)
		(layer "B.Cu")
		(net "PCIE_SCC_B_TO_COMP_B_4_DN")
	)
	(segment
		(start 268.618462 -162.515296)
		(end 268.584934 -162.357054)
		(width 0.1651)
		(layer "B.Cu")
		(net "PCIE_SCC_B_TO_COMP_B_4_DN")
	)
	(segment
		(start 267.920978 -163.379658)
		(end 268.190726 -162.964114)
		(width 0.1651)
		(layer "B.Cu")
		(net "PCIE_SCC_B_TO_COMP_B_4_DN")
	)
	(segment
		(start 268.584934 -162.357054)
		(end 268.854682 -161.941764)
		(width 0.1651)
		(layer "B.Cu")
		(net "PCIE_SCC_B_TO_COMP_B_4_DN")
	)
	(segment
		(start 263.432036 -170.292268)
		(end 263.701784 -169.876978)
		(width 0.1651)
		(layer "B.Cu")
		(net "PCIE_SCC_B_TO_COMP_B_4_DN")
	)
	(segment
		(start 264.79373 -168.405302)
		(end 264.760202 -168.247314)
		(width 0.1651)
		(layer "B.Cu")
		(net "PCIE_SCC_B_TO_COMP_B_4_DN")
	)
	(segment
		(start 273.24304 -155.183586)
		(end 273.415252 -155.14701)
		(width 0.1651)
		(layer "B.Cu")
		(net "PCIE_SCC_B_TO_COMP_B_4_DN")
	)
	(segment
		(start 274.09013 -154.107642)
		(end 274.359878 -153.692098)
		(width 0.1651)
		(layer "B.Cu")
		(net "PCIE_SCC_B_TO_COMP_B_4_DN")
	)
	(segment
		(start 264.095992 -169.269918)
		(end 264.36574 -168.854374)
		(width 0.1651)
		(layer "B.Cu")
		(net "PCIE_SCC_B_TO_COMP_B_4_DN")
	)
	(segment
		(start 214.134954 -394.349732)
		(end 215.997282 -385.941062)
		(width 0.1651)
		(layer "B.Cu")
		(net "PCIE_SCC_B_TO_COMP_B_4_DN")
	)
	(segment
		(start 273.918172 -154.144218)
		(end 274.09013 -154.107642)
		(width 0.1651)
		(layer "B.Cu")
		(net "PCIE_SCC_B_TO_COMP_B_4_DN")
	)
	(segment
		(start 269.946628 -160.470088)
		(end 269.912846 -160.3121)
		(width 0.1651)
		(layer "B.Cu")
		(net "PCIE_SCC_B_TO_COMP_B_4_DN")
	)
	(segment
		(start 275.721572 -151.650954)
		(end 275.8821 -151.66848)
		(width 0.1651)
		(layer "B.Cu")
		(net "PCIE_SCC_B_TO_COMP_B_4_DN")
	)
	(segment
		(start 216.4461 -404.569676)
		(end 214.134954 -394.349732)
		(width 0.1651)
		(layer "B.Cu")
		(net "PCIE_SCC_B_TO_COMP_B_4_DN")
	)
	(segment
		(start 263.037828 -170.899582)
		(end 263.19607 -170.8658)
		(width 0.1651)
		(layer "B.Cu")
		(net "PCIE_SCC_B_TO_COMP_B_4_DN")
	)
	(segment
		(start 277.21814 -150.593806)
		(end 277.235666 -150.433024)
		(width 0.1651)
		(layer "B.Cu")
		(net "PCIE_SCC_B_TO_COMP_B_4_DN")
	)
	(segment
		(start 264.129774 -169.427906)
		(end 264.095992 -169.269918)
		(width 0.1651)
		(layer "B.Cu")
		(net "PCIE_SCC_B_TO_COMP_B_4_DN")
	)
	(segment
		(start 267.954506 -163.537646)
		(end 267.920978 -163.379658)
		(width 0.1651)
		(layer "B.Cu")
		(net "PCIE_SCC_B_TO_COMP_B_4_DN")
	)
	(segment
		(start 273.415252 -155.14701)
		(end 273.685 -154.73172)
		(width 0.1651)
		(layer "B.Cu")
		(net "PCIE_SCC_B_TO_COMP_B_4_DN")
	)
	(segment
		(start 268.190726 -162.964114)
		(end 268.348714 -162.930586)
		(width 0.1651)
		(layer "B.Cu")
		(net "PCIE_SCC_B_TO_COMP_B_4_DN")
	)
	(segment
		(start 279.471628 -149.769576)
		(end 279.545542 -149.916896)
		(width 0.1651)
		(layer "B.Cu")
		(net "PCIE_SCC_B_TO_COMP_B_4_DN")
	)
	(segment
		(start 269.67688 -160.885632)
		(end 269.946628 -160.470088)
		(width 0.1651)
		(layer "B.Cu")
		(net "PCIE_SCC_B_TO_COMP_B_4_DN")
	)
	(segment
		(start 274.998434 -152.480518)
		(end 275.335492 -151.961342)
		(width 0.1651)
		(layer "B.Cu")
		(net "PCIE_SCC_B_TO_COMP_B_4_DN")
	)
	(segment
		(start 276.671532 -150.886922)
		(end 276.832314 -150.904194)
		(width 0.1651)
		(layer "B.Cu")
		(net "PCIE_SCC_B_TO_COMP_B_4_DN")
	)
	(segment
		(start 216.4461 -407.354278)
		(end 216.4461 -404.569676)
		(width 0.1651)
		(layer "B.Cu")
		(net "PCIE_SCC_B_TO_COMP_B_4_DN")
	)
	(segment
		(start 262.76808 -171.314872)
		(end 263.037828 -170.899582)
		(width 0.1651)
		(layer "B.Cu")
		(net "PCIE_SCC_B_TO_COMP_B_4_DN")
	)
	(segment
		(start 278.214074 -149.646132)
		(end 279.173686 -149.646132)
		(width 0.1651)
		(layer "B.Cu")
		(net "PCIE_SCC_B_TO_COMP_B_4_DN")
	)
	(segment
		(start 269.012924 -161.907982)
		(end 269.282672 -161.492692)
		(width 0.1651)
		(layer "B.Cu")
		(net "PCIE_SCC_B_TO_COMP_B_4_DN")
	)
	(segment
		(start 276.285452 -151.19731)
		(end 276.671532 -150.886922)
		(width 0.1651)
		(layer "B.Cu")
		(net "PCIE_SCC_B_TO_COMP_B_4_DN")
	)
	(segment
		(start 267.52677 -163.986718)
		(end 267.684758 -163.95319)
		(width 0.1651)
		(layer "B.Cu")
		(net "PCIE_SCC_B_TO_COMP_B_4_DN")
	)
	(segment
		(start 275.03501 -152.652476)
		(end 274.998434 -152.480518)
		(width 0.1651)
		(layer "B.Cu")
		(net "PCIE_SCC_B_TO_COMP_B_4_DN")
	)
	(segment
		(start 269.24889 -161.33445)
		(end 269.518638 -160.91916)
		(width 0.1651)
		(layer "B.Cu")
		(net "PCIE_SCC_B_TO_COMP_B_4_DN")
	)
	(segment
		(start 215.997282 -385.941062)
		(end 209.766408 -358.43083)
		(width 0.1651)
		(layer "B.Cu")
		(net "PCIE_SCC_B_TO_COMP_B_4_DN")
	)
	(segment
		(start 264.36574 -168.854374)
		(end 264.523982 -168.820846)
		(width 0.1651)
		(layer "B.Cu")
		(net "PCIE_SCC_B_TO_COMP_B_4_DN")
	)
	(segment
		(start 268.348714 -162.930586)
		(end 268.618462 -162.515296)
		(width 0.1651)
		(layer "B.Cu")
		(net "PCIE_SCC_B_TO_COMP_B_4_DN")
	)
	(segment
		(start 262.532114 -171.888404)
		(end 262.801862 -171.47286)
		(width 0.1651)
		(layer "B.Cu")
		(net "PCIE_SCC_B_TO_COMP_B_4_DN")
	)
	(segment
		(start 262.373872 -171.921932)
		(end 262.532114 -171.888404)
		(width 0.1651)
		(layer "B.Cu")
		(net "PCIE_SCC_B_TO_COMP_B_4_DN")
	)
	(segment
		(start 277.235666 -150.433024)
		(end 278.214074 -149.646132)
		(width 0.1651)
		(layer "B.Cu")
		(net "PCIE_SCC_B_TO_COMP_B_4_DN")
	)
	(segment
		(start 279.471882 -150.138638)
		(end 278.750014 -150.499826)
		(width 0.1651)
		(layer "B.Cu")
		(net "PCIE_SCC_B_TO_COMP_B_4_DN")
	)
	(segment
		(start 263.465818 -170.45051)
		(end 263.432036 -170.292268)
		(width 0.1651)
		(layer "B.Cu")
		(net "PCIE_SCC_B_TO_COMP_B_4_DN")
	)
	(segment
		(start 263.701784 -169.876978)
		(end 263.860026 -169.843196)
		(width 0.1651)
		(layer "B.Cu")
		(net "PCIE_SCC_B_TO_COMP_B_4_DN")
	)
	(segment
		(start 269.912846 -160.3121)
		(end 273.24304 -155.183586)
		(width 0.1651)
		(layer "B.Cu")
		(net "PCIE_SCC_B_TO_COMP_B_4_DN")
	)
	(segment
		(start 263.19607 -170.8658)
		(end 263.465818 -170.45051)
		(width 0.1651)
		(layer "B.Cu")
		(net "PCIE_SCC_B_TO_COMP_B_4_DN")
	)
	(segment
		(start 267.684758 -163.95319)
		(end 267.954506 -163.537646)
		(width 0.1651)
		(layer "B.Cu")
		(net "PCIE_SCC_B_TO_COMP_B_4_DN")
	)
	(segment
		(start 273.648424 -154.559508)
		(end 273.918172 -154.144218)
		(width 0.1651)
		(layer "B.Cu")
		(net "PCIE_SCC_B_TO_COMP_B_4_DN")
	)
	(segment
		(start 274.323302 -153.519886)
		(end 274.59305 -153.104596)
		(width 0.1651)
		(layer "B.Cu")
		(net "PCIE_SCC_B_TO_COMP_B_4_DN")
	)
	(segment
		(start 276.832314 -150.904194)
		(end 277.21814 -150.593806)
		(width 0.1651)
		(layer "B.Cu")
		(net "PCIE_SCC_B_TO_COMP_B_4_DN")
	)
	(segment
		(start 274.359878 -153.692098)
		(end 274.323302 -153.519886)
		(width 0.1651)
		(layer "B.Cu")
		(net "PCIE_SCC_B_TO_COMP_B_4_DN")
	)
	(segment
		(start 275.335492 -151.961342)
		(end 275.721572 -151.650954)
		(width 0.1651)
		(layer "B.Cu")
		(net "PCIE_SCC_B_TO_COMP_B_4_DN")
	)
	(segment
		(start 279.545542 -149.916896)
		(end 279.545542 -149.91715)
		(width 0.1651)
		(layer "B.Cu")
		(net "PCIE_SCC_B_TO_COMP_B_4_DN")
	)
	(segment
		(start 217.199972 -407.000202)
		(end 217.199972 -407.369518)
		(width 0.1651)
		(layer "B.Cu")
		(net "PCIE_SCC_B_TO_COMP_B_4_DN")
	)
	(segment
		(start 273.685 -154.73172)
		(end 273.648424 -154.559508)
		(width 0.1651)
		(layer "B.Cu")
		(net "PCIE_SCC_B_TO_COMP_B_4_DN")
	)
	(segment
		(start 211.325206 -351.392236)
		(end 209.487008 -343.257886)
		(width 0.1651)
		(layer "B.Cu")
		(net "PCIE_SCC_B_TO_COMP_B_4_DN")
	)
	(segment
		(start 209.487008 -343.257886)
		(end 260.570472 -174.698914)
		(width 0.1651)
		(layer "B.Cu")
		(net "PCIE_SCC_B_TO_COMP_B_4_DN")
	)
	(segment
		(start 268.854682 -161.941764)
		(end 269.012924 -161.907982)
		(width 0.1651)
		(layer "B.Cu")
		(net "PCIE_SCC_B_TO_COMP_B_4_DN")
	)
	(segment
		(start 269.518638 -160.91916)
		(end 269.67688 -160.885632)
		(width 0.1651)
		(layer "B.Cu")
		(net "PCIE_SCC_B_TO_COMP_B_4_DN")
	)
	(segment
		(start 209.766408 -358.43083)
		(end 211.325206 -351.392236)
		(width 0.1651)
		(layer "B.Cu")
		(net "PCIE_SCC_B_TO_COMP_B_4_DN")
	)
	(segment
		(start 274.59305 -153.104596)
		(end 274.765262 -153.06802)
		(width 0.1651)
		(layer "B.Cu")
		(net "PCIE_SCC_B_TO_COMP_B_4_DN")
	)
	(segment
		(start 264.760202 -168.247314)
		(end 267.52677 -163.986718)
		(width 0.1651)
		(layer "B.Cu")
		(net "PCIE_SCC_B_TO_COMP_B_4_DN")
	)
	(segment
		(start 275.8821 -151.66848)
		(end 276.26818 -151.357838)
		(width 0.1651)
		(layer "B.Cu")
		(net "PCIE_SCC_B_TO_COMP_B_4_DN")
	)
	(segment
		(start 262.801862 -171.47286)
		(end 262.76808 -171.314872)
		(width 0.1651)
		(layer "B.Cu")
		(net "PCIE_SCC_B_TO_COMP_B_4_DN")
	)
	(arc
		(start 216.498932 -407.489406)
		(mid 216.459778 -407.426816)
		(end 216.4461 -407.354278)
		(width 0.1651)
		(layer "B.Cu")
		(net "PCIE_SCC_B_TO_COMP_B_4_DN")
	)
	(arc
		(start 216.645744 -407.553922)
		(mid 216.565557 -407.537087)
		(end 216.498932 -407.489406)
		(width 0.1651)
		(layer "B.Cu")
		(net "PCIE_SCC_B_TO_COMP_B_4_DN")
	)
	(arc
		(start 279.173686 -149.646132)
		(mid 279.334943 -149.678208)
		(end 279.471628 -149.769576)
		(width 0.1651)
		(layer "B.Cu")
		(net "PCIE_SCC_B_TO_COMP_B_4_DN")
	)
	(arc
		(start 279.545542 -149.91715)
		(mid 279.554584 -150.043149)
		(end 279.471882 -150.138638)
		(width 0.1651)
		(layer "B.Cu")
		(net "PCIE_SCC_B_TO_COMP_B_4_DN")
	)
	(arc
		(start 217.080338 -407.542492)
		(mid 217.049487 -407.551058)
		(end 217.0176 -407.553922)
		(width 0.1651)
		(layer "B.Cu")
		(net "PCIE_SCC_B_TO_COMP_B_4_DN")
	)
	(arc
		(start 217.199972 -407.369518)
		(mid 217.167154 -407.474684)
		(end 217.080338 -407.542492)
		(width 0.1651)
		(layer "B.Cu")
		(net "PCIE_SCC_B_TO_COMP_B_4_DN")
	)
	(segment
		(start 266.58062 -147.862544)
		(end 266.934442 -146.69643)
		(width 0.1651)
		(layer "B.Cu")
		(net "PCIE_SCC_B_TO_COMP_B_3_DP")
	)
	(segment
		(start 267.49883 -144.836388)
		(end 267.499084 -144.835626)
		(width 0.1651)
		(layer "B.Cu")
		(net "PCIE_SCC_B_TO_COMP_B_3_DP")
	)
	(segment
		(start 211.992464 -394.92682)
		(end 213.999064 -385.86791)
		(width 0.1651)
		(layer "B.Cu")
		(net "PCIE_SCC_B_TO_COMP_B_3_DP")
	)
	(segment
		(start 214.354156 -405.369014)
		(end 211.992464 -394.92682)
		(width 0.1651)
		(layer "B.Cu")
		(net "PCIE_SCC_B_TO_COMP_B_3_DP")
	)
	(segment
		(start 209.349848 -351.344738)
		(end 207.42656 -342.834214)
		(width 0.1651)
		(layer "B.Cu")
		(net "PCIE_SCC_B_TO_COMP_B_3_DP")
	)
	(segment
		(start 215.21547 -406.846024)
		(end 214.8459 -406.846024)
		(width 0.1651)
		(layer "B.Cu")
		(net "PCIE_SCC_B_TO_COMP_B_3_DP")
	)
	(segment
		(start 279.764744 -129.702052)
		(end 279.807162 -129.786888)
		(width 0.1651)
		(layer "B.Cu")
		(net "PCIE_SCC_B_TO_COMP_B_3_DP")
	)
	(segment
		(start 266.934696 -146.695668)
		(end 267.49883 -144.836388)
		(width 0.1651)
		(layer "B.Cu")
		(net "PCIE_SCC_B_TO_COMP_B_3_DP")
	)
	(segment
		(start 207.42656 -342.834214)
		(end 264.187686 -155.750514)
		(width 0.1651)
		(layer "B.Cu")
		(net "PCIE_SCC_B_TO_COMP_B_3_DP")
	)
	(segment
		(start 276.693122 -130.398774)
		(end 277.992586 -129.354072)
		(width 0.1651)
		(layer "B.Cu")
		(net "PCIE_SCC_B_TO_COMP_B_3_DP")
	)
	(segment
		(start 280.02865 -129.860802)
		(end 280.75001 -129.499868)
		(width 0.1651)
		(layer "B.Cu")
		(net "PCIE_SCC_B_TO_COMP_B_3_DP")
	)
	(segment
		(start 266.934442 -146.69643)
		(end 266.934696 -146.695668)
		(width 0.1651)
		(layer "B.Cu")
		(net "PCIE_SCC_B_TO_COMP_B_3_DP")
	)
	(segment
		(start 264.187686 -155.750514)
		(end 264.187432 -155.750514)
		(width 0.1651)
		(layer "B.Cu")
		(net "PCIE_SCC_B_TO_COMP_B_3_DP")
	)
	(segment
		(start 208.581752 -354.81387)
		(end 208.581498 -354.81387)
		(width 0.1651)
		(layer "B.Cu")
		(net "PCIE_SCC_B_TO_COMP_B_3_DP")
	)
	(segment
		(start 215.400128 -407.399998)
		(end 215.400128 -407.030682)
		(width 0.1651)
		(layer "B.Cu")
		(net "PCIE_SCC_B_TO_COMP_B_3_DP")
	)
	(segment
		(start 208.581498 -354.81387)
		(end 209.349848 -351.344738)
		(width 0.1651)
		(layer "B.Cu")
		(net "PCIE_SCC_B_TO_COMP_B_3_DP")
	)
	(segment
		(start 213.999064 -385.86791)
		(end 207.785208 -358.410764)
		(width 0.1651)
		(layer "B.Cu")
		(net "PCIE_SCC_B_TO_COMP_B_3_DP")
	)
	(segment
		(start 264.187432 -155.750514)
		(end 266.580366 -147.863306)
		(width 0.1651)
		(layer "B.Cu")
		(net "PCIE_SCC_B_TO_COMP_B_3_DP")
	)
	(segment
		(start 266.580366 -147.863306)
		(end 266.58062 -147.862544)
		(width 0.1651)
		(layer "B.Cu")
		(net "PCIE_SCC_B_TO_COMP_B_3_DP")
	)
	(segment
		(start 267.499084 -144.835626)
		(end 267.654532 -144.323308)
		(width 0.1651)
		(layer "B.Cu")
		(net "PCIE_SCC_B_TO_COMP_B_3_DP")
	)
	(segment
		(start 277.992586 -129.354072)
		(end 279.17394 -129.354072)
		(width 0.1651)
		(layer "B.Cu")
		(net "PCIE_SCC_B_TO_COMP_B_3_DP")
	)
	(segment
		(start 214.354156 -406.35428)
		(end 214.354156 -405.369014)
		(width 0.1651)
		(layer "B.Cu")
		(net "PCIE_SCC_B_TO_COMP_B_3_DP")
	)
	(segment
		(start 279.714452 -129.601976)
		(end 279.764744 -129.702052)
		(width 0.1651)
		(layer "B.Cu")
		(net "PCIE_SCC_B_TO_COMP_B_3_DP")
	)
	(segment
		(start 207.785208 -358.410764)
		(end 208.581752 -354.81387)
		(width 0.1651)
		(layer "B.Cu")
		(net "PCIE_SCC_B_TO_COMP_B_3_DP")
	)
	(segment
		(start 267.654532 -144.323308)
		(end 276.693122 -130.398774)
		(width 0.1651)
		(layer "B.Cu")
		(net "PCIE_SCC_B_TO_COMP_B_3_DP")
	)
	(arc
		(start 279.17394 -129.354072)
		(mid 279.471223 -129.419072)
		(end 279.714452 -129.601976)
		(width 0.1651)
		(layer "B.Cu")
		(net "PCIE_SCC_B_TO_COMP_B_3_DP")
	)
	(arc
		(start 214.484204 -406.687274)
		(mid 214.387817 -406.533019)
		(end 214.354156 -406.35428)
		(width 0.1651)
		(layer "B.Cu")
		(net "PCIE_SCC_B_TO_COMP_B_3_DP")
	)
	(arc
		(start 279.807162 -129.786888)
		(mid 279.902579 -129.8697)
		(end 280.02865 -129.860802)
		(width 0.1651)
		(layer "B.Cu")
		(net "PCIE_SCC_B_TO_COMP_B_3_DP")
	)
	(arc
		(start 215.400128 -407.030682)
		(mid 215.346043 -406.900109)
		(end 215.21547 -406.846024)
		(width 0.1651)
		(layer "B.Cu")
		(net "PCIE_SCC_B_TO_COMP_B_3_DP")
	)
	(arc
		(start 214.8459 -406.846024)
		(mid 214.648395 -406.804594)
		(end 214.484204 -406.687274)
		(width 0.1651)
		(layer "B.Cu")
		(net "PCIE_SCC_B_TO_COMP_B_3_DP")
	)
	(segment
		(start 267.146786 -147.397724)
		(end 267.070586 -147.254976)
		(width 0.1651)
		(layer "B.Cu")
		(net "PCIE_SCC_B_TO_COMP_B_3_DN")
	)
	(segment
		(start 275.799042 -132.541518)
		(end 275.762466 -132.369306)
		(width 0.1651)
		(layer "B.Cu")
		(net "PCIE_SCC_B_TO_COMP_B_3_DN")
	)
	(segment
		(start 214.29853 -385.867148)
		(end 208.084674 -358.410002)
		(width 0.1651)
		(layer "B.Cu")
		(net "PCIE_SCC_B_TO_COMP_B_3_DN")
	)
	(segment
		(start 269.769844 -141.60119)
		(end 269.928086 -141.567662)
		(width 0.1651)
		(layer "B.Cu")
		(net "PCIE_SCC_B_TO_COMP_B_3_DN")
	)
	(segment
		(start 274.449286 -134.620762)
		(end 274.41271 -134.448804)
		(width 0.1651)
		(layer "B.Cu")
		(net "PCIE_SCC_B_TO_COMP_B_3_DN")
	)
	(segment
		(start 267.778992 -144.920208)
		(end 267.922248 -144.447768)
		(width 0.1651)
		(layer "B.Cu")
		(net "PCIE_SCC_B_TO_COMP_B_3_DN")
	)
	(segment
		(start 267.356844 -146.705066)
		(end 267.500608 -146.231102)
		(width 0.1651)
		(layer "B.Cu")
		(net "PCIE_SCC_B_TO_COMP_B_3_DN")
	)
	(segment
		(start 267.424408 -146.088354)
		(end 267.568172 -145.61439)
		(width 0.1651)
		(layer "B.Cu")
		(net "PCIE_SCC_B_TO_COMP_B_3_DN")
	)
	(segment
		(start 264.46734 -155.835096)
		(end 264.609834 -155.758896)
		(width 0.1651)
		(layer "B.Cu")
		(net "PCIE_SCC_B_TO_COMP_B_3_DN")
	)
	(segment
		(start 266.860274 -147.947888)
		(end 267.002768 -147.871688)
		(width 0.1651)
		(layer "B.Cu")
		(net "PCIE_SCC_B_TO_COMP_B_3_DN")
	)
	(segment
		(start 265.031474 -153.975562)
		(end 266.506452 -149.11451)
		(width 0.1651)
		(layer "B.Cu")
		(net "PCIE_SCC_B_TO_COMP_B_3_DN")
	)
	(segment
		(start 271.525238 -139.10691)
		(end 271.49171 -138.948668)
		(width 0.1651)
		(layer "B.Cu")
		(net "PCIE_SCC_B_TO_COMP_B_3_DN")
	)
	(segment
		(start 269.106142 -142.623794)
		(end 269.264384 -142.590266)
		(width 0.1651)
		(layer "B.Cu")
		(net "PCIE_SCC_B_TO_COMP_B_3_DN")
	)
	(segment
		(start 264.96391 -154.592274)
		(end 265.107674 -154.11831)
		(width 0.1651)
		(layer "B.Cu")
		(net "PCIE_SCC_B_TO_COMP_B_3_DN")
	)
	(segment
		(start 271.255744 -139.5222)
		(end 271.525238 -139.10691)
		(width 0.1651)
		(layer "B.Cu")
		(net "PCIE_SCC_B_TO_COMP_B_3_DN")
	)
	(segment
		(start 275.762466 -132.369306)
		(end 276.912832 -130.597148)
		(width 0.1651)
		(layer "B.Cu")
		(net "PCIE_SCC_B_TO_COMP_B_3_DN")
	)
	(segment
		(start 270.591788 -140.545058)
		(end 270.861536 -140.129514)
		(width 0.1651)
		(layer "B.Cu")
		(net "PCIE_SCC_B_TO_COMP_B_3_DN")
	)
	(segment
		(start 264.753598 -155.284932)
		(end 264.677398 -155.142438)
		(width 0.1651)
		(layer "B.Cu")
		(net "PCIE_SCC_B_TO_COMP_B_3_DN")
	)
	(segment
		(start 270.828008 -139.971526)
		(end 271.097502 -139.555982)
		(width 0.1651)
		(layer "B.Cu")
		(net "PCIE_SCC_B_TO_COMP_B_3_DN")
	)
	(segment
		(start 209.649314 -351.343976)
		(end 207.728566 -342.845136)
		(width 0.1651)
		(layer "B.Cu")
		(net "PCIE_SCC_B_TO_COMP_B_3_DN")
	)
	(segment
		(start 269.928086 -141.567662)
		(end 270.197834 -141.152118)
		(width 0.1651)
		(layer "B.Cu")
		(net "PCIE_SCC_B_TO_COMP_B_3_DN")
	)
	(segment
		(start 275.529548 -132.956808)
		(end 275.799042 -132.541518)
		(width 0.1651)
		(layer "B.Cu")
		(net "PCIE_SCC_B_TO_COMP_B_3_DN")
	)
	(segment
		(start 270.197834 -141.152118)
		(end 270.164052 -140.99413)
		(width 0.1651)
		(layer "B.Cu")
		(net "PCIE_SCC_B_TO_COMP_B_3_DN")
	)
	(segment
		(start 269.533878 -142.174722)
		(end 269.50035 -142.016734)
		(width 0.1651)
		(layer "B.Cu")
		(net "PCIE_SCC_B_TO_COMP_B_3_DN")
	)
	(segment
		(start 276.912832 -130.597148)
		(end 278.095456 -129.646172)
		(width 0.1651)
		(layer "B.Cu")
		(net "PCIE_SCC_B_TO_COMP_B_3_DN")
	)
	(segment
		(start 274.682458 -134.03326)
		(end 274.85467 -133.996684)
		(width 0.1651)
		(layer "B.Cu")
		(net "PCIE_SCC_B_TO_COMP_B_3_DN")
	)
	(segment
		(start 274.179792 -135.036306)
		(end 274.449286 -134.620762)
		(width 0.1651)
		(layer "B.Cu")
		(net "PCIE_SCC_B_TO_COMP_B_3_DN")
	)
	(segment
		(start 265.107674 -154.11831)
		(end 265.031474 -153.975562)
		(width 0.1651)
		(layer "B.Cu")
		(net "PCIE_SCC_B_TO_COMP_B_3_DN")
	)
	(segment
		(start 279.471882 -130.138678)
		(end 278.750014 -130.499866)
		(width 0.1651)
		(layer "B.Cu")
		(net "PCIE_SCC_B_TO_COMP_B_3_DN")
	)
	(segment
		(start 267.500608 -146.231102)
		(end 267.424408 -146.088354)
		(width 0.1651)
		(layer "B.Cu")
		(net "PCIE_SCC_B_TO_COMP_B_3_DN")
	)
	(segment
		(start 278.095456 -129.646172)
		(end 279.173686 -129.646172)
		(width 0.1651)
		(layer "B.Cu")
		(net "PCIE_SCC_B_TO_COMP_B_3_DN")
	)
	(segment
		(start 275.124164 -133.58114)
		(end 275.087588 -133.408928)
		(width 0.1651)
		(layer "B.Cu")
		(net "PCIE_SCC_B_TO_COMP_B_3_DN")
	)
	(segment
		(start 264.609834 -155.758896)
		(end 264.753598 -155.284932)
		(width 0.1651)
		(layer "B.Cu")
		(net "PCIE_SCC_B_TO_COMP_B_3_DN")
	)
	(segment
		(start 275.087588 -133.408928)
		(end 275.357336 -132.993638)
		(width 0.1651)
		(layer "B.Cu")
		(net "PCIE_SCC_B_TO_COMP_B_3_DN")
	)
	(segment
		(start 271.097502 -139.555982)
		(end 271.255744 -139.5222)
		(width 0.1651)
		(layer "B.Cu")
		(net "PCIE_SCC_B_TO_COMP_B_3_DN")
	)
	(segment
		(start 271.49171 -138.948668)
		(end 274.00758 -135.072882)
		(width 0.1651)
		(layer "B.Cu")
		(net "PCIE_SCC_B_TO_COMP_B_3_DN")
	)
	(segment
		(start 214.646256 -406.35428)
		(end 214.646256 -405.336248)
		(width 0.1651)
		(layer "B.Cu")
		(net "PCIE_SCC_B_TO_COMP_B_3_DN")
	)
	(segment
		(start 275.357336 -132.993638)
		(end 275.529548 -132.956808)
		(width 0.1651)
		(layer "B.Cu")
		(net "PCIE_SCC_B_TO_COMP_B_3_DN")
	)
	(segment
		(start 214.646256 -405.336248)
		(end 212.29193 -394.926058)
		(width 0.1651)
		(layer "B.Cu")
		(net "PCIE_SCC_B_TO_COMP_B_3_DN")
	)
	(segment
		(start 264.821162 -154.668474)
		(end 264.96391 -154.592274)
		(width 0.1651)
		(layer "B.Cu")
		(net "PCIE_SCC_B_TO_COMP_B_3_DN")
	)
	(segment
		(start 266.71651 -148.421852)
		(end 266.860274 -147.947888)
		(width 0.1651)
		(layer "B.Cu")
		(net "PCIE_SCC_B_TO_COMP_B_3_DN")
	)
	(segment
		(start 270.861536 -140.129514)
		(end 270.828008 -139.971526)
		(width 0.1651)
		(layer "B.Cu")
		(net "PCIE_SCC_B_TO_COMP_B_3_DN")
	)
	(segment
		(start 269.264384 -142.590266)
		(end 269.533878 -142.174722)
		(width 0.1651)
		(layer "B.Cu")
		(net "PCIE_SCC_B_TO_COMP_B_3_DN")
	)
	(segment
		(start 270.164052 -140.99413)
		(end 270.4338 -140.578586)
		(width 0.1651)
		(layer "B.Cu")
		(net "PCIE_SCC_B_TO_COMP_B_3_DN")
	)
	(segment
		(start 267.922248 -144.447768)
		(end 269.106142 -142.623794)
		(width 0.1651)
		(layer "B.Cu")
		(net "PCIE_SCC_B_TO_COMP_B_3_DN")
	)
	(segment
		(start 215.217756 -406.553924)
		(end 214.8459 -406.553924)
		(width 0.1651)
		(layer "B.Cu")
		(net "PCIE_SCC_B_TO_COMP_B_3_DN")
	)
	(segment
		(start 267.778484 -144.921732)
		(end 267.778992 -144.920208)
		(width 0.1651)
		(layer "B.Cu")
		(net "PCIE_SCC_B_TO_COMP_B_3_DN")
	)
	(segment
		(start 267.854684 -145.064226)
		(end 267.778484 -144.921732)
		(width 0.1651)
		(layer "B.Cu")
		(net "PCIE_SCC_B_TO_COMP_B_3_DN")
	)
	(segment
		(start 267.568172 -145.61439)
		(end 267.71092 -145.53819)
		(width 0.1651)
		(layer "B.Cu")
		(net "PCIE_SCC_B_TO_COMP_B_3_DN")
	)
	(segment
		(start 266.506452 -149.11451)
		(end 266.648946 -149.03831)
		(width 0.1651)
		(layer "B.Cu")
		(net "PCIE_SCC_B_TO_COMP_B_3_DN")
	)
	(segment
		(start 264.677398 -155.142438)
		(end 264.821162 -154.668474)
		(width 0.1651)
		(layer "B.Cu")
		(net "PCIE_SCC_B_TO_COMP_B_3_DN")
	)
	(segment
		(start 267.002768 -147.871688)
		(end 267.146786 -147.397724)
		(width 0.1651)
		(layer "B.Cu")
		(net "PCIE_SCC_B_TO_COMP_B_3_DN")
	)
	(segment
		(start 274.00758 -135.072882)
		(end 274.179792 -135.036306)
		(width 0.1651)
		(layer "B.Cu")
		(net "PCIE_SCC_B_TO_COMP_B_3_DN")
	)
	(segment
		(start 266.79271 -148.564346)
		(end 266.71651 -148.421852)
		(width 0.1651)
		(layer "B.Cu")
		(net "PCIE_SCC_B_TO_COMP_B_3_DN")
	)
	(segment
		(start 274.85467 -133.996684)
		(end 275.124164 -133.58114)
		(width 0.1651)
		(layer "B.Cu")
		(net "PCIE_SCC_B_TO_COMP_B_3_DN")
	)
	(segment
		(start 274.41271 -134.448804)
		(end 274.682458 -134.03326)
		(width 0.1651)
		(layer "B.Cu")
		(net "PCIE_SCC_B_TO_COMP_B_3_DN")
	)
	(segment
		(start 267.07084 -147.254214)
		(end 267.21435 -146.781012)
		(width 0.1651)
		(layer "B.Cu")
		(net "PCIE_SCC_B_TO_COMP_B_3_DN")
	)
	(segment
		(start 267.21435 -146.781012)
		(end 267.356844 -146.705066)
		(width 0.1651)
		(layer "B.Cu")
		(net "PCIE_SCC_B_TO_COMP_B_3_DN")
	)
	(segment
		(start 269.50035 -142.016734)
		(end 269.769844 -141.60119)
		(width 0.1651)
		(layer "B.Cu")
		(net "PCIE_SCC_B_TO_COMP_B_3_DN")
	)
	(segment
		(start 212.29193 -394.926058)
		(end 214.29853 -385.867148)
		(width 0.1651)
		(layer "B.Cu")
		(net "PCIE_SCC_B_TO_COMP_B_3_DN")
	)
	(segment
		(start 208.084674 -358.410002)
		(end 209.649314 -351.343976)
		(width 0.1651)
		(layer "B.Cu")
		(net "PCIE_SCC_B_TO_COMP_B_3_DN")
	)
	(segment
		(start 266.648946 -149.03831)
		(end 266.79271 -148.564346)
		(width 0.1651)
		(layer "B.Cu")
		(net "PCIE_SCC_B_TO_COMP_B_3_DN")
	)
	(segment
		(start 279.471628 -129.769616)
		(end 279.545542 -129.916936)
		(width 0.1651)
		(layer "B.Cu")
		(net "PCIE_SCC_B_TO_COMP_B_3_DN")
	)
	(segment
		(start 279.545542 -129.916936)
		(end 279.545542 -129.91719)
		(width 0.1651)
		(layer "B.Cu")
		(net "PCIE_SCC_B_TO_COMP_B_3_DN")
	)
	(segment
		(start 215.400128 -405.99995)
		(end 215.400128 -406.36952)
		(width 0.1651)
		(layer "B.Cu")
		(net "PCIE_SCC_B_TO_COMP_B_3_DN")
	)
	(segment
		(start 207.728566 -342.845136)
		(end 264.46734 -155.835096)
		(width 0.1651)
		(layer "B.Cu")
		(net "PCIE_SCC_B_TO_COMP_B_3_DN")
	)
	(segment
		(start 267.71092 -145.53819)
		(end 267.854684 -145.064226)
		(width 0.1651)
		(layer "B.Cu")
		(net "PCIE_SCC_B_TO_COMP_B_3_DN")
	)
	(segment
		(start 267.070586 -147.254976)
		(end 267.07084 -147.254214)
		(width 0.1651)
		(layer "B.Cu")
		(net "PCIE_SCC_B_TO_COMP_B_3_DN")
	)
	(segment
		(start 270.4338 -140.578586)
		(end 270.591788 -140.545058)
		(width 0.1651)
		(layer "B.Cu")
		(net "PCIE_SCC_B_TO_COMP_B_3_DN")
	)
	(arc
		(start 279.173686 -129.646172)
		(mid 279.334943 -129.678248)
		(end 279.471628 -129.769616)
		(width 0.1651)
		(layer "B.Cu")
		(net "PCIE_SCC_B_TO_COMP_B_3_DN")
	)
	(arc
		(start 214.8459 -406.553924)
		(mid 214.765713 -406.537089)
		(end 214.699088 -406.489408)
		(width 0.1651)
		(layer "B.Cu")
		(net "PCIE_SCC_B_TO_COMP_B_3_DN")
	)
	(arc
		(start 279.545542 -129.91719)
		(mid 279.554584 -130.043189)
		(end 279.471882 -130.138678)
		(width 0.1651)
		(layer "B.Cu")
		(net "PCIE_SCC_B_TO_COMP_B_3_DN")
	)
	(arc
		(start 215.280494 -406.542494)
		(mid 215.249643 -406.55106)
		(end 215.217756 -406.553924)
		(width 0.1651)
		(layer "B.Cu")
		(net "PCIE_SCC_B_TO_COMP_B_3_DN")
	)
	(arc
		(start 214.699088 -406.489408)
		(mid 214.659934 -406.426818)
		(end 214.646256 -406.35428)
		(width 0.1651)
		(layer "B.Cu")
		(net "PCIE_SCC_B_TO_COMP_B_3_DN")
	)
	(arc
		(start 215.400128 -406.36952)
		(mid 215.36731 -406.474686)
		(end 215.280494 -406.542494)
		(width 0.1651)
		(layer "B.Cu")
		(net "PCIE_SCC_B_TO_COMP_B_3_DN")
	)
	(segment
		(start 280.02865 -125.86081)
		(end 280.75001 -125.499876)
		(width 0.1651)
		(layer "B.Cu")
		(net "PCIE_SCC_B_TO_COMP_B_2_DP")
	)
	(segment
		(start 212.554058 -407.354278)
		(end 212.554058 -404.97633)
		(width 0.1651)
		(layer "B.Cu")
		(net "PCIE_SCC_B_TO_COMP_B_2_DP")
	)
	(segment
		(start 207.69961 -351.213674)
		(end 205.70571 -342.391492)
		(width 0.1651)
		(layer "B.Cu")
		(net "PCIE_SCC_B_TO_COMP_B_2_DP")
	)
	(segment
		(start 263.08304 -153.277316)
		(end 265.121898 -146.557492)
		(width 0.1651)
		(layer "B.Cu")
		(net "PCIE_SCC_B_TO_COMP_B_2_DP")
	)
	(segment
		(start 206.096108 -358.453944)
		(end 207.69961 -351.213674)
		(width 0.1651)
		(layer "B.Cu")
		(net "PCIE_SCC_B_TO_COMP_B_2_DP")
	)
	(segment
		(start 213.415372 -407.846022)
		(end 213.045802 -407.846022)
		(width 0.1651)
		(layer "B.Cu")
		(net "PCIE_SCC_B_TO_COMP_B_2_DP")
	)
	(segment
		(start 265.121898 -146.557492)
		(end 265.122152 -146.55673)
		(width 0.1651)
		(layer "B.Cu")
		(net "PCIE_SCC_B_TO_COMP_B_2_DP")
	)
	(segment
		(start 265.122152 -146.55673)
		(end 266.19581 -143.018002)
		(width 0.1651)
		(layer "B.Cu")
		(net "PCIE_SCC_B_TO_COMP_B_2_DP")
	)
	(segment
		(start 213.60003 -408.399996)
		(end 213.60003 -408.03068)
		(width 0.1651)
		(layer "B.Cu")
		(net "PCIE_SCC_B_TO_COMP_B_2_DP")
	)
	(segment
		(start 212.554058 -404.97633)
		(end 209.752184 -392.594338)
		(width 0.1651)
		(layer "B.Cu")
		(net "PCIE_SCC_B_TO_COMP_B_2_DP")
	)
	(segment
		(start 278.354536 -125.35408)
		(end 279.17394 -125.35408)
		(width 0.1651)
		(layer "B.Cu")
		(net "PCIE_SCC_B_TO_COMP_B_2_DP")
	)
	(segment
		(start 279.764744 -125.70206)
		(end 279.807162 -125.786896)
		(width 0.1651)
		(layer "B.Cu")
		(net "PCIE_SCC_B_TO_COMP_B_2_DP")
	)
	(segment
		(start 211.76615 -383.502408)
		(end 206.096108 -358.453944)
		(width 0.1651)
		(layer "B.Cu")
		(net "PCIE_SCC_B_TO_COMP_B_2_DP")
	)
	(segment
		(start 279.714452 -125.601984)
		(end 279.764744 -125.70206)
		(width 0.1651)
		(layer "B.Cu")
		(net "PCIE_SCC_B_TO_COMP_B_2_DP")
	)
	(segment
		(start 263.082786 -153.278078)
		(end 263.08304 -153.277316)
		(width 0.1651)
		(layer "B.Cu")
		(net "PCIE_SCC_B_TO_COMP_B_2_DP")
	)
	(segment
		(start 205.70571 -342.391492)
		(end 263.082786 -153.278078)
		(width 0.1651)
		(layer "B.Cu")
		(net "PCIE_SCC_B_TO_COMP_B_2_DP")
	)
	(segment
		(start 276.694646 -126.68885)
		(end 278.354536 -125.35408)
		(width 0.1651)
		(layer "B.Cu")
		(net "PCIE_SCC_B_TO_COMP_B_2_DP")
	)
	(segment
		(start 209.752184 -392.594338)
		(end 211.76615 -383.502408)
		(width 0.1651)
		(layer "B.Cu")
		(net "PCIE_SCC_B_TO_COMP_B_2_DP")
	)
	(segment
		(start 266.19581 -143.018002)
		(end 276.694646 -126.68885)
		(width 0.1651)
		(layer "B.Cu")
		(net "PCIE_SCC_B_TO_COMP_B_2_DP")
	)
	(arc
		(start 213.60003 -408.03068)
		(mid 213.545945 -407.900107)
		(end 213.415372 -407.846022)
		(width 0.1651)
		(layer "B.Cu")
		(net "PCIE_SCC_B_TO_COMP_B_2_DP")
	)
	(arc
		(start 213.045802 -407.846022)
		(mid 212.698086 -407.701994)
		(end 212.554058 -407.354278)
		(width 0.1651)
		(layer "B.Cu")
		(net "PCIE_SCC_B_TO_COMP_B_2_DP")
	)
	(arc
		(start 279.17394 -125.35408)
		(mid 279.471223 -125.41908)
		(end 279.714452 -125.601984)
		(width 0.1651)
		(layer "B.Cu")
		(net "PCIE_SCC_B_TO_COMP_B_2_DP")
	)
	(arc
		(start 279.807162 -125.786896)
		(mid 279.902579 -125.869708)
		(end 280.02865 -125.86081)
		(width 0.1651)
		(layer "B.Cu")
		(net "PCIE_SCC_B_TO_COMP_B_2_DP")
	)
	(segment
		(start 269.551912 -138.33856)
		(end 269.819882 -137.922)
		(width 0.1651)
		(layer "B.Cu")
		(net "PCIE_SCC_B_TO_COMP_B_2_DN")
	)
	(segment
		(start 278.45766 -125.64618)
		(end 279.173686 -125.64618)
		(width 0.1651)
		(layer "B.Cu")
		(net "PCIE_SCC_B_TO_COMP_B_2_DN")
	)
	(segment
		(start 274.197064 -131.114038)
		(end 274.369022 -131.0767)
		(width 0.1651)
		(layer "B.Cu")
		(net "PCIE_SCC_B_TO_COMP_B_2_DN")
	)
	(segment
		(start 207.999076 -351.212912)
		(end 206.007716 -342.402414)
		(width 0.1651)
		(layer "B.Cu")
		(net "PCIE_SCC_B_TO_COMP_B_2_DN")
	)
	(segment
		(start 269.819882 -137.922)
		(end 269.97787 -137.88771)
		(width 0.1651)
		(layer "B.Cu")
		(net "PCIE_SCC_B_TO_COMP_B_2_DN")
	)
	(segment
		(start 273.929094 -131.530598)
		(end 274.197064 -131.114038)
		(width 0.1651)
		(layer "B.Cu")
		(net "PCIE_SCC_B_TO_COMP_B_2_DN")
	)
	(segment
		(start 275.307298 -129.61747)
		(end 275.26996 -129.445512)
		(width 0.1651)
		(layer "B.Cu")
		(net "PCIE_SCC_B_TO_COMP_B_2_DN")
	)
	(segment
		(start 270.245586 -137.47115)
		(end 270.211296 -137.313162)
		(width 0.1651)
		(layer "B.Cu")
		(net "PCIE_SCC_B_TO_COMP_B_2_DN")
	)
	(segment
		(start 265.755882 -145.475198)
		(end 265.898376 -145.399252)
		(width 0.1651)
		(layer "B.Cu")
		(net "PCIE_SCC_B_TO_COMP_B_2_DN")
	)
	(segment
		(start 263.649206 -152.812496)
		(end 263.573006 -152.669748)
		(width 0.1651)
		(layer "B.Cu")
		(net "PCIE_SCC_B_TO_COMP_B_2_DN")
	)
	(segment
		(start 206.395574 -358.453182)
		(end 207.999076 -351.212912)
		(width 0.1651)
		(layer "B.Cu")
		(net "PCIE_SCC_B_TO_COMP_B_2_DN")
	)
	(segment
		(start 279.545542 -125.916944)
		(end 279.545542 -125.917198)
		(width 0.1651)
		(layer "B.Cu")
		(net "PCIE_SCC_B_TO_COMP_B_2_DN")
	)
	(segment
		(start 265.612118 -145.949162)
		(end 265.755882 -145.475198)
		(width 0.1651)
		(layer "B.Cu")
		(net "PCIE_SCC_B_TO_COMP_B_2_DN")
	)
	(segment
		(start 265.966194 -144.781778)
		(end 266.109704 -144.308576)
		(width 0.1651)
		(layer "B.Cu")
		(net "PCIE_SCC_B_TO_COMP_B_2_DN")
	)
	(segment
		(start 271.530064 -135.262112)
		(end 273.526758 -132.156708)
		(width 0.1651)
		(layer "B.Cu")
		(net "PCIE_SCC_B_TO_COMP_B_2_DN")
	)
	(segment
		(start 270.479266 -136.896602)
		(end 270.637254 -136.862058)
		(width 0.1651)
		(layer "B.Cu")
		(net "PCIE_SCC_B_TO_COMP_B_2_DN")
	)
	(segment
		(start 269.97787 -137.88771)
		(end 270.245586 -137.47115)
		(width 0.1651)
		(layer "B.Cu")
		(net "PCIE_SCC_B_TO_COMP_B_2_DN")
	)
	(segment
		(start 266.252452 -144.232376)
		(end 266.396216 -143.758412)
		(width 0.1651)
		(layer "B.Cu")
		(net "PCIE_SCC_B_TO_COMP_B_2_DN")
	)
	(segment
		(start 276.914864 -126.88697)
		(end 278.45766 -125.64618)
		(width 0.1651)
		(layer "B.Cu")
		(net "PCIE_SCC_B_TO_COMP_B_2_DN")
	)
	(segment
		(start 265.190478 -147.732496)
		(end 265.334242 -147.258532)
		(width 0.1651)
		(layer "B.Cu")
		(net "PCIE_SCC_B_TO_COMP_B_2_DN")
	)
	(segment
		(start 279.471882 -126.138686)
		(end 278.750014 -126.499874)
		(width 0.1651)
		(layer "B.Cu")
		(net "PCIE_SCC_B_TO_COMP_B_2_DN")
	)
	(segment
		(start 210.05165 -392.593576)
		(end 212.065616 -383.501646)
		(width 0.1651)
		(layer "B.Cu")
		(net "PCIE_SCC_B_TO_COMP_B_2_DN")
	)
	(segment
		(start 271.296638 -135.83666)
		(end 271.564354 -135.4201)
		(width 0.1651)
		(layer "B.Cu")
		(net "PCIE_SCC_B_TO_COMP_B_2_DN")
	)
	(segment
		(start 273.526758 -132.156708)
		(end 273.698716 -132.11937)
		(width 0.1651)
		(layer "B.Cu")
		(net "PCIE_SCC_B_TO_COMP_B_2_DN")
	)
	(segment
		(start 279.471628 -125.769624)
		(end 279.545542 -125.916944)
		(width 0.1651)
		(layer "B.Cu")
		(net "PCIE_SCC_B_TO_COMP_B_2_DN")
	)
	(segment
		(start 263.362694 -153.36266)
		(end 263.505442 -153.28646)
		(width 0.1651)
		(layer "B.Cu")
		(net "PCIE_SCC_B_TO_COMP_B_2_DN")
	)
	(segment
		(start 275.26996 -129.445512)
		(end 276.914864 -126.88697)
		(width 0.1651)
		(layer "B.Cu")
		(net "PCIE_SCC_B_TO_COMP_B_2_DN")
	)
	(segment
		(start 269.318486 -138.913108)
		(end 269.586456 -138.496548)
		(width 0.1651)
		(layer "B.Cu")
		(net "PCIE_SCC_B_TO_COMP_B_2_DN")
	)
	(segment
		(start 265.96594 -144.78254)
		(end 265.966194 -144.781778)
		(width 0.1651)
		(layer "B.Cu")
		(net "PCIE_SCC_B_TO_COMP_B_2_DN")
	)
	(segment
		(start 265.334242 -147.258532)
		(end 265.258042 -147.116038)
		(width 0.1651)
		(layer "B.Cu")
		(net "PCIE_SCC_B_TO_COMP_B_2_DN")
	)
	(segment
		(start 275.039328 -130.03403)
		(end 275.307298 -129.61747)
		(width 0.1651)
		(layer "B.Cu")
		(net "PCIE_SCC_B_TO_COMP_B_2_DN")
	)
	(segment
		(start 266.396216 -143.758412)
		(end 266.320016 -143.615918)
		(width 0.1651)
		(layer "B.Cu")
		(net "PCIE_SCC_B_TO_COMP_B_2_DN")
	)
	(segment
		(start 212.846158 -407.354278)
		(end 212.846158 -404.943564)
		(width 0.1651)
		(layer "B.Cu")
		(net "PCIE_SCC_B_TO_COMP_B_2_DN")
	)
	(segment
		(start 263.21893 -153.836624)
		(end 263.362694 -153.36266)
		(width 0.1651)
		(layer "B.Cu")
		(net "PCIE_SCC_B_TO_COMP_B_2_DN")
	)
	(segment
		(start 274.86737 -130.071368)
		(end 275.039328 -130.03403)
		(width 0.1651)
		(layer "B.Cu")
		(net "PCIE_SCC_B_TO_COMP_B_2_DN")
	)
	(segment
		(start 273.966686 -131.702556)
		(end 273.929094 -131.530598)
		(width 0.1651)
		(layer "B.Cu")
		(net "PCIE_SCC_B_TO_COMP_B_2_DN")
	)
	(segment
		(start 271.564354 -135.4201)
		(end 271.530064 -135.262112)
		(width 0.1651)
		(layer "B.Cu")
		(net "PCIE_SCC_B_TO_COMP_B_2_DN")
	)
	(segment
		(start 266.320016 -143.615918)
		(end 266.46378 -143.141954)
		(width 0.1651)
		(layer "B.Cu")
		(net "PCIE_SCC_B_TO_COMP_B_2_DN")
	)
	(segment
		(start 274.599654 -130.488182)
		(end 274.86737 -130.071368)
		(width 0.1651)
		(layer "B.Cu")
		(net "PCIE_SCC_B_TO_COMP_B_2_DN")
	)
	(segment
		(start 265.688318 -146.09191)
		(end 265.612118 -145.949162)
		(width 0.1651)
		(layer "B.Cu")
		(net "PCIE_SCC_B_TO_COMP_B_2_DN")
	)
	(segment
		(start 274.369022 -131.0767)
		(end 274.636992 -130.66014)
		(width 0.1651)
		(layer "B.Cu")
		(net "PCIE_SCC_B_TO_COMP_B_2_DN")
	)
	(segment
		(start 269.160498 -138.947652)
		(end 269.318486 -138.913108)
		(width 0.1651)
		(layer "B.Cu")
		(net "PCIE_SCC_B_TO_COMP_B_2_DN")
	)
	(segment
		(start 266.109704 -144.308576)
		(end 266.252452 -144.232376)
		(width 0.1651)
		(layer "B.Cu")
		(net "PCIE_SCC_B_TO_COMP_B_2_DN")
	)
	(segment
		(start 265.5443 -146.565874)
		(end 265.688318 -146.09191)
		(width 0.1651)
		(layer "B.Cu")
		(net "PCIE_SCC_B_TO_COMP_B_2_DN")
	)
	(segment
		(start 271.13865 -135.87095)
		(end 271.296638 -135.83666)
		(width 0.1651)
		(layer "B.Cu")
		(net "PCIE_SCC_B_TO_COMP_B_2_DN")
	)
	(segment
		(start 263.151366 -154.453082)
		(end 263.29513 -153.979118)
		(width 0.1651)
		(layer "B.Cu")
		(net "PCIE_SCC_B_TO_COMP_B_2_DN")
	)
	(segment
		(start 265.258042 -147.116038)
		(end 265.401806 -146.642074)
		(width 0.1651)
		(layer "B.Cu")
		(net "PCIE_SCC_B_TO_COMP_B_2_DN")
	)
	(segment
		(start 265.898376 -145.399252)
		(end 266.04214 -144.925288)
		(width 0.1651)
		(layer "B.Cu")
		(net "PCIE_SCC_B_TO_COMP_B_2_DN")
	)
	(segment
		(start 270.637254 -136.862058)
		(end 270.90497 -136.445498)
		(width 0.1651)
		(layer "B.Cu")
		(net "PCIE_SCC_B_TO_COMP_B_2_DN")
	)
	(segment
		(start 265.401806 -146.642074)
		(end 265.5443 -146.565874)
		(width 0.1651)
		(layer "B.Cu")
		(net "PCIE_SCC_B_TO_COMP_B_2_DN")
	)
	(segment
		(start 263.573006 -152.669748)
		(end 263.57326 -152.668986)
		(width 0.1651)
		(layer "B.Cu")
		(net "PCIE_SCC_B_TO_COMP_B_2_DN")
	)
	(segment
		(start 212.846158 -404.943564)
		(end 210.05165 -392.593576)
		(width 0.1651)
		(layer "B.Cu")
		(net "PCIE_SCC_B_TO_COMP_B_2_DN")
	)
	(segment
		(start 213.417658 -407.553922)
		(end 213.045802 -407.553922)
		(width 0.1651)
		(layer "B.Cu")
		(net "PCIE_SCC_B_TO_COMP_B_2_DN")
	)
	(segment
		(start 273.698716 -132.11937)
		(end 273.966686 -131.702556)
		(width 0.1651)
		(layer "B.Cu")
		(net "PCIE_SCC_B_TO_COMP_B_2_DN")
	)
	(segment
		(start 212.065616 -383.501646)
		(end 206.395574 -358.453182)
		(width 0.1651)
		(layer "B.Cu")
		(net "PCIE_SCC_B_TO_COMP_B_2_DN")
	)
	(segment
		(start 270.211296 -137.313162)
		(end 270.479266 -136.896602)
		(width 0.1651)
		(layer "B.Cu")
		(net "PCIE_SCC_B_TO_COMP_B_2_DN")
	)
	(segment
		(start 269.586456 -138.496548)
		(end 269.551912 -138.33856)
		(width 0.1651)
		(layer "B.Cu")
		(net "PCIE_SCC_B_TO_COMP_B_2_DN")
	)
	(segment
		(start 206.007716 -342.402414)
		(end 263.008872 -154.529282)
		(width 0.1651)
		(layer "B.Cu")
		(net "PCIE_SCC_B_TO_COMP_B_2_DN")
	)
	(segment
		(start 213.60003 -407.000202)
		(end 213.60003 -407.369518)
		(width 0.1651)
		(layer "B.Cu")
		(net "PCIE_SCC_B_TO_COMP_B_2_DN")
	)
	(segment
		(start 263.57326 -152.668986)
		(end 265.047984 -147.808696)
		(width 0.1651)
		(layer "B.Cu")
		(net "PCIE_SCC_B_TO_COMP_B_2_DN")
	)
	(segment
		(start 263.008872 -154.529282)
		(end 263.151366 -154.453082)
		(width 0.1651)
		(layer "B.Cu")
		(net "PCIE_SCC_B_TO_COMP_B_2_DN")
	)
	(segment
		(start 265.047984 -147.808696)
		(end 265.190478 -147.732496)
		(width 0.1651)
		(layer "B.Cu")
		(net "PCIE_SCC_B_TO_COMP_B_2_DN")
	)
	(segment
		(start 266.04214 -144.925288)
		(end 265.96594 -144.78254)
		(width 0.1651)
		(layer "B.Cu")
		(net "PCIE_SCC_B_TO_COMP_B_2_DN")
	)
	(segment
		(start 266.46378 -143.141954)
		(end 269.160498 -138.947652)
		(width 0.1651)
		(layer "B.Cu")
		(net "PCIE_SCC_B_TO_COMP_B_2_DN")
	)
	(segment
		(start 263.29513 -153.979118)
		(end 263.21893 -153.836624)
		(width 0.1651)
		(layer "B.Cu")
		(net "PCIE_SCC_B_TO_COMP_B_2_DN")
	)
	(segment
		(start 270.90497 -136.445498)
		(end 270.87068 -136.28751)
		(width 0.1651)
		(layer "B.Cu")
		(net "PCIE_SCC_B_TO_COMP_B_2_DN")
	)
	(segment
		(start 270.87068 -136.28751)
		(end 271.13865 -135.87095)
		(width 0.1651)
		(layer "B.Cu")
		(net "PCIE_SCC_B_TO_COMP_B_2_DN")
	)
	(segment
		(start 274.636992 -130.66014)
		(end 274.599654 -130.488182)
		(width 0.1651)
		(layer "B.Cu")
		(net "PCIE_SCC_B_TO_COMP_B_2_DN")
	)
	(segment
		(start 263.505442 -153.28646)
		(end 263.649206 -152.812496)
		(width 0.1651)
		(layer "B.Cu")
		(net "PCIE_SCC_B_TO_COMP_B_2_DN")
	)
	(arc
		(start 212.89899 -407.489406)
		(mid 212.859836 -407.426816)
		(end 212.846158 -407.354278)
		(width 0.1651)
		(layer "B.Cu")
		(net "PCIE_SCC_B_TO_COMP_B_2_DN")
	)
	(arc
		(start 213.480396 -407.542492)
		(mid 213.449545 -407.551058)
		(end 213.417658 -407.553922)
		(width 0.1651)
		(layer "B.Cu")
		(net "PCIE_SCC_B_TO_COMP_B_2_DN")
	)
	(arc
		(start 213.60003 -407.369518)
		(mid 213.567212 -407.474684)
		(end 213.480396 -407.542492)
		(width 0.1651)
		(layer "B.Cu")
		(net "PCIE_SCC_B_TO_COMP_B_2_DN")
	)
	(arc
		(start 213.045802 -407.553922)
		(mid 212.965615 -407.537087)
		(end 212.89899 -407.489406)
		(width 0.1651)
		(layer "B.Cu")
		(net "PCIE_SCC_B_TO_COMP_B_2_DN")
	)
	(arc
		(start 279.173686 -125.64618)
		(mid 279.334943 -125.678256)
		(end 279.471628 -125.769624)
		(width 0.1651)
		(layer "B.Cu")
		(net "PCIE_SCC_B_TO_COMP_B_2_DN")
	)
	(arc
		(start 279.545542 -125.917198)
		(mid 279.554584 -126.043197)
		(end 279.471882 -126.138686)
		(width 0.1651)
		(layer "B.Cu")
		(net "PCIE_SCC_B_TO_COMP_B_2_DN")
	)
	(segment
		(start 210.119214 -383.455164)
		(end 204.464412 -358.46766)
		(width 0.1651)
		(layer "B.Cu")
		(net "PCIE_SCC_B_TO_COMP_B_1_DP")
	)
	(segment
		(start 210.754214 -406.35428)
		(end 210.754214 -405.128222)
		(width 0.1651)
		(layer "B.Cu")
		(net "PCIE_SCC_B_TO_COMP_B_1_DP")
	)
	(segment
		(start 279.714452 -121.601992)
		(end 279.764744 -121.702068)
		(width 0.1651)
		(layer "B.Cu")
		(net "PCIE_SCC_B_TO_COMP_B_1_DP")
	)
	(segment
		(start 280.02865 -121.860818)
		(end 280.75001 -121.499884)
		(width 0.1651)
		(layer "B.Cu")
		(net "PCIE_SCC_B_TO_COMP_B_1_DP")
	)
	(segment
		(start 263.524746 -145.04162)
		(end 263.525 -145.040858)
		(width 0.1651)
		(layer "B.Cu")
		(net "PCIE_SCC_B_TO_COMP_B_1_DP")
	)
	(segment
		(start 211.615528 -406.846024)
		(end 211.245958 -406.846024)
		(width 0.1651)
		(layer "B.Cu")
		(net "PCIE_SCC_B_TO_COMP_B_1_DP")
	)
	(segment
		(start 262.816848 -147.375118)
		(end 262.817102 -147.374356)
		(width 0.1651)
		(layer "B.Cu")
		(net "PCIE_SCC_B_TO_COMP_B_1_DP")
	)
	(segment
		(start 208.007966 -392.986006)
		(end 210.119214 -383.455164)
		(width 0.1651)
		(layer "B.Cu")
		(net "PCIE_SCC_B_TO_COMP_B_1_DP")
	)
	(segment
		(start 211.800186 -407.399998)
		(end 211.800186 -407.030682)
		(width 0.1651)
		(layer "B.Cu")
		(net "PCIE_SCC_B_TO_COMP_B_1_DP")
	)
	(segment
		(start 264.089134 -143.181578)
		(end 264.741152 -141.032738)
		(width 0.1651)
		(layer "B.Cu")
		(net "PCIE_SCC_B_TO_COMP_B_1_DP")
	)
	(segment
		(start 260.988048 -153.403046)
		(end 260.988302 -153.402284)
		(width 0.1651)
		(layer "B.Cu")
		(net "PCIE_SCC_B_TO_COMP_B_1_DP")
	)
	(segment
		(start 278.28621 -121.354088)
		(end 279.17394 -121.354088)
		(width 0.1651)
		(layer "B.Cu")
		(net "PCIE_SCC_B_TO_COMP_B_1_DP")
	)
	(segment
		(start 263.525 -145.040858)
		(end 264.08888 -143.18234)
		(width 0.1651)
		(layer "B.Cu")
		(net "PCIE_SCC_B_TO_COMP_B_1_DP")
	)
	(segment
		(start 203.885546 -341.608156)
		(end 260.988048 -153.403046)
		(width 0.1651)
		(layer "B.Cu")
		(net "PCIE_SCC_B_TO_COMP_B_1_DP")
	)
	(segment
		(start 260.988302 -153.402284)
		(end 262.816848 -147.375118)
		(width 0.1651)
		(layer "B.Cu")
		(net "PCIE_SCC_B_TO_COMP_B_1_DP")
	)
	(segment
		(start 264.741152 -141.032738)
		(end 276.683724 -122.64263)
		(width 0.1651)
		(layer "B.Cu")
		(net "PCIE_SCC_B_TO_COMP_B_1_DP")
	)
	(segment
		(start 264.08888 -143.18234)
		(end 264.089134 -143.181578)
		(width 0.1651)
		(layer "B.Cu")
		(net "PCIE_SCC_B_TO_COMP_B_1_DP")
	)
	(segment
		(start 210.754214 -405.128222)
		(end 208.007966 -392.986006)
		(width 0.1651)
		(layer "B.Cu")
		(net "PCIE_SCC_B_TO_COMP_B_1_DP")
	)
	(segment
		(start 276.683724 -122.64263)
		(end 278.28621 -121.354088)
		(width 0.1651)
		(layer "B.Cu")
		(net "PCIE_SCC_B_TO_COMP_B_1_DP")
	)
	(segment
		(start 279.764744 -121.702068)
		(end 279.807162 -121.786904)
		(width 0.1651)
		(layer "B.Cu")
		(net "PCIE_SCC_B_TO_COMP_B_1_DP")
	)
	(segment
		(start 204.464412 -358.46766)
		(end 206.064104 -351.245424)
		(width 0.1651)
		(layer "B.Cu")
		(net "PCIE_SCC_B_TO_COMP_B_1_DP")
	)
	(segment
		(start 262.817102 -147.374356)
		(end 263.524746 -145.04162)
		(width 0.1651)
		(layer "B.Cu")
		(net "PCIE_SCC_B_TO_COMP_B_1_DP")
	)
	(segment
		(start 206.064104 -351.245424)
		(end 203.885546 -341.608156)
		(width 0.1651)
		(layer "B.Cu")
		(net "PCIE_SCC_B_TO_COMP_B_1_DP")
	)
	(arc
		(start 211.245958 -406.846024)
		(mid 210.898242 -406.701996)
		(end 210.754214 -406.35428)
		(width 0.1651)
		(layer "B.Cu")
		(net "PCIE_SCC_B_TO_COMP_B_1_DP")
	)
	(arc
		(start 279.807162 -121.786904)
		(mid 279.902579 -121.869716)
		(end 280.02865 -121.860818)
		(width 0.1651)
		(layer "B.Cu")
		(net "PCIE_SCC_B_TO_COMP_B_1_DP")
	)
	(arc
		(start 279.17394 -121.354088)
		(mid 279.471223 -121.419088)
		(end 279.714452 -121.601992)
		(width 0.1651)
		(layer "B.Cu")
		(net "PCIE_SCC_B_TO_COMP_B_1_DP")
	)
	(arc
		(start 211.800186 -407.030682)
		(mid 211.746101 -406.900109)
		(end 211.615528 -406.846024)
		(width 0.1651)
		(layer "B.Cu")
		(net "PCIE_SCC_B_TO_COMP_B_1_DP")
	)
	(segment
		(start 204.763878 -358.466898)
		(end 206.36357 -351.244662)
		(width 0.1651)
		(layer "B.Cu")
		(net "PCIE_SCC_B_TO_COMP_B_1_DN")
	)
	(segment
		(start 263.73709 -145.74266)
		(end 263.66089 -145.600166)
		(width 0.1651)
		(layer "B.Cu")
		(net "PCIE_SCC_B_TO_COMP_B_1_DN")
	)
	(segment
		(start 274.375118 -126.962662)
		(end 274.64512 -126.547118)
		(width 0.1651)
		(layer "B.Cu")
		(net "PCIE_SCC_B_TO_COMP_B_1_DN")
	)
	(segment
		(start 264.444988 -143.409416)
		(end 264.368788 -143.266922)
		(width 0.1651)
		(layer "B.Cu")
		(net "PCIE_SCC_B_TO_COMP_B_1_DN")
	)
	(segment
		(start 261.697978 -152.463246)
		(end 261.621778 -152.320752)
		(width 0.1651)
		(layer "B.Cu")
		(net "PCIE_SCC_B_TO_COMP_B_1_DN")
	)
	(segment
		(start 264.090912 -144.576038)
		(end 264.014712 -144.433544)
		(width 0.1651)
		(layer "B.Cu")
		(net "PCIE_SCC_B_TO_COMP_B_1_DN")
	)
	(segment
		(start 270.816578 -132.214112)
		(end 271.086326 -131.798568)
		(width 0.1651)
		(layer "B.Cu")
		(net "PCIE_SCC_B_TO_COMP_B_1_DN")
	)
	(segment
		(start 264.301224 -143.88338)
		(end 264.444988 -143.409416)
		(width 0.1651)
		(layer "B.Cu")
		(net "PCIE_SCC_B_TO_COMP_B_1_DN")
	)
	(segment
		(start 263.804654 -145.126202)
		(end 263.947148 -145.050002)
		(width 0.1651)
		(layer "B.Cu")
		(net "PCIE_SCC_B_TO_COMP_B_1_DN")
	)
	(segment
		(start 265.008868 -141.157198)
		(end 269.094204 -134.866126)
		(width 0.1651)
		(layer "B.Cu")
		(net "PCIE_SCC_B_TO_COMP_B_1_DN")
	)
	(segment
		(start 276.903434 -122.841004)
		(end 278.389334 -121.646188)
		(width 0.1651)
		(layer "B.Cu")
		(net "PCIE_SCC_B_TO_COMP_B_1_DN")
	)
	(segment
		(start 263.306814 -146.766788)
		(end 263.450578 -146.292824)
		(width 0.1651)
		(layer "B.Cu")
		(net "PCIE_SCC_B_TO_COMP_B_1_DN")
	)
	(segment
		(start 208.307432 -392.985244)
		(end 210.41868 -383.454402)
		(width 0.1651)
		(layer "B.Cu")
		(net "PCIE_SCC_B_TO_COMP_B_1_DN")
	)
	(segment
		(start 269.488412 -134.259066)
		(end 269.75816 -133.843522)
		(width 0.1651)
		(layer "B.Cu")
		(net "PCIE_SCC_B_TO_COMP_B_1_DN")
	)
	(segment
		(start 271.086326 -131.798568)
		(end 271.244314 -131.76504)
		(width 0.1651)
		(layer "B.Cu")
		(net "PCIE_SCC_B_TO_COMP_B_1_DN")
	)
	(segment
		(start 269.522194 -134.417054)
		(end 269.488412 -134.259066)
		(width 0.1651)
		(layer "B.Cu")
		(net "PCIE_SCC_B_TO_COMP_B_1_DN")
	)
	(segment
		(start 275.283422 -125.335538)
		(end 275.55317 -124.919994)
		(width 0.1651)
		(layer "B.Cu")
		(net "PCIE_SCC_B_TO_COMP_B_1_DN")
	)
	(segment
		(start 261.200138 -154.104086)
		(end 261.343902 -153.630122)
		(width 0.1651)
		(layer "B.Cu")
		(net "PCIE_SCC_B_TO_COMP_B_1_DN")
	)
	(segment
		(start 206.36357 -351.244662)
		(end 204.187552 -341.619078)
		(width 0.1651)
		(layer "B.Cu")
		(net "PCIE_SCC_B_TO_COMP_B_1_DN")
	)
	(segment
		(start 270.42237 -132.821172)
		(end 270.580358 -132.78739)
		(width 0.1651)
		(layer "B.Cu")
		(net "PCIE_SCC_B_TO_COMP_B_1_DN")
	)
	(segment
		(start 278.389334 -121.646188)
		(end 279.173686 -121.646188)
		(width 0.1651)
		(layer "B.Cu")
		(net "PCIE_SCC_B_TO_COMP_B_1_DN")
	)
	(segment
		(start 261.267702 -153.487374)
		(end 261.41172 -153.01341)
		(width 0.1651)
		(layer "B.Cu")
		(net "PCIE_SCC_B_TO_COMP_B_1_DN")
	)
	(segment
		(start 271.480534 -131.191508)
		(end 274.20316 -126.999238)
		(width 0.1651)
		(layer "B.Cu")
		(net "PCIE_SCC_B_TO_COMP_B_1_DN")
	)
	(segment
		(start 264.369042 -143.26616)
		(end 265.008868 -141.157198)
		(width 0.1651)
		(layer "B.Cu")
		(net "PCIE_SCC_B_TO_COMP_B_1_DN")
	)
	(segment
		(start 211.617814 -406.553924)
		(end 211.245958 -406.553924)
		(width 0.1651)
		(layer "B.Cu")
		(net "PCIE_SCC_B_TO_COMP_B_1_DN")
	)
	(segment
		(start 270.850106 -132.3721)
		(end 270.816578 -132.214112)
		(width 0.1651)
		(layer "B.Cu")
		(net "PCIE_SCC_B_TO_COMP_B_1_DN")
	)
	(segment
		(start 270.580358 -132.78739)
		(end 270.850106 -132.3721)
		(width 0.1651)
		(layer "B.Cu")
		(net "PCIE_SCC_B_TO_COMP_B_1_DN")
	)
	(segment
		(start 279.471882 -122.138694)
		(end 278.750014 -122.499882)
		(width 0.1651)
		(layer "B.Cu")
		(net "PCIE_SCC_B_TO_COMP_B_1_DN")
	)
	(segment
		(start 261.621778 -152.320752)
		(end 263.096756 -147.4597)
		(width 0.1651)
		(layer "B.Cu")
		(net "PCIE_SCC_B_TO_COMP_B_1_DN")
	)
	(segment
		(start 275.319998 -125.50775)
		(end 275.283422 -125.335538)
		(width 0.1651)
		(layer "B.Cu")
		(net "PCIE_SCC_B_TO_COMP_B_1_DN")
	)
	(segment
		(start 232.622598 -247.899682)
		(end 261.057644 -154.180286)
		(width 0.1651)
		(layer "B.Cu")
		(net "PCIE_SCC_B_TO_COMP_B_1_DN")
	)
	(segment
		(start 204.187552 -341.619078)
		(end 232.622852 -247.899682)
		(width 0.1651)
		(layer "B.Cu")
		(net "PCIE_SCC_B_TO_COMP_B_1_DN")
	)
	(segment
		(start 279.471628 -121.769632)
		(end 279.545542 -121.916952)
		(width 0.1651)
		(layer "B.Cu")
		(net "PCIE_SCC_B_TO_COMP_B_1_DN")
	)
	(segment
		(start 264.368788 -143.266922)
		(end 264.369042 -143.26616)
		(width 0.1651)
		(layer "B.Cu")
		(net "PCIE_SCC_B_TO_COMP_B_1_DN")
	)
	(segment
		(start 264.014712 -144.433544)
		(end 264.158222 -143.961104)
		(width 0.1651)
		(layer "B.Cu")
		(net "PCIE_SCC_B_TO_COMP_B_1_DN")
	)
	(segment
		(start 275.958554 -124.295916)
		(end 276.903434 -122.841004)
		(width 0.1651)
		(layer "B.Cu")
		(net "PCIE_SCC_B_TO_COMP_B_1_DN")
	)
	(segment
		(start 263.383014 -146.909536)
		(end 263.306814 -146.766788)
		(width 0.1651)
		(layer "B.Cu")
		(net "PCIE_SCC_B_TO_COMP_B_1_DN")
	)
	(segment
		(start 270.152622 -133.236462)
		(end 270.42237 -132.821172)
		(width 0.1651)
		(layer "B.Cu")
		(net "PCIE_SCC_B_TO_COMP_B_1_DN")
	)
	(segment
		(start 211.046314 -406.35428)
		(end 211.046314 -405.095456)
		(width 0.1651)
		(layer "B.Cu")
		(net "PCIE_SCC_B_TO_COMP_B_1_DN")
	)
	(segment
		(start 271.514062 -131.349496)
		(end 271.480534 -131.191508)
		(width 0.1651)
		(layer "B.Cu")
		(net "PCIE_SCC_B_TO_COMP_B_1_DN")
	)
	(segment
		(start 263.947148 -145.050002)
		(end 264.090912 -144.576038)
		(width 0.1651)
		(layer "B.Cu")
		(net "PCIE_SCC_B_TO_COMP_B_1_DN")
	)
	(segment
		(start 274.64512 -126.547118)
		(end 274.60829 -126.37516)
		(width 0.1651)
		(layer "B.Cu")
		(net "PCIE_SCC_B_TO_COMP_B_1_DN")
	)
	(segment
		(start 264.158222 -143.961104)
		(end 264.15873 -143.95958)
		(width 0.1651)
		(layer "B.Cu")
		(net "PCIE_SCC_B_TO_COMP_B_1_DN")
	)
	(segment
		(start 269.252446 -134.832598)
		(end 269.522194 -134.417054)
		(width 0.1651)
		(layer "B.Cu")
		(net "PCIE_SCC_B_TO_COMP_B_1_DN")
	)
	(segment
		(start 211.800186 -405.99995)
		(end 211.800186 -406.36952)
		(width 0.1651)
		(layer "B.Cu")
		(net "PCIE_SCC_B_TO_COMP_B_1_DN")
	)
	(segment
		(start 274.60829 -126.37516)
		(end 274.878038 -125.959616)
		(width 0.1651)
		(layer "B.Cu")
		(net "PCIE_SCC_B_TO_COMP_B_1_DN")
	)
	(segment
		(start 263.450578 -146.292824)
		(end 263.593326 -146.216624)
		(width 0.1651)
		(layer "B.Cu")
		(net "PCIE_SCC_B_TO_COMP_B_1_DN")
	)
	(segment
		(start 271.244314 -131.76504)
		(end 271.514062 -131.349496)
		(width 0.1651)
		(layer "B.Cu")
		(net "PCIE_SCC_B_TO_COMP_B_1_DN")
	)
	(segment
		(start 210.41868 -383.454402)
		(end 204.763878 -358.466898)
		(width 0.1651)
		(layer "B.Cu")
		(net "PCIE_SCC_B_TO_COMP_B_1_DN")
	)
	(segment
		(start 274.20316 -126.999238)
		(end 274.375118 -126.962662)
		(width 0.1651)
		(layer "B.Cu")
		(net "PCIE_SCC_B_TO_COMP_B_1_DN")
	)
	(segment
		(start 261.343902 -153.630122)
		(end 261.267702 -153.487374)
		(width 0.1651)
		(layer "B.Cu")
		(net "PCIE_SCC_B_TO_COMP_B_1_DN")
	)
	(segment
		(start 275.725382 -124.883418)
		(end 275.99513 -124.468128)
		(width 0.1651)
		(layer "B.Cu")
		(net "PCIE_SCC_B_TO_COMP_B_1_DN")
	)
	(segment
		(start 263.23925 -147.3835)
		(end 263.383014 -146.909536)
		(width 0.1651)
		(layer "B.Cu")
		(net "PCIE_SCC_B_TO_COMP_B_1_DN")
	)
	(segment
		(start 270.18615 -133.394704)
		(end 270.152622 -133.236462)
		(width 0.1651)
		(layer "B.Cu")
		(net "PCIE_SCC_B_TO_COMP_B_1_DN")
	)
	(segment
		(start 269.094204 -134.866126)
		(end 269.252446 -134.832598)
		(width 0.1651)
		(layer "B.Cu")
		(net "PCIE_SCC_B_TO_COMP_B_1_DN")
	)
	(segment
		(start 275.05025 -125.92304)
		(end 275.319998 -125.50775)
		(width 0.1651)
		(layer "B.Cu")
		(net "PCIE_SCC_B_TO_COMP_B_1_DN")
	)
	(segment
		(start 279.545542 -121.916952)
		(end 279.545542 -121.917206)
		(width 0.1651)
		(layer "B.Cu")
		(net "PCIE_SCC_B_TO_COMP_B_1_DN")
	)
	(segment
		(start 264.15873 -143.95958)
		(end 264.301224 -143.88338)
		(width 0.1651)
		(layer "B.Cu")
		(net "PCIE_SCC_B_TO_COMP_B_1_DN")
	)
	(segment
		(start 275.55317 -124.919994)
		(end 275.725382 -124.883418)
		(width 0.1651)
		(layer "B.Cu")
		(net "PCIE_SCC_B_TO_COMP_B_1_DN")
	)
	(segment
		(start 263.593326 -146.216624)
		(end 263.73709 -145.74266)
		(width 0.1651)
		(layer "B.Cu")
		(net "PCIE_SCC_B_TO_COMP_B_1_DN")
	)
	(segment
		(start 261.41172 -153.01341)
		(end 261.554214 -152.93721)
		(width 0.1651)
		(layer "B.Cu")
		(net "PCIE_SCC_B_TO_COMP_B_1_DN")
	)
	(segment
		(start 263.096756 -147.4597)
		(end 263.23925 -147.3835)
		(width 0.1651)
		(layer "B.Cu")
		(net "PCIE_SCC_B_TO_COMP_B_1_DN")
	)
	(segment
		(start 274.878038 -125.959616)
		(end 275.05025 -125.92304)
		(width 0.1651)
		(layer "B.Cu")
		(net "PCIE_SCC_B_TO_COMP_B_1_DN")
	)
	(segment
		(start 275.99513 -124.468128)
		(end 275.958554 -124.295916)
		(width 0.1651)
		(layer "B.Cu")
		(net "PCIE_SCC_B_TO_COMP_B_1_DN")
	)
	(segment
		(start 269.916402 -133.809994)
		(end 270.18615 -133.394704)
		(width 0.1651)
		(layer "B.Cu")
		(net "PCIE_SCC_B_TO_COMP_B_1_DN")
	)
	(segment
		(start 261.554214 -152.93721)
		(end 261.697978 -152.463246)
		(width 0.1651)
		(layer "B.Cu")
		(net "PCIE_SCC_B_TO_COMP_B_1_DN")
	)
	(segment
		(start 261.057644 -154.180286)
		(end 261.200138 -154.104086)
		(width 0.1651)
		(layer "B.Cu")
		(net "PCIE_SCC_B_TO_COMP_B_1_DN")
	)
	(segment
		(start 263.66089 -145.600166)
		(end 263.804654 -145.126202)
		(width 0.1651)
		(layer "B.Cu")
		(net "PCIE_SCC_B_TO_COMP_B_1_DN")
	)
	(segment
		(start 211.046314 -405.095456)
		(end 208.307432 -392.985244)
		(width 0.1651)
		(layer "B.Cu")
		(net "PCIE_SCC_B_TO_COMP_B_1_DN")
	)
	(segment
		(start 232.622852 -247.899682)
		(end 232.622598 -247.899682)
		(width 0.1651)
		(layer "B.Cu")
		(net "PCIE_SCC_B_TO_COMP_B_1_DN")
	)
	(segment
		(start 269.75816 -133.843522)
		(end 269.916402 -133.809994)
		(width 0.1651)
		(layer "B.Cu")
		(net "PCIE_SCC_B_TO_COMP_B_1_DN")
	)
	(arc
		(start 211.099146 -406.489408)
		(mid 211.059992 -406.426818)
		(end 211.046314 -406.35428)
		(width 0.1651)
		(layer "B.Cu")
		(net "PCIE_SCC_B_TO_COMP_B_1_DN")
	)
	(arc
		(start 211.680552 -406.542494)
		(mid 211.649701 -406.55106)
		(end 211.617814 -406.553924)
		(width 0.1651)
		(layer "B.Cu")
		(net "PCIE_SCC_B_TO_COMP_B_1_DN")
	)
	(arc
		(start 279.173686 -121.646188)
		(mid 279.334943 -121.678264)
		(end 279.471628 -121.769632)
		(width 0.1651)
		(layer "B.Cu")
		(net "PCIE_SCC_B_TO_COMP_B_1_DN")
	)
	(arc
		(start 279.545542 -121.917206)
		(mid 279.554584 -122.043205)
		(end 279.471882 -122.138694)
		(width 0.1651)
		(layer "B.Cu")
		(net "PCIE_SCC_B_TO_COMP_B_1_DN")
	)
	(arc
		(start 211.800186 -406.36952)
		(mid 211.767368 -406.474686)
		(end 211.680552 -406.542494)
		(width 0.1651)
		(layer "B.Cu")
		(net "PCIE_SCC_B_TO_COMP_B_1_DN")
	)
	(arc
		(start 211.245958 -406.553924)
		(mid 211.165771 -406.537089)
		(end 211.099146 -406.489408)
		(width 0.1651)
		(layer "B.Cu")
		(net "PCIE_SCC_B_TO_COMP_B_1_DN")
	)
	(segment
		(start 204.324966 -350.97974)
		(end 202.15606 -341.383112)
		(width 0.1651)
		(layer "B.Cu")
		(net "PCIE_SCC_B_TO_COMP_B_0_DP")
	)
	(segment
		(start 202.730354 -358.18064)
		(end 204.324966 -350.97974)
		(width 0.1651)
		(layer "B.Cu")
		(net "PCIE_SCC_B_TO_COMP_B_0_DP")
	)
	(segment
		(start 209.81543 -407.846022)
		(end 209.44586 -407.846022)
		(width 0.1651)
		(layer "B.Cu")
		(net "PCIE_SCC_B_TO_COMP_B_0_DP")
	)
	(segment
		(start 279.764744 -117.702076)
		(end 279.807162 -117.786912)
		(width 0.1651)
		(layer "B.Cu")
		(net "PCIE_SCC_B_TO_COMP_B_0_DP")
	)
	(segment
		(start 277.318216 -118.044214)
		(end 278.176228 -117.354096)
		(width 0.1651)
		(layer "B.Cu")
		(net "PCIE_SCC_B_TO_COMP_B_0_DP")
	)
	(segment
		(start 210.000088 -408.399996)
		(end 210.000088 -408.03068)
		(width 0.1651)
		(layer "B.Cu")
		(net "PCIE_SCC_B_TO_COMP_B_0_DP")
	)
	(segment
		(start 206.168752 -393.481052)
		(end 208.418684 -383.32283)
		(width 0.1651)
		(layer "B.Cu")
		(net "PCIE_SCC_B_TO_COMP_B_0_DP")
	)
	(segment
		(start 263.43864 -139.41679)
		(end 277.318216 -118.044214)
		(width 0.1651)
		(layer "B.Cu")
		(net "PCIE_SCC_B_TO_COMP_B_0_DP")
	)
	(segment
		(start 280.02865 -117.860826)
		(end 280.75001 -117.499892)
		(width 0.1651)
		(layer "B.Cu")
		(net "PCIE_SCC_B_TO_COMP_B_0_DP")
	)
	(segment
		(start 279.714452 -117.602)
		(end 279.764744 -117.702076)
		(width 0.1651)
		(layer "B.Cu")
		(net "PCIE_SCC_B_TO_COMP_B_0_DP")
	)
	(segment
		(start 278.176228 -117.354096)
		(end 279.17394 -117.354096)
		(width 0.1651)
		(layer "B.Cu")
		(net "PCIE_SCC_B_TO_COMP_B_0_DP")
	)
	(segment
		(start 208.418684 -383.32283)
		(end 202.730354 -358.18064)
		(width 0.1651)
		(layer "B.Cu")
		(net "PCIE_SCC_B_TO_COMP_B_0_DP")
	)
	(segment
		(start 208.954116 -407.354532)
		(end 208.954116 -405.793702)
		(width 0.1651)
		(layer "B.Cu")
		(net "PCIE_SCC_B_TO_COMP_B_0_DP")
	)
	(segment
		(start 202.15606 -341.383112)
		(end 263.43864 -139.41679)
		(width 0.1651)
		(layer "B.Cu")
		(net "PCIE_SCC_B_TO_COMP_B_0_DP")
	)
	(segment
		(start 208.954116 -405.793702)
		(end 206.168752 -393.481052)
		(width 0.1651)
		(layer "B.Cu")
		(net "PCIE_SCC_B_TO_COMP_B_0_DP")
	)
	(arc
		(start 279.807162 -117.786912)
		(mid 279.902579 -117.869724)
		(end 280.02865 -117.860826)
		(width 0.1651)
		(layer "B.Cu")
		(net "PCIE_SCC_B_TO_COMP_B_0_DP")
	)
	(arc
		(start 279.17394 -117.354096)
		(mid 279.471223 -117.419096)
		(end 279.714452 -117.602)
		(width 0.1651)
		(layer "B.Cu")
		(net "PCIE_SCC_B_TO_COMP_B_0_DP")
	)
	(arc
		(start 209.44586 -407.846022)
		(mid 209.248355 -407.804592)
		(end 209.084164 -407.687272)
		(width 0.1651)
		(layer "B.Cu")
		(net "PCIE_SCC_B_TO_COMP_B_0_DP")
	)
	(arc
		(start 209.084164 -407.687272)
		(mid 208.987823 -407.533135)
		(end 208.954116 -407.354532)
		(width 0.1651)
		(layer "B.Cu")
		(net "PCIE_SCC_B_TO_COMP_B_0_DP")
	)
	(arc
		(start 210.000088 -408.03068)
		(mid 209.946003 -407.900107)
		(end 209.81543 -407.846022)
		(width 0.1651)
		(layer "B.Cu")
		(net "PCIE_SCC_B_TO_COMP_B_0_DP")
	)
	(segment
		(start 206.468218 -393.48029)
		(end 208.71815 -383.322068)
		(width 0.1651)
		(layer "B.Cu")
		(net "PCIE_SCC_B_TO_COMP_B_0_DN")
	)
	(segment
		(start 275.684742 -121.324624)
		(end 275.95449 -120.909334)
		(width 0.1651)
		(layer "B.Cu")
		(net "PCIE_SCC_B_TO_COMP_B_0_DN")
	)
	(segment
		(start 279.471882 -118.138702)
		(end 278.750014 -118.49989)
		(width 0.1651)
		(layer "B.Cu")
		(net "PCIE_SCC_B_TO_COMP_B_0_DN")
	)
	(segment
		(start 275.00961 -122.364246)
		(end 275.279612 -121.948702)
		(width 0.1651)
		(layer "B.Cu")
		(net "PCIE_SCC_B_TO_COMP_B_0_DN")
	)
	(segment
		(start 275.51253 -121.3612)
		(end 275.684742 -121.324624)
		(width 0.1651)
		(layer "B.Cu")
		(net "PCIE_SCC_B_TO_COMP_B_0_DN")
	)
	(segment
		(start 263.140952 -141.798294)
		(end 263.284716 -141.32433)
		(width 0.1651)
		(layer "B.Cu")
		(net "PCIE_SCC_B_TO_COMP_B_0_DN")
	)
	(segment
		(start 263.562592 -140.015214)
		(end 263.562846 -140.014452)
		(width 0.1651)
		(layer "B.Cu")
		(net "PCIE_SCC_B_TO_COMP_B_0_DN")
	)
	(segment
		(start 265.003534 -137.753852)
		(end 264.970006 -137.59561)
		(width 0.1651)
		(layer "B.Cu")
		(net "PCIE_SCC_B_TO_COMP_B_0_DN")
	)
	(segment
		(start 274.837652 -122.400822)
		(end 275.00961 -122.364246)
		(width 0.1651)
		(layer "B.Cu")
		(net "PCIE_SCC_B_TO_COMP_B_0_DN")
	)
	(segment
		(start 266.725908 -135.101584)
		(end 266.995656 -134.686294)
		(width 0.1651)
		(layer "B.Cu")
		(net "PCIE_SCC_B_TO_COMP_B_0_DN")
	)
	(segment
		(start 270.820642 -128.796288)
		(end 270.787114 -128.638046)
		(width 0.1651)
		(layer "B.Cu")
		(net "PCIE_SCC_B_TO_COMP_B_0_DN")
	)
	(segment
		(start 209.246216 -405.760936)
		(end 206.468218 -393.48029)
		(width 0.1651)
		(layer "B.Cu")
		(net "PCIE_SCC_B_TO_COMP_B_0_DN")
	)
	(segment
		(start 270.156686 -129.818638)
		(end 270.122904 -129.66065)
		(width 0.1651)
		(layer "B.Cu")
		(net "PCIE_SCC_B_TO_COMP_B_0_DN")
	)
	(segment
		(start 276.629622 -119.869712)
		(end 276.593046 -119.6975)
		(width 0.1651)
		(layer "B.Cu")
		(net "PCIE_SCC_B_TO_COMP_B_0_DN")
	)
	(segment
		(start 271.878806 -127.166624)
		(end 272.148554 -126.75108)
		(width 0.1651)
		(layer "B.Cu")
		(net "PCIE_SCC_B_TO_COMP_B_0_DN")
	)
	(segment
		(start 203.02982 -358.179878)
		(end 204.624432 -350.978978)
		(width 0.1651)
		(layer "B.Cu")
		(net "PCIE_SCC_B_TO_COMP_B_0_DN")
	)
	(segment
		(start 276.359874 -120.285002)
		(end 276.629622 -119.869712)
		(width 0.1651)
		(layer "B.Cu")
		(net "PCIE_SCC_B_TO_COMP_B_0_DN")
	)
	(segment
		(start 265.239754 -137.18032)
		(end 265.397742 -137.146538)
		(width 0.1651)
		(layer "B.Cu")
		(net "PCIE_SCC_B_TO_COMP_B_0_DN")
	)
	(segment
		(start 202.458066 -341.394034)
		(end 262.998458 -141.874494)
		(width 0.1651)
		(layer "B.Cu")
		(net "PCIE_SCC_B_TO_COMP_B_0_DN")
	)
	(segment
		(start 265.66749 -136.731248)
		(end 265.633962 -136.57326)
		(width 0.1651)
		(layer "B.Cu")
		(net "PCIE_SCC_B_TO_COMP_B_0_DN")
	)
	(segment
		(start 264.575544 -138.20267)
		(end 264.733786 -138.169142)
		(width 0.1651)
		(layer "B.Cu")
		(net "PCIE_SCC_B_TO_COMP_B_0_DN")
	)
	(segment
		(start 270.787114 -128.638046)
		(end 271.056862 -128.222756)
		(width 0.1651)
		(layer "B.Cu")
		(net "PCIE_SCC_B_TO_COMP_B_0_DN")
	)
	(segment
		(start 275.917914 -120.737122)
		(end 276.187662 -120.321578)
		(width 0.1651)
		(layer "B.Cu")
		(net "PCIE_SCC_B_TO_COMP_B_0_DN")
	)
	(segment
		(start 210.000088 -407.000202)
		(end 210.000088 -407.369518)
		(width 0.1651)
		(layer "B.Cu")
		(net "PCIE_SCC_B_TO_COMP_B_0_DN")
	)
	(segment
		(start 264.970006 -137.59561)
		(end 265.239754 -137.18032)
		(width 0.1651)
		(layer "B.Cu")
		(net "PCIE_SCC_B_TO_COMP_B_0_DN")
	)
	(segment
		(start 275.95449 -120.909334)
		(end 275.917914 -120.737122)
		(width 0.1651)
		(layer "B.Cu")
		(net "PCIE_SCC_B_TO_COMP_B_0_DN")
	)
	(segment
		(start 279.545542 -117.91696)
		(end 279.545542 -117.917214)
		(width 0.1651)
		(layer "B.Cu")
		(net "PCIE_SCC_B_TO_COMP_B_0_DN")
	)
	(segment
		(start 266.567666 -135.135366)
		(end 266.725908 -135.101584)
		(width 0.1651)
		(layer "B.Cu")
		(net "PCIE_SCC_B_TO_COMP_B_0_DN")
	)
	(segment
		(start 208.71815 -383.322068)
		(end 203.02982 -358.179878)
		(width 0.1651)
		(layer "B.Cu")
		(net "PCIE_SCC_B_TO_COMP_B_0_DN")
	)
	(segment
		(start 269.728696 -130.26771)
		(end 269.886938 -130.234182)
		(width 0.1651)
		(layer "B.Cu")
		(net "PCIE_SCC_B_TO_COMP_B_0_DN")
	)
	(segment
		(start 266.995656 -134.686294)
		(end 266.961874 -134.528052)
		(width 0.1651)
		(layer "B.Cu")
		(net "PCIE_SCC_B_TO_COMP_B_0_DN")
	)
	(segment
		(start 271.484598 -127.773684)
		(end 271.45107 -127.615696)
		(width 0.1651)
		(layer "B.Cu")
		(net "PCIE_SCC_B_TO_COMP_B_0_DN")
	)
	(segment
		(start 272.115026 -126.593092)
		(end 274.837652 -122.400822)
		(width 0.1651)
		(layer "B.Cu")
		(net "PCIE_SCC_B_TO_COMP_B_0_DN")
	)
	(segment
		(start 270.122904 -129.66065)
		(end 270.392652 -129.245106)
		(width 0.1651)
		(layer "B.Cu")
		(net "PCIE_SCC_B_TO_COMP_B_0_DN")
	)
	(segment
		(start 266.961874 -134.528052)
		(end 269.728696 -130.26771)
		(width 0.1651)
		(layer "B.Cu")
		(net "PCIE_SCC_B_TO_COMP_B_0_DN")
	)
	(segment
		(start 276.593046 -119.6975)
		(end 277.537926 -118.242588)
		(width 0.1651)
		(layer "B.Cu")
		(net "PCIE_SCC_B_TO_COMP_B_0_DN")
	)
	(segment
		(start 263.562846 -140.014452)
		(end 263.706356 -139.54125)
		(width 0.1651)
		(layer "B.Cu")
		(net "PCIE_SCC_B_TO_COMP_B_0_DN")
	)
	(segment
		(start 263.638792 -140.157708)
		(end 263.562592 -140.015214)
		(width 0.1651)
		(layer "B.Cu")
		(net "PCIE_SCC_B_TO_COMP_B_0_DN")
	)
	(segment
		(start 263.706356 -139.54125)
		(end 264.575544 -138.20267)
		(width 0.1651)
		(layer "B.Cu")
		(net "PCIE_SCC_B_TO_COMP_B_0_DN")
	)
	(segment
		(start 263.495028 -140.631672)
		(end 263.638792 -140.157708)
		(width 0.1651)
		(layer "B.Cu")
		(net "PCIE_SCC_B_TO_COMP_B_0_DN")
	)
	(segment
		(start 271.45107 -127.615696)
		(end 271.720818 -127.200152)
		(width 0.1651)
		(layer "B.Cu")
		(net "PCIE_SCC_B_TO_COMP_B_0_DN")
	)
	(segment
		(start 272.148554 -126.75108)
		(end 272.115026 -126.593092)
		(width 0.1651)
		(layer "B.Cu")
		(net "PCIE_SCC_B_TO_COMP_B_0_DN")
	)
	(segment
		(start 266.061698 -136.124188)
		(end 266.331446 -135.708644)
		(width 0.1651)
		(layer "B.Cu")
		(net "PCIE_SCC_B_TO_COMP_B_0_DN")
	)
	(segment
		(start 263.208516 -141.181836)
		(end 263.35228 -140.707872)
		(width 0.1651)
		(layer "B.Cu")
		(net "PCIE_SCC_B_TO_COMP_B_0_DN")
	)
	(segment
		(start 263.35228 -140.707872)
		(end 263.495028 -140.631672)
		(width 0.1651)
		(layer "B.Cu")
		(net "PCIE_SCC_B_TO_COMP_B_0_DN")
	)
	(segment
		(start 278.279352 -117.646196)
		(end 279.173686 -117.646196)
		(width 0.1651)
		(layer "B.Cu")
		(net "PCIE_SCC_B_TO_COMP_B_0_DN")
	)
	(segment
		(start 209.246216 -407.354278)
		(end 209.246216 -405.760936)
		(width 0.1651)
		(layer "B.Cu")
		(net "PCIE_SCC_B_TO_COMP_B_0_DN")
	)
	(segment
		(start 209.817716 -407.553922)
		(end 209.44586 -407.553922)
		(width 0.1651)
		(layer "B.Cu")
		(net "PCIE_SCC_B_TO_COMP_B_0_DN")
	)
	(segment
		(start 271.720818 -127.200152)
		(end 271.878806 -127.166624)
		(width 0.1651)
		(layer "B.Cu")
		(net "PCIE_SCC_B_TO_COMP_B_0_DN")
	)
	(segment
		(start 204.624432 -350.978978)
		(end 202.458066 -341.394034)
		(width 0.1651)
		(layer "B.Cu")
		(net "PCIE_SCC_B_TO_COMP_B_0_DN")
	)
	(segment
		(start 265.90371 -136.157716)
		(end 266.061698 -136.124188)
		(width 0.1651)
		(layer "B.Cu")
		(net "PCIE_SCC_B_TO_COMP_B_0_DN")
	)
	(segment
		(start 266.331446 -135.708644)
		(end 266.297918 -135.550656)
		(width 0.1651)
		(layer "B.Cu")
		(net "PCIE_SCC_B_TO_COMP_B_0_DN")
	)
	(segment
		(start 265.633962 -136.57326)
		(end 265.90371 -136.157716)
		(width 0.1651)
		(layer "B.Cu")
		(net "PCIE_SCC_B_TO_COMP_B_0_DN")
	)
	(segment
		(start 275.242782 -121.776744)
		(end 275.51253 -121.3612)
		(width 0.1651)
		(layer "B.Cu")
		(net "PCIE_SCC_B_TO_COMP_B_0_DN")
	)
	(segment
		(start 271.056862 -128.222756)
		(end 271.21485 -128.188974)
		(width 0.1651)
		(layer "B.Cu")
		(net "PCIE_SCC_B_TO_COMP_B_0_DN")
	)
	(segment
		(start 266.297918 -135.550656)
		(end 266.567666 -135.135366)
		(width 0.1651)
		(layer "B.Cu")
		(net "PCIE_SCC_B_TO_COMP_B_0_DN")
	)
	(segment
		(start 262.998458 -141.874494)
		(end 263.140952 -141.798294)
		(width 0.1651)
		(layer "B.Cu")
		(net "PCIE_SCC_B_TO_COMP_B_0_DN")
	)
	(segment
		(start 263.284716 -141.32433)
		(end 263.208516 -141.181836)
		(width 0.1651)
		(layer "B.Cu")
		(net "PCIE_SCC_B_TO_COMP_B_0_DN")
	)
	(segment
		(start 270.550894 -129.211578)
		(end 270.820642 -128.796288)
		(width 0.1651)
		(layer "B.Cu")
		(net "PCIE_SCC_B_TO_COMP_B_0_DN")
	)
	(segment
		(start 265.397742 -137.146538)
		(end 265.66749 -136.731248)
		(width 0.1651)
		(layer "B.Cu")
		(net "PCIE_SCC_B_TO_COMP_B_0_DN")
	)
	(segment
		(start 276.187662 -120.321578)
		(end 276.359874 -120.285002)
		(width 0.1651)
		(layer "B.Cu")
		(net "PCIE_SCC_B_TO_COMP_B_0_DN")
	)
	(segment
		(start 264.733786 -138.169142)
		(end 265.003534 -137.753852)
		(width 0.1651)
		(layer "B.Cu")
		(net "PCIE_SCC_B_TO_COMP_B_0_DN")
	)
	(segment
		(start 279.471628 -117.76964)
		(end 279.545542 -117.91696)
		(width 0.1651)
		(layer "B.Cu")
		(net "PCIE_SCC_B_TO_COMP_B_0_DN")
	)
	(segment
		(start 269.886938 -130.234182)
		(end 270.156686 -129.818638)
		(width 0.1651)
		(layer "B.Cu")
		(net "PCIE_SCC_B_TO_COMP_B_0_DN")
	)
	(segment
		(start 271.21485 -128.188974)
		(end 271.484598 -127.773684)
		(width 0.1651)
		(layer "B.Cu")
		(net "PCIE_SCC_B_TO_COMP_B_0_DN")
	)
	(segment
		(start 275.279612 -121.948702)
		(end 275.242782 -121.776744)
		(width 0.1651)
		(layer "B.Cu")
		(net "PCIE_SCC_B_TO_COMP_B_0_DN")
	)
	(segment
		(start 270.392652 -129.245106)
		(end 270.550894 -129.211578)
		(width 0.1651)
		(layer "B.Cu")
		(net "PCIE_SCC_B_TO_COMP_B_0_DN")
	)
	(segment
		(start 277.537926 -118.242588)
		(end 278.279352 -117.646196)
		(width 0.1651)
		(layer "B.Cu")
		(net "PCIE_SCC_B_TO_COMP_B_0_DN")
	)
	(arc
		(start 210.000088 -407.369518)
		(mid 209.96727 -407.474684)
		(end 209.880454 -407.542492)
		(width 0.1651)
		(layer "B.Cu")
		(net "PCIE_SCC_B_TO_COMP_B_0_DN")
	)
	(arc
		(start 279.545542 -117.917214)
		(mid 279.554584 -118.043213)
		(end 279.471882 -118.138702)
		(width 0.1651)
		(layer "B.Cu")
		(net "PCIE_SCC_B_TO_COMP_B_0_DN")
	)
	(arc
		(start 209.299048 -407.489406)
		(mid 209.259894 -407.426816)
		(end 209.246216 -407.354278)
		(width 0.1651)
		(layer "B.Cu")
		(net "PCIE_SCC_B_TO_COMP_B_0_DN")
	)
	(arc
		(start 279.173686 -117.646196)
		(mid 279.334943 -117.678272)
		(end 279.471628 -117.76964)
		(width 0.1651)
		(layer "B.Cu")
		(net "PCIE_SCC_B_TO_COMP_B_0_DN")
	)
	(arc
		(start 209.880454 -407.542492)
		(mid 209.849603 -407.551058)
		(end 209.817716 -407.553922)
		(width 0.1651)
		(layer "B.Cu")
		(net "PCIE_SCC_B_TO_COMP_B_0_DN")
	)
	(arc
		(start 209.44586 -407.553922)
		(mid 209.365673 -407.537087)
		(end 209.299048 -407.489406)
		(width 0.1651)
		(layer "B.Cu")
		(net "PCIE_SCC_B_TO_COMP_B_0_DN")
	)
	(segment
		(start 237.230158 -192.064132)
		(end 232.479342 -173.56455)
		(width 0.127)
		(layer "In7.Cu")
		(net "PCIE_SCC_A_TO_COMP_A_7_DP")
	)
	(segment
		(start 232.479342 -173.56455)
		(end 232.440226 -173.505368)
		(width 0.127)
		(layer "In7.Cu")
		(net "PCIE_SCC_A_TO_COMP_A_7_DP")
	)
	(segment
		(start 234.824016 -161.79927)
		(end 235.544106 -161.360866)
		(width 0.127)
		(layer "In7.Cu")
		(net "PCIE_SCC_A_TO_COMP_A_7_DP")
	)
	(segment
		(start 235.544106 -161.360866)
		(end 235.544106 -161.360612)
		(width 0.127)
		(layer "In7.Cu")
		(net "PCIE_SCC_A_TO_COMP_A_7_DP")
	)
	(segment
		(start 234.824016 -161.799016)
		(end 234.824016 -161.79927)
		(width 0.127)
		(layer "In7.Cu")
		(net "PCIE_SCC_A_TO_COMP_A_7_DP")
	)
	(segment
		(start 279.636728 -251.102368)
		(end 279.203404 -251.102368)
		(width 0.127)
		(layer "In7.Cu")
		(net "PCIE_SCC_A_TO_COMP_A_7_DP")
	)
	(segment
		(start 271.533874 -248.466864)
		(end 271.534128 -248.466864)
		(width 0.127)
		(layer "In7.Cu")
		(net "PCIE_SCC_A_TO_COMP_A_7_DP")
	)
	(segment
		(start 233.575352 -167.93083)
		(end 233.575606 -167.930576)
		(width 0.127)
		(layer "In7.Cu")
		(net "PCIE_SCC_A_TO_COMP_A_7_DP")
	)
	(segment
		(start 271.534128 -248.466864)
		(end 237.230158 -192.064132)
		(width 0.127)
		(layer "In7.Cu")
		(net "PCIE_SCC_A_TO_COMP_A_7_DP")
	)
	(segment
		(start 232.440226 -173.505368)
		(end 233.575352 -167.93083)
		(width 0.127)
		(layer "In7.Cu")
		(net "PCIE_SCC_A_TO_COMP_A_7_DP")
	)
	(segment
		(start 235.544106 -161.360612)
		(end 236.437678 -161.360612)
		(width 0.127)
		(layer "In7.Cu")
		(net "PCIE_SCC_A_TO_COMP_A_7_DP")
	)
	(segment
		(start 278.637746 -252.14199)
		(end 276.964648 -252.14199)
		(width 0.127)
		(layer "In7.Cu")
		(net "PCIE_SCC_A_TO_COMP_A_7_DP")
	)
	(segment
		(start 237.324138 -161.863278)
		(end 238.05007 -161.499804)
		(width 0.127)
		(layer "In7.Cu")
		(net "PCIE_SCC_A_TO_COMP_A_7_DP")
	)
	(segment
		(start 279.076404 -251.229368)
		(end 279.076404 -251.703332)
		(width 0.127)
		(layer "In7.Cu")
		(net "PCIE_SCC_A_TO_COMP_A_7_DP")
	)
	(segment
		(start 276.964648 -252.14199)
		(end 271.533874 -248.466864)
		(width 0.127)
		(layer "In7.Cu")
		(net "PCIE_SCC_A_TO_COMP_A_7_DP")
	)
	(segment
		(start 233.575606 -167.930576)
		(end 234.824016 -161.799016)
		(width 0.127)
		(layer "In7.Cu")
		(net "PCIE_SCC_A_TO_COMP_A_7_DP")
	)
	(segment
		(start 236.840776 -161.52749)
		(end 237.148116 -161.83483)
		(width 0.127)
		(layer "In7.Cu")
		(net "PCIE_SCC_A_TO_COMP_A_7_DP")
	)
	(arc
		(start 279.203404 -251.102368)
		(mid 279.113601 -251.139565)
		(end 279.076404 -251.229368)
		(width 0.127)
		(layer "In7.Cu")
		(net "PCIE_SCC_A_TO_COMP_A_7_DP")
	)
	(arc
		(start 237.148116 -161.83483)
		(mid 237.231528 -161.877491)
		(end 237.324138 -161.863278)
		(width 0.127)
		(layer "In7.Cu")
		(net "PCIE_SCC_A_TO_COMP_A_7_DP")
	)
	(arc
		(start 236.437678 -161.360612)
		(mid 236.655798 -161.403999)
		(end 236.840776 -161.52749)
		(width 0.127)
		(layer "In7.Cu")
		(net "PCIE_SCC_A_TO_COMP_A_7_DP")
	)
	(arc
		(start 279.076404 -251.703332)
		(mid 278.947924 -252.01351)
		(end 278.637746 -252.14199)
		(width 0.127)
		(layer "In7.Cu")
		(net "PCIE_SCC_A_TO_COMP_A_7_DP")
	)
	(segment
		(start 236.643164 -161.725102)
		(end 236.836966 -161.918904)
		(width 0.127)
		(layer "In7.Cu")
		(net "PCIE_SCC_A_TO_COMP_A_7_DN")
	)
	(segment
		(start 271.543272 -247.943878)
		(end 271.590008 -247.752108)
		(width 0.127)
		(layer "In7.Cu")
		(net "PCIE_SCC_A_TO_COMP_A_7_DN")
	)
	(segment
		(start 235.073698 -161.97453)
		(end 235.622592 -161.640266)
		(width 0.127)
		(layer "In7.Cu")
		(net "PCIE_SCC_A_TO_COMP_A_7_DN")
	)
	(segment
		(start 273.089624 -249.182128)
		(end 271.741138 -248.269506)
		(width 0.127)
		(layer "In7.Cu")
		(net "PCIE_SCC_A_TO_COMP_A_7_DN")
	)
	(segment
		(start 266.052554 -238.91621)
		(end 265.854434 -238.590582)
		(width 0.127)
		(layer "In7.Cu")
		(net "PCIE_SCC_A_TO_COMP_A_7_DN")
	)
	(segment
		(start 261.236968 -230.998268)
		(end 261.283704 -230.806498)
		(width 0.127)
		(layer "In7.Cu")
		(net "PCIE_SCC_A_TO_COMP_A_7_DN")
	)
	(segment
		(start 270.309594 -245.646956)
		(end 270.11757 -245.60022)
		(width 0.127)
		(layer "In7.Cu")
		(net "PCIE_SCC_A_TO_COMP_A_7_DN")
	)
	(segment
		(start 274.176998 -249.737118)
		(end 273.968972 -249.776996)
		(width 0.127)
		(layer "In7.Cu")
		(net "PCIE_SCC_A_TO_COMP_A_7_DN")
	)
	(segment
		(start 278.23668 -251.102368)
		(end 278.670004 -251.102368)
		(width 0.127)
		(layer "In7.Cu")
		(net "PCIE_SCC_A_TO_COMP_A_7_DN")
	)
	(segment
		(start 275.411946 -250.753626)
		(end 275.371814 -250.5456)
		(width 0.127)
		(layer "In7.Cu")
		(net "PCIE_SCC_A_TO_COMP_A_7_DN")
	)
	(segment
		(start 270.658844 -246.489982)
		(end 270.460978 -246.164354)
		(width 0.127)
		(layer "In7.Cu")
		(net "PCIE_SCC_A_TO_COMP_A_7_DN")
	)
	(segment
		(start 260.20141 -229.026974)
		(end 260.003544 -228.701346)
		(width 0.127)
		(layer "In7.Cu")
		(net "PCIE_SCC_A_TO_COMP_A_7_DN")
	)
	(segment
		(start 271.048734 -246.862346)
		(end 270.850868 -246.536718)
		(width 0.127)
		(layer "In7.Cu")
		(net "PCIE_SCC_A_TO_COMP_A_7_DN")
	)
	(segment
		(start 269.57655 -244.710458)
		(end 266.936728 -240.370106)
		(width 0.127)
		(layer "In7.Cu")
		(net "PCIE_SCC_A_TO_COMP_A_7_DN")
	)
	(segment
		(start 265.854434 -238.590582)
		(end 265.90117 -238.398812)
		(width 0.127)
		(layer "In7.Cu")
		(net "PCIE_SCC_A_TO_COMP_A_7_DN")
	)
	(segment
		(start 266.593574 -239.805972)
		(end 266.395708 -239.480344)
		(width 0.127)
		(layer "In7.Cu")
		(net "PCIE_SCC_A_TO_COMP_A_7_DN")
	)
	(segment
		(start 237.490508 -191.954404)
		(end 232.738422 -173.449488)
		(width 0.127)
		(layer "In7.Cu")
		(net "PCIE_SCC_A_TO_COMP_A_7_DN")
	)
	(segment
		(start 265.90117 -238.398812)
		(end 265.703304 -238.073184)
		(width 0.127)
		(layer "In7.Cu")
		(net "PCIE_SCC_A_TO_COMP_A_7_DN")
	)
	(segment
		(start 269.96644 -245.082822)
		(end 269.768574 -244.757194)
		(width 0.127)
		(layer "In7.Cu")
		(net "PCIE_SCC_A_TO_COMP_A_7_DN")
	)
	(segment
		(start 235.70946 -161.640012)
		(end 236.437678 -161.640012)
		(width 0.127)
		(layer "In7.Cu")
		(net "PCIE_SCC_A_TO_COMP_A_7_DN")
	)
	(segment
		(start 271.590008 -247.752108)
		(end 271.391888 -247.42648)
		(width 0.127)
		(layer "In7.Cu")
		(net "PCIE_SCC_A_TO_COMP_A_7_DN")
	)
	(segment
		(start 266.983464 -240.178336)
		(end 266.785598 -239.852708)
		(width 0.127)
		(layer "In7.Cu")
		(net "PCIE_SCC_A_TO_COMP_A_7_DN")
	)
	(segment
		(start 235.70946 -161.640266)
		(end 235.70946 -161.640012)
		(width 0.127)
		(layer "In7.Cu")
		(net "PCIE_SCC_A_TO_COMP_A_7_DN")
	)
	(segment
		(start 260.154674 -229.218998)
		(end 260.20141 -229.026974)
		(width 0.127)
		(layer "In7.Cu")
		(net "PCIE_SCC_A_TO_COMP_A_7_DN")
	)
	(segment
		(start 260.74243 -229.916736)
		(end 260.544564 -229.591108)
		(width 0.127)
		(layer "In7.Cu")
		(net "PCIE_SCC_A_TO_COMP_A_7_DN")
	)
	(segment
		(start 275.056346 -250.331986)
		(end 274.848066 -250.372118)
		(width 0.127)
		(layer "In7.Cu")
		(net "PCIE_SCC_A_TO_COMP_A_7_DN")
	)
	(segment
		(start 274.848066 -250.372118)
		(end 274.532598 -250.158758)
		(width 0.127)
		(layer "In7.Cu")
		(net "PCIE_SCC_A_TO_COMP_A_7_DN")
	)
	(segment
		(start 265.16203 -237.183422)
		(end 264.97026 -237.136686)
		(width 0.127)
		(layer "In7.Cu")
		(net "PCIE_SCC_A_TO_COMP_A_7_DN")
	)
	(segment
		(start 260.003544 -228.701346)
		(end 259.81152 -228.65461)
		(width 0.127)
		(layer "In7.Cu")
		(net "PCIE_SCC_A_TO_COMP_A_7_DN")
	)
	(segment
		(start 260.893814 -230.434134)
		(end 260.695694 -230.108506)
		(width 0.127)
		(layer "In7.Cu")
		(net "PCIE_SCC_A_TO_COMP_A_7_DN")
	)
	(segment
		(start 269.768574 -244.757194)
		(end 269.57655 -244.710458)
		(width 0.127)
		(layer "In7.Cu")
		(net "PCIE_SCC_A_TO_COMP_A_7_DN")
	)
	(segment
		(start 236.803946 -162.122104)
		(end 236.79404 -162.127184)
		(width 0.127)
		(layer "In7.Cu")
		(net "PCIE_SCC_A_TO_COMP_A_7_DN")
	)
	(segment
		(start 232.737152 -173.44771)
		(end 233.8324 -168.069006)
		(width 0.127)
		(layer "In7.Cu")
		(net "PCIE_SCC_A_TO_COMP_A_7_DN")
	)
	(segment
		(start 233.832654 -168.068752)
		(end 233.849418 -167.986456)
		(width 0.127)
		(layer "In7.Cu")
		(net "PCIE_SCC_A_TO_COMP_A_7_DN")
	)
	(segment
		(start 273.968972 -249.776996)
		(end 273.65325 -249.563636)
		(width 0.127)
		(layer "In7.Cu")
		(net "PCIE_SCC_A_TO_COMP_A_7_DN")
	)
	(segment
		(start 260.35254 -229.544372)
		(end 260.154674 -229.218998)
		(width 0.127)
		(layer "In7.Cu")
		(net "PCIE_SCC_A_TO_COMP_A_7_DN")
	)
	(segment
		(start 270.11757 -245.60022)
		(end 269.919704 -245.274592)
		(width 0.127)
		(layer "In7.Cu")
		(net "PCIE_SCC_A_TO_COMP_A_7_DN")
	)
	(segment
		(start 273.65325 -249.563636)
		(end 273.613118 -249.355356)
		(width 0.127)
		(layer "In7.Cu")
		(net "PCIE_SCC_A_TO_COMP_A_7_DN")
	)
	(segment
		(start 264.97026 -237.136686)
		(end 261.236968 -230.998268)
		(width 0.127)
		(layer "In7.Cu")
		(net "PCIE_SCC_A_TO_COMP_A_7_DN")
	)
	(segment
		(start 271.199864 -247.379744)
		(end 271.001998 -247.054116)
		(width 0.127)
		(layer "In7.Cu")
		(net "PCIE_SCC_A_TO_COMP_A_7_DN")
	)
	(segment
		(start 269.919704 -245.274592)
		(end 269.96644 -245.082822)
		(width 0.127)
		(layer "In7.Cu")
		(net "PCIE_SCC_A_TO_COMP_A_7_DN")
	)
	(segment
		(start 233.849418 -167.986456)
		(end 233.849418 -167.986202)
		(width 0.127)
		(layer "In7.Cu")
		(net "PCIE_SCC_A_TO_COMP_A_7_DN")
	)
	(segment
		(start 275.371814 -250.5456)
		(end 275.056346 -250.331986)
		(width 0.127)
		(layer "In7.Cu")
		(net "PCIE_SCC_A_TO_COMP_A_7_DN")
	)
	(segment
		(start 266.395708 -239.480344)
		(end 266.442444 -239.288574)
		(width 0.127)
		(layer "In7.Cu")
		(net "PCIE_SCC_A_TO_COMP_A_7_DN")
	)
	(segment
		(start 274.492466 -249.950478)
		(end 274.176998 -249.737118)
		(width 0.127)
		(layer "In7.Cu")
		(net "PCIE_SCC_A_TO_COMP_A_7_DN")
	)
	(segment
		(start 232.738422 -173.449488)
		(end 232.737152 -173.44771)
		(width 0.127)
		(layer "In7.Cu")
		(net "PCIE_SCC_A_TO_COMP_A_7_DN")
	)
	(segment
		(start 266.244324 -238.962946)
		(end 266.052554 -238.91621)
		(width 0.127)
		(layer "In7.Cu")
		(net "PCIE_SCC_A_TO_COMP_A_7_DN")
	)
	(segment
		(start 265.703304 -238.073184)
		(end 265.51128 -238.026448)
		(width 0.127)
		(layer "In7.Cu")
		(net "PCIE_SCC_A_TO_COMP_A_7_DN")
	)
	(segment
		(start 271.391888 -247.42648)
		(end 271.199864 -247.379744)
		(width 0.127)
		(layer "In7.Cu")
		(net "PCIE_SCC_A_TO_COMP_A_7_DN")
	)
	(segment
		(start 278.797004 -251.229368)
		(end 278.797004 -251.703332)
		(width 0.127)
		(layer "In7.Cu")
		(net "PCIE_SCC_A_TO_COMP_A_7_DN")
	)
	(segment
		(start 265.36015 -237.50905)
		(end 265.16203 -237.183422)
		(width 0.127)
		(layer "In7.Cu")
		(net "PCIE_SCC_A_TO_COMP_A_7_DN")
	)
	(segment
		(start 277.0505 -251.86259)
		(end 275.411946 -250.753626)
		(width 0.127)
		(layer "In7.Cu")
		(net "PCIE_SCC_A_TO_COMP_A_7_DN")
	)
	(segment
		(start 233.849418 -167.986202)
		(end 235.073698 -161.97453)
		(width 0.127)
		(layer "In7.Cu")
		(net "PCIE_SCC_A_TO_COMP_A_7_DN")
	)
	(segment
		(start 266.785598 -239.852708)
		(end 266.593574 -239.805972)
		(width 0.127)
		(layer "In7.Cu")
		(net "PCIE_SCC_A_TO_COMP_A_7_DN")
	)
	(segment
		(start 259.81152 -228.65461)
		(end 237.490508 -191.954404)
		(width 0.127)
		(layer "In7.Cu")
		(net "PCIE_SCC_A_TO_COMP_A_7_DN")
	)
	(segment
		(start 274.532598 -250.158758)
		(end 274.492466 -249.950478)
		(width 0.127)
		(layer "In7.Cu")
		(net "PCIE_SCC_A_TO_COMP_A_7_DN")
	)
	(segment
		(start 270.850868 -246.536718)
		(end 270.658844 -246.489982)
		(width 0.127)
		(layer "In7.Cu")
		(net "PCIE_SCC_A_TO_COMP_A_7_DN")
	)
	(segment
		(start 233.8324 -168.069006)
		(end 233.832654 -168.068752)
		(width 0.127)
		(layer "In7.Cu")
		(net "PCIE_SCC_A_TO_COMP_A_7_DN")
	)
	(segment
		(start 270.460978 -246.164354)
		(end 270.507714 -245.972584)
		(width 0.127)
		(layer "In7.Cu")
		(net "PCIE_SCC_A_TO_COMP_A_7_DN")
	)
	(segment
		(start 271.001998 -247.054116)
		(end 271.048734 -246.862346)
		(width 0.127)
		(layer "In7.Cu")
		(net "PCIE_SCC_A_TO_COMP_A_7_DN")
	)
	(segment
		(start 235.622592 -161.640266)
		(end 235.70946 -161.640266)
		(width 0.127)
		(layer "In7.Cu")
		(net "PCIE_SCC_A_TO_COMP_A_7_DN")
	)
	(segment
		(start 265.313414 -237.70082)
		(end 265.36015 -237.50905)
		(width 0.127)
		(layer "In7.Cu")
		(net "PCIE_SCC_A_TO_COMP_A_7_DN")
	)
	(segment
		(start 236.79404 -162.127184)
		(end 236.050074 -162.499802)
		(width 0.127)
		(layer "In7.Cu")
		(net "PCIE_SCC_A_TO_COMP_A_7_DN")
	)
	(segment
		(start 266.936728 -240.370106)
		(end 266.983464 -240.178336)
		(width 0.127)
		(layer "In7.Cu")
		(net "PCIE_SCC_A_TO_COMP_A_7_DN")
	)
	(segment
		(start 260.544564 -229.591108)
		(end 260.35254 -229.544372)
		(width 0.127)
		(layer "In7.Cu")
		(net "PCIE_SCC_A_TO_COMP_A_7_DN")
	)
	(segment
		(start 265.51128 -238.026448)
		(end 265.313414 -237.70082)
		(width 0.127)
		(layer "In7.Cu")
		(net "PCIE_SCC_A_TO_COMP_A_7_DN")
	)
	(segment
		(start 273.29765 -249.141996)
		(end 273.089624 -249.182128)
		(width 0.127)
		(layer "In7.Cu")
		(net "PCIE_SCC_A_TO_COMP_A_7_DN")
	)
	(segment
		(start 266.442444 -239.288574)
		(end 266.244324 -238.962946)
		(width 0.127)
		(layer "In7.Cu")
		(net "PCIE_SCC_A_TO_COMP_A_7_DN")
	)
	(segment
		(start 261.283704 -230.806498)
		(end 261.085838 -230.48087)
		(width 0.127)
		(layer "In7.Cu")
		(net "PCIE_SCC_A_TO_COMP_A_7_DN")
	)
	(segment
		(start 260.695694 -230.108506)
		(end 260.74243 -229.916736)
		(width 0.127)
		(layer "In7.Cu")
		(net "PCIE_SCC_A_TO_COMP_A_7_DN")
	)
	(segment
		(start 271.741138 -248.269506)
		(end 271.543272 -247.943878)
		(width 0.127)
		(layer "In7.Cu")
		(net "PCIE_SCC_A_TO_COMP_A_7_DN")
	)
	(segment
		(start 261.085838 -230.48087)
		(end 260.893814 -230.434134)
		(width 0.127)
		(layer "In7.Cu")
		(net "PCIE_SCC_A_TO_COMP_A_7_DN")
	)
	(segment
		(start 278.637746 -251.86259)
		(end 277.0505 -251.86259)
		(width 0.127)
		(layer "In7.Cu")
		(net "PCIE_SCC_A_TO_COMP_A_7_DN")
	)
	(segment
		(start 270.507714 -245.972584)
		(end 270.309594 -245.646956)
		(width 0.127)
		(layer "In7.Cu")
		(net "PCIE_SCC_A_TO_COMP_A_7_DN")
	)
	(segment
		(start 273.613118 -249.355356)
		(end 273.29765 -249.141996)
		(width 0.127)
		(layer "In7.Cu")
		(net "PCIE_SCC_A_TO_COMP_A_7_DN")
	)
	(arc
		(start 278.670004 -251.102368)
		(mid 278.759807 -251.139565)
		(end 278.797004 -251.229368)
		(width 0.127)
		(layer "In7.Cu")
		(net "PCIE_SCC_A_TO_COMP_A_7_DN")
	)
	(arc
		(start 236.437678 -161.640012)
		(mid 236.548877 -161.662131)
		(end 236.643164 -161.725102)
		(width 0.127)
		(layer "In7.Cu")
		(net "PCIE_SCC_A_TO_COMP_A_7_DN")
	)
	(arc
		(start 278.797004 -251.703332)
		(mid 278.750358 -251.815944)
		(end 278.637746 -251.86259)
		(width 0.127)
		(layer "In7.Cu")
		(net "PCIE_SCC_A_TO_COMP_A_7_DN")
	)
	(arc
		(start 236.836966 -161.918904)
		(mid 236.872386 -162.028939)
		(end 236.803946 -162.122104)
		(width 0.127)
		(layer "In7.Cu")
		(net "PCIE_SCC_A_TO_COMP_A_7_DN")
	)
	(segment
		(start 276.872192 -253.941834)
		(end 268.819884 -248.491756)
		(width 0.127)
		(layer "In7.Cu")
		(net "PCIE_SCC_A_TO_COMP_A_6_DP")
	)
	(segment
		(start 230.665274 -172.339254)
		(end 230.665274 -172.273468)
		(width 0.127)
		(layer "In7.Cu")
		(net "PCIE_SCC_A_TO_COMP_A_6_DP")
	)
	(segment
		(start 236.837728 -157.52445)
		(end 237.148116 -157.834838)
		(width 0.127)
		(layer "In7.Cu")
		(net "PCIE_SCC_A_TO_COMP_A_6_DP")
	)
	(segment
		(start 236.642402 -195.612766)
		(end 235.887006 -192.672716)
		(width 0.127)
		(layer "In7.Cu")
		(net "PCIE_SCC_A_TO_COMP_A_6_DP")
	)
	(segment
		(start 235.887006 -192.672716)
		(end 235.887006 -192.671446)
		(width 0.127)
		(layer "In7.Cu")
		(net "PCIE_SCC_A_TO_COMP_A_6_DP")
	)
	(segment
		(start 280.076402 -253.029212)
		(end 280.076402 -253.503176)
		(width 0.127)
		(layer "In7.Cu")
		(net "PCIE_SCC_A_TO_COMP_A_6_DP")
	)
	(segment
		(start 235.887006 -192.671446)
		(end 230.665274 -172.339254)
		(width 0.127)
		(layer "In7.Cu")
		(net "PCIE_SCC_A_TO_COMP_A_6_DP")
	)
	(segment
		(start 268.819884 -248.491756)
		(end 268.777212 -248.449084)
		(width 0.127)
		(layer "In7.Cu")
		(net "PCIE_SCC_A_TO_COMP_A_6_DP")
	)
	(segment
		(start 230.665274 -172.273468)
		(end 233.442256 -158.638748)
		(width 0.127)
		(layer "In7.Cu")
		(net "PCIE_SCC_A_TO_COMP_A_6_DP")
	)
	(segment
		(start 280.636726 -252.902212)
		(end 280.203402 -252.902212)
		(width 0.127)
		(layer "In7.Cu")
		(net "PCIE_SCC_A_TO_COMP_A_6_DP")
	)
	(segment
		(start 237.324138 -157.863286)
		(end 238.05007 -157.499812)
		(width 0.127)
		(layer "In7.Cu")
		(net "PCIE_SCC_A_TO_COMP_A_6_DP")
	)
	(segment
		(start 279.637744 -253.941834)
		(end 276.872192 -253.941834)
		(width 0.127)
		(layer "In7.Cu")
		(net "PCIE_SCC_A_TO_COMP_A_6_DP")
	)
	(segment
		(start 233.442256 -158.638748)
		(end 235.544868 -157.360112)
		(width 0.127)
		(layer "In7.Cu")
		(net "PCIE_SCC_A_TO_COMP_A_6_DP")
	)
	(segment
		(start 268.777212 -248.449084)
		(end 236.642402 -195.612766)
		(width 0.127)
		(layer "In7.Cu")
		(net "PCIE_SCC_A_TO_COMP_A_6_DP")
	)
	(segment
		(start 235.544868 -157.360112)
		(end 236.440726 -157.360112)
		(width 0.127)
		(layer "In7.Cu")
		(net "PCIE_SCC_A_TO_COMP_A_6_DP")
	)
	(arc
		(start 280.076402 -253.503176)
		(mid 279.947922 -253.813354)
		(end 279.637744 -253.941834)
		(width 0.127)
		(layer "In7.Cu")
		(net "PCIE_SCC_A_TO_COMP_A_6_DP")
	)
	(arc
		(start 280.203402 -252.902212)
		(mid 280.113599 -252.939409)
		(end 280.076402 -253.029212)
		(width 0.127)
		(layer "In7.Cu")
		(net "PCIE_SCC_A_TO_COMP_A_6_DP")
	)
	(arc
		(start 237.148116 -157.834838)
		(mid 237.231528 -157.877499)
		(end 237.324138 -157.863286)
		(width 0.127)
		(layer "In7.Cu")
		(net "PCIE_SCC_A_TO_COMP_A_6_DP")
	)
	(arc
		(start 236.440726 -157.360112)
		(mid 236.655595 -157.402758)
		(end 236.837728 -157.52445)
		(width 0.127)
		(layer "In7.Cu")
		(net "PCIE_SCC_A_TO_COMP_A_6_DP")
	)
	(segment
		(start 258.341368 -230.752142)
		(end 258.388104 -230.560118)
		(width 0.127)
		(layer "In7.Cu")
		(net "PCIE_SCC_A_TO_COMP_A_6_DN")
	)
	(segment
		(start 235.623354 -157.639512)
		(end 236.440726 -157.639512)
		(width 0.127)
		(layer "In7.Cu")
		(net "PCIE_SCC_A_TO_COMP_A_6_DN")
	)
	(segment
		(start 230.944674 -172.301662)
		(end 233.691938 -158.814262)
		(width 0.127)
		(layer "In7.Cu")
		(net "PCIE_SCC_A_TO_COMP_A_6_DN")
	)
	(segment
		(start 267.567156 -245.652544)
		(end 267.375132 -245.605808)
		(width 0.127)
		(layer "In7.Cu")
		(net "PCIE_SCC_A_TO_COMP_A_6_DN")
	)
	(segment
		(start 267.71854 -246.169942)
		(end 267.765276 -245.978172)
		(width 0.127)
		(layer "In7.Cu")
		(net "PCIE_SCC_A_TO_COMP_A_6_DN")
	)
	(segment
		(start 267.026136 -244.762782)
		(end 266.834112 -244.716046)
		(width 0.127)
		(layer "In7.Cu")
		(net "PCIE_SCC_A_TO_COMP_A_6_DN")
	)
	(segment
		(start 236.16666 -192.63614)
		(end 236.166406 -192.63614)
		(width 0.127)
		(layer "In7.Cu")
		(net "PCIE_SCC_A_TO_COMP_A_6_DN")
	)
	(segment
		(start 273.430492 -251.275088)
		(end 273.39036 -251.066808)
		(width 0.127)
		(layer "In7.Cu")
		(net "PCIE_SCC_A_TO_COMP_A_6_DN")
	)
	(segment
		(start 263.700006 -239.294162)
		(end 263.501886 -238.968534)
		(width 0.127)
		(layer "In7.Cu")
		(net "PCIE_SCC_A_TO_COMP_A_6_DN")
	)
	(segment
		(start 257.45694 -229.297992)
		(end 236.902752 -195.503038)
		(width 0.127)
		(layer "In7.Cu")
		(net "PCIE_SCC_A_TO_COMP_A_6_DN")
	)
	(segment
		(start 268.25956 -247.059704)
		(end 268.306296 -246.867934)
		(width 0.127)
		(layer "In7.Cu")
		(net "PCIE_SCC_A_TO_COMP_A_6_DN")
	)
	(segment
		(start 267.224002 -245.08841)
		(end 267.026136 -244.762782)
		(width 0.127)
		(layer "In7.Cu")
		(net "PCIE_SCC_A_TO_COMP_A_6_DN")
	)
	(segment
		(start 268.9987 -248.275094)
		(end 268.800834 -247.949466)
		(width 0.127)
		(layer "In7.Cu")
		(net "PCIE_SCC_A_TO_COMP_A_6_DN")
	)
	(segment
		(start 258.388104 -230.560118)
		(end 258.189984 -230.234744)
		(width 0.127)
		(layer "In7.Cu")
		(net "PCIE_SCC_A_TO_COMP_A_6_DN")
	)
	(segment
		(start 262.768842 -238.032036)
		(end 262.570976 -237.706408)
		(width 0.127)
		(layer "In7.Cu")
		(net "PCIE_SCC_A_TO_COMP_A_6_DN")
	)
	(segment
		(start 236.166406 -192.63614)
		(end 230.944674 -172.303948)
		(width 0.127)
		(layer "In7.Cu")
		(net "PCIE_SCC_A_TO_COMP_A_6_DN")
	)
	(segment
		(start 258.929124 -231.44988)
		(end 258.731258 -231.124252)
		(width 0.127)
		(layer "In7.Cu")
		(net "PCIE_SCC_A_TO_COMP_A_6_DN")
	)
	(segment
		(start 257.84683 -229.670356)
		(end 257.648964 -229.344982)
		(width 0.127)
		(layer "In7.Cu")
		(net "PCIE_SCC_A_TO_COMP_A_6_DN")
	)
	(segment
		(start 267.375132 -245.605808)
		(end 267.177266 -245.28018)
		(width 0.127)
		(layer "In7.Cu")
		(net "PCIE_SCC_A_TO_COMP_A_6_DN")
	)
	(segment
		(start 264.04316 -239.858296)
		(end 263.851136 -239.81156)
		(width 0.127)
		(layer "In7.Cu")
		(net "PCIE_SCC_A_TO_COMP_A_6_DN")
	)
	(segment
		(start 263.111996 -238.59617)
		(end 263.158732 -238.4044)
		(width 0.127)
		(layer "In7.Cu")
		(net "PCIE_SCC_A_TO_COMP_A_6_DN")
	)
	(segment
		(start 257.998214 -230.187754)
		(end 257.800094 -229.86238)
		(width 0.127)
		(layer "In7.Cu")
		(net "PCIE_SCC_A_TO_COMP_A_6_DN")
	)
	(segment
		(start 263.851136 -239.81156)
		(end 263.65327 -239.485932)
		(width 0.127)
		(layer "In7.Cu")
		(net "PCIE_SCC_A_TO_COMP_A_6_DN")
	)
	(segment
		(start 266.834112 -244.716046)
		(end 264.19429 -240.375694)
		(width 0.127)
		(layer "In7.Cu")
		(net "PCIE_SCC_A_TO_COMP_A_6_DN")
	)
	(segment
		(start 262.227822 -237.142274)
		(end 258.882388 -231.641904)
		(width 0.127)
		(layer "In7.Cu")
		(net "PCIE_SCC_A_TO_COMP_A_6_DN")
	)
	(segment
		(start 268.9987 -248.275348)
		(end 268.9987 -248.275094)
		(width 0.127)
		(layer "In7.Cu")
		(net "PCIE_SCC_A_TO_COMP_A_6_DN")
	)
	(segment
		(start 264.19429 -240.375694)
		(end 264.241026 -240.183924)
		(width 0.127)
		(layer "In7.Cu")
		(net "PCIE_SCC_A_TO_COMP_A_6_DN")
	)
	(segment
		(start 268.457426 -247.385332)
		(end 268.25956 -247.059704)
		(width 0.127)
		(layer "In7.Cu")
		(net "PCIE_SCC_A_TO_COMP_A_6_DN")
	)
	(segment
		(start 272.866866 -250.893326)
		(end 272.551398 -250.679966)
		(width 0.127)
		(layer "In7.Cu")
		(net "PCIE_SCC_A_TO_COMP_A_6_DN")
	)
	(segment
		(start 263.501886 -238.968534)
		(end 263.310116 -238.921798)
		(width 0.127)
		(layer "In7.Cu")
		(net "PCIE_SCC_A_TO_COMP_A_6_DN")
	)
	(segment
		(start 258.882388 -231.641904)
		(end 258.929124 -231.44988)
		(width 0.127)
		(layer "In7.Cu")
		(net "PCIE_SCC_A_TO_COMP_A_6_DN")
	)
	(segment
		(start 230.944674 -172.303948)
		(end 230.944674 -172.301662)
		(width 0.127)
		(layer "In7.Cu")
		(net "PCIE_SCC_A_TO_COMP_A_6_DN")
	)
	(segment
		(start 267.916406 -246.49557)
		(end 267.71854 -246.169942)
		(width 0.127)
		(layer "In7.Cu")
		(net "PCIE_SCC_A_TO_COMP_A_6_DN")
	)
	(segment
		(start 276.958044 -253.662434)
		(end 273.430492 -251.275088)
		(width 0.127)
		(layer "In7.Cu")
		(net "PCIE_SCC_A_TO_COMP_A_6_DN")
	)
	(segment
		(start 267.765276 -245.978172)
		(end 267.567156 -245.652544)
		(width 0.127)
		(layer "In7.Cu")
		(net "PCIE_SCC_A_TO_COMP_A_6_DN")
	)
	(segment
		(start 271.31645 -249.663204)
		(end 271.108424 -249.703336)
		(width 0.127)
		(layer "In7.Cu")
		(net "PCIE_SCC_A_TO_COMP_A_6_DN")
	)
	(segment
		(start 263.310116 -238.921798)
		(end 263.111996 -238.59617)
		(width 0.127)
		(layer "In7.Cu")
		(net "PCIE_SCC_A_TO_COMP_A_6_DN")
	)
	(segment
		(start 279.797002 -253.029212)
		(end 279.797002 -253.503176)
		(width 0.127)
		(layer "In7.Cu")
		(net "PCIE_SCC_A_TO_COMP_A_6_DN")
	)
	(segment
		(start 258.731258 -231.124252)
		(end 258.539234 -231.077516)
		(width 0.127)
		(layer "In7.Cu")
		(net "PCIE_SCC_A_TO_COMP_A_6_DN")
	)
	(segment
		(start 236.803946 -158.122112)
		(end 236.79404 -158.127192)
		(width 0.127)
		(layer "In7.Cu")
		(net "PCIE_SCC_A_TO_COMP_A_6_DN")
	)
	(segment
		(start 271.631918 -249.876564)
		(end 271.31645 -249.663204)
		(width 0.127)
		(layer "In7.Cu")
		(net "PCIE_SCC_A_TO_COMP_A_6_DN")
	)
	(segment
		(start 271.108424 -249.703336)
		(end 268.9987 -248.275348)
		(width 0.127)
		(layer "In7.Cu")
		(net "PCIE_SCC_A_TO_COMP_A_6_DN")
	)
	(segment
		(start 271.987518 -250.298204)
		(end 271.67205 -250.084844)
		(width 0.127)
		(layer "In7.Cu")
		(net "PCIE_SCC_A_TO_COMP_A_6_DN")
	)
	(segment
		(start 236.902752 -195.503038)
		(end 236.16666 -192.63614)
		(width 0.127)
		(layer "In7.Cu")
		(net "PCIE_SCC_A_TO_COMP_A_6_DN")
	)
	(segment
		(start 233.691938 -158.814262)
		(end 235.623354 -157.639512)
		(width 0.127)
		(layer "In7.Cu")
		(net "PCIE_SCC_A_TO_COMP_A_6_DN")
	)
	(segment
		(start 263.158732 -238.4044)
		(end 262.960866 -238.078772)
		(width 0.127)
		(layer "In7.Cu")
		(net "PCIE_SCC_A_TO_COMP_A_6_DN")
	)
	(segment
		(start 272.551398 -250.679966)
		(end 272.511266 -250.471686)
		(width 0.127)
		(layer "In7.Cu")
		(net "PCIE_SCC_A_TO_COMP_A_6_DN")
	)
	(segment
		(start 268.10843 -246.542306)
		(end 267.916406 -246.49557)
		(width 0.127)
		(layer "In7.Cu")
		(net "PCIE_SCC_A_TO_COMP_A_6_DN")
	)
	(segment
		(start 262.617712 -237.514638)
		(end 262.419592 -237.18901)
		(width 0.127)
		(layer "In7.Cu")
		(net "PCIE_SCC_A_TO_COMP_A_6_DN")
	)
	(segment
		(start 268.64945 -247.432068)
		(end 268.457426 -247.385332)
		(width 0.127)
		(layer "In7.Cu")
		(net "PCIE_SCC_A_TO_COMP_A_6_DN")
	)
	(segment
		(start 262.419592 -237.18901)
		(end 262.227822 -237.142274)
		(width 0.127)
		(layer "In7.Cu")
		(net "PCIE_SCC_A_TO_COMP_A_6_DN")
	)
	(segment
		(start 272.511266 -250.471686)
		(end 272.195544 -250.258326)
		(width 0.127)
		(layer "In7.Cu")
		(net "PCIE_SCC_A_TO_COMP_A_6_DN")
	)
	(segment
		(start 258.189984 -230.234744)
		(end 257.998214 -230.187754)
		(width 0.127)
		(layer "In7.Cu")
		(net "PCIE_SCC_A_TO_COMP_A_6_DN")
	)
	(segment
		(start 258.539234 -231.077516)
		(end 258.341368 -230.752142)
		(width 0.127)
		(layer "In7.Cu")
		(net "PCIE_SCC_A_TO_COMP_A_6_DN")
	)
	(segment
		(start 262.960866 -238.078772)
		(end 262.768842 -238.032036)
		(width 0.127)
		(layer "In7.Cu")
		(net "PCIE_SCC_A_TO_COMP_A_6_DN")
	)
	(segment
		(start 262.570976 -237.706408)
		(end 262.617712 -237.514638)
		(width 0.127)
		(layer "In7.Cu")
		(net "PCIE_SCC_A_TO_COMP_A_6_DN")
	)
	(segment
		(start 268.306296 -246.867934)
		(end 268.10843 -246.542306)
		(width 0.127)
		(layer "In7.Cu")
		(net "PCIE_SCC_A_TO_COMP_A_6_DN")
	)
	(segment
		(start 273.39036 -251.066808)
		(end 273.074892 -250.853194)
		(width 0.127)
		(layer "In7.Cu")
		(net "PCIE_SCC_A_TO_COMP_A_6_DN")
	)
	(segment
		(start 268.800834 -247.949466)
		(end 268.84757 -247.757696)
		(width 0.127)
		(layer "In7.Cu")
		(net "PCIE_SCC_A_TO_COMP_A_6_DN")
	)
	(segment
		(start 264.241026 -240.183924)
		(end 264.04316 -239.858296)
		(width 0.127)
		(layer "In7.Cu")
		(net "PCIE_SCC_A_TO_COMP_A_6_DN")
	)
	(segment
		(start 268.84757 -247.757696)
		(end 268.64945 -247.432068)
		(width 0.127)
		(layer "In7.Cu")
		(net "PCIE_SCC_A_TO_COMP_A_6_DN")
	)
	(segment
		(start 279.637744 -253.662434)
		(end 276.958044 -253.662434)
		(width 0.127)
		(layer "In7.Cu")
		(net "PCIE_SCC_A_TO_COMP_A_6_DN")
	)
	(segment
		(start 271.67205 -250.084844)
		(end 271.631918 -249.876564)
		(width 0.127)
		(layer "In7.Cu")
		(net "PCIE_SCC_A_TO_COMP_A_6_DN")
	)
	(segment
		(start 272.195544 -250.258326)
		(end 271.987518 -250.298204)
		(width 0.127)
		(layer "In7.Cu")
		(net "PCIE_SCC_A_TO_COMP_A_6_DN")
	)
	(segment
		(start 279.236678 -252.902212)
		(end 279.670002 -252.902212)
		(width 0.127)
		(layer "In7.Cu")
		(net "PCIE_SCC_A_TO_COMP_A_6_DN")
	)
	(segment
		(start 267.177266 -245.28018)
		(end 267.224002 -245.08841)
		(width 0.127)
		(layer "In7.Cu")
		(net "PCIE_SCC_A_TO_COMP_A_6_DN")
	)
	(segment
		(start 236.640116 -157.722062)
		(end 236.836966 -157.918912)
		(width 0.127)
		(layer "In7.Cu")
		(net "PCIE_SCC_A_TO_COMP_A_6_DN")
	)
	(segment
		(start 257.648964 -229.344982)
		(end 257.45694 -229.297992)
		(width 0.127)
		(layer "In7.Cu")
		(net "PCIE_SCC_A_TO_COMP_A_6_DN")
	)
	(segment
		(start 257.800094 -229.86238)
		(end 257.84683 -229.670356)
		(width 0.127)
		(layer "In7.Cu")
		(net "PCIE_SCC_A_TO_COMP_A_6_DN")
	)
	(segment
		(start 273.074892 -250.853194)
		(end 272.866866 -250.893326)
		(width 0.127)
		(layer "In7.Cu")
		(net "PCIE_SCC_A_TO_COMP_A_6_DN")
	)
	(segment
		(start 236.79404 -158.127192)
		(end 236.050074 -158.49981)
		(width 0.127)
		(layer "In7.Cu")
		(net "PCIE_SCC_A_TO_COMP_A_6_DN")
	)
	(segment
		(start 263.65327 -239.485932)
		(end 263.700006 -239.294162)
		(width 0.127)
		(layer "In7.Cu")
		(net "PCIE_SCC_A_TO_COMP_A_6_DN")
	)
	(arc
		(start 236.836966 -157.918912)
		(mid 236.872386 -158.028947)
		(end 236.803946 -158.122112)
		(width 0.127)
		(layer "In7.Cu")
		(net "PCIE_SCC_A_TO_COMP_A_6_DN")
	)
	(arc
		(start 279.797002 -253.503176)
		(mid 279.750356 -253.615788)
		(end 279.637744 -253.662434)
		(width 0.127)
		(layer "In7.Cu")
		(net "PCIE_SCC_A_TO_COMP_A_6_DN")
	)
	(arc
		(start 279.670002 -252.902212)
		(mid 279.759805 -252.939409)
		(end 279.797002 -253.029212)
		(width 0.127)
		(layer "In7.Cu")
		(net "PCIE_SCC_A_TO_COMP_A_6_DN")
	)
	(arc
		(start 236.440726 -157.639512)
		(mid 236.54862 -157.660973)
		(end 236.640116 -157.722062)
		(width 0.127)
		(layer "In7.Cu")
		(net "PCIE_SCC_A_TO_COMP_A_6_DN")
	)
	(segment
		(start 276.339808 -255.424686)
		(end 266.827 -248.986548)
		(width 0.127)
		(layer "In7.Cu")
		(net "PCIE_SCC_A_TO_COMP_A_5_DP")
	)
	(segment
		(start 235.963714 -198.240396)
		(end 232.397808 -184.35955)
		(width 0.127)
		(layer "In7.Cu")
		(net "PCIE_SCC_A_TO_COMP_A_5_DP")
	)
	(segment
		(start 276.808946 -255.741932)
		(end 276.656292 -255.639062)
		(width 0.127)
		(layer "In7.Cu")
		(net "PCIE_SCC_A_TO_COMP_A_5_DP")
	)
	(segment
		(start 278.637746 -255.741932)
		(end 276.808946 -255.741932)
		(width 0.127)
		(layer "In7.Cu")
		(net "PCIE_SCC_A_TO_COMP_A_5_DP")
	)
	(segment
		(start 236.830616 -153.517346)
		(end 237.148116 -153.834846)
		(width 0.127)
		(layer "In7.Cu")
		(net "PCIE_SCC_A_TO_COMP_A_5_DP")
	)
	(segment
		(start 276.339554 -255.424686)
		(end 276.339808 -255.424686)
		(width 0.127)
		(layer "In7.Cu")
		(net "PCIE_SCC_A_TO_COMP_A_5_DP")
	)
	(segment
		(start 279.636728 -254.70231)
		(end 279.203404 -254.70231)
		(width 0.127)
		(layer "In7.Cu")
		(net "PCIE_SCC_A_TO_COMP_A_5_DP")
	)
	(segment
		(start 231.878378 -155.467812)
		(end 235.563156 -153.36012)
		(width 0.127)
		(layer "In7.Cu")
		(net "PCIE_SCC_A_TO_COMP_A_5_DP")
	)
	(segment
		(start 228.8159 -170.507152)
		(end 231.878378 -155.467812)
		(width 0.127)
		(layer "In7.Cu")
		(net "PCIE_SCC_A_TO_COMP_A_5_DP")
	)
	(segment
		(start 228.854 -170.56481)
		(end 228.8159 -170.507152)
		(width 0.127)
		(layer "In7.Cu")
		(net "PCIE_SCC_A_TO_COMP_A_5_DP")
	)
	(segment
		(start 237.324138 -153.863294)
		(end 238.05007 -153.49982)
		(width 0.127)
		(layer "In7.Cu")
		(net "PCIE_SCC_A_TO_COMP_A_5_DP")
	)
	(segment
		(start 232.397808 -184.35955)
		(end 228.854 -170.56481)
		(width 0.127)
		(layer "In7.Cu")
		(net "PCIE_SCC_A_TO_COMP_A_5_DP")
	)
	(segment
		(start 279.076404 -254.82931)
		(end 279.076404 -255.303274)
		(width 0.127)
		(layer "In7.Cu")
		(net "PCIE_SCC_A_TO_COMP_A_5_DP")
	)
	(segment
		(start 276.656292 -255.639062)
		(end 276.339554 -255.424686)
		(width 0.127)
		(layer "In7.Cu")
		(net "PCIE_SCC_A_TO_COMP_A_5_DP")
	)
	(segment
		(start 266.827 -248.986548)
		(end 235.963714 -198.240396)
		(width 0.127)
		(layer "In7.Cu")
		(net "PCIE_SCC_A_TO_COMP_A_5_DP")
	)
	(segment
		(start 235.563156 -153.36012)
		(end 236.45114 -153.36012)
		(width 0.127)
		(layer "In7.Cu")
		(net "PCIE_SCC_A_TO_COMP_A_5_DP")
	)
	(arc
		(start 237.148116 -153.834846)
		(mid 237.231528 -153.877507)
		(end 237.324138 -153.863294)
		(width 0.127)
		(layer "In7.Cu")
		(net "PCIE_SCC_A_TO_COMP_A_5_DP")
	)
	(arc
		(start 279.076404 -255.303274)
		(mid 278.947924 -255.613452)
		(end 278.637746 -255.741932)
		(width 0.127)
		(layer "In7.Cu")
		(net "PCIE_SCC_A_TO_COMP_A_5_DP")
	)
	(arc
		(start 236.45114 -153.36012)
		(mid 236.656488 -153.401042)
		(end 236.830616 -153.517346)
		(width 0.127)
		(layer "In7.Cu")
		(net "PCIE_SCC_A_TO_COMP_A_5_DP")
	)
	(arc
		(start 279.203404 -254.70231)
		(mid 279.113601 -254.739507)
		(end 279.076404 -254.82931)
		(width 0.127)
		(layer "In7.Cu")
		(net "PCIE_SCC_A_TO_COMP_A_5_DP")
	)
	(segment
		(start 260.134608 -237.444788)
		(end 259.936742 -237.119414)
		(width 0.127)
		(layer "In7.Cu")
		(net "PCIE_SCC_A_TO_COMP_A_5_DN")
	)
	(segment
		(start 269.99565 -250.612656)
		(end 269.680182 -250.399042)
		(width 0.127)
		(layer "In7.Cu")
		(net "PCIE_SCC_A_TO_COMP_A_5_DN")
	)
	(segment
		(start 261.216902 -239.224312)
		(end 261.019036 -238.898938)
		(width 0.127)
		(layer "In7.Cu")
		(net "PCIE_SCC_A_TO_COMP_A_5_DN")
	)
	(segment
		(start 261.606792 -239.596676)
		(end 261.408926 -239.271302)
		(width 0.127)
		(layer "In7.Cu")
		(net "PCIE_SCC_A_TO_COMP_A_5_DN")
	)
	(segment
		(start 266.166346 -247.362472)
		(end 266.213082 -247.170702)
		(width 0.127)
		(layer "In7.Cu")
		(net "PCIE_SCC_A_TO_COMP_A_5_DN")
	)
	(segment
		(start 261.408926 -239.271302)
		(end 261.216902 -239.224312)
		(width 0.127)
		(layer "In7.Cu")
		(net "PCIE_SCC_A_TO_COMP_A_5_DN")
	)
	(segment
		(start 269.156434 -250.22556)
		(end 269.116302 -250.017534)
		(width 0.127)
		(layer "In7.Cu")
		(net "PCIE_SCC_A_TO_COMP_A_5_DN")
	)
	(segment
		(start 260.524498 -237.817152)
		(end 260.326632 -237.491524)
		(width 0.127)
		(layer "In7.Cu")
		(net "PCIE_SCC_A_TO_COMP_A_5_DN")
	)
	(segment
		(start 265.473942 -245.955312)
		(end 265.282172 -245.908576)
		(width 0.127)
		(layer "In7.Cu")
		(net "PCIE_SCC_A_TO_COMP_A_5_DN")
	)
	(segment
		(start 269.116302 -250.017534)
		(end 268.800834 -249.80392)
		(width 0.127)
		(layer "In7.Cu")
		(net "PCIE_SCC_A_TO_COMP_A_5_DN")
	)
	(segment
		(start 274.375372 -253.75743)
		(end 274.33778 -253.563628)
		(width 0.127)
		(layer "In7.Cu")
		(net "PCIE_SCC_A_TO_COMP_A_5_DN")
	)
	(segment
		(start 265.282172 -245.908576)
		(end 265.084052 -245.582948)
		(width 0.127)
		(layer "In7.Cu")
		(net "PCIE_SCC_A_TO_COMP_A_5_DN")
	)
	(segment
		(start 274.022312 -253.350014)
		(end 273.828256 -253.387352)
		(width 0.127)
		(layer "In7.Cu")
		(net "PCIE_SCC_A_TO_COMP_A_5_DN")
	)
	(segment
		(start 235.637578 -153.63952)
		(end 236.450886 -153.63952)
		(width 0.127)
		(layer "In7.Cu")
		(net "PCIE_SCC_A_TO_COMP_A_5_DN")
	)
	(segment
		(start 275.74748 -254.517398)
		(end 275.553424 -254.554736)
		(width 0.127)
		(layer "In7.Cu")
		(net "PCIE_SCC_A_TO_COMP_A_5_DN")
	)
	(segment
		(start 274.884896 -253.933706)
		(end 274.69084 -253.971044)
		(width 0.127)
		(layer "In7.Cu")
		(net "PCIE_SCC_A_TO_COMP_A_5_DN")
	)
	(segment
		(start 259.936742 -237.119414)
		(end 259.983478 -236.92739)
		(width 0.127)
		(layer "In7.Cu")
		(net "PCIE_SCC_A_TO_COMP_A_5_DN")
	)
	(segment
		(start 264.740898 -245.018814)
		(end 264.543032 -244.693186)
		(width 0.127)
		(layer "In7.Cu")
		(net "PCIE_SCC_A_TO_COMP_A_5_DN")
	)
	(segment
		(start 264.589768 -244.501162)
		(end 264.391648 -244.175788)
		(width 0.127)
		(layer "In7.Cu")
		(net "PCIE_SCC_A_TO_COMP_A_5_DN")
	)
	(segment
		(start 265.625326 -246.47271)
		(end 265.672062 -246.280686)
		(width 0.127)
		(layer "In7.Cu")
		(net "PCIE_SCC_A_TO_COMP_A_5_DN")
	)
	(segment
		(start 264.543032 -244.693186)
		(end 264.589768 -244.501162)
		(width 0.127)
		(layer "In7.Cu")
		(net "PCIE_SCC_A_TO_COMP_A_5_DN")
	)
	(segment
		(start 275.553424 -254.554736)
		(end 275.237956 -254.341376)
		(width 0.127)
		(layer "In7.Cu")
		(net "PCIE_SCC_A_TO_COMP_A_5_DN")
	)
	(segment
		(start 270.035782 -250.820682)
		(end 269.99565 -250.612656)
		(width 0.127)
		(layer "In7.Cu")
		(net "PCIE_SCC_A_TO_COMP_A_5_DN")
	)
	(segment
		(start 259.593588 -236.555026)
		(end 236.224064 -198.130668)
		(width 0.127)
		(layer "In7.Cu")
		(net "PCIE_SCC_A_TO_COMP_A_5_DN")
	)
	(segment
		(start 261.019036 -238.898938)
		(end 261.065772 -238.706914)
		(width 0.127)
		(layer "In7.Cu")
		(net "PCIE_SCC_A_TO_COMP_A_5_DN")
	)
	(segment
		(start 232.127044 -155.647644)
		(end 235.637578 -153.63952)
		(width 0.127)
		(layer "In7.Cu")
		(net "PCIE_SCC_A_TO_COMP_A_5_DN")
	)
	(segment
		(start 266.015216 -246.845074)
		(end 265.823192 -246.798338)
		(width 0.127)
		(layer "In7.Cu")
		(net "PCIE_SCC_A_TO_COMP_A_5_DN")
	)
	(segment
		(start 269.472156 -250.439174)
		(end 269.156434 -250.22556)
		(width 0.127)
		(layer "In7.Cu")
		(net "PCIE_SCC_A_TO_COMP_A_5_DN")
	)
	(segment
		(start 229.112826 -170.449494)
		(end 232.127044 -155.647644)
		(width 0.127)
		(layer "In7.Cu")
		(net "PCIE_SCC_A_TO_COMP_A_5_DN")
	)
	(segment
		(start 229.11308 -170.449748)
		(end 229.112826 -170.449494)
		(width 0.127)
		(layer "In7.Cu")
		(net "PCIE_SCC_A_TO_COMP_A_5_DN")
	)
	(segment
		(start 273.828256 -253.387352)
		(end 270.035782 -250.820682)
		(width 0.127)
		(layer "In7.Cu")
		(net "PCIE_SCC_A_TO_COMP_A_5_DN")
	)
	(segment
		(start 260.326632 -237.491524)
		(end 260.134608 -237.444788)
		(width 0.127)
		(layer "In7.Cu")
		(net "PCIE_SCC_A_TO_COMP_A_5_DN")
	)
	(segment
		(start 265.823192 -246.798338)
		(end 265.625326 -246.47271)
		(width 0.127)
		(layer "In7.Cu")
		(net "PCIE_SCC_A_TO_COMP_A_5_DN")
	)
	(segment
		(start 260.675882 -238.33455)
		(end 260.477762 -238.009176)
		(width 0.127)
		(layer "In7.Cu")
		(net "PCIE_SCC_A_TO_COMP_A_5_DN")
	)
	(segment
		(start 267.921486 -249.209052)
		(end 267.71346 -249.24893)
		(width 0.127)
		(layer "In7.Cu")
		(net "PCIE_SCC_A_TO_COMP_A_5_DN")
	)
	(segment
		(start 260.477762 -238.009176)
		(end 260.524498 -237.817152)
		(width 0.127)
		(layer "In7.Cu")
		(net "PCIE_SCC_A_TO_COMP_A_5_DN")
	)
	(segment
		(start 260.867652 -238.38154)
		(end 260.675882 -238.33455)
		(width 0.127)
		(layer "In7.Cu")
		(net "PCIE_SCC_A_TO_COMP_A_5_DN")
	)
	(segment
		(start 232.668572 -184.289954)
		(end 229.11308 -170.449748)
		(width 0.127)
		(layer "In7.Cu")
		(net "PCIE_SCC_A_TO_COMP_A_5_DN")
	)
	(segment
		(start 265.130788 -245.390924)
		(end 264.932922 -245.06555)
		(width 0.127)
		(layer "In7.Cu")
		(net "PCIE_SCC_A_TO_COMP_A_5_DN")
	)
	(segment
		(start 268.592808 -249.844052)
		(end 268.27734 -249.630692)
		(width 0.127)
		(layer "In7.Cu")
		(net "PCIE_SCC_A_TO_COMP_A_5_DN")
	)
	(segment
		(start 275.237956 -254.341376)
		(end 275.200364 -254.14732)
		(width 0.127)
		(layer "In7.Cu")
		(net "PCIE_SCC_A_TO_COMP_A_5_DN")
	)
	(segment
		(start 267.03401 -248.78919)
		(end 266.166346 -247.362472)
		(width 0.127)
		(layer "In7.Cu")
		(net "PCIE_SCC_A_TO_COMP_A_5_DN")
	)
	(segment
		(start 268.237208 -249.422412)
		(end 267.921486 -249.209052)
		(width 0.127)
		(layer "In7.Cu")
		(net "PCIE_SCC_A_TO_COMP_A_5_DN")
	)
	(segment
		(start 261.560056 -239.7887)
		(end 261.606792 -239.596676)
		(width 0.127)
		(layer "In7.Cu")
		(net "PCIE_SCC_A_TO_COMP_A_5_DN")
	)
	(segment
		(start 278.23668 -254.70231)
		(end 278.670004 -254.70231)
		(width 0.127)
		(layer "In7.Cu")
		(net "PCIE_SCC_A_TO_COMP_A_5_DN")
	)
	(segment
		(start 264.391648 -244.175788)
		(end 264.199878 -244.129052)
		(width 0.127)
		(layer "In7.Cu")
		(net "PCIE_SCC_A_TO_COMP_A_5_DN")
	)
	(segment
		(start 261.065772 -238.706914)
		(end 260.867652 -238.38154)
		(width 0.127)
		(layer "In7.Cu")
		(net "PCIE_SCC_A_TO_COMP_A_5_DN")
	)
	(segment
		(start 265.672062 -246.280686)
		(end 265.473942 -245.955312)
		(width 0.127)
		(layer "In7.Cu")
		(net "PCIE_SCC_A_TO_COMP_A_5_DN")
	)
	(segment
		(start 236.79404 -154.1272)
		(end 236.050074 -154.499818)
		(width 0.127)
		(layer "In7.Cu")
		(net "PCIE_SCC_A_TO_COMP_A_5_DN")
	)
	(segment
		(start 264.199878 -244.129052)
		(end 261.560056 -239.7887)
		(width 0.127)
		(layer "In7.Cu")
		(net "PCIE_SCC_A_TO_COMP_A_5_DN")
	)
	(segment
		(start 236.633004 -153.714958)
		(end 236.836966 -153.91892)
		(width 0.127)
		(layer "In7.Cu")
		(net "PCIE_SCC_A_TO_COMP_A_5_DN")
	)
	(segment
		(start 276.062948 -254.731012)
		(end 275.74748 -254.517398)
		(width 0.127)
		(layer "In7.Cu")
		(net "PCIE_SCC_A_TO_COMP_A_5_DN")
	)
	(segment
		(start 274.33778 -253.563628)
		(end 274.022312 -253.350014)
		(width 0.127)
		(layer "In7.Cu")
		(net "PCIE_SCC_A_TO_COMP_A_5_DN")
	)
	(segment
		(start 266.213082 -247.170702)
		(end 266.015216 -246.845074)
		(width 0.127)
		(layer "In7.Cu")
		(net "PCIE_SCC_A_TO_COMP_A_5_DN")
	)
	(segment
		(start 269.680182 -250.399042)
		(end 269.472156 -250.439174)
		(width 0.127)
		(layer "In7.Cu")
		(net "PCIE_SCC_A_TO_COMP_A_5_DN")
	)
	(segment
		(start 275.200364 -254.14732)
		(end 274.884896 -253.933706)
		(width 0.127)
		(layer "In7.Cu")
		(net "PCIE_SCC_A_TO_COMP_A_5_DN")
	)
	(segment
		(start 259.785358 -236.601762)
		(end 259.593588 -236.555026)
		(width 0.127)
		(layer "In7.Cu")
		(net "PCIE_SCC_A_TO_COMP_A_5_DN")
	)
	(segment
		(start 236.224064 -198.130668)
		(end 232.668572 -184.289954)
		(width 0.127)
		(layer "In7.Cu")
		(net "PCIE_SCC_A_TO_COMP_A_5_DN")
	)
	(segment
		(start 274.69084 -253.971044)
		(end 274.375372 -253.75743)
		(width 0.127)
		(layer "In7.Cu")
		(net "PCIE_SCC_A_TO_COMP_A_5_DN")
	)
	(segment
		(start 268.800834 -249.80392)
		(end 268.592808 -249.844052)
		(width 0.127)
		(layer "In7.Cu")
		(net "PCIE_SCC_A_TO_COMP_A_5_DN")
	)
	(segment
		(start 278.797004 -254.82931)
		(end 278.797004 -255.303274)
		(width 0.127)
		(layer "In7.Cu")
		(net "PCIE_SCC_A_TO_COMP_A_5_DN")
	)
	(segment
		(start 276.100286 -254.925068)
		(end 276.062948 -254.731012)
		(width 0.127)
		(layer "In7.Cu")
		(net "PCIE_SCC_A_TO_COMP_A_5_DN")
	)
	(segment
		(start 264.932922 -245.06555)
		(end 264.740898 -245.018814)
		(width 0.127)
		(layer "In7.Cu")
		(net "PCIE_SCC_A_TO_COMP_A_5_DN")
	)
	(segment
		(start 267.71346 -249.24893)
		(end 267.03401 -248.78919)
		(width 0.127)
		(layer "In7.Cu")
		(net "PCIE_SCC_A_TO_COMP_A_5_DN")
	)
	(segment
		(start 265.084052 -245.582948)
		(end 265.130788 -245.390924)
		(width 0.127)
		(layer "In7.Cu")
		(net "PCIE_SCC_A_TO_COMP_A_5_DN")
	)
	(segment
		(start 278.637746 -255.462532)
		(end 276.894544 -255.462532)
		(width 0.127)
		(layer "In7.Cu")
		(net "PCIE_SCC_A_TO_COMP_A_5_DN")
	)
	(segment
		(start 236.803946 -154.12212)
		(end 236.79404 -154.1272)
		(width 0.127)
		(layer "In7.Cu")
		(net "PCIE_SCC_A_TO_COMP_A_5_DN")
	)
	(segment
		(start 276.36343 -255.103122)
		(end 276.100286 -254.925068)
		(width 0.127)
		(layer "In7.Cu")
		(net "PCIE_SCC_A_TO_COMP_A_5_DN")
	)
	(segment
		(start 276.894544 -255.462532)
		(end 276.36343 -255.103122)
		(width 0.127)
		(layer "In7.Cu")
		(net "PCIE_SCC_A_TO_COMP_A_5_DN")
	)
	(segment
		(start 259.983478 -236.92739)
		(end 259.785358 -236.601762)
		(width 0.127)
		(layer "In7.Cu")
		(net "PCIE_SCC_A_TO_COMP_A_5_DN")
	)
	(segment
		(start 268.27734 -249.630692)
		(end 268.237208 -249.422412)
		(width 0.127)
		(layer "In7.Cu")
		(net "PCIE_SCC_A_TO_COMP_A_5_DN")
	)
	(arc
		(start 278.670004 -254.70231)
		(mid 278.759807 -254.739507)
		(end 278.797004 -254.82931)
		(width 0.127)
		(layer "In7.Cu")
		(net "PCIE_SCC_A_TO_COMP_A_5_DN")
	)
	(arc
		(start 236.836966 -153.91892)
		(mid 236.871756 -154.02885)
		(end 236.803946 -154.12212)
		(width 0.127)
		(layer "In7.Cu")
		(net "PCIE_SCC_A_TO_COMP_A_5_DN")
	)
	(arc
		(start 278.797004 -255.303274)
		(mid 278.750358 -255.415886)
		(end 278.637746 -255.462532)
		(width 0.127)
		(layer "In7.Cu")
		(net "PCIE_SCC_A_TO_COMP_A_5_DN")
	)
	(arc
		(start 236.450886 -153.63952)
		(mid 236.549448 -153.659125)
		(end 236.633004 -153.714958)
		(width 0.127)
		(layer "In7.Cu")
		(net "PCIE_SCC_A_TO_COMP_A_5_DN")
	)
	(segment
		(start 264.131806 -248.924318)
		(end 235.34624 -201.593196)
		(width 0.127)
		(layer "In7.Cu")
		(net "PCIE_SCC_A_TO_COMP_A_4_DP")
	)
	(segment
		(start 235.75772 -149.360128)
		(end 236.452664 -149.360128)
		(width 0.127)
		(layer "In7.Cu")
		(net "PCIE_SCC_A_TO_COMP_A_4_DP")
	)
	(segment
		(start 236.829346 -149.516084)
		(end 237.148116 -149.834854)
		(width 0.127)
		(layer "In7.Cu")
		(net "PCIE_SCC_A_TO_COMP_A_4_DP")
	)
	(segment
		(start 280.076402 -256.629408)
		(end 280.076402 -257.103372)
		(width 0.127)
		(layer "In7.Cu")
		(net "PCIE_SCC_A_TO_COMP_A_4_DP")
	)
	(segment
		(start 230.754428 -152.406604)
		(end 235.75772 -149.360128)
		(width 0.127)
		(layer "In7.Cu")
		(net "PCIE_SCC_A_TO_COMP_A_4_DP")
	)
	(segment
		(start 227.199444 -169.87012)
		(end 230.754428 -152.406604)
		(width 0.127)
		(layer "In7.Cu")
		(net "PCIE_SCC_A_TO_COMP_A_4_DP")
	)
	(segment
		(start 276.86635 -257.54203)
		(end 264.131806 -248.924318)
		(width 0.127)
		(layer "In7.Cu")
		(net "PCIE_SCC_A_TO_COMP_A_4_DP")
	)
	(segment
		(start 279.637744 -257.54203)
		(end 276.86635 -257.54203)
		(width 0.127)
		(layer "In7.Cu")
		(net "PCIE_SCC_A_TO_COMP_A_4_DP")
	)
	(segment
		(start 237.324138 -149.863302)
		(end 238.05007 -149.499828)
		(width 0.127)
		(layer "In7.Cu")
		(net "PCIE_SCC_A_TO_COMP_A_4_DP")
	)
	(segment
		(start 235.34624 -201.593196)
		(end 227.199444 -169.87012)
		(width 0.127)
		(layer "In7.Cu")
		(net "PCIE_SCC_A_TO_COMP_A_4_DP")
	)
	(segment
		(start 280.636726 -256.502408)
		(end 280.203402 -256.502408)
		(width 0.127)
		(layer "In7.Cu")
		(net "PCIE_SCC_A_TO_COMP_A_4_DP")
	)
	(arc
		(start 280.203402 -256.502408)
		(mid 280.113599 -256.539605)
		(end 280.076402 -256.629408)
		(width 0.127)
		(layer "In7.Cu")
		(net "PCIE_SCC_A_TO_COMP_A_4_DP")
	)
	(arc
		(start 236.452664 -149.360128)
		(mid 236.656496 -149.400673)
		(end 236.829346 -149.516084)
		(width 0.127)
		(layer "In7.Cu")
		(net "PCIE_SCC_A_TO_COMP_A_4_DP")
	)
	(arc
		(start 280.076402 -257.103372)
		(mid 279.947922 -257.41355)
		(end 279.637744 -257.54203)
		(width 0.127)
		(layer "In7.Cu")
		(net "PCIE_SCC_A_TO_COMP_A_4_DP")
	)
	(arc
		(start 237.148116 -149.834854)
		(mid 237.231528 -149.877515)
		(end 237.324138 -149.863302)
		(width 0.127)
		(layer "In7.Cu")
		(net "PCIE_SCC_A_TO_COMP_A_4_DP")
	)
	(segment
		(start 231.00411 -152.581864)
		(end 235.836206 -149.639528)
		(width 0.127)
		(layer "In7.Cu")
		(net "PCIE_SCC_A_TO_COMP_A_4_DN")
	)
	(segment
		(start 267.9573 -251.17552)
		(end 267.641832 -250.96216)
		(width 0.127)
		(layer "In7.Cu")
		(net "PCIE_SCC_A_TO_COMP_A_4_DN")
	)
	(segment
		(start 227.48621 -169.862754)
		(end 231.00411 -152.581864)
		(width 0.127)
		(layer "In7.Cu")
		(net "PCIE_SCC_A_TO_COMP_A_4_DN")
	)
	(segment
		(start 262.375142 -245.229126)
		(end 262.177022 -244.903752)
		(width 0.127)
		(layer "In7.Cu")
		(net "PCIE_SCC_A_TO_COMP_A_4_DN")
	)
	(segment
		(start 265.563858 -249.387106)
		(end 265.369802 -249.424698)
		(width 0.127)
		(layer "In7.Cu")
		(net "PCIE_SCC_A_TO_COMP_A_4_DN")
	)
	(segment
		(start 236.631734 -149.713696)
		(end 236.836966 -149.918928)
		(width 0.127)
		(layer "In7.Cu")
		(net "PCIE_SCC_A_TO_COMP_A_4_DN")
	)
	(segment
		(start 265.879326 -249.60072)
		(end 265.563858 -249.387106)
		(width 0.127)
		(layer "In7.Cu")
		(net "PCIE_SCC_A_TO_COMP_A_4_DN")
	)
	(segment
		(start 262.916162 -246.118888)
		(end 262.718296 -245.793514)
		(width 0.127)
		(layer "In7.Cu")
		(net "PCIE_SCC_A_TO_COMP_A_4_DN")
	)
	(segment
		(start 276.952202 -257.26263)
		(end 275.873464 -256.532634)
		(width 0.127)
		(layer "In7.Cu")
		(net "PCIE_SCC_A_TO_COMP_A_4_DN")
	)
	(segment
		(start 263.067546 -246.63654)
		(end 262.869426 -246.310912)
		(width 0.127)
		(layer "In7.Cu")
		(net "PCIE_SCC_A_TO_COMP_A_4_DN")
	)
	(segment
		(start 263.95172 -248.090436)
		(end 263.998456 -247.898412)
		(width 0.127)
		(layer "In7.Cu")
		(net "PCIE_SCC_A_TO_COMP_A_4_DN")
	)
	(segment
		(start 236.79404 -150.127208)
		(end 236.050074 -150.499826)
		(width 0.127)
		(layer "In7.Cu")
		(net "PCIE_SCC_A_TO_COMP_A_4_DN")
	)
	(segment
		(start 275.873464 -256.532634)
		(end 275.833332 -256.324608)
		(width 0.127)
		(layer "In7.Cu")
		(net "PCIE_SCC_A_TO_COMP_A_4_DN")
	)
	(segment
		(start 274.43049 -255.556004)
		(end 274.114768 -255.342644)
		(width 0.127)
		(layer "In7.Cu")
		(net "PCIE_SCC_A_TO_COMP_A_4_DN")
	)
	(segment
		(start 231.546654 -185.673238)
		(end 227.48621 -169.862754)
		(width 0.127)
		(layer "In7.Cu")
		(net "PCIE_SCC_A_TO_COMP_A_4_DN")
	)
	(segment
		(start 279.797002 -256.629408)
		(end 279.797002 -257.103372)
		(width 0.127)
		(layer "In7.Cu")
		(net "PCIE_SCC_A_TO_COMP_A_4_DN")
	)
	(segment
		(start 262.526272 -245.746778)
		(end 262.328406 -245.42115)
		(width 0.127)
		(layer "In7.Cu")
		(net "PCIE_SCC_A_TO_COMP_A_4_DN")
	)
	(segment
		(start 266.426442 -249.970798)
		(end 266.232386 -250.00839)
		(width 0.127)
		(layer "In7.Cu")
		(net "PCIE_SCC_A_TO_COMP_A_4_DN")
	)
	(segment
		(start 265.916918 -249.794776)
		(end 265.879326 -249.60072)
		(width 0.127)
		(layer "In7.Cu")
		(net "PCIE_SCC_A_TO_COMP_A_4_DN")
	)
	(segment
		(start 235.60659 -201.483468)
		(end 231.546654 -185.673238)
		(width 0.127)
		(layer "In7.Cu")
		(net "PCIE_SCC_A_TO_COMP_A_4_DN")
	)
	(segment
		(start 255.190498 -233.684318)
		(end 254.992378 -233.35869)
		(width 0.127)
		(layer "In7.Cu")
		(net "PCIE_SCC_A_TO_COMP_A_4_DN")
	)
	(segment
		(start 274.638516 -255.515872)
		(end 274.43049 -255.556004)
		(width 0.127)
		(layer "In7.Cu")
		(net "PCIE_SCC_A_TO_COMP_A_4_DN")
	)
	(segment
		(start 262.328406 -245.42115)
		(end 262.375142 -245.229126)
		(width 0.127)
		(layer "In7.Cu")
		(net "PCIE_SCC_A_TO_COMP_A_4_DN")
	)
	(segment
		(start 256.121408 -234.946444)
		(end 255.923288 -234.620816)
		(width 0.127)
		(layer "In7.Cu")
		(net "PCIE_SCC_A_TO_COMP_A_4_DN")
	)
	(segment
		(start 265.369802 -249.424698)
		(end 264.338816 -248.72696)
		(width 0.127)
		(layer "In7.Cu")
		(net "PCIE_SCC_A_TO_COMP_A_4_DN")
	)
	(segment
		(start 267.288772 -250.55449)
		(end 267.094716 -250.591828)
		(width 0.127)
		(layer "In7.Cu")
		(net "PCIE_SCC_A_TO_COMP_A_4_DN")
	)
	(segment
		(start 262.177022 -244.903752)
		(end 261.985252 -244.857016)
		(width 0.127)
		(layer "In7.Cu")
		(net "PCIE_SCC_A_TO_COMP_A_4_DN")
	)
	(segment
		(start 266.74191 -250.184412)
		(end 266.426442 -249.970798)
		(width 0.127)
		(layer "In7.Cu")
		(net "PCIE_SCC_A_TO_COMP_A_4_DN")
	)
	(segment
		(start 254.841248 -232.841292)
		(end 254.649224 -232.794556)
		(width 0.127)
		(layer "In7.Cu")
		(net "PCIE_SCC_A_TO_COMP_A_4_DN")
	)
	(segment
		(start 273.759168 -254.921004)
		(end 273.551142 -254.961136)
		(width 0.127)
		(layer "In7.Cu")
		(net "PCIE_SCC_A_TO_COMP_A_4_DN")
	)
	(segment
		(start 263.80059 -247.573038)
		(end 263.608566 -247.526302)
		(width 0.127)
		(layer "In7.Cu")
		(net "PCIE_SCC_A_TO_COMP_A_4_DN")
	)
	(segment
		(start 254.992378 -233.35869)
		(end 255.039114 -233.16692)
		(width 0.127)
		(layer "In7.Cu")
		(net "PCIE_SCC_A_TO_COMP_A_4_DN")
	)
	(segment
		(start 235.836206 -149.639528)
		(end 236.452664 -149.639528)
		(width 0.127)
		(layer "In7.Cu")
		(net "PCIE_SCC_A_TO_COMP_A_4_DN")
	)
	(segment
		(start 262.869426 -246.310912)
		(end 262.916162 -246.118888)
		(width 0.127)
		(layer "In7.Cu")
		(net "PCIE_SCC_A_TO_COMP_A_4_DN")
	)
	(segment
		(start 274.074636 -255.134364)
		(end 273.759168 -254.921004)
		(width 0.127)
		(layer "In7.Cu")
		(net "PCIE_SCC_A_TO_COMP_A_4_DN")
	)
	(segment
		(start 275.833332 -256.324608)
		(end 275.517864 -256.110994)
		(width 0.127)
		(layer "In7.Cu")
		(net "PCIE_SCC_A_TO_COMP_A_4_DN")
	)
	(segment
		(start 274.994116 -255.937512)
		(end 274.953984 -255.729486)
		(width 0.127)
		(layer "In7.Cu")
		(net "PCIE_SCC_A_TO_COMP_A_4_DN")
	)
	(segment
		(start 279.637744 -257.26263)
		(end 276.952202 -257.26263)
		(width 0.127)
		(layer "In7.Cu")
		(net "PCIE_SCC_A_TO_COMP_A_4_DN")
	)
	(segment
		(start 268.504162 -251.545598)
		(end 268.466824 -251.351796)
		(width 0.127)
		(layer "In7.Cu")
		(net "PCIE_SCC_A_TO_COMP_A_4_DN")
	)
	(segment
		(start 263.457436 -247.00865)
		(end 263.259316 -246.683276)
		(width 0.127)
		(layer "In7.Cu")
		(net "PCIE_SCC_A_TO_COMP_A_4_DN")
	)
	(segment
		(start 266.779248 -250.378468)
		(end 266.74191 -250.184412)
		(width 0.127)
		(layer "In7.Cu")
		(net "PCIE_SCC_A_TO_COMP_A_4_DN")
	)
	(segment
		(start 268.466824 -251.351796)
		(end 268.151356 -251.138182)
		(width 0.127)
		(layer "In7.Cu")
		(net "PCIE_SCC_A_TO_COMP_A_4_DN")
	)
	(segment
		(start 267.60424 -250.768104)
		(end 267.288772 -250.55449)
		(width 0.127)
		(layer "In7.Cu")
		(net "PCIE_SCC_A_TO_COMP_A_4_DN")
	)
	(segment
		(start 263.998456 -247.898412)
		(end 263.80059 -247.573038)
		(width 0.127)
		(layer "In7.Cu")
		(net "PCIE_SCC_A_TO_COMP_A_4_DN")
	)
	(segment
		(start 255.533652 -234.248452)
		(end 255.580388 -234.056682)
		(width 0.127)
		(layer "In7.Cu")
		(net "PCIE_SCC_A_TO_COMP_A_4_DN")
	)
	(segment
		(start 255.731518 -234.57408)
		(end 255.533652 -234.248452)
		(width 0.127)
		(layer "In7.Cu")
		(net "PCIE_SCC_A_TO_COMP_A_4_DN")
	)
	(segment
		(start 275.517864 -256.110994)
		(end 275.309584 -256.151126)
		(width 0.127)
		(layer "In7.Cu")
		(net "PCIE_SCC_A_TO_COMP_A_4_DN")
	)
	(segment
		(start 279.236678 -256.502408)
		(end 279.670002 -256.502408)
		(width 0.127)
		(layer "In7.Cu")
		(net "PCIE_SCC_A_TO_COMP_A_4_DN")
	)
	(segment
		(start 255.039114 -233.16692)
		(end 254.841248 -232.841292)
		(width 0.127)
		(layer "In7.Cu")
		(net "PCIE_SCC_A_TO_COMP_A_4_DN")
	)
	(segment
		(start 262.718296 -245.793514)
		(end 262.526272 -245.746778)
		(width 0.127)
		(layer "In7.Cu")
		(net "PCIE_SCC_A_TO_COMP_A_4_DN")
	)
	(segment
		(start 263.4107 -247.200674)
		(end 263.457436 -247.00865)
		(width 0.127)
		(layer "In7.Cu")
		(net "PCIE_SCC_A_TO_COMP_A_4_DN")
	)
	(segment
		(start 263.608566 -247.526302)
		(end 263.4107 -247.200674)
		(width 0.127)
		(layer "In7.Cu")
		(net "PCIE_SCC_A_TO_COMP_A_4_DN")
	)
	(segment
		(start 256.074672 -235.138214)
		(end 256.121408 -234.946444)
		(width 0.127)
		(layer "In7.Cu")
		(net "PCIE_SCC_A_TO_COMP_A_4_DN")
	)
	(segment
		(start 255.382268 -233.731054)
		(end 255.190498 -233.684318)
		(width 0.127)
		(layer "In7.Cu")
		(net "PCIE_SCC_A_TO_COMP_A_4_DN")
	)
	(segment
		(start 264.338816 -248.72696)
		(end 263.95172 -248.090436)
		(width 0.127)
		(layer "In7.Cu")
		(net "PCIE_SCC_A_TO_COMP_A_4_DN")
	)
	(segment
		(start 274.114768 -255.342644)
		(end 274.074636 -255.134364)
		(width 0.127)
		(layer "In7.Cu")
		(net "PCIE_SCC_A_TO_COMP_A_4_DN")
	)
	(segment
		(start 275.309584 -256.151126)
		(end 274.994116 -255.937512)
		(width 0.127)
		(layer "In7.Cu")
		(net "PCIE_SCC_A_TO_COMP_A_4_DN")
	)
	(segment
		(start 267.094716 -250.591828)
		(end 266.779248 -250.378468)
		(width 0.127)
		(layer "In7.Cu")
		(net "PCIE_SCC_A_TO_COMP_A_4_DN")
	)
	(segment
		(start 266.232386 -250.00839)
		(end 265.916918 -249.794776)
		(width 0.127)
		(layer "In7.Cu")
		(net "PCIE_SCC_A_TO_COMP_A_4_DN")
	)
	(segment
		(start 267.641832 -250.96216)
		(end 267.60424 -250.768104)
		(width 0.127)
		(layer "In7.Cu")
		(net "PCIE_SCC_A_TO_COMP_A_4_DN")
	)
	(segment
		(start 274.953984 -255.729486)
		(end 274.638516 -255.515872)
		(width 0.127)
		(layer "In7.Cu")
		(net "PCIE_SCC_A_TO_COMP_A_4_DN")
	)
	(segment
		(start 254.649224 -232.794556)
		(end 235.60659 -201.483468)
		(width 0.127)
		(layer "In7.Cu")
		(net "PCIE_SCC_A_TO_COMP_A_4_DN")
	)
	(segment
		(start 255.923288 -234.620816)
		(end 255.731518 -234.57408)
		(width 0.127)
		(layer "In7.Cu")
		(net "PCIE_SCC_A_TO_COMP_A_4_DN")
	)
	(segment
		(start 261.985252 -244.857016)
		(end 256.074672 -235.138214)
		(width 0.127)
		(layer "In7.Cu")
		(net "PCIE_SCC_A_TO_COMP_A_4_DN")
	)
	(segment
		(start 255.580388 -234.056682)
		(end 255.382268 -233.731054)
		(width 0.127)
		(layer "In7.Cu")
		(net "PCIE_SCC_A_TO_COMP_A_4_DN")
	)
	(segment
		(start 236.803946 -150.122128)
		(end 236.79404 -150.127208)
		(width 0.127)
		(layer "In7.Cu")
		(net "PCIE_SCC_A_TO_COMP_A_4_DN")
	)
	(segment
		(start 268.151356 -251.138182)
		(end 267.9573 -251.17552)
		(width 0.127)
		(layer "In7.Cu")
		(net "PCIE_SCC_A_TO_COMP_A_4_DN")
	)
	(segment
		(start 273.551142 -254.961136)
		(end 268.504162 -251.545598)
		(width 0.127)
		(layer "In7.Cu")
		(net "PCIE_SCC_A_TO_COMP_A_4_DN")
	)
	(segment
		(start 263.259316 -246.683276)
		(end 263.067546 -246.63654)
		(width 0.127)
		(layer "In7.Cu")
		(net "PCIE_SCC_A_TO_COMP_A_4_DN")
	)
	(arc
		(start 279.670002 -256.502408)
		(mid 279.759805 -256.539605)
		(end 279.797002 -256.629408)
		(width 0.127)
		(layer "In7.Cu")
		(net "PCIE_SCC_A_TO_COMP_A_4_DN")
	)
	(arc
		(start 236.836966 -149.918928)
		(mid 236.872386 -150.028963)
		(end 236.803946 -150.122128)
		(width 0.127)
		(layer "In7.Cu")
		(net "PCIE_SCC_A_TO_COMP_A_4_DN")
	)
	(arc
		(start 279.797002 -257.103372)
		(mid 279.750356 -257.215984)
		(end 279.637744 -257.26263)
		(width 0.127)
		(layer "In7.Cu")
		(net "PCIE_SCC_A_TO_COMP_A_4_DN")
	)
	(arc
		(start 236.452664 -149.639528)
		(mid 236.549574 -149.658805)
		(end 236.631734 -149.713696)
		(width 0.127)
		(layer "In7.Cu")
		(net "PCIE_SCC_A_TO_COMP_A_4_DN")
	)
	(segment
		(start 234.12069 -202.541886)
		(end 222.669354 -157.960822)
		(width 0.127)
		(layer "In7.Cu")
		(net "PCIE_SCC_A_TO_COMP_A_3_DP")
	)
	(segment
		(start 236.813344 -129.500122)
		(end 237.148116 -129.834894)
		(width 0.127)
		(layer "In7.Cu")
		(net "PCIE_SCC_A_TO_COMP_A_3_DP")
	)
	(segment
		(start 279.076404 -258.429252)
		(end 279.076404 -258.903216)
		(width 0.127)
		(layer "In7.Cu")
		(net "PCIE_SCC_A_TO_COMP_A_3_DP")
	)
	(segment
		(start 235.544614 -129.360168)
		(end 236.47527 -129.360168)
		(width 0.127)
		(layer "In7.Cu")
		(net "PCIE_SCC_A_TO_COMP_A_3_DP")
	)
	(segment
		(start 237.324138 -129.863342)
		(end 238.05007 -129.499868)
		(width 0.127)
		(layer "In7.Cu")
		(net "PCIE_SCC_A_TO_COMP_A_3_DP")
	)
	(segment
		(start 222.669354 -157.960822)
		(end 225.960686 -141.793468)
		(width 0.127)
		(layer "In7.Cu")
		(net "PCIE_SCC_A_TO_COMP_A_3_DP")
	)
	(segment
		(start 279.636728 -258.302252)
		(end 279.203404 -258.302252)
		(width 0.127)
		(layer "In7.Cu")
		(net "PCIE_SCC_A_TO_COMP_A_3_DP")
	)
	(segment
		(start 225.960686 -141.793468)
		(end 233.047286 -130.880358)
		(width 0.127)
		(layer "In7.Cu")
		(net "PCIE_SCC_A_TO_COMP_A_3_DP")
	)
	(segment
		(start 262.805418 -249.707146)
		(end 234.12069 -202.541886)
		(width 0.127)
		(layer "In7.Cu")
		(net "PCIE_SCC_A_TO_COMP_A_3_DP")
	)
	(segment
		(start 277.047452 -259.341874)
		(end 262.805418 -249.707146)
		(width 0.127)
		(layer "In7.Cu")
		(net "PCIE_SCC_A_TO_COMP_A_3_DP")
	)
	(segment
		(start 278.637746 -259.341874)
		(end 277.047452 -259.341874)
		(width 0.127)
		(layer "In7.Cu")
		(net "PCIE_SCC_A_TO_COMP_A_3_DP")
	)
	(segment
		(start 233.047286 -130.880358)
		(end 235.544614 -129.360168)
		(width 0.127)
		(layer "In7.Cu")
		(net "PCIE_SCC_A_TO_COMP_A_3_DP")
	)
	(arc
		(start 237.148116 -129.834894)
		(mid 237.231528 -129.877555)
		(end 237.324138 -129.863342)
		(width 0.127)
		(layer "In7.Cu")
		(net "PCIE_SCC_A_TO_COMP_A_3_DP")
	)
	(arc
		(start 279.203404 -258.302252)
		(mid 279.113601 -258.339449)
		(end 279.076404 -258.429252)
		(width 0.127)
		(layer "In7.Cu")
		(net "PCIE_SCC_A_TO_COMP_A_3_DP")
	)
	(arc
		(start 279.076404 -258.903216)
		(mid 278.947924 -259.213394)
		(end 278.637746 -259.341874)
		(width 0.127)
		(layer "In7.Cu")
		(net "PCIE_SCC_A_TO_COMP_A_3_DP")
	)
	(arc
		(start 236.47527 -129.360168)
		(mid 236.658203 -129.396556)
		(end 236.813344 -129.500122)
		(width 0.127)
		(layer "In7.Cu")
		(net "PCIE_SCC_A_TO_COMP_A_3_DP")
	)
	(segment
		(start 274.951444 -257.405378)
		(end 274.635976 -257.192018)
		(width 0.127)
		(layer "In7.Cu")
		(net "PCIE_SCC_A_TO_COMP_A_3_DN")
	)
	(segment
		(start 266.146026 -251.461016)
		(end 265.830304 -251.247402)
		(width 0.127)
		(layer "In7.Cu")
		(net "PCIE_SCC_A_TO_COMP_A_3_DN")
	)
	(segment
		(start 260.49859 -245.107714)
		(end 260.30682 -245.060978)
		(width 0.127)
		(layer "In7.Cu")
		(net "PCIE_SCC_A_TO_COMP_A_3_DN")
	)
	(segment
		(start 236.615732 -129.697734)
		(end 236.836966 -129.918968)
		(width 0.127)
		(layer "In7.Cu")
		(net "PCIE_SCC_A_TO_COMP_A_3_DN")
	)
	(segment
		(start 222.95612 -157.953456)
		(end 226.224084 -141.901164)
		(width 0.127)
		(layer "In7.Cu")
		(net "PCIE_SCC_A_TO_COMP_A_3_DN")
	)
	(segment
		(start 226.224084 -141.901164)
		(end 233.247184 -131.086098)
		(width 0.127)
		(layer "In7.Cu")
		(net "PCIE_SCC_A_TO_COMP_A_3_DN")
	)
	(segment
		(start 267.361416 -252.45187)
		(end 267.045948 -252.23851)
		(width 0.127)
		(layer "In7.Cu")
		(net "PCIE_SCC_A_TO_COMP_A_3_DN")
	)
	(segment
		(start 262.273288 -248.294398)
		(end 262.320024 -248.102628)
		(width 0.127)
		(layer "In7.Cu")
		(net "PCIE_SCC_A_TO_COMP_A_3_DN")
	)
	(segment
		(start 275.870924 -258.208526)
		(end 275.830792 -258.0005)
		(width 0.127)
		(layer "In7.Cu")
		(net "PCIE_SCC_A_TO_COMP_A_3_DN")
	)
	(segment
		(start 274.112228 -257.018536)
		(end 274.072096 -256.81051)
		(width 0.127)
		(layer "In7.Cu")
		(net "PCIE_SCC_A_TO_COMP_A_3_DN")
	)
	(segment
		(start 262.122158 -247.777)
		(end 261.930134 -247.730264)
		(width 0.127)
		(layer "In7.Cu")
		(net "PCIE_SCC_A_TO_COMP_A_3_DN")
	)
	(segment
		(start 267.871194 -252.627892)
		(end 267.555472 -252.414532)
		(width 0.127)
		(layer "In7.Cu")
		(net "PCIE_SCC_A_TO_COMP_A_3_DN")
	)
	(segment
		(start 236.803946 -130.122168)
		(end 236.79404 -130.127248)
		(width 0.127)
		(layer "In7.Cu")
		(net "PCIE_SCC_A_TO_COMP_A_3_DN")
	)
	(segment
		(start 262.320024 -248.102628)
		(end 262.122158 -247.777)
		(width 0.127)
		(layer "In7.Cu")
		(net "PCIE_SCC_A_TO_COMP_A_3_DN")
	)
	(segment
		(start 267.00861 -252.044454)
		(end 266.692888 -251.831094)
		(width 0.127)
		(layer "In7.Cu")
		(net "PCIE_SCC_A_TO_COMP_A_3_DN")
	)
	(segment
		(start 261.389114 -246.840502)
		(end 261.190994 -246.514874)
		(width 0.127)
		(layer "In7.Cu")
		(net "PCIE_SCC_A_TO_COMP_A_3_DN")
	)
	(segment
		(start 265.636502 -251.284994)
		(end 263.012428 -249.509788)
		(width 0.127)
		(layer "In7.Cu")
		(net "PCIE_SCC_A_TO_COMP_A_3_DN")
	)
	(segment
		(start 253.79045 -234.07751)
		(end 253.598426 -234.030774)
		(width 0.127)
		(layer "In7.Cu")
		(net "PCIE_SCC_A_TO_COMP_A_3_DN")
	)
	(segment
		(start 254.52959 -235.2929)
		(end 254.33147 -234.967272)
		(width 0.127)
		(layer "In7.Cu")
		(net "PCIE_SCC_A_TO_COMP_A_3_DN")
	)
	(segment
		(start 267.045948 -252.23851)
		(end 267.00861 -252.044454)
		(width 0.127)
		(layer "In7.Cu")
		(net "PCIE_SCC_A_TO_COMP_A_3_DN")
	)
	(segment
		(start 268.224 -253.035562)
		(end 267.908532 -252.821948)
		(width 0.127)
		(layer "In7.Cu")
		(net "PCIE_SCC_A_TO_COMP_A_3_DN")
	)
	(segment
		(start 267.908532 -252.821948)
		(end 267.871194 -252.627892)
		(width 0.127)
		(layer "In7.Cu")
		(net "PCIE_SCC_A_TO_COMP_A_3_DN")
	)
	(segment
		(start 253.598426 -234.030774)
		(end 253.40056 -233.705146)
		(width 0.127)
		(layer "In7.Cu")
		(net "PCIE_SCC_A_TO_COMP_A_3_DN")
	)
	(segment
		(start 233.247184 -131.086098)
		(end 235.6231 -129.639568)
		(width 0.127)
		(layer "In7.Cu")
		(net "PCIE_SCC_A_TO_COMP_A_3_DN")
	)
	(segment
		(start 267.555472 -252.414532)
		(end 267.361416 -252.45187)
		(width 0.127)
		(layer "In7.Cu")
		(net "PCIE_SCC_A_TO_COMP_A_3_DN")
	)
	(segment
		(start 254.33147 -234.967272)
		(end 254.1397 -234.920536)
		(width 0.127)
		(layer "In7.Cu")
		(net "PCIE_SCC_A_TO_COMP_A_3_DN")
	)
	(segment
		(start 268.733524 -253.211584)
		(end 268.418056 -252.99797)
		(width 0.127)
		(layer "In7.Cu")
		(net "PCIE_SCC_A_TO_COMP_A_3_DN")
	)
	(segment
		(start 253.94158 -234.594908)
		(end 253.988316 -234.403138)
		(width 0.127)
		(layer "In7.Cu")
		(net "PCIE_SCC_A_TO_COMP_A_3_DN")
	)
	(segment
		(start 274.072096 -256.81051)
		(end 273.756374 -256.59715)
		(width 0.127)
		(layer "In7.Cu")
		(net "PCIE_SCC_A_TO_COMP_A_3_DN")
	)
	(segment
		(start 234.38104 -202.432158)
		(end 222.95612 -157.953456)
		(width 0.127)
		(layer "In7.Cu")
		(net "PCIE_SCC_A_TO_COMP_A_3_DN")
	)
	(segment
		(start 266.692888 -251.831094)
		(end 266.498832 -251.868432)
		(width 0.127)
		(layer "In7.Cu")
		(net "PCIE_SCC_A_TO_COMP_A_3_DN")
	)
	(segment
		(start 266.183364 -251.655072)
		(end 266.146026 -251.461016)
		(width 0.127)
		(layer "In7.Cu")
		(net "PCIE_SCC_A_TO_COMP_A_3_DN")
	)
	(segment
		(start 236.79404 -130.127248)
		(end 236.050074 -130.499866)
		(width 0.127)
		(layer "In7.Cu")
		(net "PCIE_SCC_A_TO_COMP_A_3_DN")
	)
	(segment
		(start 261.190994 -246.514874)
		(end 261.23773 -246.323104)
		(width 0.127)
		(layer "In7.Cu")
		(net "PCIE_SCC_A_TO_COMP_A_3_DN")
	)
	(segment
		(start 254.482854 -235.48467)
		(end 254.52959 -235.2929)
		(width 0.127)
		(layer "In7.Cu")
		(net "PCIE_SCC_A_TO_COMP_A_3_DN")
	)
	(segment
		(start 274.635976 -257.192018)
		(end 274.427696 -257.23215)
		(width 0.127)
		(layer "In7.Cu")
		(net "PCIE_SCC_A_TO_COMP_A_3_DN")
	)
	(segment
		(start 278.637746 -259.062474)
		(end 277.133304 -259.062474)
		(width 0.127)
		(layer "In7.Cu")
		(net "PCIE_SCC_A_TO_COMP_A_3_DN")
	)
	(segment
		(start 268.418056 -252.99797)
		(end 268.224 -253.035562)
		(width 0.127)
		(layer "In7.Cu")
		(net "PCIE_SCC_A_TO_COMP_A_3_DN")
	)
	(segment
		(start 261.23773 -246.323104)
		(end 261.039864 -245.997476)
		(width 0.127)
		(layer "In7.Cu")
		(net "PCIE_SCC_A_TO_COMP_A_3_DN")
	)
	(segment
		(start 274.991576 -257.613658)
		(end 274.951444 -257.405378)
		(width 0.127)
		(layer "In7.Cu")
		(net "PCIE_SCC_A_TO_COMP_A_3_DN")
	)
	(segment
		(start 277.133304 -259.062474)
		(end 275.870924 -258.208526)
		(width 0.127)
		(layer "In7.Cu")
		(net "PCIE_SCC_A_TO_COMP_A_3_DN")
	)
	(segment
		(start 253.447296 -233.513376)
		(end 253.249176 -233.187748)
		(width 0.127)
		(layer "In7.Cu")
		(net "PCIE_SCC_A_TO_COMP_A_3_DN")
	)
	(segment
		(start 254.1397 -234.920536)
		(end 253.94158 -234.594908)
		(width 0.127)
		(layer "In7.Cu")
		(net "PCIE_SCC_A_TO_COMP_A_3_DN")
	)
	(segment
		(start 261.732268 -247.404636)
		(end 261.779004 -247.212866)
		(width 0.127)
		(layer "In7.Cu")
		(net "PCIE_SCC_A_TO_COMP_A_3_DN")
	)
	(segment
		(start 273.548348 -256.637282)
		(end 268.771116 -253.405386)
		(width 0.127)
		(layer "In7.Cu")
		(net "PCIE_SCC_A_TO_COMP_A_3_DN")
	)
	(segment
		(start 260.69671 -245.433342)
		(end 260.49859 -245.107714)
		(width 0.127)
		(layer "In7.Cu")
		(net "PCIE_SCC_A_TO_COMP_A_3_DN")
	)
	(segment
		(start 261.930134 -247.730264)
		(end 261.732268 -247.404636)
		(width 0.127)
		(layer "In7.Cu")
		(net "PCIE_SCC_A_TO_COMP_A_3_DN")
	)
	(segment
		(start 260.84784 -245.95074)
		(end 260.649974 -245.625112)
		(width 0.127)
		(layer "In7.Cu")
		(net "PCIE_SCC_A_TO_COMP_A_3_DN")
	)
	(segment
		(start 273.756374 -256.59715)
		(end 273.548348 -256.637282)
		(width 0.127)
		(layer "In7.Cu")
		(net "PCIE_SCC_A_TO_COMP_A_3_DN")
	)
	(segment
		(start 275.515324 -257.786886)
		(end 275.307044 -257.827018)
		(width 0.127)
		(layer "In7.Cu")
		(net "PCIE_SCC_A_TO_COMP_A_3_DN")
	)
	(segment
		(start 275.830792 -258.0005)
		(end 275.515324 -257.786886)
		(width 0.127)
		(layer "In7.Cu")
		(net "PCIE_SCC_A_TO_COMP_A_3_DN")
	)
	(segment
		(start 261.580884 -246.887238)
		(end 261.389114 -246.840502)
		(width 0.127)
		(layer "In7.Cu")
		(net "PCIE_SCC_A_TO_COMP_A_3_DN")
	)
	(segment
		(start 260.649974 -245.625112)
		(end 260.69671 -245.433342)
		(width 0.127)
		(layer "In7.Cu")
		(net "PCIE_SCC_A_TO_COMP_A_3_DN")
	)
	(segment
		(start 253.40056 -233.705146)
		(end 253.447296 -233.513376)
		(width 0.127)
		(layer "In7.Cu")
		(net "PCIE_SCC_A_TO_COMP_A_3_DN")
	)
	(segment
		(start 278.797004 -258.429252)
		(end 278.797004 -258.903216)
		(width 0.127)
		(layer "In7.Cu")
		(net "PCIE_SCC_A_TO_COMP_A_3_DN")
	)
	(segment
		(start 274.427696 -257.23215)
		(end 274.112228 -257.018536)
		(width 0.127)
		(layer "In7.Cu")
		(net "PCIE_SCC_A_TO_COMP_A_3_DN")
	)
	(segment
		(start 260.30682 -245.060978)
		(end 254.482854 -235.48467)
		(width 0.127)
		(layer "In7.Cu")
		(net "PCIE_SCC_A_TO_COMP_A_3_DN")
	)
	(segment
		(start 265.830304 -251.247402)
		(end 265.636502 -251.284994)
		(width 0.127)
		(layer "In7.Cu")
		(net "PCIE_SCC_A_TO_COMP_A_3_DN")
	)
	(segment
		(start 261.039864 -245.997476)
		(end 260.84784 -245.95074)
		(width 0.127)
		(layer "In7.Cu")
		(net "PCIE_SCC_A_TO_COMP_A_3_DN")
	)
	(segment
		(start 253.249176 -233.187748)
		(end 253.057406 -233.141012)
		(width 0.127)
		(layer "In7.Cu")
		(net "PCIE_SCC_A_TO_COMP_A_3_DN")
	)
	(segment
		(start 253.057406 -233.141012)
		(end 234.38104 -202.432158)
		(width 0.127)
		(layer "In7.Cu")
		(net "PCIE_SCC_A_TO_COMP_A_3_DN")
	)
	(segment
		(start 268.771116 -253.405386)
		(end 268.733524 -253.211584)
		(width 0.127)
		(layer "In7.Cu")
		(net "PCIE_SCC_A_TO_COMP_A_3_DN")
	)
	(segment
		(start 253.988316 -234.403138)
		(end 253.79045 -234.07751)
		(width 0.127)
		(layer "In7.Cu")
		(net "PCIE_SCC_A_TO_COMP_A_3_DN")
	)
	(segment
		(start 266.498832 -251.868432)
		(end 266.183364 -251.655072)
		(width 0.127)
		(layer "In7.Cu")
		(net "PCIE_SCC_A_TO_COMP_A_3_DN")
	)
	(segment
		(start 235.6231 -129.639568)
		(end 236.47527 -129.639568)
		(width 0.127)
		(layer "In7.Cu")
		(net "PCIE_SCC_A_TO_COMP_A_3_DN")
	)
	(segment
		(start 263.012428 -249.509788)
		(end 262.273288 -248.294398)
		(width 0.127)
		(layer "In7.Cu")
		(net "PCIE_SCC_A_TO_COMP_A_3_DN")
	)
	(segment
		(start 261.779004 -247.212866)
		(end 261.580884 -246.887238)
		(width 0.127)
		(layer "In7.Cu")
		(net "PCIE_SCC_A_TO_COMP_A_3_DN")
	)
	(segment
		(start 275.307044 -257.827018)
		(end 274.991576 -257.613658)
		(width 0.127)
		(layer "In7.Cu")
		(net "PCIE_SCC_A_TO_COMP_A_3_DN")
	)
	(segment
		(start 278.23668 -258.302252)
		(end 278.670004 -258.302252)
		(width 0.127)
		(layer "In7.Cu")
		(net "PCIE_SCC_A_TO_COMP_A_3_DN")
	)
	(arc
		(start 278.797004 -258.903216)
		(mid 278.750358 -259.015828)
		(end 278.637746 -259.062474)
		(width 0.127)
		(layer "In7.Cu")
		(net "PCIE_SCC_A_TO_COMP_A_3_DN")
	)
	(arc
		(start 236.836966 -129.918968)
		(mid 236.872386 -130.029003)
		(end 236.803946 -130.122168)
		(width 0.127)
		(layer "In7.Cu")
		(net "PCIE_SCC_A_TO_COMP_A_3_DN")
	)
	(arc
		(start 278.670004 -258.302252)
		(mid 278.759807 -258.339449)
		(end 278.797004 -258.429252)
		(width 0.127)
		(layer "In7.Cu")
		(net "PCIE_SCC_A_TO_COMP_A_3_DN")
	)
	(arc
		(start 236.47527 -129.639568)
		(mid 236.551282 -129.654688)
		(end 236.615732 -129.697734)
		(width 0.127)
		(layer "In7.Cu")
		(net "PCIE_SCC_A_TO_COMP_A_3_DN")
	)
	(segment
		(start 236.83341 -125.520196)
		(end 237.148116 -125.834902)
		(width 0.127)
		(layer "In7.Cu")
		(net "PCIE_SCC_A_TO_COMP_A_2_DP")
	)
	(segment
		(start 235.545122 -125.360176)
		(end 236.446822 -125.360176)
		(width 0.127)
		(layer "In7.Cu")
		(net "PCIE_SCC_A_TO_COMP_A_2_DP")
	)
	(segment
		(start 279.637744 -261.141972)
		(end 277.106634 -261.141972)
		(width 0.127)
		(layer "In7.Cu")
		(net "PCIE_SCC_A_TO_COMP_A_2_DP")
	)
	(segment
		(start 237.324138 -125.86335)
		(end 238.05007 -125.499876)
		(width 0.127)
		(layer "In7.Cu")
		(net "PCIE_SCC_A_TO_COMP_A_2_DP")
	)
	(segment
		(start 232.767378 -203.056236)
		(end 231.271318 -197.230238)
		(width 0.127)
		(layer "In7.Cu")
		(net "PCIE_SCC_A_TO_COMP_A_2_DP")
	)
	(segment
		(start 221.105984 -157.644084)
		(end 224.50806 -140.894054)
		(width 0.127)
		(layer "In7.Cu")
		(net "PCIE_SCC_A_TO_COMP_A_2_DP")
	)
	(segment
		(start 229.23881 -133.609588)
		(end 233.975148 -126.315724)
		(width 0.127)
		(layer "In7.Cu")
		(net "PCIE_SCC_A_TO_COMP_A_2_DP")
	)
	(segment
		(start 277.106634 -261.141972)
		(end 261.785354 -250.773692)
		(width 0.127)
		(layer "In7.Cu")
		(net "PCIE_SCC_A_TO_COMP_A_2_DP")
	)
	(segment
		(start 224.50806 -140.894054)
		(end 229.23881 -133.609588)
		(width 0.127)
		(layer "In7.Cu")
		(net "PCIE_SCC_A_TO_COMP_A_2_DP")
	)
	(segment
		(start 261.785354 -250.773692)
		(end 232.767378 -203.056236)
		(width 0.127)
		(layer "In7.Cu")
		(net "PCIE_SCC_A_TO_COMP_A_2_DP")
	)
	(segment
		(start 280.076402 -260.22935)
		(end 280.076402 -260.703314)
		(width 0.127)
		(layer "In7.Cu")
		(net "PCIE_SCC_A_TO_COMP_A_2_DP")
	)
	(segment
		(start 280.636726 -260.10235)
		(end 280.203402 -260.10235)
		(width 0.127)
		(layer "In7.Cu")
		(net "PCIE_SCC_A_TO_COMP_A_2_DP")
	)
	(segment
		(start 233.975148 -126.315724)
		(end 235.545122 -125.360176)
		(width 0.127)
		(layer "In7.Cu")
		(net "PCIE_SCC_A_TO_COMP_A_2_DP")
	)
	(segment
		(start 231.271318 -197.230238)
		(end 221.105984 -157.644084)
		(width 0.127)
		(layer "In7.Cu")
		(net "PCIE_SCC_A_TO_COMP_A_2_DP")
	)
	(arc
		(start 280.076402 -260.703314)
		(mid 279.947922 -261.013492)
		(end 279.637744 -261.141972)
		(width 0.127)
		(layer "In7.Cu")
		(net "PCIE_SCC_A_TO_COMP_A_2_DP")
	)
	(arc
		(start 237.148116 -125.834902)
		(mid 237.231528 -125.877563)
		(end 237.324138 -125.86335)
		(width 0.127)
		(layer "In7.Cu")
		(net "PCIE_SCC_A_TO_COMP_A_2_DP")
	)
	(arc
		(start 236.446822 -125.360176)
		(mid 236.656054 -125.401701)
		(end 236.83341 -125.520196)
		(width 0.127)
		(layer "In7.Cu")
		(net "PCIE_SCC_A_TO_COMP_A_2_DP")
	)
	(arc
		(start 280.203402 -260.10235)
		(mid 280.113599 -260.139547)
		(end 280.076402 -260.22935)
		(width 0.127)
		(layer "In7.Cu")
		(net "PCIE_SCC_A_TO_COMP_A_2_DP")
	)
	(segment
		(start 252.190758 -234.458002)
		(end 233.027728 -202.946508)
		(width 0.127)
		(layer "In7.Cu")
		(net "PCIE_SCC_A_TO_COMP_A_2_DN")
	)
	(segment
		(start 253.074932 -235.911898)
		(end 253.121668 -235.720128)
		(width 0.127)
		(layer "In7.Cu")
		(net "PCIE_SCC_A_TO_COMP_A_2_DN")
	)
	(segment
		(start 265.092942 -252.493526)
		(end 264.884662 -252.533658)
		(width 0.127)
		(layer "In7.Cu")
		(net "PCIE_SCC_A_TO_COMP_A_2_DN")
	)
	(segment
		(start 256.598674 -241.7064)
		(end 256.645664 -241.51463)
		(width 0.127)
		(layer "In7.Cu")
		(net "PCIE_SCC_A_TO_COMP_A_2_DN")
	)
	(segment
		(start 264.005568 -251.938536)
		(end 261.992364 -250.576334)
		(width 0.127)
		(layer "In7.Cu")
		(net "PCIE_SCC_A_TO_COMP_A_2_DN")
	)
	(segment
		(start 279.637744 -260.862572)
		(end 277.192486 -260.862572)
		(width 0.127)
		(layer "In7.Cu")
		(net "PCIE_SCC_A_TO_COMP_A_2_DN")
	)
	(segment
		(start 276.341078 -260.117844)
		(end 276.02561 -259.90423)
		(width 0.127)
		(layer "In7.Cu")
		(net "PCIE_SCC_A_TO_COMP_A_2_DN")
	)
	(segment
		(start 234.175046 -126.521464)
		(end 235.623608 -125.639576)
		(width 0.127)
		(layer "In7.Cu")
		(net "PCIE_SCC_A_TO_COMP_A_2_DN")
	)
	(segment
		(start 265.40841 -252.70714)
		(end 265.092942 -252.493526)
		(width 0.127)
		(layer "In7.Cu")
		(net "PCIE_SCC_A_TO_COMP_A_2_DN")
	)
	(segment
		(start 274.10664 -258.774438)
		(end 273.791172 -258.560824)
		(width 0.127)
		(layer "In7.Cu")
		(net "PCIE_SCC_A_TO_COMP_A_2_DN")
	)
	(segment
		(start 273.438112 -258.153408)
		(end 273.24431 -258.190746)
		(width 0.127)
		(layer "In7.Cu")
		(net "PCIE_SCC_A_TO_COMP_A_2_DN")
	)
	(segment
		(start 257.186684 -242.404392)
		(end 256.988818 -242.078764)
		(width 0.127)
		(layer "In7.Cu")
		(net "PCIE_SCC_A_TO_COMP_A_2_DN")
	)
	(segment
		(start 257.139948 -242.596162)
		(end 257.186684 -242.404392)
		(width 0.127)
		(layer "In7.Cu")
		(net "PCIE_SCC_A_TO_COMP_A_2_DN")
	)
	(segment
		(start 279.797002 -260.22935)
		(end 279.797002 -260.703314)
		(width 0.127)
		(layer "In7.Cu")
		(net "PCIE_SCC_A_TO_COMP_A_2_DN")
	)
	(segment
		(start 264.569194 -252.320044)
		(end 264.529062 -252.112018)
		(width 0.127)
		(layer "In7.Cu")
		(net "PCIE_SCC_A_TO_COMP_A_2_DN")
	)
	(segment
		(start 257.337814 -242.92179)
		(end 257.139948 -242.596162)
		(width 0.127)
		(layer "In7.Cu")
		(net "PCIE_SCC_A_TO_COMP_A_2_DN")
	)
	(segment
		(start 258.070858 -243.858288)
		(end 257.878834 -243.811552)
		(width 0.127)
		(layer "In7.Cu")
		(net "PCIE_SCC_A_TO_COMP_A_2_DN")
	)
	(segment
		(start 257.680968 -243.485924)
		(end 257.727704 -243.294154)
		(width 0.127)
		(layer "In7.Cu")
		(net "PCIE_SCC_A_TO_COMP_A_2_DN")
	)
	(segment
		(start 274.616164 -258.95046)
		(end 274.300696 -258.736846)
		(width 0.127)
		(layer "In7.Cu")
		(net "PCIE_SCC_A_TO_COMP_A_2_DN")
	)
	(segment
		(start 253.121668 -235.720128)
		(end 252.923802 -235.3945)
		(width 0.127)
		(layer "In7.Cu")
		(net "PCIE_SCC_A_TO_COMP_A_2_DN")
	)
	(segment
		(start 275.16328 -259.320538)
		(end 274.969224 -259.35813)
		(width 0.127)
		(layer "In7.Cu")
		(net "PCIE_SCC_A_TO_COMP_A_2_DN")
	)
	(segment
		(start 252.731778 -235.347764)
		(end 252.533912 -235.022136)
		(width 0.127)
		(layer "In7.Cu")
		(net "PCIE_SCC_A_TO_COMP_A_2_DN")
	)
	(segment
		(start 257.878834 -243.811552)
		(end 257.680968 -243.485924)
		(width 0.127)
		(layer "In7.Cu")
		(net "PCIE_SCC_A_TO_COMP_A_2_DN")
	)
	(segment
		(start 275.516086 -259.728208)
		(end 275.478748 -259.534152)
		(width 0.127)
		(layer "In7.Cu")
		(net "PCIE_SCC_A_TO_COMP_A_2_DN")
	)
	(segment
		(start 253.616206 -236.801914)
		(end 253.662942 -236.60989)
		(width 0.127)
		(layer "In7.Cu")
		(net "PCIE_SCC_A_TO_COMP_A_2_DN")
	)
	(segment
		(start 261.992364 -250.576334)
		(end 258.221988 -244.37594)
		(width 0.127)
		(layer "In7.Cu")
		(net "PCIE_SCC_A_TO_COMP_A_2_DN")
	)
	(segment
		(start 264.884662 -252.533658)
		(end 264.569194 -252.320044)
		(width 0.127)
		(layer "In7.Cu")
		(net "PCIE_SCC_A_TO_COMP_A_2_DN")
	)
	(segment
		(start 224.771458 -141.00175)
		(end 234.175046 -126.521464)
		(width 0.127)
		(layer "In7.Cu")
		(net "PCIE_SCC_A_TO_COMP_A_2_DN")
	)
	(segment
		(start 253.464822 -236.284262)
		(end 253.273052 -236.237526)
		(width 0.127)
		(layer "In7.Cu")
		(net "PCIE_SCC_A_TO_COMP_A_2_DN")
	)
	(segment
		(start 274.300696 -258.736846)
		(end 274.10664 -258.774438)
		(width 0.127)
		(layer "In7.Cu")
		(net "PCIE_SCC_A_TO_COMP_A_2_DN")
	)
	(segment
		(start 265.448542 -252.915166)
		(end 265.40841 -252.70714)
		(width 0.127)
		(layer "In7.Cu")
		(net "PCIE_SCC_A_TO_COMP_A_2_DN")
	)
	(segment
		(start 258.221988 -244.37594)
		(end 258.268978 -244.183916)
		(width 0.127)
		(layer "In7.Cu")
		(net "PCIE_SCC_A_TO_COMP_A_2_DN")
	)
	(segment
		(start 253.273052 -236.237526)
		(end 253.074932 -235.911898)
		(width 0.127)
		(layer "In7.Cu")
		(net "PCIE_SCC_A_TO_COMP_A_2_DN")
	)
	(segment
		(start 252.533912 -235.022136)
		(end 252.580648 -234.830366)
		(width 0.127)
		(layer "In7.Cu")
		(net "PCIE_SCC_A_TO_COMP_A_2_DN")
	)
	(segment
		(start 253.662942 -236.60989)
		(end 253.464822 -236.284262)
		(width 0.127)
		(layer "In7.Cu")
		(net "PCIE_SCC_A_TO_COMP_A_2_DN")
	)
	(segment
		(start 231.542082 -197.160642)
		(end 221.39275 -157.636718)
		(width 0.127)
		(layer "In7.Cu")
		(net "PCIE_SCC_A_TO_COMP_A_2_DN")
	)
	(segment
		(start 257.727704 -243.294154)
		(end 257.529838 -242.968526)
		(width 0.127)
		(layer "In7.Cu")
		(net "PCIE_SCC_A_TO_COMP_A_2_DN")
	)
	(segment
		(start 236.803946 -126.122176)
		(end 236.79404 -126.127256)
		(width 0.127)
		(layer "In7.Cu")
		(net "PCIE_SCC_A_TO_COMP_A_2_DN")
	)
	(segment
		(start 252.923802 -235.3945)
		(end 252.731778 -235.347764)
		(width 0.127)
		(layer "In7.Cu")
		(net "PCIE_SCC_A_TO_COMP_A_2_DN")
	)
	(segment
		(start 264.529062 -252.112018)
		(end 264.213594 -251.898404)
		(width 0.127)
		(layer "In7.Cu")
		(net "PCIE_SCC_A_TO_COMP_A_2_DN")
	)
	(segment
		(start 273.24431 -258.190746)
		(end 266.32789 -253.510288)
		(width 0.127)
		(layer "In7.Cu")
		(net "PCIE_SCC_A_TO_COMP_A_2_DN")
	)
	(segment
		(start 233.027728 -202.946508)
		(end 231.542082 -197.160642)
		(width 0.127)
		(layer "In7.Cu")
		(net "PCIE_SCC_A_TO_COMP_A_2_DN")
	)
	(segment
		(start 256.447544 -241.189002)
		(end 256.25552 -241.142266)
		(width 0.127)
		(layer "In7.Cu")
		(net "PCIE_SCC_A_TO_COMP_A_2_DN")
	)
	(segment
		(start 266.287758 -253.302008)
		(end 265.97229 -253.088648)
		(width 0.127)
		(layer "In7.Cu")
		(net "PCIE_SCC_A_TO_COMP_A_2_DN")
	)
	(segment
		(start 235.623608 -125.639576)
		(end 236.446822 -125.639576)
		(width 0.127)
		(layer "In7.Cu")
		(net "PCIE_SCC_A_TO_COMP_A_2_DN")
	)
	(segment
		(start 274.653756 -259.144516)
		(end 274.616164 -258.95046)
		(width 0.127)
		(layer "In7.Cu")
		(net "PCIE_SCC_A_TO_COMP_A_2_DN")
	)
	(segment
		(start 221.39275 -157.636718)
		(end 224.771458 -141.00175)
		(width 0.127)
		(layer "In7.Cu")
		(net "PCIE_SCC_A_TO_COMP_A_2_DN")
	)
	(segment
		(start 275.831554 -259.941568)
		(end 275.516086 -259.728208)
		(width 0.127)
		(layer "In7.Cu")
		(net "PCIE_SCC_A_TO_COMP_A_2_DN")
	)
	(segment
		(start 258.268978 -244.183916)
		(end 258.070858 -243.858288)
		(width 0.127)
		(layer "In7.Cu")
		(net "PCIE_SCC_A_TO_COMP_A_2_DN")
	)
	(segment
		(start 275.478748 -259.534152)
		(end 275.16328 -259.320538)
		(width 0.127)
		(layer "In7.Cu")
		(net "PCIE_SCC_A_TO_COMP_A_2_DN")
	)
	(segment
		(start 257.529838 -242.968526)
		(end 257.337814 -242.92179)
		(width 0.127)
		(layer "In7.Cu")
		(net "PCIE_SCC_A_TO_COMP_A_2_DN")
	)
	(segment
		(start 252.580648 -234.830366)
		(end 252.382782 -234.504738)
		(width 0.127)
		(layer "In7.Cu")
		(net "PCIE_SCC_A_TO_COMP_A_2_DN")
	)
	(segment
		(start 265.97229 -253.088648)
		(end 265.76401 -253.12878)
		(width 0.127)
		(layer "In7.Cu")
		(net "PCIE_SCC_A_TO_COMP_A_2_DN")
	)
	(segment
		(start 276.37867 -260.3119)
		(end 276.341078 -260.117844)
		(width 0.127)
		(layer "In7.Cu")
		(net "PCIE_SCC_A_TO_COMP_A_2_DN")
	)
	(segment
		(start 236.79404 -126.127256)
		(end 236.050074 -126.499874)
		(width 0.127)
		(layer "In7.Cu")
		(net "PCIE_SCC_A_TO_COMP_A_2_DN")
	)
	(segment
		(start 266.32789 -253.510288)
		(end 266.287758 -253.302008)
		(width 0.127)
		(layer "In7.Cu")
		(net "PCIE_SCC_A_TO_COMP_A_2_DN")
	)
	(segment
		(start 252.382782 -234.504738)
		(end 252.190758 -234.458002)
		(width 0.127)
		(layer "In7.Cu")
		(net "PCIE_SCC_A_TO_COMP_A_2_DN")
	)
	(segment
		(start 256.796794 -242.032028)
		(end 256.598674 -241.7064)
		(width 0.127)
		(layer "In7.Cu")
		(net "PCIE_SCC_A_TO_COMP_A_2_DN")
	)
	(segment
		(start 264.213594 -251.898404)
		(end 264.005568 -251.938536)
		(width 0.127)
		(layer "In7.Cu")
		(net "PCIE_SCC_A_TO_COMP_A_2_DN")
	)
	(segment
		(start 273.791172 -258.560824)
		(end 273.753834 -258.366768)
		(width 0.127)
		(layer "In7.Cu")
		(net "PCIE_SCC_A_TO_COMP_A_2_DN")
	)
	(segment
		(start 256.25552 -241.142266)
		(end 253.616206 -236.801914)
		(width 0.127)
		(layer "In7.Cu")
		(net "PCIE_SCC_A_TO_COMP_A_2_DN")
	)
	(segment
		(start 276.02561 -259.90423)
		(end 275.831554 -259.941568)
		(width 0.127)
		(layer "In7.Cu")
		(net "PCIE_SCC_A_TO_COMP_A_2_DN")
	)
	(segment
		(start 277.192486 -260.862572)
		(end 276.37867 -260.3119)
		(width 0.127)
		(layer "In7.Cu")
		(net "PCIE_SCC_A_TO_COMP_A_2_DN")
	)
	(segment
		(start 274.969224 -259.35813)
		(end 274.653756 -259.144516)
		(width 0.127)
		(layer "In7.Cu")
		(net "PCIE_SCC_A_TO_COMP_A_2_DN")
	)
	(segment
		(start 256.645664 -241.51463)
		(end 256.447544 -241.189002)
		(width 0.127)
		(layer "In7.Cu")
		(net "PCIE_SCC_A_TO_COMP_A_2_DN")
	)
	(segment
		(start 279.236678 -260.10235)
		(end 279.670002 -260.10235)
		(width 0.127)
		(layer "In7.Cu")
		(net "PCIE_SCC_A_TO_COMP_A_2_DN")
	)
	(segment
		(start 273.753834 -258.366768)
		(end 273.438112 -258.153408)
		(width 0.127)
		(layer "In7.Cu")
		(net "PCIE_SCC_A_TO_COMP_A_2_DN")
	)
	(segment
		(start 236.635798 -125.717808)
		(end 236.836966 -125.918976)
		(width 0.127)
		(layer "In7.Cu")
		(net "PCIE_SCC_A_TO_COMP_A_2_DN")
	)
	(segment
		(start 265.76401 -253.12878)
		(end 265.448542 -252.915166)
		(width 0.127)
		(layer "In7.Cu")
		(net "PCIE_SCC_A_TO_COMP_A_2_DN")
	)
	(segment
		(start 256.988818 -242.078764)
		(end 256.796794 -242.032028)
		(width 0.127)
		(layer "In7.Cu")
		(net "PCIE_SCC_A_TO_COMP_A_2_DN")
	)
	(arc
		(start 279.670002 -260.10235)
		(mid 279.759805 -260.139547)
		(end 279.797002 -260.22935)
		(width 0.127)
		(layer "In7.Cu")
		(net "PCIE_SCC_A_TO_COMP_A_2_DN")
	)
	(arc
		(start 236.446822 -125.639576)
		(mid 236.549078 -125.659916)
		(end 236.635798 -125.717808)
		(width 0.127)
		(layer "In7.Cu")
		(net "PCIE_SCC_A_TO_COMP_A_2_DN")
	)
	(arc
		(start 279.797002 -260.703314)
		(mid 279.750356 -260.815926)
		(end 279.637744 -260.862572)
		(width 0.127)
		(layer "In7.Cu")
		(net "PCIE_SCC_A_TO_COMP_A_2_DN")
	)
	(arc
		(start 236.836966 -125.918976)
		(mid 236.872386 -126.029011)
		(end 236.803946 -126.122176)
		(width 0.127)
		(layer "In7.Cu")
		(net "PCIE_SCC_A_TO_COMP_A_2_DN")
	)
	(segment
		(start 216.34958 -172.996098)
		(end 223.20885 -139.293346)
		(width 0.127)
		(layer "In7.Cu")
		(net "PCIE_SCC_A_TO_COMP_A_1_DP")
	)
	(segment
		(start 223.20885 -139.293346)
		(end 234.403646 -122.05462)
		(width 0.127)
		(layer "In7.Cu")
		(net "PCIE_SCC_A_TO_COMP_A_1_DP")
	)
	(segment
		(start 218.8464 -182.719472)
		(end 216.34958 -172.996098)
		(width 0.127)
		(layer "In7.Cu")
		(net "PCIE_SCC_A_TO_COMP_A_1_DP")
	)
	(segment
		(start 276.860508 -262.94207)
		(end 261.19836 -252.344936)
		(width 0.127)
		(layer "In7.Cu")
		(net "PCIE_SCC_A_TO_COMP_A_1_DP")
	)
	(segment
		(start 279.076404 -262.029194)
		(end 279.076404 -262.503158)
		(width 0.127)
		(layer "In7.Cu")
		(net "PCIE_SCC_A_TO_COMP_A_1_DP")
	)
	(segment
		(start 261.19836 -252.344936)
		(end 218.8464 -182.719472)
		(width 0.127)
		(layer "In7.Cu")
		(net "PCIE_SCC_A_TO_COMP_A_1_DP")
	)
	(segment
		(start 278.637492 -262.94207)
		(end 276.860508 -262.94207)
		(width 0.127)
		(layer "In7.Cu")
		(net "PCIE_SCC_A_TO_COMP_A_1_DP")
	)
	(segment
		(start 279.636728 -261.902194)
		(end 279.203404 -261.902194)
		(width 0.127)
		(layer "In7.Cu")
		(net "PCIE_SCC_A_TO_COMP_A_1_DP")
	)
	(segment
		(start 234.403646 -122.05462)
		(end 235.544868 -121.360184)
		(width 0.127)
		(layer "In7.Cu")
		(net "PCIE_SCC_A_TO_COMP_A_1_DP")
	)
	(segment
		(start 236.8423 -121.529094)
		(end 237.148116 -121.83491)
		(width 0.127)
		(layer "In7.Cu")
		(net "PCIE_SCC_A_TO_COMP_A_1_DP")
	)
	(segment
		(start 237.324138 -121.863358)
		(end 238.05007 -121.499884)
		(width 0.127)
		(layer "In7.Cu")
		(net "PCIE_SCC_A_TO_COMP_A_1_DP")
	)
	(segment
		(start 235.544868 -121.360184)
		(end 236.43463 -121.360184)
		(width 0.127)
		(layer "In7.Cu")
		(net "PCIE_SCC_A_TO_COMP_A_1_DP")
	)
	(arc
		(start 279.076404 -262.503158)
		(mid 278.94785 -262.813516)
		(end 278.637492 -262.94207)
		(width 0.127)
		(layer "In7.Cu")
		(net "PCIE_SCC_A_TO_COMP_A_1_DP")
	)
	(arc
		(start 236.43463 -121.360184)
		(mid 236.655238 -121.404141)
		(end 236.8423 -121.529094)
		(width 0.127)
		(layer "In7.Cu")
		(net "PCIE_SCC_A_TO_COMP_A_1_DP")
	)
	(arc
		(start 237.148116 -121.83491)
		(mid 237.231528 -121.877571)
		(end 237.324138 -121.863358)
		(width 0.127)
		(layer "In7.Cu")
		(net "PCIE_SCC_A_TO_COMP_A_1_DP")
	)
	(arc
		(start 279.203404 -261.902194)
		(mid 279.113601 -261.939391)
		(end 279.076404 -262.029194)
		(width 0.127)
		(layer "In7.Cu")
		(net "PCIE_SCC_A_TO_COMP_A_1_DP")
	)
	(segment
		(start 260.633464 -250.609608)
		(end 260.435344 -250.284234)
		(width 0.127)
		(layer "In7.Cu")
		(net "PCIE_SCC_A_TO_COMP_A_1_DN")
	)
	(segment
		(start 248.733818 -231.046782)
		(end 248.541794 -231.000046)
		(width 0.127)
		(layer "In7.Cu")
		(net "PCIE_SCC_A_TO_COMP_A_1_DN")
	)
	(segment
		(start 275.295106 -261.364476)
		(end 275.08708 -261.404608)
		(width 0.127)
		(layer "In7.Cu")
		(net "PCIE_SCC_A_TO_COMP_A_1_DN")
	)
	(segment
		(start 219.10675 -182.609744)
		(end 216.636346 -172.988732)
		(width 0.127)
		(layer "In7.Cu")
		(net "PCIE_SCC_A_TO_COMP_A_1_DN")
	)
	(segment
		(start 260.243574 -250.237498)
		(end 260.045454 -249.91187)
		(width 0.127)
		(layer "In7.Cu")
		(net "PCIE_SCC_A_TO_COMP_A_1_DN")
	)
	(segment
		(start 276.946106 -262.662416)
		(end 276.530054 -262.380984)
		(width 0.127)
		(layer "In7.Cu")
		(net "PCIE_SCC_A_TO_COMP_A_1_DN")
	)
	(segment
		(start 255.287526 -241.820954)
		(end 255.095502 -241.774218)
		(width 0.127)
		(layer "In7.Cu")
		(net "PCIE_SCC_A_TO_COMP_A_1_DN")
	)
	(segment
		(start 254.554228 -240.884456)
		(end 254.356362 -240.558828)
		(width 0.127)
		(layer "In7.Cu")
		(net "PCIE_SCC_A_TO_COMP_A_1_DN")
	)
	(segment
		(start 254.403098 -240.366804)
		(end 254.204978 -240.04143)
		(width 0.127)
		(layer "In7.Cu")
		(net "PCIE_SCC_A_TO_COMP_A_1_DN")
	)
	(segment
		(start 274.207732 -260.809486)
		(end 261.40537 -252.147578)
		(width 0.127)
		(layer "In7.Cu")
		(net "PCIE_SCC_A_TO_COMP_A_1_DN")
	)
	(segment
		(start 248.39041 -230.482648)
		(end 248.192544 -230.15702)
		(width 0.127)
		(layer "In7.Cu")
		(net "PCIE_SCC_A_TO_COMP_A_1_DN")
	)
	(segment
		(start 278.797004 -262.029194)
		(end 278.797004 -262.503158)
		(width 0.127)
		(layer "In7.Cu")
		(net "PCIE_SCC_A_TO_COMP_A_1_DN")
	)
	(segment
		(start 254.746252 -240.931192)
		(end 254.554228 -240.884456)
		(width 0.127)
		(layer "In7.Cu")
		(net "PCIE_SCC_A_TO_COMP_A_1_DN")
	)
	(segment
		(start 275.610574 -261.577836)
		(end 275.295106 -261.364476)
		(width 0.127)
		(layer "In7.Cu")
		(net "PCIE_SCC_A_TO_COMP_A_1_DN")
	)
	(segment
		(start 255.438656 -242.338352)
		(end 255.485392 -242.146328)
		(width 0.127)
		(layer "In7.Cu")
		(net "PCIE_SCC_A_TO_COMP_A_1_DN")
	)
	(segment
		(start 274.415758 -260.769354)
		(end 274.207732 -260.809486)
		(width 0.127)
		(layer "In7.Cu")
		(net "PCIE_SCC_A_TO_COMP_A_1_DN")
	)
	(segment
		(start 247.84939 -229.592886)
		(end 247.65127 -229.267258)
		(width 0.127)
		(layer "In7.Cu")
		(net "PCIE_SCC_A_TO_COMP_A_1_DN")
	)
	(segment
		(start 255.97993 -243.228114)
		(end 256.026666 -243.03609)
		(width 0.127)
		(layer "In7.Cu")
		(net "PCIE_SCC_A_TO_COMP_A_1_DN")
	)
	(segment
		(start 260.435344 -250.284234)
		(end 260.243574 -250.237498)
		(width 0.127)
		(layer "In7.Cu")
		(net "PCIE_SCC_A_TO_COMP_A_1_DN")
	)
	(segment
		(start 276.530054 -262.380984)
		(end 276.489922 -262.172958)
		(width 0.127)
		(layer "In7.Cu")
		(net "PCIE_SCC_A_TO_COMP_A_1_DN")
	)
	(segment
		(start 254.204978 -240.04143)
		(end 254.012954 -239.994694)
		(width 0.127)
		(layer "In7.Cu")
		(net "PCIE_SCC_A_TO_COMP_A_1_DN")
	)
	(segment
		(start 247.26138 -228.895148)
		(end 247.308116 -228.703124)
		(width 0.127)
		(layer "In7.Cu")
		(net "PCIE_SCC_A_TO_COMP_A_1_DN")
	)
	(segment
		(start 255.095502 -241.774218)
		(end 254.897382 -241.44859)
		(width 0.127)
		(layer "In7.Cu")
		(net "PCIE_SCC_A_TO_COMP_A_1_DN")
	)
	(segment
		(start 274.771358 -261.190994)
		(end 274.731226 -260.982968)
		(width 0.127)
		(layer "In7.Cu")
		(net "PCIE_SCC_A_TO_COMP_A_1_DN")
	)
	(segment
		(start 259.894324 -249.394472)
		(end 259.7023 -249.347736)
		(width 0.127)
		(layer "In7.Cu")
		(net "PCIE_SCC_A_TO_COMP_A_1_DN")
	)
	(segment
		(start 274.731226 -260.982968)
		(end 274.415758 -260.769354)
		(width 0.127)
		(layer "In7.Cu")
		(net "PCIE_SCC_A_TO_COMP_A_1_DN")
	)
	(segment
		(start 229.037642 -130.830828)
		(end 234.603544 -122.26036)
		(width 0.127)
		(layer "In7.Cu")
		(net "PCIE_SCC_A_TO_COMP_A_1_DN")
	)
	(segment
		(start 254.944118 -241.256566)
		(end 254.746252 -240.931192)
		(width 0.127)
		(layer "In7.Cu")
		(net "PCIE_SCC_A_TO_COMP_A_1_DN")
	)
	(segment
		(start 234.603544 -122.26036)
		(end 235.623354 -121.639584)
		(width 0.127)
		(layer "In7.Cu")
		(net "PCIE_SCC_A_TO_COMP_A_1_DN")
	)
	(segment
		(start 275.08708 -261.404608)
		(end 274.771358 -261.190994)
		(width 0.127)
		(layer "In7.Cu")
		(net "PCIE_SCC_A_TO_COMP_A_1_DN")
	)
	(segment
		(start 255.485392 -242.146328)
		(end 255.287526 -241.820954)
		(width 0.127)
		(layer "In7.Cu")
		(net "PCIE_SCC_A_TO_COMP_A_1_DN")
	)
	(segment
		(start 275.966428 -261.999476)
		(end 275.650706 -261.786116)
		(width 0.127)
		(layer "In7.Cu")
		(net "PCIE_SCC_A_TO_COMP_A_1_DN")
	)
	(segment
		(start 255.636776 -242.663726)
		(end 255.438656 -242.338352)
		(width 0.127)
		(layer "In7.Cu")
		(net "PCIE_SCC_A_TO_COMP_A_1_DN")
	)
	(segment
		(start 236.79404 -122.127264)
		(end 236.050074 -122.499882)
		(width 0.127)
		(layer "In7.Cu")
		(net "PCIE_SCC_A_TO_COMP_A_1_DN")
	)
	(segment
		(start 259.550916 -248.830084)
		(end 259.35305 -248.50471)
		(width 0.127)
		(layer "In7.Cu")
		(net "PCIE_SCC_A_TO_COMP_A_1_DN")
	)
	(segment
		(start 254.012954 -239.994694)
		(end 248.884948 -231.56418)
		(width 0.127)
		(layer "In7.Cu")
		(net "PCIE_SCC_A_TO_COMP_A_1_DN")
	)
	(segment
		(start 276.94636 -262.66267)
		(end 276.946106 -262.662416)
		(width 0.127)
		(layer "In7.Cu")
		(net "PCIE_SCC_A_TO_COMP_A_1_DN")
	)
	(segment
		(start 255.828546 -242.710462)
		(end 255.636776 -242.663726)
		(width 0.127)
		(layer "In7.Cu")
		(net "PCIE_SCC_A_TO_COMP_A_1_DN")
	)
	(segment
		(start 248.884948 -231.56418)
		(end 248.931684 -231.37241)
		(width 0.127)
		(layer "In7.Cu")
		(net "PCIE_SCC_A_TO_COMP_A_1_DN")
	)
	(segment
		(start 260.045454 -249.91187)
		(end 260.09219 -249.719846)
		(width 0.127)
		(layer "In7.Cu")
		(net "PCIE_SCC_A_TO_COMP_A_1_DN")
	)
	(segment
		(start 261.40537 -252.147578)
		(end 260.586728 -250.801632)
		(width 0.127)
		(layer "In7.Cu")
		(net "PCIE_SCC_A_TO_COMP_A_1_DN")
	)
	(segment
		(start 248.931684 -231.37241)
		(end 248.733818 -231.046782)
		(width 0.127)
		(layer "In7.Cu")
		(net "PCIE_SCC_A_TO_COMP_A_1_DN")
	)
	(segment
		(start 259.161026 -248.457974)
		(end 255.97993 -243.228114)
		(width 0.127)
		(layer "In7.Cu")
		(net "PCIE_SCC_A_TO_COMP_A_1_DN")
	)
	(segment
		(start 247.65127 -229.267258)
		(end 247.459246 -229.220522)
		(width 0.127)
		(layer "In7.Cu")
		(net "PCIE_SCC_A_TO_COMP_A_1_DN")
	)
	(segment
		(start 247.459246 -229.220522)
		(end 247.26138 -228.895148)
		(width 0.127)
		(layer "In7.Cu")
		(net "PCIE_SCC_A_TO_COMP_A_1_DN")
	)
	(segment
		(start 247.308116 -228.703124)
		(end 247.109996 -228.377496)
		(width 0.127)
		(layer "In7.Cu")
		(net "PCIE_SCC_A_TO_COMP_A_1_DN")
	)
	(segment
		(start 259.7023 -249.347736)
		(end 259.50418 -249.022108)
		(width 0.127)
		(layer "In7.Cu")
		(net "PCIE_SCC_A_TO_COMP_A_1_DN")
	)
	(segment
		(start 260.586728 -250.801632)
		(end 260.633464 -250.609608)
		(width 0.127)
		(layer "In7.Cu")
		(net "PCIE_SCC_A_TO_COMP_A_1_DN")
	)
	(segment
		(start 248.343674 -230.674418)
		(end 248.39041 -230.482648)
		(width 0.127)
		(layer "In7.Cu")
		(net "PCIE_SCC_A_TO_COMP_A_1_DN")
	)
	(segment
		(start 260.09219 -249.719846)
		(end 259.894324 -249.394472)
		(width 0.127)
		(layer "In7.Cu")
		(net "PCIE_SCC_A_TO_COMP_A_1_DN")
	)
	(segment
		(start 256.026666 -243.03609)
		(end 255.828546 -242.710462)
		(width 0.127)
		(layer "In7.Cu")
		(net "PCIE_SCC_A_TO_COMP_A_1_DN")
	)
	(segment
		(start 276.174454 -261.959344)
		(end 275.966428 -261.999476)
		(width 0.127)
		(layer "In7.Cu")
		(net "PCIE_SCC_A_TO_COMP_A_1_DN")
	)
	(segment
		(start 248.00052 -230.110284)
		(end 247.802654 -229.78491)
		(width 0.127)
		(layer "In7.Cu")
		(net "PCIE_SCC_A_TO_COMP_A_1_DN")
	)
	(segment
		(start 259.50418 -249.022108)
		(end 259.550916 -248.830084)
		(width 0.127)
		(layer "In7.Cu")
		(net "PCIE_SCC_A_TO_COMP_A_1_DN")
	)
	(segment
		(start 216.636346 -172.988732)
		(end 223.472248 -139.401042)
		(width 0.127)
		(layer "In7.Cu")
		(net "PCIE_SCC_A_TO_COMP_A_1_DN")
	)
	(segment
		(start 247.109996 -228.377496)
		(end 246.918226 -228.33076)
		(width 0.127)
		(layer "In7.Cu")
		(net "PCIE_SCC_A_TO_COMP_A_1_DN")
	)
	(segment
		(start 259.35305 -248.50471)
		(end 259.161026 -248.457974)
		(width 0.127)
		(layer "In7.Cu")
		(net "PCIE_SCC_A_TO_COMP_A_1_DN")
	)
	(segment
		(start 278.23668 -261.902194)
		(end 278.670004 -261.902194)
		(width 0.127)
		(layer "In7.Cu")
		(net "PCIE_SCC_A_TO_COMP_A_1_DN")
	)
	(segment
		(start 254.356362 -240.558828)
		(end 254.403098 -240.366804)
		(width 0.127)
		(layer "In7.Cu")
		(net "PCIE_SCC_A_TO_COMP_A_1_DN")
	)
	(segment
		(start 236.803946 -122.122184)
		(end 236.79404 -122.127264)
		(width 0.127)
		(layer "In7.Cu")
		(net "PCIE_SCC_A_TO_COMP_A_1_DN")
	)
	(segment
		(start 235.623354 -121.639584)
		(end 236.434376 -121.639584)
		(width 0.127)
		(layer "In7.Cu")
		(net "PCIE_SCC_A_TO_COMP_A_1_DN")
	)
	(segment
		(start 254.897382 -241.44859)
		(end 254.944118 -241.256566)
		(width 0.127)
		(layer "In7.Cu")
		(net "PCIE_SCC_A_TO_COMP_A_1_DN")
	)
	(segment
		(start 248.192544 -230.15702)
		(end 248.00052 -230.110284)
		(width 0.127)
		(layer "In7.Cu")
		(net "PCIE_SCC_A_TO_COMP_A_1_DN")
	)
	(segment
		(start 247.802654 -229.78491)
		(end 247.84939 -229.592886)
		(width 0.127)
		(layer "In7.Cu")
		(net "PCIE_SCC_A_TO_COMP_A_1_DN")
	)
	(segment
		(start 276.489922 -262.172958)
		(end 276.174454 -261.959344)
		(width 0.127)
		(layer "In7.Cu")
		(net "PCIE_SCC_A_TO_COMP_A_1_DN")
	)
	(segment
		(start 275.650706 -261.786116)
		(end 275.610574 -261.577836)
		(width 0.127)
		(layer "In7.Cu")
		(net "PCIE_SCC_A_TO_COMP_A_1_DN")
	)
	(segment
		(start 278.637492 -262.66267)
		(end 276.94636 -262.66267)
		(width 0.127)
		(layer "In7.Cu")
		(net "PCIE_SCC_A_TO_COMP_A_1_DN")
	)
	(segment
		(start 248.541794 -231.000046)
		(end 248.343674 -230.674418)
		(width 0.127)
		(layer "In7.Cu")
		(net "PCIE_SCC_A_TO_COMP_A_1_DN")
	)
	(segment
		(start 246.918226 -228.33076)
		(end 219.10675 -182.609744)
		(width 0.127)
		(layer "In7.Cu")
		(net "PCIE_SCC_A_TO_COMP_A_1_DN")
	)
	(segment
		(start 236.644688 -121.726706)
		(end 236.836966 -121.918984)
		(width 0.127)
		(layer "In7.Cu")
		(net "PCIE_SCC_A_TO_COMP_A_1_DN")
	)
	(segment
		(start 223.472248 -139.401042)
		(end 229.037642 -130.830828)
		(width 0.127)
		(layer "In7.Cu")
		(net "PCIE_SCC_A_TO_COMP_A_1_DN")
	)
	(arc
		(start 236.836966 -121.918984)
		(mid 236.872386 -122.029019)
		(end 236.803946 -122.122184)
		(width 0.127)
		(layer "In7.Cu")
		(net "PCIE_SCC_A_TO_COMP_A_1_DN")
	)
	(arc
		(start 278.797004 -262.503158)
		(mid 278.750284 -262.61595)
		(end 278.637492 -262.66267)
		(width 0.127)
		(layer "In7.Cu")
		(net "PCIE_SCC_A_TO_COMP_A_1_DN")
	)
	(arc
		(start 278.670004 -261.902194)
		(mid 278.759807 -261.939391)
		(end 278.797004 -262.029194)
		(width 0.127)
		(layer "In7.Cu")
		(net "PCIE_SCC_A_TO_COMP_A_1_DN")
	)
	(arc
		(start 236.434376 -121.639584)
		(mid 236.548199 -121.662225)
		(end 236.644688 -121.726706)
		(width 0.127)
		(layer "In7.Cu")
		(net "PCIE_SCC_A_TO_COMP_A_1_DN")
	)
	(segment
		(start 280.636726 -263.702292)
		(end 280.203402 -263.702292)
		(width 0.127)
		(layer "In7.Cu")
		(net "PCIE_SCC_A_TO_COMP_A_0_DP")
	)
	(segment
		(start 264.365232 -256.351024)
		(end 263.330944 -255.651254)
		(width 0.127)
		(layer "In7.Cu")
		(net "PCIE_SCC_A_TO_COMP_A_0_DP")
	)
	(segment
		(start 234.744768 -117.848126)
		(end 235.138722 -117.608096)
		(width 0.127)
		(layer "In7.Cu")
		(net "PCIE_SCC_A_TO_COMP_A_0_DP")
	)
	(segment
		(start 235.545376 -117.360192)
		(end 236.454442 -117.360192)
		(width 0.127)
		(layer "In7.Cu")
		(net "PCIE_SCC_A_TO_COMP_A_0_DP")
	)
	(segment
		(start 276.845522 -264.796016)
		(end 264.365232 -256.351024)
		(width 0.127)
		(layer "In7.Cu")
		(net "PCIE_SCC_A_TO_COMP_A_0_DP")
	)
	(segment
		(start 260.17855 -253.517654)
		(end 253.976886 -243.321332)
		(width 0.127)
		(layer "In7.Cu")
		(net "PCIE_SCC_A_TO_COMP_A_0_DP")
	)
	(segment
		(start 262.29691 -254.951484)
		(end 260.17855 -253.517654)
		(width 0.127)
		(layer "In7.Cu")
		(net "PCIE_SCC_A_TO_COMP_A_0_DP")
	)
	(segment
		(start 280.076402 -263.829292)
		(end 280.076402 -264.303256)
		(width 0.127)
		(layer "In7.Cu")
		(net "PCIE_SCC_A_TO_COMP_A_0_DP")
	)
	(segment
		(start 218.068906 -184.28208)
		(end 214.949532 -172.127164)
		(width 0.127)
		(layer "In7.Cu")
		(net "PCIE_SCC_A_TO_COMP_A_0_DP")
	)
	(segment
		(start 279.583642 -264.796016)
		(end 276.845522 -264.796016)
		(width 0.127)
		(layer "In7.Cu")
		(net "PCIE_SCC_A_TO_COMP_A_0_DP")
	)
	(segment
		(start 235.138722 -117.608096)
		(end 235.545376 -117.360192)
		(width 0.127)
		(layer "In7.Cu")
		(net "PCIE_SCC_A_TO_COMP_A_0_DP")
	)
	(segment
		(start 214.949532 -172.127164)
		(end 222.011494 -137.44702)
		(width 0.127)
		(layer "In7.Cu")
		(net "PCIE_SCC_A_TO_COMP_A_0_DP")
	)
	(segment
		(start 237.324138 -117.863366)
		(end 238.05007 -117.499892)
		(width 0.127)
		(layer "In7.Cu")
		(net "PCIE_SCC_A_TO_COMP_A_0_DP")
	)
	(segment
		(start 253.976886 -243.321332)
		(end 218.068906 -184.28208)
		(width 0.127)
		(layer "In7.Cu")
		(net "PCIE_SCC_A_TO_COMP_A_0_DP")
	)
	(segment
		(start 236.828076 -117.514878)
		(end 237.148116 -117.834918)
		(width 0.127)
		(layer "In7.Cu")
		(net "PCIE_SCC_A_TO_COMP_A_0_DP")
	)
	(segment
		(start 222.011494 -137.44702)
		(end 234.744768 -117.848126)
		(width 0.127)
		(layer "In7.Cu")
		(net "PCIE_SCC_A_TO_COMP_A_0_DP")
	)
	(segment
		(start 263.330944 -255.651254)
		(end 262.29691 -254.951484)
		(width 0.127)
		(layer "In7.Cu")
		(net "PCIE_SCC_A_TO_COMP_A_0_DP")
	)
	(arc
		(start 280.203402 -263.702292)
		(mid 280.113599 -263.739489)
		(end 280.076402 -263.829292)
		(width 0.127)
		(layer "In7.Cu")
		(net "PCIE_SCC_A_TO_COMP_A_0_DP")
	)
	(arc
		(start 236.454442 -117.360192)
		(mid 236.656621 -117.400408)
		(end 236.828076 -117.514878)
		(width 0.127)
		(layer "In7.Cu")
		(net "PCIE_SCC_A_TO_COMP_A_0_DP")
	)
	(arc
		(start 237.148116 -117.834918)
		(mid 237.231528 -117.877579)
		(end 237.324138 -117.863366)
		(width 0.127)
		(layer "In7.Cu")
		(net "PCIE_SCC_A_TO_COMP_A_0_DP")
	)
	(arc
		(start 280.076402 -264.303256)
		(mid 279.932076 -264.65169)
		(end 279.583642 -264.796016)
		(width 0.127)
		(layer "In7.Cu")
		(net "PCIE_SCC_A_TO_COMP_A_0_DP")
	)
	(segment
		(start 275.831808 -263.591548)
		(end 275.623528 -263.63168)
		(width 0.127)
		(layer "In7.Cu")
		(net "PCIE_SCC_A_TO_COMP_A_0_DN")
	)
	(segment
		(start 259.49529 -251.587254)
		(end 259.303266 -251.540518)
		(width 0.127)
		(layer "In7.Cu")
		(net "PCIE_SCC_A_TO_COMP_A_0_DN")
	)
	(segment
		(start 234.944666 -118.053866)
		(end 235.623862 -117.639592)
		(width 0.127)
		(layer "In7.Cu")
		(net "PCIE_SCC_A_TO_COMP_A_0_DN")
	)
	(segment
		(start 260.38556 -253.320296)
		(end 260.38556 -253.320042)
		(width 0.127)
		(layer "In7.Cu")
		(net "PCIE_SCC_A_TO_COMP_A_0_DN")
	)
	(segment
		(start 279.236678 -263.702292)
		(end 279.670002 -263.702292)
		(width 0.127)
		(layer "In7.Cu")
		(net "PCIE_SCC_A_TO_COMP_A_0_DN")
	)
	(segment
		(start 267.196316 -257.760216)
		(end 267.00226 -257.797554)
		(width 0.127)
		(layer "In7.Cu")
		(net "PCIE_SCC_A_TO_COMP_A_0_DN")
	)
	(segment
		(start 254.545846 -243.449348)
		(end 254.347726 -243.12372)
		(width 0.127)
		(layer "In7.Cu")
		(net "PCIE_SCC_A_TO_COMP_A_0_DN")
	)
	(segment
		(start 267.864844 -258.381246)
		(end 267.549122 -258.167886)
		(width 0.127)
		(layer "In7.Cu")
		(net "PCIE_SCC_A_TO_COMP_A_0_DN")
	)
	(segment
		(start 274.95246 -262.996426)
		(end 274.744434 -263.036558)
		(width 0.127)
		(layer "In7.Cu")
		(net "PCIE_SCC_A_TO_COMP_A_0_DN")
	)
	(segment
		(start 276.187408 -264.013188)
		(end 276.147276 -263.805162)
		(width 0.127)
		(layer "In7.Cu")
		(net "PCIE_SCC_A_TO_COMP_A_0_DN")
	)
	(segment
		(start 264.52195 -256.119376)
		(end 260.38556 -253.320296)
		(width 0.127)
		(layer "In7.Cu")
		(net "PCIE_SCC_A_TO_COMP_A_0_DN")
	)
	(segment
		(start 255.04013 -244.53088)
		(end 255.086866 -244.33911)
		(width 0.127)
		(layer "In7.Cu")
		(net "PCIE_SCC_A_TO_COMP_A_0_DN")
	)
	(segment
		(start 268.058646 -258.343908)
		(end 267.864844 -258.381246)
		(width 0.127)
		(layer "In7.Cu")
		(net "PCIE_SCC_A_TO_COMP_A_0_DN")
	)
	(segment
		(start 236.79404 -118.127272)
		(end 236.050074 -118.49989)
		(width 0.127)
		(layer "In7.Cu")
		(net "PCIE_SCC_A_TO_COMP_A_0_DN")
	)
	(segment
		(start 222.274892 -137.55497)
		(end 234.944666 -118.053866)
		(width 0.127)
		(layer "In7.Cu")
		(net "PCIE_SCC_A_TO_COMP_A_0_DN")
	)
	(segment
		(start 254.347726 -243.12372)
		(end 254.155702 -243.076984)
		(width 0.127)
		(layer "In7.Cu")
		(net "PCIE_SCC_A_TO_COMP_A_0_DN")
	)
	(segment
		(start 255.237996 -244.856508)
		(end 255.04013 -244.53088)
		(width 0.127)
		(layer "In7.Cu")
		(net "PCIE_SCC_A_TO_COMP_A_0_DN")
	)
	(segment
		(start 268.727174 -258.964938)
		(end 268.411706 -258.751324)
		(width 0.127)
		(layer "In7.Cu")
		(net "PCIE_SCC_A_TO_COMP_A_0_DN")
	)
	(segment
		(start 258.610862 -250.133358)
		(end 258.412996 -249.80773)
		(width 0.127)
		(layer "In7.Cu")
		(net "PCIE_SCC_A_TO_COMP_A_0_DN")
	)
	(segment
		(start 259.844286 -252.43028)
		(end 259.64642 -252.104652)
		(width 0.127)
		(layer "In7.Cu")
		(net "PCIE_SCC_A_TO_COMP_A_0_DN")
	)
	(segment
		(start 235.623862 -117.639592)
		(end 236.454442 -117.639592)
		(width 0.127)
		(layer "In7.Cu")
		(net "PCIE_SCC_A_TO_COMP_A_0_DN")
	)
	(segment
		(start 255.627886 -245.228872)
		(end 255.43002 -244.903244)
		(width 0.127)
		(layer "In7.Cu")
		(net "PCIE_SCC_A_TO_COMP_A_0_DN")
	)
	(segment
		(start 254.155702 -243.076984)
		(end 218.329256 -184.172352)
		(width 0.127)
		(layer "In7.Cu")
		(net "PCIE_SCC_A_TO_COMP_A_0_DN")
	)
	(segment
		(start 274.744434 -263.036558)
		(end 274.428712 -262.823198)
		(width 0.127)
		(layer "In7.Cu")
		(net "PCIE_SCC_A_TO_COMP_A_0_DN")
	)
	(segment
		(start 215.236298 -172.120052)
		(end 222.274892 -137.55497)
		(width 0.127)
		(layer "In7.Cu")
		(net "PCIE_SCC_A_TO_COMP_A_0_DN")
	)
	(segment
		(start 236.630464 -117.71249)
		(end 236.836966 -117.918992)
		(width 0.127)
		(layer "In7.Cu")
		(net "PCIE_SCC_A_TO_COMP_A_0_DN")
	)
	(segment
		(start 254.696976 -243.966746)
		(end 254.49911 -243.641118)
		(width 0.127)
		(layer "In7.Cu")
		(net "PCIE_SCC_A_TO_COMP_A_0_DN")
	)
	(segment
		(start 266.139676 -257.214116)
		(end 264.52195 -256.119376)
		(width 0.127)
		(layer "In7.Cu")
		(net "PCIE_SCC_A_TO_COMP_A_0_DN")
	)
	(segment
		(start 259.152136 -251.02312)
		(end 258.954016 -250.697492)
		(width 0.127)
		(layer "In7.Cu")
		(net "PCIE_SCC_A_TO_COMP_A_0_DN")
	)
	(segment
		(start 267.00226 -257.797554)
		(end 266.686792 -257.584194)
		(width 0.127)
		(layer "In7.Cu")
		(net "PCIE_SCC_A_TO_COMP_A_0_DN")
	)
	(segment
		(start 279.797002 -263.829292)
		(end 279.797002 -264.303256)
		(width 0.127)
		(layer "In7.Cu")
		(net "PCIE_SCC_A_TO_COMP_A_0_DN")
	)
	(segment
		(start 255.58115 -245.420642)
		(end 255.627886 -245.228872)
		(width 0.127)
		(layer "In7.Cu")
		(net "PCIE_SCC_A_TO_COMP_A_0_DN")
	)
	(segment
		(start 269.236698 -259.14096)
		(end 268.92123 -258.9276)
		(width 0.127)
		(layer "In7.Cu")
		(net "PCIE_SCC_A_TO_COMP_A_0_DN")
	)
	(segment
		(start 268.411706 -258.751324)
		(end 268.374368 -258.557522)
		(width 0.127)
		(layer "In7.Cu")
		(net "PCIE_SCC_A_TO_COMP_A_0_DN")
	)
	(segment
		(start 259.64642 -252.104652)
		(end 259.693156 -251.912882)
		(width 0.127)
		(layer "In7.Cu")
		(net "PCIE_SCC_A_TO_COMP_A_0_DN")
	)
	(segment
		(start 268.92123 -258.9276)
		(end 268.727174 -258.964938)
		(width 0.127)
		(layer "In7.Cu")
		(net "PCIE_SCC_A_TO_COMP_A_0_DN")
	)
	(segment
		(start 274.073112 -262.401558)
		(end 273.865086 -262.44169)
		(width 0.127)
		(layer "In7.Cu")
		(net "PCIE_SCC_A_TO_COMP_A_0_DN")
	)
	(segment
		(start 218.329256 -184.172352)
		(end 215.236298 -172.120052)
		(width 0.127)
		(layer "In7.Cu")
		(net "PCIE_SCC_A_TO_COMP_A_0_DN")
	)
	(segment
		(start 266.686792 -257.584194)
		(end 266.649454 -257.390138)
		(width 0.127)
		(layer "In7.Cu")
		(net "PCIE_SCC_A_TO_COMP_A_0_DN")
	)
	(segment
		(start 269.27429 -259.335016)
		(end 269.236698 -259.14096)
		(width 0.127)
		(layer "In7.Cu")
		(net "PCIE_SCC_A_TO_COMP_A_0_DN")
	)
	(segment
		(start 258.761992 -250.650756)
		(end 258.564126 -250.325128)
		(width 0.127)
		(layer "In7.Cu")
		(net "PCIE_SCC_A_TO_COMP_A_0_DN")
	)
	(segment
		(start 258.954016 -250.697492)
		(end 258.761992 -250.650756)
		(width 0.127)
		(layer "In7.Cu")
		(net "PCIE_SCC_A_TO_COMP_A_0_DN")
	)
	(segment
		(start 266.333732 -257.176524)
		(end 266.139676 -257.214116)
		(width 0.127)
		(layer "In7.Cu")
		(net "PCIE_SCC_A_TO_COMP_A_0_DN")
	)
	(segment
		(start 259.693156 -251.912882)
		(end 259.49529 -251.587254)
		(width 0.127)
		(layer "In7.Cu")
		(net "PCIE_SCC_A_TO_COMP_A_0_DN")
	)
	(segment
		(start 258.564126 -250.325128)
		(end 258.610862 -250.133358)
		(width 0.127)
		(layer "In7.Cu")
		(net "PCIE_SCC_A_TO_COMP_A_0_DN")
	)
	(segment
		(start 275.623528 -263.63168)
		(end 275.30806 -263.418066)
		(width 0.127)
		(layer "In7.Cu")
		(net "PCIE_SCC_A_TO_COMP_A_0_DN")
	)
	(segment
		(start 259.303266 -251.540518)
		(end 259.1054 -251.21489)
		(width 0.127)
		(layer "In7.Cu")
		(net "PCIE_SCC_A_TO_COMP_A_0_DN")
	)
	(segment
		(start 274.38858 -262.614918)
		(end 274.073112 -262.401558)
		(width 0.127)
		(layer "In7.Cu")
		(net "PCIE_SCC_A_TO_COMP_A_0_DN")
	)
	(segment
		(start 279.583642 -264.516616)
		(end 276.931374 -264.516616)
		(width 0.127)
		(layer "In7.Cu")
		(net "PCIE_SCC_A_TO_COMP_A_0_DN")
	)
	(segment
		(start 275.267928 -263.21004)
		(end 274.95246 -262.996426)
		(width 0.127)
		(layer "In7.Cu")
		(net "PCIE_SCC_A_TO_COMP_A_0_DN")
	)
	(segment
		(start 267.549122 -258.167886)
		(end 267.511784 -257.97383)
		(width 0.127)
		(layer "In7.Cu")
		(net "PCIE_SCC_A_TO_COMP_A_0_DN")
	)
	(segment
		(start 260.23443 -252.802644)
		(end 260.03631 -252.477016)
		(width 0.127)
		(layer "In7.Cu")
		(net "PCIE_SCC_A_TO_COMP_A_0_DN")
	)
	(segment
		(start 275.30806 -263.418066)
		(end 275.267928 -263.21004)
		(width 0.127)
		(layer "In7.Cu")
		(net "PCIE_SCC_A_TO_COMP_A_0_DN")
	)
	(segment
		(start 258.412996 -249.80773)
		(end 258.220972 -249.760994)
		(width 0.127)
		(layer "In7.Cu")
		(net "PCIE_SCC_A_TO_COMP_A_0_DN")
	)
	(segment
		(start 267.511784 -257.97383)
		(end 267.196316 -257.760216)
		(width 0.127)
		(layer "In7.Cu")
		(net "PCIE_SCC_A_TO_COMP_A_0_DN")
	)
	(segment
		(start 274.428712 -262.823198)
		(end 274.38858 -262.614918)
		(width 0.127)
		(layer "In7.Cu")
		(net "PCIE_SCC_A_TO_COMP_A_0_DN")
	)
	(segment
		(start 254.888746 -244.013482)
		(end 254.696976 -243.966746)
		(width 0.127)
		(layer "In7.Cu")
		(net "PCIE_SCC_A_TO_COMP_A_0_DN")
	)
	(segment
		(start 273.865086 -262.44169)
		(end 269.27429 -259.335016)
		(width 0.127)
		(layer "In7.Cu")
		(net "PCIE_SCC_A_TO_COMP_A_0_DN")
	)
	(segment
		(start 266.649454 -257.390138)
		(end 266.333732 -257.176524)
		(width 0.127)
		(layer "In7.Cu")
		(net "PCIE_SCC_A_TO_COMP_A_0_DN")
	)
	(segment
		(start 268.374368 -258.557522)
		(end 268.058646 -258.343908)
		(width 0.127)
		(layer "In7.Cu")
		(net "PCIE_SCC_A_TO_COMP_A_0_DN")
	)
	(segment
		(start 236.803946 -118.122192)
		(end 236.79404 -118.127272)
		(width 0.127)
		(layer "In7.Cu")
		(net "PCIE_SCC_A_TO_COMP_A_0_DN")
	)
	(segment
		(start 260.03631 -252.477016)
		(end 259.844286 -252.43028)
		(width 0.127)
		(layer "In7.Cu")
		(net "PCIE_SCC_A_TO_COMP_A_0_DN")
	)
	(segment
		(start 276.147276 -263.805162)
		(end 275.831808 -263.591548)
		(width 0.127)
		(layer "In7.Cu")
		(net "PCIE_SCC_A_TO_COMP_A_0_DN")
	)
	(segment
		(start 255.43002 -244.903244)
		(end 255.237996 -244.856508)
		(width 0.127)
		(layer "In7.Cu")
		(net "PCIE_SCC_A_TO_COMP_A_0_DN")
	)
	(segment
		(start 259.1054 -251.21489)
		(end 259.152136 -251.02312)
		(width 0.127)
		(layer "In7.Cu")
		(net "PCIE_SCC_A_TO_COMP_A_0_DN")
	)
	(segment
		(start 254.49911 -243.641118)
		(end 254.545846 -243.449348)
		(width 0.127)
		(layer "In7.Cu")
		(net "PCIE_SCC_A_TO_COMP_A_0_DN")
	)
	(segment
		(start 276.931374 -264.516616)
		(end 276.187408 -264.013188)
		(width 0.127)
		(layer "In7.Cu")
		(net "PCIE_SCC_A_TO_COMP_A_0_DN")
	)
	(segment
		(start 255.086866 -244.33911)
		(end 254.888746 -244.013482)
		(width 0.127)
		(layer "In7.Cu")
		(net "PCIE_SCC_A_TO_COMP_A_0_DN")
	)
	(segment
		(start 260.38556 -253.320042)
		(end 260.187694 -252.994414)
		(width 0.127)
		(layer "In7.Cu")
		(net "PCIE_SCC_A_TO_COMP_A_0_DN")
	)
	(segment
		(start 258.220972 -249.760994)
		(end 255.58115 -245.420642)
		(width 0.127)
		(layer "In7.Cu")
		(net "PCIE_SCC_A_TO_COMP_A_0_DN")
	)
	(segment
		(start 260.187694 -252.994414)
		(end 260.23443 -252.802644)
		(width 0.127)
		(layer "In7.Cu")
		(net "PCIE_SCC_A_TO_COMP_A_0_DN")
	)
	(arc
		(start 236.454442 -117.639592)
		(mid 236.5497 -117.65854)
		(end 236.630464 -117.71249)
		(width 0.127)
		(layer "In7.Cu")
		(net "PCIE_SCC_A_TO_COMP_A_0_DN")
	)
	(arc
		(start 279.797002 -264.303256)
		(mid 279.73451 -264.454124)
		(end 279.583642 -264.516616)
		(width 0.127)
		(layer "In7.Cu")
		(net "PCIE_SCC_A_TO_COMP_A_0_DN")
	)
	(arc
		(start 279.670002 -263.702292)
		(mid 279.759805 -263.739489)
		(end 279.797002 -263.829292)
		(width 0.127)
		(layer "In7.Cu")
		(net "PCIE_SCC_A_TO_COMP_A_0_DN")
	)
	(arc
		(start 236.836966 -117.918992)
		(mid 236.872386 -118.029027)
		(end 236.803946 -118.122192)
		(width 0.127)
		(layer "In7.Cu")
		(net "PCIE_SCC_A_TO_COMP_A_0_DN")
	)
	(segment
		(start 388.59587 -34.595562)
		(end 380.863856 -45.757846)
		(width 0.1651)
		(layer "B.Cu")
		(net "PCIE_IOM_B_TO_COMP_B_9_DP")
	)
	(segment
		(start 273.61261 -186.132978)
		(end 272.320004 -181.23281)
		(width 0.1651)
		(layer "B.Cu")
		(net "PCIE_IOM_B_TO_COMP_B_9_DP")
	)
	(segment
		(start 387.716268 -21.504148)
		(end 388.078472 -21.504148)
		(width 0.1651)
		(layer "B.Cu")
		(net "PCIE_IOM_B_TO_COMP_B_9_DP")
	)
	(segment
		(start 272.320004 -181.23281)
		(end 276.969982 -170.171618)
		(width 0.1651)
		(layer "B.Cu")
		(net "PCIE_IOM_B_TO_COMP_B_9_DP")
	)
	(segment
		(start 278.04237 -189.696598)
		(end 273.61261 -186.132978)
		(width 0.1651)
		(layer "B.Cu")
		(net "PCIE_IOM_B_TO_COMP_B_9_DP")
	)
	(segment
		(start 276.969982 -170.171618)
		(end 278.386286 -169.38117)
		(width 0.1651)
		(layer "B.Cu")
		(net "PCIE_IOM_B_TO_COMP_B_9_DP")
	)
	(segment
		(start 281.715464 -190.86957)
		(end 278.04237 -189.696598)
		(width 0.1651)
		(layer "B.Cu")
		(net "PCIE_IOM_B_TO_COMP_B_9_DP")
	)
	(segment
		(start 372.222268 -65.962276)
		(end 289.443668 -186.394598)
		(width 0.1651)
		(layer "B.Cu")
		(net "PCIE_IOM_B_TO_COMP_B_9_DP")
	)
	(segment
		(start 380.863856 -45.757846)
		(end 372.222268 -65.962276)
		(width 0.1651)
		(layer "B.Cu")
		(net "PCIE_IOM_B_TO_COMP_B_9_DP")
	)
	(segment
		(start 387.549898 -20.950174)
		(end 387.549898 -21.337778)
		(width 0.1651)
		(layer "B.Cu")
		(net "PCIE_IOM_B_TO_COMP_B_9_DP")
	)
	(segment
		(start 280.089356 -169.83837)
		(end 280.75001 -169.499788)
		(width 0.1651)
		(layer "B.Cu")
		(net "PCIE_IOM_B_TO_COMP_B_9_DP")
	)
	(segment
		(start 279.918414 -169.860722)
		(end 279.933908 -169.863262)
		(width 0.1651)
		(layer "B.Cu")
		(net "PCIE_IOM_B_TO_COMP_B_9_DP")
	)
	(segment
		(start 279.573228 -169.584624)
		(end 279.778206 -169.789602)
		(width 0.1651)
		(layer "B.Cu")
		(net "PCIE_IOM_B_TO_COMP_B_9_DP")
	)
	(segment
		(start 278.386286 -169.38117)
		(end 279.088088 -169.38371)
		(width 0.1651)
		(layer "B.Cu")
		(net "PCIE_IOM_B_TO_COMP_B_9_DP")
	)
	(segment
		(start 289.443668 -186.394598)
		(end 285.300166 -189.7253)
		(width 0.1651)
		(layer "B.Cu")
		(net "PCIE_IOM_B_TO_COMP_B_9_DP")
	)
	(segment
		(start 285.300166 -189.7253)
		(end 281.715464 -190.86957)
		(width 0.1651)
		(layer "B.Cu")
		(net "PCIE_IOM_B_TO_COMP_B_9_DP")
	)
	(segment
		(start 388.59587 -22.021546)
		(end 388.59587 -34.595562)
		(width 0.1651)
		(layer "B.Cu")
		(net "PCIE_IOM_B_TO_COMP_B_9_DP")
	)
	(arc
		(start 279.933908 -169.863262)
		(mid 280.013618 -169.863189)
		(end 280.089356 -169.83837)
		(width 0.1651)
		(layer "B.Cu")
		(net "PCIE_IOM_B_TO_COMP_B_9_DP")
	)
	(arc
		(start 279.778206 -169.789602)
		(mid 279.842672 -169.836274)
		(end 279.918414 -169.860722)
		(width 0.1651)
		(layer "B.Cu")
		(net "PCIE_IOM_B_TO_COMP_B_9_DP")
	)
	(arc
		(start 387.549898 -21.337778)
		(mid 387.598627 -21.455419)
		(end 387.716268 -21.504148)
		(width 0.1651)
		(layer "B.Cu")
		(net "PCIE_IOM_B_TO_COMP_B_9_DP")
	)
	(arc
		(start 279.088088 -169.38371)
		(mid 279.25853 -169.405154)
		(end 279.418288 -169.468292)
		(width 0.1651)
		(layer "B.Cu")
		(net "PCIE_IOM_B_TO_COMP_B_9_DP")
	)
	(arc
		(start 388.078472 -21.504148)
		(mid 388.444328 -21.65569)
		(end 388.59587 -22.021546)
		(width 0.1651)
		(layer "B.Cu")
		(net "PCIE_IOM_B_TO_COMP_B_9_DP")
	)
	(arc
		(start 279.418288 -169.468292)
		(mid 279.499871 -169.520977)
		(end 279.573228 -169.584624)
		(width 0.1651)
		(layer "B.Cu")
		(net "PCIE_IOM_B_TO_COMP_B_9_DP")
	)
	(segment
		(start 289.22726 -186.193684)
		(end 285.15945 -189.463426)
		(width 0.1651)
		(layer "B.Cu")
		(net "PCIE_IOM_B_TO_COMP_B_9_DN")
	)
	(segment
		(start 290.207192 -184.566052)
		(end 290.236656 -184.725056)
		(width 0.1651)
		(layer "B.Cu")
		(net "PCIE_IOM_B_TO_COMP_B_9_DN")
	)
	(segment
		(start 336.83956 -116.70411)
		(end 336.871564 -116.877084)
		(width 0.1651)
		(layer "B.Cu")
		(net "PCIE_IOM_B_TO_COMP_B_9_DN")
	)
	(segment
		(start 301.338234 -168.353486)
		(end 301.370492 -168.52646)
		(width 0.1651)
		(layer "B.Cu")
		(net "PCIE_IOM_B_TO_COMP_B_9_DN")
	)
	(segment
		(start 326.382126 -131.935728)
		(end 326.10171 -132.343906)
		(width 0.1651)
		(layer "B.Cu")
		(net "PCIE_IOM_B_TO_COMP_B_9_DN")
	)
	(segment
		(start 371.964966 -65.820544)
		(end 337.99526 -115.24234)
		(width 0.1651)
		(layer "B.Cu")
		(net "PCIE_IOM_B_TO_COMP_B_9_DN")
	)
	(segment
		(start 301.791878 -167.913304)
		(end 301.618904 -167.945308)
		(width 0.1651)
		(layer "B.Cu")
		(net "PCIE_IOM_B_TO_COMP_B_9_DN")
	)
	(segment
		(start 315.444378 -148.050758)
		(end 315.285628 -148.080222)
		(width 0.1651)
		(layer "B.Cu")
		(net "PCIE_IOM_B_TO_COMP_B_9_DN")
	)
	(segment
		(start 300.214792 -169.98823)
		(end 299.934122 -170.396408)
		(width 0.1651)
		(layer "B.Cu")
		(net "PCIE_IOM_B_TO_COMP_B_9_DN")
	)
	(segment
		(start 301.370492 -168.52646)
		(end 301.089822 -168.934638)
		(width 0.1651)
		(layer "B.Cu")
		(net "PCIE_IOM_B_TO_COMP_B_9_DN")
	)
	(segment
		(start 327.922382 -129.89687)
		(end 327.763378 -129.926334)
		(width 0.1651)
		(layer "B.Cu")
		(net "PCIE_IOM_B_TO_COMP_B_9_DN")
	)
	(segment
		(start 290.487862 -184.157874)
		(end 290.207192 -184.566052)
		(width 0.1651)
		(layer "B.Cu")
		(net "PCIE_IOM_B_TO_COMP_B_9_DN")
	)
	(segment
		(start 315.695584 -147.483576)
		(end 315.725048 -147.64258)
		(width 0.1651)
		(layer "B.Cu")
		(net "PCIE_IOM_B_TO_COMP_B_9_DN")
	)
	(segment
		(start 300.916848 -168.966896)
		(end 300.636178 -169.375074)
		(width 0.1651)
		(layer "B.Cu")
		(net "PCIE_IOM_B_TO_COMP_B_9_DN")
	)
	(segment
		(start 327.763378 -129.926334)
		(end 327.482708 -130.334512)
		(width 0.1651)
		(layer "B.Cu")
		(net "PCIE_IOM_B_TO_COMP_B_9_DN")
	)
	(segment
		(start 316.38621 -146.479006)
		(end 316.415674 -146.637756)
		(width 0.1651)
		(layer "B.Cu")
		(net "PCIE_IOM_B_TO_COMP_B_9_DN")
	)
	(segment
		(start 301.089822 -168.934638)
		(end 300.916848 -168.966896)
		(width 0.1651)
		(layer "B.Cu")
		(net "PCIE_IOM_B_TO_COMP_B_9_DN")
	)
	(segment
		(start 309.320184 -156.75864)
		(end 309.349648 -156.917644)
		(width 0.1651)
		(layer "B.Cu")
		(net "PCIE_IOM_B_TO_COMP_B_9_DN")
	)
	(segment
		(start 316.415674 -146.637756)
		(end 316.135004 -147.045934)
		(width 0.1651)
		(layer "B.Cu")
		(net "PCIE_IOM_B_TO_COMP_B_9_DN")
	)
	(segment
		(start 315.034422 -148.647404)
		(end 309.759858 -156.320998)
		(width 0.1651)
		(layer "B.Cu")
		(net "PCIE_IOM_B_TO_COMP_B_9_DN")
	)
	(segment
		(start 307.528976 -159.36468)
		(end 307.248306 -159.772858)
		(width 0.1651)
		(layer "B.Cu")
		(net "PCIE_IOM_B_TO_COMP_B_9_DN")
	)
	(segment
		(start 316.82563 -146.041364)
		(end 316.66688 -146.070828)
		(width 0.1651)
		(layer "B.Cu")
		(net "PCIE_IOM_B_TO_COMP_B_9_DN")
	)
	(segment
		(start 326.54113 -131.906264)
		(end 326.382126 -131.935728)
		(width 0.1651)
		(layer "B.Cu")
		(net "PCIE_IOM_B_TO_COMP_B_9_DN")
	)
	(segment
		(start 299.232066 -171.417996)
		(end 299.26407 -171.59097)
		(width 0.1651)
		(layer "B.Cu")
		(net "PCIE_IOM_B_TO_COMP_B_9_DN")
	)
	(segment
		(start 290.236656 -184.725056)
		(end 289.22726 -186.193684)
		(width 0.1651)
		(layer "B.Cu")
		(net "PCIE_IOM_B_TO_COMP_B_9_DN")
	)
	(segment
		(start 299.966126 -170.569636)
		(end 299.68571 -170.977814)
		(width 0.1651)
		(layer "B.Cu")
		(net "PCIE_IOM_B_TO_COMP_B_9_DN")
	)
	(segment
		(start 300.387766 -169.956226)
		(end 300.214792 -169.98823)
		(width 0.1651)
		(layer "B.Cu")
		(net "PCIE_IOM_B_TO_COMP_B_9_DN")
	)
	(segment
		(start 337.822286 -115.274344)
		(end 337.541616 -115.682522)
		(width 0.1651)
		(layer "B.Cu")
		(net "PCIE_IOM_B_TO_COMP_B_9_DN")
	)
	(segment
		(start 326.792082 -131.339082)
		(end 326.821546 -131.498086)
		(width 0.1651)
		(layer "B.Cu")
		(net "PCIE_IOM_B_TO_COMP_B_9_DN")
	)
	(segment
		(start 337.99526 -115.24234)
		(end 337.822286 -115.274344)
		(width 0.1651)
		(layer "B.Cu")
		(net "PCIE_IOM_B_TO_COMP_B_9_DN")
	)
	(segment
		(start 316.66688 -146.070828)
		(end 316.38621 -146.479006)
		(width 0.1651)
		(layer "B.Cu")
		(net "PCIE_IOM_B_TO_COMP_B_9_DN")
	)
	(segment
		(start 326.10171 -132.343906)
		(end 326.131174 -132.50291)
		(width 0.1651)
		(layer "B.Cu")
		(net "PCIE_IOM_B_TO_COMP_B_9_DN")
	)
	(segment
		(start 292.308534 -181.710584)
		(end 292.028118 -182.118762)
		(width 0.1651)
		(layer "B.Cu")
		(net "PCIE_IOM_B_TO_COMP_B_9_DN")
	)
	(segment
		(start 327.072752 -130.930904)
		(end 326.792082 -131.339082)
		(width 0.1651)
		(layer "B.Cu")
		(net "PCIE_IOM_B_TO_COMP_B_9_DN")
	)
	(segment
		(start 337.541616 -115.682522)
		(end 337.57362 -115.855496)
		(width 0.1651)
		(layer "B.Cu")
		(net "PCIE_IOM_B_TO_COMP_B_9_DN")
	)
	(segment
		(start 317.1063 -145.633186)
		(end 316.82563 -146.041364)
		(width 0.1651)
		(layer "B.Cu")
		(net "PCIE_IOM_B_TO_COMP_B_9_DN")
	)
	(segment
		(start 387.549898 -22.350222)
		(end 387.549898 -21.962618)
		(width 0.1651)
		(layer "B.Cu")
		(net "PCIE_IOM_B_TO_COMP_B_9_DN")
	)
	(segment
		(start 273.870674 -185.965592)
		(end 273.870674 -185.965338)
		(width 0.1651)
		(layer "B.Cu")
		(net "PCIE_IOM_B_TO_COMP_B_9_DN")
	)
	(segment
		(start 308.629558 -157.763464)
		(end 308.659022 -157.922468)
		(width 0.1651)
		(layer "B.Cu")
		(net "PCIE_IOM_B_TO_COMP_B_9_DN")
	)
	(segment
		(start 277.20036 -170.377612)
		(end 278.461724 -169.673778)
		(width 0.1651)
		(layer "B.Cu")
		(net "PCIE_IOM_B_TO_COMP_B_9_DN")
	)
	(segment
		(start 328.454004 -128.92151)
		(end 328.173334 -129.329688)
		(width 0.1651)
		(layer "B.Cu")
		(net "PCIE_IOM_B_TO_COMP_B_9_DN")
	)
	(segment
		(start 299.934122 -170.396408)
		(end 299.966126 -170.569636)
		(width 0.1651)
		(layer "B.Cu")
		(net "PCIE_IOM_B_TO_COMP_B_9_DN")
	)
	(segment
		(start 307.248306 -159.772858)
		(end 307.27777 -159.931862)
		(width 0.1651)
		(layer "B.Cu")
		(net "PCIE_IOM_B_TO_COMP_B_9_DN")
	)
	(segment
		(start 307.27777 -159.931862)
		(end 301.791878 -167.913304)
		(width 0.1651)
		(layer "B.Cu")
		(net "PCIE_IOM_B_TO_COMP_B_9_DN")
	)
	(segment
		(start 316.135004 -147.045934)
		(end 315.976254 -147.075398)
		(width 0.1651)
		(layer "B.Cu")
		(net "PCIE_IOM_B_TO_COMP_B_9_DN")
	)
	(segment
		(start 315.285628 -148.080222)
		(end 315.004958 -148.4884)
		(width 0.1651)
		(layer "B.Cu")
		(net "PCIE_IOM_B_TO_COMP_B_9_DN")
	)
	(segment
		(start 278.183086 -189.434724)
		(end 273.870674 -185.965592)
		(width 0.1651)
		(layer "B.Cu")
		(net "PCIE_IOM_B_TO_COMP_B_9_DN")
	)
	(segment
		(start 388.30377 -22.021546)
		(end 388.30377 -34.504122)
		(width 0.1651)
		(layer "B.Cu")
		(net "PCIE_IOM_B_TO_COMP_B_9_DN")
	)
	(segment
		(start 309.349648 -156.917644)
		(end 309.069232 -157.325822)
		(width 0.1651)
		(layer "B.Cu")
		(net "PCIE_IOM_B_TO_COMP_B_9_DN")
	)
	(segment
		(start 315.725048 -147.64258)
		(end 315.444378 -148.050758)
		(width 0.1651)
		(layer "B.Cu")
		(net "PCIE_IOM_B_TO_COMP_B_9_DN")
	)
	(segment
		(start 388.30377 -34.504122)
		(end 385.369562 -38.739826)
		(width 0.1651)
		(layer "B.Cu")
		(net "PCIE_IOM_B_TO_COMP_B_9_DN")
	)
	(segment
		(start 299.26407 -171.59097)
		(end 292.71849 -181.114192)
		(width 0.1651)
		(layer "B.Cu")
		(net "PCIE_IOM_B_TO_COMP_B_9_DN")
	)
	(segment
		(start 307.68798 -159.335216)
		(end 307.528976 -159.36468)
		(width 0.1651)
		(layer "B.Cu")
		(net "PCIE_IOM_B_TO_COMP_B_9_DN")
	)
	(segment
		(start 326.821546 -131.498086)
		(end 326.54113 -131.906264)
		(width 0.1651)
		(layer "B.Cu")
		(net "PCIE_IOM_B_TO_COMP_B_9_DN")
	)
	(segment
		(start 300.668182 -169.548048)
		(end 300.387766 -169.956226)
		(width 0.1651)
		(layer "B.Cu")
		(net "PCIE_IOM_B_TO_COMP_B_9_DN")
	)
	(segment
		(start 300.636178 -169.375074)
		(end 300.668182 -169.548048)
		(width 0.1651)
		(layer "B.Cu")
		(net "PCIE_IOM_B_TO_COMP_B_9_DN")
	)
	(segment
		(start 387.716268 -21.796248)
		(end 388.078472 -21.796248)
		(width 0.1651)
		(layer "B.Cu")
		(net "PCIE_IOM_B_TO_COMP_B_9_DN")
	)
	(segment
		(start 336.591148 -117.285262)
		(end 336.41792 -117.317266)
		(width 0.1651)
		(layer "B.Cu")
		(net "PCIE_IOM_B_TO_COMP_B_9_DN")
	)
	(segment
		(start 327.512172 -130.493262)
		(end 327.231756 -130.90144)
		(width 0.1651)
		(layer "B.Cu")
		(net "PCIE_IOM_B_TO_COMP_B_9_DN")
	)
	(segment
		(start 292.71849 -181.114192)
		(end 292.55974 -181.143656)
		(width 0.1651)
		(layer "B.Cu")
		(net "PCIE_IOM_B_TO_COMP_B_9_DN")
	)
	(segment
		(start 279.423622 -170.162474)
		(end 278.750014 -170.499786)
		(width 0.1651)
		(layer "B.Cu")
		(net "PCIE_IOM_B_TO_COMP_B_9_DN")
	)
	(segment
		(start 308.378606 -158.330646)
		(end 308.219602 -158.36011)
		(width 0.1651)
		(layer "B.Cu")
		(net "PCIE_IOM_B_TO_COMP_B_9_DN")
	)
	(segment
		(start 309.759858 -156.320998)
		(end 309.600854 -156.350462)
		(width 0.1651)
		(layer "B.Cu")
		(net "PCIE_IOM_B_TO_COMP_B_9_DN")
	)
	(segment
		(start 380.606808 -45.61586)
		(end 371.964966 -65.820544)
		(width 0.1651)
		(layer "B.Cu")
		(net "PCIE_IOM_B_TO_COMP_B_9_DN")
	)
	(segment
		(start 328.173334 -129.329688)
		(end 328.202798 -129.488692)
		(width 0.1651)
		(layer "B.Cu")
		(net "PCIE_IOM_B_TO_COMP_B_9_DN")
	)
	(segment
		(start 299.68571 -170.977814)
		(end 299.512482 -171.009818)
		(width 0.1651)
		(layer "B.Cu")
		(net "PCIE_IOM_B_TO_COMP_B_9_DN")
	)
	(segment
		(start 317.516256 -145.03654)
		(end 317.357506 -145.066004)
		(width 0.1651)
		(layer "B.Cu")
		(net "PCIE_IOM_B_TO_COMP_B_9_DN")
	)
	(segment
		(start 308.219602 -158.36011)
		(end 307.938932 -158.768288)
		(width 0.1651)
		(layer "B.Cu")
		(net "PCIE_IOM_B_TO_COMP_B_9_DN")
	)
	(segment
		(start 278.461724 -169.673778)
		(end 279.087072 -169.67581)
		(width 0.1651)
		(layer "B.Cu")
		(net "PCIE_IOM_B_TO_COMP_B_9_DN")
	)
	(segment
		(start 281.715464 -190.562738)
		(end 278.183086 -189.434724)
		(width 0.1651)
		(layer "B.Cu")
		(net "PCIE_IOM_B_TO_COMP_B_9_DN")
	)
	(segment
		(start 301.618904 -167.945308)
		(end 301.338234 -168.353486)
		(width 0.1651)
		(layer "B.Cu")
		(net "PCIE_IOM_B_TO_COMP_B_9_DN")
	)
	(segment
		(start 336.169508 -117.898672)
		(end 328.613008 -128.892046)
		(width 0.1651)
		(layer "B.Cu")
		(net "PCIE_IOM_B_TO_COMP_B_9_DN")
	)
	(segment
		(start 328.613008 -128.892046)
		(end 328.454004 -128.92151)
		(width 0.1651)
		(layer "B.Cu")
		(net "PCIE_IOM_B_TO_COMP_B_9_DN")
	)
	(segment
		(start 337.293204 -116.263674)
		(end 337.119976 -116.295932)
		(width 0.1651)
		(layer "B.Cu")
		(net "PCIE_IOM_B_TO_COMP_B_9_DN")
	)
	(segment
		(start 308.659022 -157.922468)
		(end 308.378606 -158.330646)
		(width 0.1651)
		(layer "B.Cu")
		(net "PCIE_IOM_B_TO_COMP_B_9_DN")
	)
	(segment
		(start 315.004958 -148.4884)
		(end 315.034422 -148.647404)
		(width 0.1651)
		(layer "B.Cu")
		(net "PCIE_IOM_B_TO_COMP_B_9_DN")
	)
	(segment
		(start 299.512482 -171.009818)
		(end 299.232066 -171.417996)
		(width 0.1651)
		(layer "B.Cu")
		(net "PCIE_IOM_B_TO_COMP_B_9_DN")
	)
	(segment
		(start 290.646866 -184.12841)
		(end 290.487862 -184.157874)
		(width 0.1651)
		(layer "B.Cu")
		(net "PCIE_IOM_B_TO_COMP_B_9_DN")
	)
	(segment
		(start 290.927282 -183.720232)
		(end 290.646866 -184.12841)
		(width 0.1651)
		(layer "B.Cu")
		(net "PCIE_IOM_B_TO_COMP_B_9_DN")
	)
	(segment
		(start 291.869114 -182.148226)
		(end 291.588444 -182.556404)
		(width 0.1651)
		(layer "B.Cu")
		(net "PCIE_IOM_B_TO_COMP_B_9_DN")
	)
	(segment
		(start 336.41792 -117.317266)
		(end 336.137504 -117.725444)
		(width 0.1651)
		(layer "B.Cu")
		(net "PCIE_IOM_B_TO_COMP_B_9_DN")
	)
	(segment
		(start 385.369562 -38.739826)
		(end 380.606808 -45.61586)
		(width 0.1651)
		(layer "B.Cu")
		(net "PCIE_IOM_B_TO_COMP_B_9_DN")
	)
	(segment
		(start 328.202798 -129.488692)
		(end 327.922382 -129.89687)
		(width 0.1651)
		(layer "B.Cu")
		(net "PCIE_IOM_B_TO_COMP_B_9_DN")
	)
	(segment
		(start 315.976254 -147.075398)
		(end 315.695584 -147.483576)
		(width 0.1651)
		(layer "B.Cu")
		(net "PCIE_IOM_B_TO_COMP_B_9_DN")
	)
	(segment
		(start 292.028118 -182.118762)
		(end 291.869114 -182.148226)
		(width 0.1651)
		(layer "B.Cu")
		(net "PCIE_IOM_B_TO_COMP_B_9_DN")
	)
	(segment
		(start 337.57362 -115.855496)
		(end 337.293204 -116.263674)
		(width 0.1651)
		(layer "B.Cu")
		(net "PCIE_IOM_B_TO_COMP_B_9_DN")
	)
	(segment
		(start 291.588444 -182.556404)
		(end 291.617908 -182.715408)
		(width 0.1651)
		(layer "B.Cu")
		(net "PCIE_IOM_B_TO_COMP_B_9_DN")
	)
	(segment
		(start 273.870674 -185.965338)
		(end 272.627852 -181.2544)
		(width 0.1651)
		(layer "B.Cu")
		(net "PCIE_IOM_B_TO_COMP_B_9_DN")
	)
	(segment
		(start 317.357506 -145.066004)
		(end 317.076836 -145.474182)
		(width 0.1651)
		(layer "B.Cu")
		(net "PCIE_IOM_B_TO_COMP_B_9_DN")
	)
	(segment
		(start 326.131174 -132.50291)
		(end 317.516256 -145.03654)
		(width 0.1651)
		(layer "B.Cu")
		(net "PCIE_IOM_B_TO_COMP_B_9_DN")
	)
	(segment
		(start 309.600854 -156.350462)
		(end 309.320184 -156.75864)
		(width 0.1651)
		(layer "B.Cu")
		(net "PCIE_IOM_B_TO_COMP_B_9_DN")
	)
	(segment
		(start 337.119976 -116.295932)
		(end 336.83956 -116.70411)
		(width 0.1651)
		(layer "B.Cu")
		(net "PCIE_IOM_B_TO_COMP_B_9_DN")
	)
	(segment
		(start 327.482708 -130.334512)
		(end 327.512172 -130.493262)
		(width 0.1651)
		(layer "B.Cu")
		(net "PCIE_IOM_B_TO_COMP_B_9_DN")
	)
	(segment
		(start 290.897818 -183.561228)
		(end 290.927282 -183.720232)
		(width 0.1651)
		(layer "B.Cu")
		(net "PCIE_IOM_B_TO_COMP_B_9_DN")
	)
	(segment
		(start 309.069232 -157.325822)
		(end 308.910228 -157.355286)
		(width 0.1651)
		(layer "B.Cu")
		(net "PCIE_IOM_B_TO_COMP_B_9_DN")
	)
	(segment
		(start 285.15945 -189.463426)
		(end 281.715464 -190.562738)
		(width 0.1651)
		(layer "B.Cu")
		(net "PCIE_IOM_B_TO_COMP_B_9_DN")
	)
	(segment
		(start 308.910228 -157.355286)
		(end 308.629558 -157.763464)
		(width 0.1651)
		(layer "B.Cu")
		(net "PCIE_IOM_B_TO_COMP_B_9_DN")
	)
	(segment
		(start 291.178488 -183.15305)
		(end 290.897818 -183.561228)
		(width 0.1651)
		(layer "B.Cu")
		(net "PCIE_IOM_B_TO_COMP_B_9_DN")
	)
	(segment
		(start 272.627852 -181.2544)
		(end 277.20036 -170.377612)
		(width 0.1651)
		(layer "B.Cu")
		(net "PCIE_IOM_B_TO_COMP_B_9_DN")
	)
	(segment
		(start 279.087072 -169.67581)
		(end 279.088342 -169.67581)
		(width 0.1651)
		(layer "B.Cu")
		(net "PCIE_IOM_B_TO_COMP_B_9_DN")
	)
	(segment
		(start 327.231756 -130.90144)
		(end 327.072752 -130.930904)
		(width 0.1651)
		(layer "B.Cu")
		(net "PCIE_IOM_B_TO_COMP_B_9_DN")
	)
	(segment
		(start 291.337492 -183.123586)
		(end 291.178488 -183.15305)
		(width 0.1651)
		(layer "B.Cu")
		(net "PCIE_IOM_B_TO_COMP_B_9_DN")
	)
	(segment
		(start 291.617908 -182.715408)
		(end 291.337492 -183.123586)
		(width 0.1651)
		(layer "B.Cu")
		(net "PCIE_IOM_B_TO_COMP_B_9_DN")
	)
	(segment
		(start 336.137504 -117.725444)
		(end 336.169508 -117.898672)
		(width 0.1651)
		(layer "B.Cu")
		(net "PCIE_IOM_B_TO_COMP_B_9_DN")
	)
	(segment
		(start 292.55974 -181.143656)
		(end 292.27907 -181.551834)
		(width 0.1651)
		(layer "B.Cu")
		(net "PCIE_IOM_B_TO_COMP_B_9_DN")
	)
	(segment
		(start 307.938932 -158.768288)
		(end 307.968396 -158.927038)
		(width 0.1651)
		(layer "B.Cu")
		(net "PCIE_IOM_B_TO_COMP_B_9_DN")
	)
	(segment
		(start 317.076836 -145.474182)
		(end 317.1063 -145.633186)
		(width 0.1651)
		(layer "B.Cu")
		(net "PCIE_IOM_B_TO_COMP_B_9_DN")
	)
	(segment
		(start 336.871564 -116.877084)
		(end 336.591148 -117.285262)
		(width 0.1651)
		(layer "B.Cu")
		(net "PCIE_IOM_B_TO_COMP_B_9_DN")
	)
	(segment
		(start 279.366472 -169.79138)
		(end 279.467564 -169.892472)
		(width 0.1651)
		(layer "B.Cu")
		(net "PCIE_IOM_B_TO_COMP_B_9_DN")
	)
	(segment
		(start 307.968396 -158.927038)
		(end 307.68798 -159.335216)
		(width 0.1651)
		(layer "B.Cu")
		(net "PCIE_IOM_B_TO_COMP_B_9_DN")
	)
	(segment
		(start 292.27907 -181.551834)
		(end 292.308534 -181.710584)
		(width 0.1651)
		(layer "B.Cu")
		(net "PCIE_IOM_B_TO_COMP_B_9_DN")
	)
	(arc
		(start 279.277572 -169.724578)
		(mid 279.324385 -169.754832)
		(end 279.366472 -169.79138)
		(width 0.1651)
		(layer "B.Cu")
		(net "PCIE_IOM_B_TO_COMP_B_9_DN")
	)
	(arc
		(start 279.467564 -169.892472)
		(mid 279.508792 -169.959812)
		(end 279.514808 -170.038522)
		(width 0.1651)
		(layer "B.Cu")
		(net "PCIE_IOM_B_TO_COMP_B_9_DN")
	)
	(arc
		(start 388.078472 -21.796248)
		(mid 388.237782 -21.862236)
		(end 388.30377 -22.021546)
		(width 0.1651)
		(layer "B.Cu")
		(net "PCIE_IOM_B_TO_COMP_B_9_DN")
	)
	(arc
		(start 279.514808 -170.038522)
		(mid 279.484105 -170.111453)
		(end 279.423622 -170.162474)
		(width 0.1651)
		(layer "B.Cu")
		(net "PCIE_IOM_B_TO_COMP_B_9_DN")
	)
	(arc
		(start 387.549898 -21.962618)
		(mid 387.598627 -21.844977)
		(end 387.716268 -21.796248)
		(width 0.1651)
		(layer "B.Cu")
		(net "PCIE_IOM_B_TO_COMP_B_9_DN")
	)
	(arc
		(start 279.088342 -169.67581)
		(mid 279.18604 -169.688246)
		(end 279.277572 -169.724578)
		(width 0.1651)
		(layer "B.Cu")
		(net "PCIE_IOM_B_TO_COMP_B_9_DN")
	)
	(segment
		(start 389.349996 -21.950172)
		(end 389.349996 -22.337776)
		(width 0.1651)
		(layer "B.Cu")
		(net "PCIE_IOM_B_TO_COMP_B_8_DP")
	)
	(segment
		(start 381.902208 -55.846472)
		(end 292.25113 -186.196224)
		(width 0.1651)
		(layer "B.Cu")
		(net "PCIE_IOM_B_TO_COMP_B_8_DP")
	)
	(segment
		(start 276.667976 -166.186866)
		(end 278.113236 -165.380162)
		(width 0.1651)
		(layer "B.Cu")
		(net "PCIE_IOM_B_TO_COMP_B_8_DP")
	)
	(segment
		(start 279.573228 -165.584632)
		(end 279.778206 -165.78961)
		(width 0.1651)
		(layer "B.Cu")
		(net "PCIE_IOM_B_TO_COMP_B_8_DP")
	)
	(segment
		(start 279.918414 -165.86073)
		(end 279.933908 -165.86327)
		(width 0.1651)
		(layer "B.Cu")
		(net "PCIE_IOM_B_TO_COMP_B_8_DP")
	)
	(segment
		(start 390.172956 -39.676324)
		(end 386.349748 -45.450506)
		(width 0.1651)
		(layer "B.Cu")
		(net "PCIE_IOM_B_TO_COMP_B_8_DP")
	)
	(segment
		(start 277.598632 -191.379094)
		(end 272.149824 -186.995562)
		(width 0.1651)
		(layer "B.Cu")
		(net "PCIE_IOM_B_TO_COMP_B_8_DP")
	)
	(segment
		(start 292.25113 -186.196224)
		(end 286.054546 -191.177672)
		(width 0.1651)
		(layer "B.Cu")
		(net "PCIE_IOM_B_TO_COMP_B_8_DP")
	)
	(segment
		(start 281.51836 -192.629536)
		(end 277.650702 -191.395858)
		(width 0.1651)
		(layer "B.Cu")
		(net "PCIE_IOM_B_TO_COMP_B_8_DP")
	)
	(segment
		(start 278.113236 -165.380162)
		(end 279.088088 -165.383718)
		(width 0.1651)
		(layer "B.Cu")
		(net "PCIE_IOM_B_TO_COMP_B_8_DP")
	)
	(segment
		(start 286.054546 -191.177672)
		(end 281.51836 -192.629536)
		(width 0.1651)
		(layer "B.Cu")
		(net "PCIE_IOM_B_TO_COMP_B_8_DP")
	)
	(segment
		(start 270.519144 -180.814472)
		(end 276.667976 -166.186866)
		(width 0.1651)
		(layer "B.Cu")
		(net "PCIE_IOM_B_TO_COMP_B_8_DP")
	)
	(segment
		(start 272.149824 -186.995562)
		(end 270.519144 -180.814472)
		(width 0.1651)
		(layer "B.Cu")
		(net "PCIE_IOM_B_TO_COMP_B_8_DP")
	)
	(segment
		(start 390.396222 -38.577012)
		(end 390.172956 -39.676324)
		(width 0.1651)
		(layer "B.Cu")
		(net "PCIE_IOM_B_TO_COMP_B_8_DP")
	)
	(segment
		(start 389.516366 -22.504146)
		(end 389.876792 -22.504146)
		(width 0.1651)
		(layer "B.Cu")
		(net "PCIE_IOM_B_TO_COMP_B_8_DP")
	)
	(segment
		(start 277.650702 -191.395858)
		(end 277.598632 -191.379094)
		(width 0.1651)
		(layer "B.Cu")
		(net "PCIE_IOM_B_TO_COMP_B_8_DP")
	)
	(segment
		(start 386.349748 -45.450506)
		(end 381.902208 -55.846472)
		(width 0.1651)
		(layer "B.Cu")
		(net "PCIE_IOM_B_TO_COMP_B_8_DP")
	)
	(segment
		(start 280.089356 -165.838378)
		(end 280.75001 -165.499796)
		(width 0.1651)
		(layer "B.Cu")
		(net "PCIE_IOM_B_TO_COMP_B_8_DP")
	)
	(segment
		(start 390.396222 -23.023576)
		(end 390.396222 -38.577012)
		(width 0.1651)
		(layer "B.Cu")
		(net "PCIE_IOM_B_TO_COMP_B_8_DP")
	)
	(arc
		(start 279.418288 -165.4683)
		(mid 279.499871 -165.520985)
		(end 279.573228 -165.584632)
		(width 0.1651)
		(layer "B.Cu")
		(net "PCIE_IOM_B_TO_COMP_B_8_DP")
	)
	(arc
		(start 389.876792 -22.504146)
		(mid 390.244084 -22.656284)
		(end 390.396222 -23.023576)
		(width 0.1651)
		(layer "B.Cu")
		(net "PCIE_IOM_B_TO_COMP_B_8_DP")
	)
	(arc
		(start 389.349996 -22.337776)
		(mid 389.398725 -22.455417)
		(end 389.516366 -22.504146)
		(width 0.1651)
		(layer "B.Cu")
		(net "PCIE_IOM_B_TO_COMP_B_8_DP")
	)
	(arc
		(start 279.778206 -165.78961)
		(mid 279.842672 -165.836282)
		(end 279.918414 -165.86073)
		(width 0.1651)
		(layer "B.Cu")
		(net "PCIE_IOM_B_TO_COMP_B_8_DP")
	)
	(arc
		(start 279.088088 -165.383718)
		(mid 279.25853 -165.405162)
		(end 279.418288 -165.4683)
		(width 0.1651)
		(layer "B.Cu")
		(net "PCIE_IOM_B_TO_COMP_B_8_DP")
	)
	(arc
		(start 279.933908 -165.86327)
		(mid 280.013618 -165.863197)
		(end 280.089356 -165.838378)
		(width 0.1651)
		(layer "B.Cu")
		(net "PCIE_IOM_B_TO_COMP_B_8_DP")
	)
	(segment
		(start 329.97267 -130.83413)
		(end 329.692 -131.242308)
		(width 0.1651)
		(layer "B.Cu")
		(net "PCIE_IOM_B_TO_COMP_B_8_DN")
	)
	(segment
		(start 317.433706 -149.065488)
		(end 317.153036 -149.473666)
		(width 0.1651)
		(layer "B.Cu")
		(net "PCIE_IOM_B_TO_COMP_B_8_DN")
	)
	(segment
		(start 328.842116 -132.276342)
		(end 328.561446 -132.684266)
		(width 0.1651)
		(layer "B.Cu")
		(net "PCIE_IOM_B_TO_COMP_B_8_DN")
	)
	(segment
		(start 319.225676 -146.459956)
		(end 319.066672 -146.48942)
		(width 0.1651)
		(layer "B.Cu")
		(net "PCIE_IOM_B_TO_COMP_B_8_DN")
	)
	(segment
		(start 337.883754 -119.331486)
		(end 330.38288 -130.237738)
		(width 0.1651)
		(layer "B.Cu")
		(net "PCIE_IOM_B_TO_COMP_B_8_DN")
	)
	(segment
		(start 328.59091 -132.84327)
		(end 328.31024 -133.251448)
		(width 0.1651)
		(layer "B.Cu")
		(net "PCIE_IOM_B_TO_COMP_B_8_DN")
	)
	(segment
		(start 310.687466 -158.67253)
		(end 310.406796 -159.080708)
		(width 0.1651)
		(layer "B.Cu")
		(net "PCIE_IOM_B_TO_COMP_B_8_DN")
	)
	(segment
		(start 319.066672 -146.48942)
		(end 318.786002 -146.897344)
		(width 0.1651)
		(layer "B.Cu")
		(net "PCIE_IOM_B_TO_COMP_B_8_DN")
	)
	(segment
		(start 318.124586 -148.060918)
		(end 317.843916 -148.469096)
		(width 0.1651)
		(layer "B.Cu")
		(net "PCIE_IOM_B_TO_COMP_B_8_DN")
	)
	(segment
		(start 317.153036 -149.473666)
		(end 316.994032 -149.50313)
		(width 0.1651)
		(layer "B.Cu")
		(net "PCIE_IOM_B_TO_COMP_B_8_DN")
	)
	(segment
		(start 294.158924 -182.90667)
		(end 293.99992 -182.936134)
		(width 0.1651)
		(layer "B.Cu")
		(net "PCIE_IOM_B_TO_COMP_B_8_DN")
	)
	(segment
		(start 281.518106 -192.322704)
		(end 277.739348 -191.116966)
		(width 0.1651)
		(layer "B.Cu")
		(net "PCIE_IOM_B_TO_COMP_B_8_DN")
	)
	(segment
		(start 294.439594 -182.498746)
		(end 294.158924 -182.90667)
		(width 0.1651)
		(layer "B.Cu")
		(net "PCIE_IOM_B_TO_COMP_B_8_DN")
	)
	(segment
		(start 309.46471 -160.652206)
		(end 309.305706 -160.68167)
		(width 0.1651)
		(layer "B.Cu")
		(net "PCIE_IOM_B_TO_COMP_B_8_DN")
	)
	(segment
		(start 302.865028 -170.248072)
		(end 302.6918 -170.28033)
		(width 0.1651)
		(layer "B.Cu")
		(net "PCIE_IOM_B_TO_COMP_B_8_DN")
	)
	(segment
		(start 301.460154 -172.29074)
		(end 301.28718 -172.322744)
		(width 0.1651)
		(layer "B.Cu")
		(net "PCIE_IOM_B_TO_COMP_B_8_DN")
	)
	(segment
		(start 329.692 -131.242308)
		(end 329.532996 -131.271772)
		(width 0.1651)
		(layer "B.Cu")
		(net "PCIE_IOM_B_TO_COMP_B_8_DN")
	)
	(segment
		(start 277.739348 -191.116966)
		(end 277.739348 -191.11722)
		(width 0.1651)
		(layer "B.Cu")
		(net "PCIE_IOM_B_TO_COMP_B_8_DN")
	)
	(segment
		(start 338.13242 -118.750334)
		(end 337.85175 -119.158512)
		(width 0.1651)
		(layer "B.Cu")
		(net "PCIE_IOM_B_TO_COMP_B_8_DN")
	)
	(segment
		(start 381.644906 -55.70474)
		(end 339.710268 -116.675916)
		(width 0.1651)
		(layer "B.Cu")
		(net "PCIE_IOM_B_TO_COMP_B_8_DN")
	)
	(segment
		(start 270.826992 -180.836062)
		(end 276.898354 -166.39286)
		(width 0.1651)
		(layer "B.Cu")
		(net "PCIE_IOM_B_TO_COMP_B_8_DN")
	)
	(segment
		(start 302.41113 -170.688254)
		(end 302.443388 -170.861482)
		(width 0.1651)
		(layer "B.Cu")
		(net "PCIE_IOM_B_TO_COMP_B_8_DN")
	)
	(segment
		(start 316.742572 -150.070058)
		(end 311.53735 -157.638496)
		(width 0.1651)
		(layer "B.Cu")
		(net "PCIE_IOM_B_TO_COMP_B_8_DN")
	)
	(segment
		(start 330.38288 -130.237738)
		(end 330.223876 -130.267202)
		(width 0.1651)
		(layer "B.Cu")
		(net "PCIE_IOM_B_TO_COMP_B_8_DN")
	)
	(segment
		(start 337.85175 -119.158512)
		(end 337.883754 -119.331486)
		(width 0.1651)
		(layer "B.Cu")
		(net "PCIE_IOM_B_TO_COMP_B_8_DN")
	)
	(segment
		(start 293.468044 -183.91124)
		(end 293.30904 -183.940704)
		(width 0.1651)
		(layer "B.Cu")
		(net "PCIE_IOM_B_TO_COMP_B_8_DN")
	)
	(segment
		(start 293.748714 -183.503062)
		(end 293.468044 -183.91124)
		(width 0.1651)
		(layer "B.Cu")
		(net "PCIE_IOM_B_TO_COMP_B_8_DN")
	)
	(segment
		(start 310.15559 -159.647636)
		(end 309.996586 -159.6771)
		(width 0.1651)
		(layer "B.Cu")
		(net "PCIE_IOM_B_TO_COMP_B_8_DN")
	)
	(segment
		(start 292.034722 -185.99531)
		(end 285.91383 -190.915798)
		(width 0.1651)
		(layer "B.Cu")
		(net "PCIE_IOM_B_TO_COMP_B_8_DN")
	)
	(segment
		(start 309.74538 -160.244028)
		(end 309.46471 -160.652206)
		(width 0.1651)
		(layer "B.Cu")
		(net "PCIE_IOM_B_TO_COMP_B_8_DN")
	)
	(segment
		(start 311.12714 -158.235142)
		(end 310.84647 -158.643066)
		(width 0.1651)
		(layer "B.Cu")
		(net "PCIE_IOM_B_TO_COMP_B_8_DN")
	)
	(segment
		(start 303.394364 -169.258996)
		(end 303.113694 -169.66692)
		(width 0.1651)
		(layer "B.Cu")
		(net "PCIE_IOM_B_TO_COMP_B_8_DN")
	)
	(segment
		(start 301.00651 -172.730922)
		(end 301.038514 -172.903896)
		(width 0.1651)
		(layer "B.Cu")
		(net "PCIE_IOM_B_TO_COMP_B_8_DN")
	)
	(segment
		(start 316.713362 -149.911054)
		(end 316.742572 -150.070058)
		(width 0.1651)
		(layer "B.Cu")
		(net "PCIE_IOM_B_TO_COMP_B_8_DN")
	)
	(segment
		(start 390.104122 -38.547548)
		(end 389.897874 -39.562278)
		(width 0.1651)
		(layer "B.Cu")
		(net "PCIE_IOM_B_TO_COMP_B_8_DN")
	)
	(segment
		(start 309.715916 -160.085278)
		(end 309.74538 -160.244028)
		(width 0.1651)
		(layer "B.Cu")
		(net "PCIE_IOM_B_TO_COMP_B_8_DN")
	)
	(segment
		(start 301.70882 -171.709588)
		(end 301.740824 -171.882562)
		(width 0.1651)
		(layer "B.Cu")
		(net "PCIE_IOM_B_TO_COMP_B_8_DN")
	)
	(segment
		(start 386.09143 -45.31106)
		(end 381.644906 -55.70474)
		(width 0.1651)
		(layer "B.Cu")
		(net "PCIE_IOM_B_TO_COMP_B_8_DN")
	)
	(segment
		(start 318.095122 -147.901914)
		(end 318.124586 -148.060918)
		(width 0.1651)
		(layer "B.Cu")
		(net "PCIE_IOM_B_TO_COMP_B_8_DN")
	)
	(segment
		(start 389.897874 -39.562278)
		(end 386.09143 -45.31106)
		(width 0.1651)
		(layer "B.Cu")
		(net "PCIE_IOM_B_TO_COMP_B_8_DN")
	)
	(segment
		(start 294.6908 -181.931564)
		(end 294.41013 -182.339742)
		(width 0.1651)
		(layer "B.Cu")
		(net "PCIE_IOM_B_TO_COMP_B_8_DN")
	)
	(segment
		(start 311.097676 -158.076138)
		(end 311.12714 -158.235142)
		(width 0.1651)
		(layer "B.Cu")
		(net "PCIE_IOM_B_TO_COMP_B_8_DN")
	)
	(segment
		(start 318.534796 -147.464526)
		(end 318.375792 -147.49399)
		(width 0.1651)
		(layer "B.Cu")
		(net "PCIE_IOM_B_TO_COMP_B_8_DN")
	)
	(segment
		(start 329.28179 -131.8387)
		(end 329.00112 -132.246878)
		(width 0.1651)
		(layer "B.Cu")
		(net "PCIE_IOM_B_TO_COMP_B_8_DN")
	)
	(segment
		(start 339.007958 -117.696996)
		(end 338.834984 -117.729254)
		(width 0.1651)
		(layer "B.Cu")
		(net "PCIE_IOM_B_TO_COMP_B_8_DN")
	)
	(segment
		(start 311.378346 -157.66796)
		(end 311.097676 -158.076138)
		(width 0.1651)
		(layer "B.Cu")
		(net "PCIE_IOM_B_TO_COMP_B_8_DN")
	)
	(segment
		(start 310.84647 -158.643066)
		(end 310.687466 -158.67253)
		(width 0.1651)
		(layer "B.Cu")
		(net "PCIE_IOM_B_TO_COMP_B_8_DN")
	)
	(segment
		(start 301.98949 -171.30141)
		(end 301.70882 -171.709588)
		(width 0.1651)
		(layer "B.Cu")
		(net "PCIE_IOM_B_TO_COMP_B_8_DN")
	)
	(segment
		(start 301.038514 -172.903896)
		(end 294.849804 -181.9021)
		(width 0.1651)
		(layer "B.Cu")
		(net "PCIE_IOM_B_TO_COMP_B_8_DN")
	)
	(segment
		(start 338.55406 -118.137178)
		(end 338.586318 -118.310406)
		(width 0.1651)
		(layer "B.Cu")
		(net "PCIE_IOM_B_TO_COMP_B_8_DN")
	)
	(segment
		(start 330.223876 -130.267202)
		(end 329.943206 -130.675126)
		(width 0.1651)
		(layer "B.Cu")
		(net "PCIE_IOM_B_TO_COMP_B_8_DN")
	)
	(segment
		(start 292.366954 -185.512202)
		(end 292.034722 -185.99531)
		(width 0.1651)
		(layer "B.Cu")
		(net "PCIE_IOM_B_TO_COMP_B_8_DN")
	)
	(segment
		(start 390.104122 -23.023576)
		(end 390.104122 -38.547548)
		(width 0.1651)
		(layer "B.Cu")
		(net "PCIE_IOM_B_TO_COMP_B_8_DN")
	)
	(segment
		(start 285.91383 -190.915798)
		(end 281.518106 -192.322704)
		(width 0.1651)
		(layer "B.Cu")
		(net "PCIE_IOM_B_TO_COMP_B_8_DN")
	)
	(segment
		(start 293.99992 -182.936134)
		(end 293.71925 -183.344312)
		(width 0.1651)
		(layer "B.Cu")
		(net "PCIE_IOM_B_TO_COMP_B_8_DN")
	)
	(segment
		(start 279.423622 -166.162482)
		(end 278.750014 -166.499794)
		(width 0.1651)
		(layer "B.Cu")
		(net "PCIE_IOM_B_TO_COMP_B_8_DN")
	)
	(segment
		(start 318.815466 -147.056348)
		(end 318.534796 -147.464526)
		(width 0.1651)
		(layer "B.Cu")
		(net "PCIE_IOM_B_TO_COMP_B_8_DN")
	)
	(segment
		(start 302.162464 -171.269406)
		(end 301.98949 -171.30141)
		(width 0.1651)
		(layer "B.Cu")
		(net "PCIE_IOM_B_TO_COMP_B_8_DN")
	)
	(segment
		(start 302.6918 -170.28033)
		(end 302.41113 -170.688254)
		(width 0.1651)
		(layer "B.Cu")
		(net "PCIE_IOM_B_TO_COMP_B_8_DN")
	)
	(segment
		(start 329.532996 -131.271772)
		(end 329.252326 -131.679696)
		(width 0.1651)
		(layer "B.Cu")
		(net "PCIE_IOM_B_TO_COMP_B_8_DN")
	)
	(segment
		(start 329.00112 -132.246878)
		(end 328.842116 -132.276342)
		(width 0.1651)
		(layer "B.Cu")
		(net "PCIE_IOM_B_TO_COMP_B_8_DN")
	)
	(segment
		(start 328.151236 -133.280658)
		(end 327.870566 -133.688836)
		(width 0.1651)
		(layer "B.Cu")
		(net "PCIE_IOM_B_TO_COMP_B_8_DN")
	)
	(segment
		(start 309.0545 -161.248598)
		(end 303.567338 -169.226992)
		(width 0.1651)
		(layer "B.Cu")
		(net "PCIE_IOM_B_TO_COMP_B_8_DN")
	)
	(segment
		(start 316.994032 -149.50313)
		(end 316.713362 -149.911054)
		(width 0.1651)
		(layer "B.Cu")
		(net "PCIE_IOM_B_TO_COMP_B_8_DN")
	)
	(segment
		(start 293.02837 -184.348882)
		(end 293.057834 -184.507632)
		(width 0.1651)
		(layer "B.Cu")
		(net "PCIE_IOM_B_TO_COMP_B_8_DN")
	)
	(segment
		(start 317.404242 -148.906484)
		(end 317.433706 -149.065488)
		(width 0.1651)
		(layer "B.Cu")
		(net "PCIE_IOM_B_TO_COMP_B_8_DN")
	)
	(segment
		(start 292.777164 -184.91581)
		(end 292.61816 -184.945274)
		(width 0.1651)
		(layer "B.Cu")
		(net "PCIE_IOM_B_TO_COMP_B_8_DN")
	)
	(segment
		(start 309.025036 -161.089594)
		(end 309.0545 -161.248598)
		(width 0.1651)
		(layer "B.Cu")
		(net "PCIE_IOM_B_TO_COMP_B_8_DN")
	)
	(segment
		(start 277.739348 -191.11722)
		(end 272.407888 -186.828176)
		(width 0.1651)
		(layer "B.Cu")
		(net "PCIE_IOM_B_TO_COMP_B_8_DN")
	)
	(segment
		(start 292.61816 -184.945274)
		(end 292.33749 -185.353452)
		(width 0.1651)
		(layer "B.Cu")
		(net "PCIE_IOM_B_TO_COMP_B_8_DN")
	)
	(segment
		(start 294.41013 -182.339742)
		(end 294.439594 -182.498746)
		(width 0.1651)
		(layer "B.Cu")
		(net "PCIE_IOM_B_TO_COMP_B_8_DN")
	)
	(segment
		(start 318.786002 -146.897344)
		(end 318.815466 -147.056348)
		(width 0.1651)
		(layer "B.Cu")
		(net "PCIE_IOM_B_TO_COMP_B_8_DN")
	)
	(segment
		(start 309.305706 -160.68167)
		(end 309.025036 -161.089594)
		(width 0.1651)
		(layer "B.Cu")
		(net "PCIE_IOM_B_TO_COMP_B_8_DN")
	)
	(segment
		(start 294.849804 -181.9021)
		(end 294.6908 -181.931564)
		(width 0.1651)
		(layer "B.Cu")
		(net "PCIE_IOM_B_TO_COMP_B_8_DN")
	)
	(segment
		(start 279.366472 -165.791388)
		(end 279.467564 -165.89248)
		(width 0.1651)
		(layer "B.Cu")
		(net "PCIE_IOM_B_TO_COMP_B_8_DN")
	)
	(segment
		(start 328.561446 -132.684266)
		(end 328.59091 -132.84327)
		(width 0.1651)
		(layer "B.Cu")
		(net "PCIE_IOM_B_TO_COMP_B_8_DN")
	)
	(segment
		(start 317.843916 -148.469096)
		(end 317.684912 -148.49856)
		(width 0.1651)
		(layer "B.Cu")
		(net "PCIE_IOM_B_TO_COMP_B_8_DN")
	)
	(segment
		(start 389.516366 -22.796246)
		(end 389.876792 -22.796246)
		(width 0.1651)
		(layer "B.Cu")
		(net "PCIE_IOM_B_TO_COMP_B_8_DN")
	)
	(segment
		(start 329.252326 -131.679696)
		(end 329.28179 -131.8387)
		(width 0.1651)
		(layer "B.Cu")
		(net "PCIE_IOM_B_TO_COMP_B_8_DN")
	)
	(segment
		(start 303.567338 -169.226992)
		(end 303.394364 -169.258996)
		(width 0.1651)
		(layer "B.Cu")
		(net "PCIE_IOM_B_TO_COMP_B_8_DN")
	)
	(segment
		(start 276.898354 -166.39286)
		(end 278.18842 -165.673024)
		(width 0.1651)
		(layer "B.Cu")
		(net "PCIE_IOM_B_TO_COMP_B_8_DN")
	)
	(segment
		(start 301.28718 -172.322744)
		(end 301.00651 -172.730922)
		(width 0.1651)
		(layer "B.Cu")
		(net "PCIE_IOM_B_TO_COMP_B_8_DN")
	)
	(segment
		(start 303.145698 -169.840148)
		(end 302.865028 -170.248072)
		(width 0.1651)
		(layer "B.Cu")
		(net "PCIE_IOM_B_TO_COMP_B_8_DN")
	)
	(segment
		(start 339.710268 -116.675916)
		(end 339.537294 -116.70792)
		(width 0.1651)
		(layer "B.Cu")
		(net "PCIE_IOM_B_TO_COMP_B_8_DN")
	)
	(segment
		(start 279.087072 -165.675818)
		(end 279.088342 -165.675818)
		(width 0.1651)
		(layer "B.Cu")
		(net "PCIE_IOM_B_TO_COMP_B_8_DN")
	)
	(segment
		(start 338.834984 -117.729254)
		(end 338.55406 -118.137178)
		(width 0.1651)
		(layer "B.Cu")
		(net "PCIE_IOM_B_TO_COMP_B_8_DN")
	)
	(segment
		(start 338.586318 -118.310406)
		(end 338.305648 -118.71833)
		(width 0.1651)
		(layer "B.Cu")
		(net "PCIE_IOM_B_TO_COMP_B_8_DN")
	)
	(segment
		(start 339.256624 -117.115844)
		(end 339.288628 -117.289072)
		(width 0.1651)
		(layer "B.Cu")
		(net "PCIE_IOM_B_TO_COMP_B_8_DN")
	)
	(segment
		(start 327.870566 -133.688836)
		(end 327.90003 -133.84784)
		(width 0.1651)
		(layer "B.Cu")
		(net "PCIE_IOM_B_TO_COMP_B_8_DN")
	)
	(segment
		(start 293.057834 -184.507632)
		(end 292.777164 -184.91581)
		(width 0.1651)
		(layer "B.Cu")
		(net "PCIE_IOM_B_TO_COMP_B_8_DN")
	)
	(segment
		(start 311.53735 -157.638496)
		(end 311.378346 -157.66796)
		(width 0.1651)
		(layer "B.Cu")
		(net "PCIE_IOM_B_TO_COMP_B_8_DN")
	)
	(segment
		(start 293.30904 -183.940704)
		(end 293.02837 -184.348882)
		(width 0.1651)
		(layer "B.Cu")
		(net "PCIE_IOM_B_TO_COMP_B_8_DN")
	)
	(segment
		(start 278.18842 -165.673024)
		(end 279.087072 -165.675818)
		(width 0.1651)
		(layer "B.Cu")
		(net "PCIE_IOM_B_TO_COMP_B_8_DN")
	)
	(segment
		(start 310.43626 -159.239458)
		(end 310.15559 -159.647636)
		(width 0.1651)
		(layer "B.Cu")
		(net "PCIE_IOM_B_TO_COMP_B_8_DN")
	)
	(segment
		(start 301.740824 -171.882562)
		(end 301.460154 -172.29074)
		(width 0.1651)
		(layer "B.Cu")
		(net "PCIE_IOM_B_TO_COMP_B_8_DN")
	)
	(segment
		(start 272.407888 -186.828176)
		(end 272.407888 -186.827922)
		(width 0.1651)
		(layer "B.Cu")
		(net "PCIE_IOM_B_TO_COMP_B_8_DN")
	)
	(segment
		(start 310.406796 -159.080708)
		(end 310.43626 -159.239458)
		(width 0.1651)
		(layer "B.Cu")
		(net "PCIE_IOM_B_TO_COMP_B_8_DN")
	)
	(segment
		(start 339.288628 -117.289072)
		(end 339.007958 -117.696996)
		(width 0.1651)
		(layer "B.Cu")
		(net "PCIE_IOM_B_TO_COMP_B_8_DN")
	)
	(segment
		(start 328.31024 -133.251448)
		(end 328.151236 -133.280658)
		(width 0.1651)
		(layer "B.Cu")
		(net "PCIE_IOM_B_TO_COMP_B_8_DN")
	)
	(segment
		(start 272.407888 -186.827922)
		(end 270.826992 -180.836062)
		(width 0.1651)
		(layer "B.Cu")
		(net "PCIE_IOM_B_TO_COMP_B_8_DN")
	)
	(segment
		(start 329.943206 -130.675126)
		(end 329.97267 -130.83413)
		(width 0.1651)
		(layer "B.Cu")
		(net "PCIE_IOM_B_TO_COMP_B_8_DN")
	)
	(segment
		(start 302.443388 -170.861482)
		(end 302.162464 -171.269406)
		(width 0.1651)
		(layer "B.Cu")
		(net "PCIE_IOM_B_TO_COMP_B_8_DN")
	)
	(segment
		(start 389.349996 -23.35022)
		(end 389.349996 -22.962616)
		(width 0.1651)
		(layer "B.Cu")
		(net "PCIE_IOM_B_TO_COMP_B_8_DN")
	)
	(segment
		(start 292.33749 -185.353452)
		(end 292.366954 -185.512202)
		(width 0.1651)
		(layer "B.Cu")
		(net "PCIE_IOM_B_TO_COMP_B_8_DN")
	)
	(segment
		(start 318.375792 -147.49399)
		(end 318.095122 -147.901914)
		(width 0.1651)
		(layer "B.Cu")
		(net "PCIE_IOM_B_TO_COMP_B_8_DN")
	)
	(segment
		(start 339.537294 -116.70792)
		(end 339.256624 -117.115844)
		(width 0.1651)
		(layer "B.Cu")
		(net "PCIE_IOM_B_TO_COMP_B_8_DN")
	)
	(segment
		(start 317.684912 -148.49856)
		(end 317.404242 -148.906484)
		(width 0.1651)
		(layer "B.Cu")
		(net "PCIE_IOM_B_TO_COMP_B_8_DN")
	)
	(segment
		(start 293.71925 -183.344312)
		(end 293.748714 -183.503062)
		(width 0.1651)
		(layer "B.Cu")
		(net "PCIE_IOM_B_TO_COMP_B_8_DN")
	)
	(segment
		(start 303.113694 -169.66692)
		(end 303.145698 -169.840148)
		(width 0.1651)
		(layer "B.Cu")
		(net "PCIE_IOM_B_TO_COMP_B_8_DN")
	)
	(segment
		(start 309.996586 -159.6771)
		(end 309.715916 -160.085278)
		(width 0.1651)
		(layer "B.Cu")
		(net "PCIE_IOM_B_TO_COMP_B_8_DN")
	)
	(segment
		(start 327.90003 -133.84784)
		(end 319.225676 -146.459956)
		(width 0.1651)
		(layer "B.Cu")
		(net "PCIE_IOM_B_TO_COMP_B_8_DN")
	)
	(segment
		(start 338.305648 -118.71833)
		(end 338.13242 -118.750334)
		(width 0.1651)
		(layer "B.Cu")
		(net "PCIE_IOM_B_TO_COMP_B_8_DN")
	)
	(arc
		(start 389.349996 -22.962616)
		(mid 389.398725 -22.844975)
		(end 389.516366 -22.796246)
		(width 0.1651)
		(layer "B.Cu")
		(net "PCIE_IOM_B_TO_COMP_B_8_DN")
	)
	(arc
		(start 279.088342 -165.675818)
		(mid 279.18604 -165.688254)
		(end 279.277572 -165.724586)
		(width 0.1651)
		(layer "B.Cu")
		(net "PCIE_IOM_B_TO_COMP_B_8_DN")
	)
	(arc
		(start 279.514808 -166.03853)
		(mid 279.484105 -166.111461)
		(end 279.423622 -166.162482)
		(width 0.1651)
		(layer "B.Cu")
		(net "PCIE_IOM_B_TO_COMP_B_8_DN")
	)
	(arc
		(start 279.467564 -165.89248)
		(mid 279.508792 -165.95982)
		(end 279.514808 -166.03853)
		(width 0.1651)
		(layer "B.Cu")
		(net "PCIE_IOM_B_TO_COMP_B_8_DN")
	)
	(arc
		(start 389.876792 -22.796246)
		(mid 390.037539 -22.862829)
		(end 390.104122 -23.023576)
		(width 0.1651)
		(layer "B.Cu")
		(net "PCIE_IOM_B_TO_COMP_B_8_DN")
	)
	(arc
		(start 279.277572 -165.724586)
		(mid 279.324385 -165.75484)
		(end 279.366472 -165.791388)
		(width 0.1651)
		(layer "B.Cu")
		(net "PCIE_IOM_B_TO_COMP_B_8_DN")
	)
	(segment
		(start 292.403784 -79.181198)
		(end 292.494208 -79.04734)
		(width 0.1651)
		(layer "B.Cu")
		(net "PCIE_IOM_B_TO_COMP_B_23_DP")
	)
	(segment
		(start 350.448372 -52.718716)
		(end 354.387912 -46.534832)
		(width 0.1651)
		(layer "B.Cu")
		(net "PCIE_IOM_B_TO_COMP_B_23_DP")
	)
	(segment
		(start 290.100766 -79.512414)
		(end 290.586922 -79.417926)
		(width 0.1651)
		(layer "B.Cu")
		(net "PCIE_IOM_B_TO_COMP_B_23_DP")
	)
	(segment
		(start 361.549188 -41.510966)
		(end 366.704118 -33.422082)
		(width 0.1651)
		(layer "B.Cu")
		(net "PCIE_IOM_B_TO_COMP_B_23_DP")
	)
	(segment
		(start 283.648404 -82.053938)
		(end 284.648402 -81.05394)
		(width 0.1651)
		(layer "B.Cu")
		(net "PCIE_IOM_B_TO_COMP_B_23_DP")
	)
	(segment
		(start 291.29736 -79.27975)
		(end 291.78377 -79.185262)
		(width 0.1651)
		(layer "B.Cu")
		(net "PCIE_IOM_B_TO_COMP_B_23_DP")
	)
	(segment
		(start 290.586922 -79.417926)
		(end 290.72078 -79.50835)
		(width 0.1651)
		(layer "B.Cu")
		(net "PCIE_IOM_B_TO_COMP_B_23_DP")
	)
	(segment
		(start 291.78377 -79.185262)
		(end 291.917628 -79.275686)
		(width 0.1651)
		(layer "B.Cu")
		(net "PCIE_IOM_B_TO_COMP_B_23_DP")
	)
	(segment
		(start 290.72078 -79.50835)
		(end 291.20719 -79.413862)
		(width 0.1651)
		(layer "B.Cu")
		(net "PCIE_IOM_B_TO_COMP_B_23_DP")
	)
	(segment
		(start 288.813494 -79.87919)
		(end 288.903918 -79.745078)
		(width 0.1651)
		(layer "B.Cu")
		(net "PCIE_IOM_B_TO_COMP_B_23_DP")
	)
	(segment
		(start 316.146688 -74.566526)
		(end 350.448372 -52.718716)
		(width 0.1651)
		(layer "B.Cu")
		(net "PCIE_IOM_B_TO_COMP_B_23_DP")
	)
	(segment
		(start 280.03246 -81.807304)
		(end 280.133552 -81.908396)
		(width 0.1651)
		(layer "B.Cu")
		(net "PCIE_IOM_B_TO_COMP_B_23_DP")
	)
	(segment
		(start 284.648402 -81.05394)
		(end 286.375856 -81.05394)
		(width 0.1651)
		(layer "B.Cu")
		(net "PCIE_IOM_B_TO_COMP_B_23_DP")
	)
	(segment
		(start 287.83534 -80.069182)
		(end 288.813494 -79.87919)
		(width 0.1651)
		(layer "B.Cu")
		(net "PCIE_IOM_B_TO_COMP_B_23_DP")
	)
	(segment
		(start 293.114476 -79.043022)
		(end 316.146688 -74.566526)
		(width 0.1651)
		(layer "B.Cu")
		(net "PCIE_IOM_B_TO_COMP_B_23_DP")
	)
	(segment
		(start 292.494208 -79.04734)
		(end 292.980364 -78.952598)
		(width 0.1651)
		(layer "B.Cu")
		(net "PCIE_IOM_B_TO_COMP_B_23_DP")
	)
	(segment
		(start 280.75001 -81.19999)
		(end 280.076402 -81.537302)
		(width 0.1651)
		(layer "B.Cu")
		(net "PCIE_IOM_B_TO_COMP_B_23_DP")
	)
	(segment
		(start 289.524186 -79.741014)
		(end 290.010342 -79.646526)
		(width 0.1651)
		(layer "B.Cu")
		(net "PCIE_IOM_B_TO_COMP_B_23_DP")
	)
	(segment
		(start 290.010342 -79.646526)
		(end 290.100766 -79.512414)
		(width 0.1651)
		(layer "B.Cu")
		(net "PCIE_IOM_B_TO_COMP_B_23_DP")
	)
	(segment
		(start 367.75009 -22.337776)
		(end 367.75009 -21.950172)
		(width 0.1651)
		(layer "B.Cu")
		(net "PCIE_IOM_B_TO_COMP_B_23_DP")
	)
	(segment
		(start 291.917628 -79.275686)
		(end 292.403784 -79.181198)
		(width 0.1651)
		(layer "B.Cu")
		(net "PCIE_IOM_B_TO_COMP_B_23_DP")
	)
	(segment
		(start 289.390074 -79.65059)
		(end 289.524186 -79.741014)
		(width 0.1651)
		(layer "B.Cu")
		(net "PCIE_IOM_B_TO_COMP_B_23_DP")
	)
	(segment
		(start 291.20719 -79.413862)
		(end 291.29736 -79.27975)
		(width 0.1651)
		(layer "B.Cu")
		(net "PCIE_IOM_B_TO_COMP_B_23_DP")
	)
	(segment
		(start 366.704118 -33.422082)
		(end 366.704118 -22.99462)
		(width 0.1651)
		(layer "B.Cu")
		(net "PCIE_IOM_B_TO_COMP_B_23_DP")
	)
	(segment
		(start 280.484834 -82.053938)
		(end 283.648404 -82.053938)
		(width 0.1651)
		(layer "B.Cu")
		(net "PCIE_IOM_B_TO_COMP_B_23_DP")
	)
	(segment
		(start 288.903918 -79.745078)
		(end 289.390074 -79.65059)
		(width 0.1651)
		(layer "B.Cu")
		(net "PCIE_IOM_B_TO_COMP_B_23_DP")
	)
	(segment
		(start 354.387912 -46.534832)
		(end 361.549188 -41.510966)
		(width 0.1651)
		(layer "B.Cu")
		(net "PCIE_IOM_B_TO_COMP_B_23_DP")
	)
	(segment
		(start 292.980364 -78.952598)
		(end 293.114476 -79.043022)
		(width 0.1651)
		(layer "B.Cu")
		(net "PCIE_IOM_B_TO_COMP_B_23_DP")
	)
	(segment
		(start 286.375856 -81.05394)
		(end 287.83534 -80.069182)
		(width 0.1651)
		(layer "B.Cu")
		(net "PCIE_IOM_B_TO_COMP_B_23_DP")
	)
	(segment
		(start 367.194592 -22.504146)
		(end 367.58372 -22.504146)
		(width 0.1651)
		(layer "B.Cu")
		(net "PCIE_IOM_B_TO_COMP_B_23_DP")
	)
	(arc
		(start 280.076402 -81.537302)
		(mid 280.01592 -81.588325)
		(end 279.985216 -81.661254)
		(width 0.1651)
		(layer "B.Cu")
		(net "PCIE_IOM_B_TO_COMP_B_23_DP")
	)
	(arc
		(start 366.704118 -22.99462)
		(mid 366.847775 -22.647803)
		(end 367.194592 -22.504146)
		(width 0.1651)
		(layer "B.Cu")
		(net "PCIE_IOM_B_TO_COMP_B_23_DP")
	)
	(arc
		(start 280.133552 -81.908396)
		(mid 280.294722 -82.016086)
		(end 280.484834 -82.053938)
		(width 0.1651)
		(layer "B.Cu")
		(net "PCIE_IOM_B_TO_COMP_B_23_DP")
	)
	(arc
		(start 279.985216 -81.661254)
		(mid 279.991311 -81.739938)
		(end 280.03246 -81.807304)
		(width 0.1651)
		(layer "B.Cu")
		(net "PCIE_IOM_B_TO_COMP_B_23_DP")
	)
	(arc
		(start 367.58372 -22.504146)
		(mid 367.701361 -22.455417)
		(end 367.75009 -22.337776)
		(width 0.1651)
		(layer "B.Cu")
		(net "PCIE_IOM_B_TO_COMP_B_23_DP")
	)
	(segment
		(start 366.996218 -33.507426)
		(end 366.996218 -22.99462)
		(width 0.1651)
		(layer "B.Cu")
		(net "PCIE_IOM_B_TO_COMP_B_23_DN")
	)
	(segment
		(start 286.465264 -81.34604)
		(end 287.94964 -80.344772)
		(width 0.1651)
		(layer "B.Cu")
		(net "PCIE_IOM_B_TO_COMP_B_23_DN")
	)
	(segment
		(start 350.659954 -52.930298)
		(end 354.603304 -46.740826)
		(width 0.1651)
		(layer "B.Cu")
		(net "PCIE_IOM_B_TO_COMP_B_23_DN")
	)
	(segment
		(start 278.750014 -82.199988)
		(end 279.410668 -81.861406)
		(width 0.1651)
		(layer "B.Cu")
		(net "PCIE_IOM_B_TO_COMP_B_23_DN")
	)
	(segment
		(start 367.194592 -22.796246)
		(end 367.58372 -22.796246)
		(width 0.1651)
		(layer "B.Cu")
		(net "PCIE_IOM_B_TO_COMP_B_23_DN")
	)
	(segment
		(start 283.769562 -82.346038)
		(end 284.76956 -81.34604)
		(width 0.1651)
		(layer "B.Cu")
		(net "PCIE_IOM_B_TO_COMP_B_23_DN")
	)
	(segment
		(start 354.603304 -46.740826)
		(end 361.76458 -41.71696)
		(width 0.1651)
		(layer "B.Cu")
		(net "PCIE_IOM_B_TO_COMP_B_23_DN")
	)
	(segment
		(start 279.566116 -81.836514)
		(end 279.58161 -81.839054)
		(width 0.1651)
		(layer "B.Cu")
		(net "PCIE_IOM_B_TO_COMP_B_23_DN")
	)
	(segment
		(start 284.76956 -81.34604)
		(end 286.465264 -81.34604)
		(width 0.1651)
		(layer "B.Cu")
		(net "PCIE_IOM_B_TO_COMP_B_23_DN")
	)
	(segment
		(start 280.484326 -82.346038)
		(end 283.769562 -82.346038)
		(width 0.1651)
		(layer "B.Cu")
		(net "PCIE_IOM_B_TO_COMP_B_23_DN")
	)
	(segment
		(start 287.94964 -80.344772)
		(end 316.256924 -74.842878)
		(width 0.1651)
		(layer "B.Cu")
		(net "PCIE_IOM_B_TO_COMP_B_23_DN")
	)
	(segment
		(start 316.256924 -74.842878)
		(end 350.659954 -52.930298)
		(width 0.1651)
		(layer "B.Cu")
		(net "PCIE_IOM_B_TO_COMP_B_23_DN")
	)
	(segment
		(start 279.721818 -81.910174)
		(end 279.926796 -82.115152)
		(width 0.1651)
		(layer "B.Cu")
		(net "PCIE_IOM_B_TO_COMP_B_23_DN")
	)
	(segment
		(start 367.75009 -22.962616)
		(end 367.75009 -23.35022)
		(width 0.1651)
		(layer "B.Cu")
		(net "PCIE_IOM_B_TO_COMP_B_23_DN")
	)
	(segment
		(start 361.76458 -41.71696)
		(end 366.996218 -33.507426)
		(width 0.1651)
		(layer "B.Cu")
		(net "PCIE_IOM_B_TO_COMP_B_23_DN")
	)
	(arc
		(start 367.58372 -22.796246)
		(mid 367.701361 -22.844975)
		(end 367.75009 -22.962616)
		(width 0.1651)
		(layer "B.Cu")
		(net "PCIE_IOM_B_TO_COMP_B_23_DN")
	)
	(arc
		(start 366.996218 -22.99462)
		(mid 367.05432 -22.854348)
		(end 367.194592 -22.796246)
		(width 0.1651)
		(layer "B.Cu")
		(net "PCIE_IOM_B_TO_COMP_B_23_DN")
	)
	(arc
		(start 279.926796 -82.115152)
		(mid 280.182593 -82.28607)
		(end 280.484326 -82.346038)
		(width 0.1651)
		(layer "B.Cu")
		(net "PCIE_IOM_B_TO_COMP_B_23_DN")
	)
	(arc
		(start 279.58161 -81.839054)
		(mid 279.657362 -81.863484)
		(end 279.721818 -81.910174)
		(width 0.1651)
		(layer "B.Cu")
		(net "PCIE_IOM_B_TO_COMP_B_23_DN")
	)
	(arc
		(start 279.410668 -81.861406)
		(mid 279.486415 -81.836643)
		(end 279.566116 -81.836514)
		(width 0.1651)
		(layer "B.Cu")
		(net "PCIE_IOM_B_TO_COMP_B_23_DN")
	)
	(segment
		(start 343.65819 -55.134764)
		(end 343.69629 -54.962806)
		(width 0.1651)
		(layer "B.Cu")
		(net "PCIE_IOM_B_TO_COMP_B_22_DP")
	)
	(segment
		(start 346.832428 -52.965096)
		(end 347.250258 -52.698904)
		(width 0.1651)
		(layer "B.Cu")
		(net "PCIE_IOM_B_TO_COMP_B_22_DP")
	)
	(segment
		(start 346.204794 -53.364892)
		(end 346.376752 -53.402992)
		(width 0.1651)
		(layer "B.Cu")
		(net "PCIE_IOM_B_TO_COMP_B_22_DP")
	)
	(segment
		(start 287.991804 -77.053948)
		(end 319.895728 -70.272148)
		(width 0.1651)
		(layer "B.Cu")
		(net "PCIE_IOM_B_TO_COMP_B_22_DP")
	)
	(segment
		(start 343.69629 -54.962806)
		(end 344.11412 -54.696868)
		(width 0.1651)
		(layer "B.Cu")
		(net "PCIE_IOM_B_TO_COMP_B_22_DP")
	)
	(segment
		(start 346.376752 -53.402992)
		(end 346.794328 -53.1368)
		(width 0.1651)
		(layer "B.Cu")
		(net "PCIE_IOM_B_TO_COMP_B_22_DP")
	)
	(segment
		(start 349.13951 -51.643026)
		(end 353.021646 -45.548804)
		(width 0.1651)
		(layer "B.Cu")
		(net "PCIE_IOM_B_TO_COMP_B_22_DP")
	)
	(segment
		(start 344.285824 -54.734968)
		(end 344.703654 -54.468776)
		(width 0.1651)
		(layer "B.Cu")
		(net "PCIE_IOM_B_TO_COMP_B_22_DP")
	)
	(segment
		(start 347.422216 -52.737004)
		(end 349.13951 -51.643026)
		(width 0.1651)
		(layer "B.Cu")
		(net "PCIE_IOM_B_TO_COMP_B_22_DP")
	)
	(segment
		(start 280.75001 -77.199998)
		(end 280.076402 -77.53731)
		(width 0.1651)
		(layer "B.Cu")
		(net "PCIE_IOM_B_TO_COMP_B_22_DP")
	)
	(segment
		(start 364.90402 -32.192976)
		(end 364.90402 -21.988018)
		(width 0.1651)
		(layer "B.Cu")
		(net "PCIE_IOM_B_TO_COMP_B_22_DP")
	)
	(segment
		(start 365.949992 -21.337778)
		(end 365.949992 -20.950174)
		(width 0.1651)
		(layer "B.Cu")
		(net "PCIE_IOM_B_TO_COMP_B_22_DP")
	)
	(segment
		(start 344.703654 -54.468776)
		(end 344.741754 -54.297072)
		(width 0.1651)
		(layer "B.Cu")
		(net "PCIE_IOM_B_TO_COMP_B_22_DP")
	)
	(segment
		(start 353.021646 -45.548804)
		(end 360.324146 -40.424862)
		(width 0.1651)
		(layer "B.Cu")
		(net "PCIE_IOM_B_TO_COMP_B_22_DP")
	)
	(segment
		(start 280.03246 -77.807312)
		(end 280.133552 -77.908404)
		(width 0.1651)
		(layer "B.Cu")
		(net "PCIE_IOM_B_TO_COMP_B_22_DP")
	)
	(segment
		(start 344.11412 -54.696868)
		(end 344.285824 -54.734968)
		(width 0.1651)
		(layer "B.Cu")
		(net "PCIE_IOM_B_TO_COMP_B_22_DP")
	)
	(segment
		(start 280.484834 -78.053946)
		(end 283.706062 -78.053946)
		(width 0.1651)
		(layer "B.Cu")
		(net "PCIE_IOM_B_TO_COMP_B_22_DP")
	)
	(segment
		(start 360.324146 -40.424862)
		(end 364.90402 -32.192976)
		(width 0.1651)
		(layer "B.Cu")
		(net "PCIE_IOM_B_TO_COMP_B_22_DP")
	)
	(segment
		(start 283.706062 -78.053946)
		(end 284.70606 -77.053948)
		(width 0.1651)
		(layer "B.Cu")
		(net "PCIE_IOM_B_TO_COMP_B_22_DP")
	)
	(segment
		(start 346.794328 -53.1368)
		(end 346.832428 -52.965096)
		(width 0.1651)
		(layer "B.Cu")
		(net "PCIE_IOM_B_TO_COMP_B_22_DP")
	)
	(segment
		(start 284.70606 -77.053948)
		(end 287.991804 -77.053948)
		(width 0.1651)
		(layer "B.Cu")
		(net "PCIE_IOM_B_TO_COMP_B_22_DP")
	)
	(segment
		(start 365.38789 -21.504148)
		(end 365.783622 -21.504148)
		(width 0.1651)
		(layer "B.Cu")
		(net "PCIE_IOM_B_TO_COMP_B_22_DP")
	)
	(segment
		(start 345.331288 -54.06898)
		(end 345.749118 -53.802788)
		(width 0.1651)
		(layer "B.Cu")
		(net "PCIE_IOM_B_TO_COMP_B_22_DP")
	)
	(segment
		(start 345.15933 -54.03088)
		(end 345.331288 -54.06898)
		(width 0.1651)
		(layer "B.Cu")
		(net "PCIE_IOM_B_TO_COMP_B_22_DP")
	)
	(segment
		(start 344.741754 -54.297072)
		(end 345.15933 -54.03088)
		(width 0.1651)
		(layer "B.Cu")
		(net "PCIE_IOM_B_TO_COMP_B_22_DP")
	)
	(segment
		(start 319.895728 -70.272148)
		(end 343.65819 -55.134764)
		(width 0.1651)
		(layer "B.Cu")
		(net "PCIE_IOM_B_TO_COMP_B_22_DP")
	)
	(segment
		(start 345.749118 -53.802788)
		(end 345.787218 -53.631084)
		(width 0.1651)
		(layer "B.Cu")
		(net "PCIE_IOM_B_TO_COMP_B_22_DP")
	)
	(segment
		(start 347.250258 -52.698904)
		(end 347.422216 -52.737004)
		(width 0.1651)
		(layer "B.Cu")
		(net "PCIE_IOM_B_TO_COMP_B_22_DP")
	)
	(segment
		(start 345.787218 -53.631084)
		(end 346.204794 -53.364892)
		(width 0.1651)
		(layer "B.Cu")
		(net "PCIE_IOM_B_TO_COMP_B_22_DP")
	)
	(arc
		(start 365.783622 -21.504148)
		(mid 365.901263 -21.455419)
		(end 365.949992 -21.337778)
		(width 0.1651)
		(layer "B.Cu")
		(net "PCIE_IOM_B_TO_COMP_B_22_DP")
	)
	(arc
		(start 279.985216 -77.661262)
		(mid 279.991311 -77.739946)
		(end 280.03246 -77.807312)
		(width 0.1651)
		(layer "B.Cu")
		(net "PCIE_IOM_B_TO_COMP_B_22_DP")
	)
	(arc
		(start 364.90402 -21.988018)
		(mid 365.045742 -21.64587)
		(end 365.38789 -21.504148)
		(width 0.1651)
		(layer "B.Cu")
		(net "PCIE_IOM_B_TO_COMP_B_22_DP")
	)
	(arc
		(start 280.076402 -77.53731)
		(mid 280.01592 -77.588333)
		(end 279.985216 -77.661262)
		(width 0.1651)
		(layer "B.Cu")
		(net "PCIE_IOM_B_TO_COMP_B_22_DP")
	)
	(arc
		(start 280.133552 -77.908404)
		(mid 280.294722 -78.016094)
		(end 280.484834 -78.053946)
		(width 0.1651)
		(layer "B.Cu")
		(net "PCIE_IOM_B_TO_COMP_B_22_DP")
	)
	(segment
		(start 278.750014 -78.199996)
		(end 279.410668 -77.861414)
		(width 0.1651)
		(layer "B.Cu")
		(net "PCIE_IOM_B_TO_COMP_B_22_DN")
	)
	(segment
		(start 280.484326 -78.346046)
		(end 283.82722 -78.346046)
		(width 0.1651)
		(layer "B.Cu")
		(net "PCIE_IOM_B_TO_COMP_B_22_DN")
	)
	(segment
		(start 349.351092 -51.854608)
		(end 353.237038 -45.754798)
		(width 0.1651)
		(layer "B.Cu")
		(net "PCIE_IOM_B_TO_COMP_B_22_DN")
	)
	(segment
		(start 288.022538 -77.346048)
		(end 320.007996 -70.546976)
		(width 0.1651)
		(layer "B.Cu")
		(net "PCIE_IOM_B_TO_COMP_B_22_DN")
	)
	(segment
		(start 320.007996 -70.546976)
		(end 349.351092 -51.854608)
		(width 0.1651)
		(layer "B.Cu")
		(net "PCIE_IOM_B_TO_COMP_B_22_DN")
	)
	(segment
		(start 284.827218 -77.346048)
		(end 288.022538 -77.346048)
		(width 0.1651)
		(layer "B.Cu")
		(net "PCIE_IOM_B_TO_COMP_B_22_DN")
	)
	(segment
		(start 283.82722 -78.346046)
		(end 284.827218 -77.346048)
		(width 0.1651)
		(layer "B.Cu")
		(net "PCIE_IOM_B_TO_COMP_B_22_DN")
	)
	(segment
		(start 365.38789 -21.796248)
		(end 365.783622 -21.796248)
		(width 0.1651)
		(layer "B.Cu")
		(net "PCIE_IOM_B_TO_COMP_B_22_DN")
	)
	(segment
		(start 279.721818 -77.910182)
		(end 279.926796 -78.11516)
		(width 0.1651)
		(layer "B.Cu")
		(net "PCIE_IOM_B_TO_COMP_B_22_DN")
	)
	(segment
		(start 365.949992 -21.962618)
		(end 365.949992 -22.350222)
		(width 0.1651)
		(layer "B.Cu")
		(net "PCIE_IOM_B_TO_COMP_B_22_DN")
	)
	(segment
		(start 360.546904 -40.625522)
		(end 365.19612 -32.268922)
		(width 0.1651)
		(layer "B.Cu")
		(net "PCIE_IOM_B_TO_COMP_B_22_DN")
	)
	(segment
		(start 353.237038 -45.754798)
		(end 360.546904 -40.625522)
		(width 0.1651)
		(layer "B.Cu")
		(net "PCIE_IOM_B_TO_COMP_B_22_DN")
	)
	(segment
		(start 365.19612 -32.268922)
		(end 365.19612 -21.988018)
		(width 0.1651)
		(layer "B.Cu")
		(net "PCIE_IOM_B_TO_COMP_B_22_DN")
	)
	(segment
		(start 279.566116 -77.836522)
		(end 279.58161 -77.839062)
		(width 0.1651)
		(layer "B.Cu")
		(net "PCIE_IOM_B_TO_COMP_B_22_DN")
	)
	(arc
		(start 365.19612 -21.988018)
		(mid 365.252288 -21.852416)
		(end 365.38789 -21.796248)
		(width 0.1651)
		(layer "B.Cu")
		(net "PCIE_IOM_B_TO_COMP_B_22_DN")
	)
	(arc
		(start 365.783622 -21.796248)
		(mid 365.901263 -21.844977)
		(end 365.949992 -21.962618)
		(width 0.1651)
		(layer "B.Cu")
		(net "PCIE_IOM_B_TO_COMP_B_22_DN")
	)
	(arc
		(start 279.58161 -77.839062)
		(mid 279.657362 -77.863492)
		(end 279.721818 -77.910182)
		(width 0.1651)
		(layer "B.Cu")
		(net "PCIE_IOM_B_TO_COMP_B_22_DN")
	)
	(arc
		(start 279.410668 -77.861414)
		(mid 279.486415 -77.836651)
		(end 279.566116 -77.836522)
		(width 0.1651)
		(layer "B.Cu")
		(net "PCIE_IOM_B_TO_COMP_B_22_DN")
	)
	(arc
		(start 279.926796 -78.11516)
		(mid 280.182593 -78.286078)
		(end 280.484326 -78.346046)
		(width 0.1651)
		(layer "B.Cu")
		(net "PCIE_IOM_B_TO_COMP_B_22_DN")
	)
	(segment
		(start 283.709618 -74.053954)
		(end 284.709616 -73.053956)
		(width 0.1651)
		(layer "B.Cu")
		(net "PCIE_IOM_B_TO_COMP_B_21_DP")
	)
	(segment
		(start 292.566344 -71.684388)
		(end 293.051738 -71.585582)
		(width 0.1651)
		(layer "B.Cu")
		(net "PCIE_IOM_B_TO_COMP_B_21_DP")
	)
	(segment
		(start 291.204904 -71.834248)
		(end 291.351716 -71.93153)
		(width 0.1651)
		(layer "B.Cu")
		(net "PCIE_IOM_B_TO_COMP_B_21_DP")
	)
	(segment
		(start 293.63416 -71.339964)
		(end 293.780972 -71.437246)
		(width 0.1651)
		(layer "B.Cu")
		(net "PCIE_IOM_B_TO_COMP_B_21_DP")
	)
	(segment
		(start 363.77372 -22.504146)
		(end 363.983524 -22.504146)
		(width 0.1651)
		(layer "B.Cu")
		(net "PCIE_IOM_B_TO_COMP_B_21_DP")
	)
	(segment
		(start 293.780972 -71.437246)
		(end 294.266366 -71.33844)
		(width 0.1651)
		(layer "B.Cu")
		(net "PCIE_IOM_B_TO_COMP_B_21_DP")
	)
	(segment
		(start 290.622482 -72.079866)
		(end 290.71951 -71.933054)
		(width 0.1651)
		(layer "B.Cu")
		(net "PCIE_IOM_B_TO_COMP_B_21_DP")
	)
	(segment
		(start 294.363394 -71.191628)
		(end 294.848788 -71.092822)
		(width 0.1651)
		(layer "B.Cu")
		(net "PCIE_IOM_B_TO_COMP_B_21_DP")
	)
	(segment
		(start 359.097834 -39.35476)
		(end 363.103922 -32.153606)
		(width 0.1651)
		(layer "B.Cu")
		(net "PCIE_IOM_B_TO_COMP_B_21_DP")
	)
	(segment
		(start 291.934138 -71.685912)
		(end 292.419532 -71.587106)
		(width 0.1651)
		(layer "B.Cu")
		(net "PCIE_IOM_B_TO_COMP_B_21_DP")
	)
	(segment
		(start 290.71951 -71.933054)
		(end 291.204904 -71.834248)
		(width 0.1651)
		(layer "B.Cu")
		(net "PCIE_IOM_B_TO_COMP_B_21_DP")
	)
	(segment
		(start 294.9956 -71.190104)
		(end 295.648126 -71.057262)
		(width 0.1651)
		(layer "B.Cu")
		(net "PCIE_IOM_B_TO_COMP_B_21_DP")
	)
	(segment
		(start 291.83711 -71.832724)
		(end 291.934138 -71.685912)
		(width 0.1651)
		(layer "B.Cu")
		(net "PCIE_IOM_B_TO_COMP_B_21_DP")
	)
	(segment
		(start 293.148766 -71.43877)
		(end 293.63416 -71.339964)
		(width 0.1651)
		(layer "B.Cu")
		(net "PCIE_IOM_B_TO_COMP_B_21_DP")
	)
	(segment
		(start 294.266366 -71.33844)
		(end 294.363394 -71.191628)
		(width 0.1651)
		(layer "B.Cu")
		(net "PCIE_IOM_B_TO_COMP_B_21_DP")
	)
	(segment
		(start 285.83509 -73.053956)
		(end 290.622482 -72.079866)
		(width 0.1651)
		(layer "B.Cu")
		(net "PCIE_IOM_B_TO_COMP_B_21_DP")
	)
	(segment
		(start 291.351716 -71.93153)
		(end 291.83711 -71.832724)
		(width 0.1651)
		(layer "B.Cu")
		(net "PCIE_IOM_B_TO_COMP_B_21_DP")
	)
	(segment
		(start 295.648126 -71.057262)
		(end 348.346776 -44.473368)
		(width 0.1651)
		(layer "B.Cu")
		(net "PCIE_IOM_B_TO_COMP_B_21_DP")
	)
	(segment
		(start 294.848788 -71.092822)
		(end 294.9956 -71.190104)
		(width 0.1651)
		(layer "B.Cu")
		(net "PCIE_IOM_B_TO_COMP_B_21_DP")
	)
	(segment
		(start 284.709616 -73.053956)
		(end 285.83509 -73.053956)
		(width 0.1651)
		(layer "B.Cu")
		(net "PCIE_IOM_B_TO_COMP_B_21_DP")
	)
	(segment
		(start 348.346776 -44.473368)
		(end 352.513138 -43.54957)
		(width 0.1651)
		(layer "B.Cu")
		(net "PCIE_IOM_B_TO_COMP_B_21_DP")
	)
	(segment
		(start 293.051738 -71.585582)
		(end 293.148766 -71.43877)
		(width 0.1651)
		(layer "B.Cu")
		(net "PCIE_IOM_B_TO_COMP_B_21_DP")
	)
	(segment
		(start 280.484834 -74.053954)
		(end 283.709618 -74.053954)
		(width 0.1651)
		(layer "B.Cu")
		(net "PCIE_IOM_B_TO_COMP_B_21_DP")
	)
	(segment
		(start 352.513138 -43.54957)
		(end 359.097834 -39.35476)
		(width 0.1651)
		(layer "B.Cu")
		(net "PCIE_IOM_B_TO_COMP_B_21_DP")
	)
	(segment
		(start 280.75001 -73.200006)
		(end 280.076402 -73.537318)
		(width 0.1651)
		(layer "B.Cu")
		(net "PCIE_IOM_B_TO_COMP_B_21_DP")
	)
	(segment
		(start 280.03246 -73.80732)
		(end 280.133552 -73.908412)
		(width 0.1651)
		(layer "B.Cu")
		(net "PCIE_IOM_B_TO_COMP_B_21_DP")
	)
	(segment
		(start 292.419532 -71.587106)
		(end 292.566344 -71.684388)
		(width 0.1651)
		(layer "B.Cu")
		(net "PCIE_IOM_B_TO_COMP_B_21_DP")
	)
	(segment
		(start 364.149894 -22.337776)
		(end 364.149894 -21.950172)
		(width 0.1651)
		(layer "B.Cu")
		(net "PCIE_IOM_B_TO_COMP_B_21_DP")
	)
	(segment
		(start 363.103922 -32.153606)
		(end 363.103922 -23.173944)
		(width 0.1651)
		(layer "B.Cu")
		(net "PCIE_IOM_B_TO_COMP_B_21_DP")
	)
	(arc
		(start 280.076402 -73.537318)
		(mid 280.01592 -73.588341)
		(end 279.985216 -73.66127)
		(width 0.1651)
		(layer "B.Cu")
		(net "PCIE_IOM_B_TO_COMP_B_21_DP")
	)
	(arc
		(start 280.133552 -73.908412)
		(mid 280.294722 -74.016102)
		(end 280.484834 -74.053954)
		(width 0.1651)
		(layer "B.Cu")
		(net "PCIE_IOM_B_TO_COMP_B_21_DP")
	)
	(arc
		(start 363.103922 -23.173944)
		(mid 363.300101 -22.700325)
		(end 363.77372 -22.504146)
		(width 0.1651)
		(layer "B.Cu")
		(net "PCIE_IOM_B_TO_COMP_B_21_DP")
	)
	(arc
		(start 279.985216 -73.66127)
		(mid 279.991311 -73.739954)
		(end 280.03246 -73.80732)
		(width 0.1651)
		(layer "B.Cu")
		(net "PCIE_IOM_B_TO_COMP_B_21_DP")
	)
	(arc
		(start 363.983524 -22.504146)
		(mid 364.101165 -22.455417)
		(end 364.149894 -22.337776)
		(width 0.1651)
		(layer "B.Cu")
		(net "PCIE_IOM_B_TO_COMP_B_21_DP")
	)
	(segment
		(start 352.626676 -43.823636)
		(end 359.31729 -39.561516)
		(width 0.1651)
		(layer "B.Cu")
		(net "PCIE_IOM_B_TO_COMP_B_21_DN")
	)
	(segment
		(start 348.445582 -44.750736)
		(end 352.626676 -43.823636)
		(width 0.1651)
		(layer "B.Cu")
		(net "PCIE_IOM_B_TO_COMP_B_21_DN")
	)
	(segment
		(start 279.721818 -73.91019)
		(end 279.926796 -74.115168)
		(width 0.1651)
		(layer "B.Cu")
		(net "PCIE_IOM_B_TO_COMP_B_21_DN")
	)
	(segment
		(start 363.77372 -22.796246)
		(end 363.983524 -22.796246)
		(width 0.1651)
		(layer "B.Cu")
		(net "PCIE_IOM_B_TO_COMP_B_21_DN")
	)
	(segment
		(start 283.830776 -74.346054)
		(end 284.830774 -73.346056)
		(width 0.1651)
		(layer "B.Cu")
		(net "PCIE_IOM_B_TO_COMP_B_21_DN")
	)
	(segment
		(start 284.830774 -73.346056)
		(end 285.864554 -73.346056)
		(width 0.1651)
		(layer "B.Cu")
		(net "PCIE_IOM_B_TO_COMP_B_21_DN")
	)
	(segment
		(start 278.750014 -74.200004)
		(end 279.410668 -73.861422)
		(width 0.1651)
		(layer "B.Cu")
		(net "PCIE_IOM_B_TO_COMP_B_21_DN")
	)
	(segment
		(start 280.484326 -74.346054)
		(end 283.830776 -74.346054)
		(width 0.1651)
		(layer "B.Cu")
		(net "PCIE_IOM_B_TO_COMP_B_21_DN")
	)
	(segment
		(start 363.396022 -32.229552)
		(end 363.396022 -23.173944)
		(width 0.1651)
		(layer "B.Cu")
		(net "PCIE_IOM_B_TO_COMP_B_21_DN")
	)
	(segment
		(start 295.7449 -71.3359)
		(end 348.445582 -44.750736)
		(width 0.1651)
		(layer "B.Cu")
		(net "PCIE_IOM_B_TO_COMP_B_21_DN")
	)
	(segment
		(start 285.864554 -73.346056)
		(end 295.7449 -71.3359)
		(width 0.1651)
		(layer "B.Cu")
		(net "PCIE_IOM_B_TO_COMP_B_21_DN")
	)
	(segment
		(start 364.149894 -22.962616)
		(end 364.149894 -23.35022)
		(width 0.1651)
		(layer "B.Cu")
		(net "PCIE_IOM_B_TO_COMP_B_21_DN")
	)
	(segment
		(start 359.31729 -39.561516)
		(end 363.396022 -32.229552)
		(width 0.1651)
		(layer "B.Cu")
		(net "PCIE_IOM_B_TO_COMP_B_21_DN")
	)
	(segment
		(start 279.566116 -73.83653)
		(end 279.58161 -73.83907)
		(width 0.1651)
		(layer "B.Cu")
		(net "PCIE_IOM_B_TO_COMP_B_21_DN")
	)
	(arc
		(start 279.410668 -73.861422)
		(mid 279.486415 -73.836659)
		(end 279.566116 -73.83653)
		(width 0.1651)
		(layer "B.Cu")
		(net "PCIE_IOM_B_TO_COMP_B_21_DN")
	)
	(arc
		(start 363.396022 -23.173944)
		(mid 363.506647 -22.906871)
		(end 363.77372 -22.796246)
		(width 0.1651)
		(layer "B.Cu")
		(net "PCIE_IOM_B_TO_COMP_B_21_DN")
	)
	(arc
		(start 279.926796 -74.115168)
		(mid 280.182593 -74.286086)
		(end 280.484326 -74.346054)
		(width 0.1651)
		(layer "B.Cu")
		(net "PCIE_IOM_B_TO_COMP_B_21_DN")
	)
	(arc
		(start 363.983524 -22.796246)
		(mid 364.101165 -22.844975)
		(end 364.149894 -22.962616)
		(width 0.1651)
		(layer "B.Cu")
		(net "PCIE_IOM_B_TO_COMP_B_21_DN")
	)
	(arc
		(start 279.58161 -73.83907)
		(mid 279.657362 -73.8635)
		(end 279.721818 -73.91019)
		(width 0.1651)
		(layer "B.Cu")
		(net "PCIE_IOM_B_TO_COMP_B_21_DN")
	)
	(segment
		(start 317.109602 -56.27878)
		(end 317.175134 -56.115458)
		(width 0.1651)
		(layer "B.Cu")
		(net "PCIE_IOM_B_TO_COMP_B_20_DP")
	)
	(segment
		(start 280.75001 -69.200014)
		(end 280.076402 -69.537326)
		(width 0.1651)
		(layer "B.Cu")
		(net "PCIE_IOM_B_TO_COMP_B_20_DP")
	)
	(segment
		(start 318.769746 -55.432452)
		(end 318.933322 -55.497984)
		(width 0.1651)
		(layer "B.Cu")
		(net "PCIE_IOM_B_TO_COMP_B_20_DP")
	)
	(segment
		(start 318.314578 -55.627524)
		(end 318.769746 -55.432452)
		(width 0.1651)
		(layer "B.Cu")
		(net "PCIE_IOM_B_TO_COMP_B_20_DP")
	)
	(segment
		(start 361.973876 -21.504148)
		(end 362.18368 -21.504148)
		(width 0.1651)
		(layer "B.Cu")
		(net "PCIE_IOM_B_TO_COMP_B_20_DP")
	)
	(segment
		(start 317.175134 -56.115458)
		(end 317.630556 -55.920386)
		(width 0.1651)
		(layer "B.Cu")
		(net "PCIE_IOM_B_TO_COMP_B_20_DP")
	)
	(segment
		(start 314.896246 -57.091326)
		(end 315.351668 -56.896254)
		(width 0.1651)
		(layer "B.Cu")
		(net "PCIE_IOM_B_TO_COMP_B_20_DP")
	)
	(segment
		(start 316.03569 -56.603392)
		(end 316.491112 -56.40832)
		(width 0.1651)
		(layer "B.Cu")
		(net "PCIE_IOM_B_TO_COMP_B_20_DP")
	)
	(segment
		(start 362.35005 -21.337778)
		(end 362.35005 -20.950174)
		(width 0.1651)
		(layer "B.Cu")
		(net "PCIE_IOM_B_TO_COMP_B_20_DP")
	)
	(segment
		(start 359.374186 -34.492438)
		(end 361.304078 -31.463488)
		(width 0.1651)
		(layer "B.Cu")
		(net "PCIE_IOM_B_TO_COMP_B_20_DP")
	)
	(segment
		(start 283.706062 -70.053962)
		(end 284.70606 -69.053964)
		(width 0.1651)
		(layer "B.Cu")
		(net "PCIE_IOM_B_TO_COMP_B_20_DP")
	)
	(segment
		(start 341.649304 -45.769784)
		(end 359.374186 -34.492438)
		(width 0.1651)
		(layer "B.Cu")
		(net "PCIE_IOM_B_TO_COMP_B_20_DP")
	)
	(segment
		(start 284.70606 -69.053964)
		(end 287.279842 -69.053964)
		(width 0.1651)
		(layer "B.Cu")
		(net "PCIE_IOM_B_TO_COMP_B_20_DP")
	)
	(segment
		(start 316.654434 -56.473852)
		(end 317.109602 -56.27878)
		(width 0.1651)
		(layer "B.Cu")
		(net "PCIE_IOM_B_TO_COMP_B_20_DP")
	)
	(segment
		(start 280.03246 -69.807328)
		(end 280.133552 -69.90842)
		(width 0.1651)
		(layer "B.Cu")
		(net "PCIE_IOM_B_TO_COMP_B_20_DP")
	)
	(segment
		(start 315.51499 -56.961786)
		(end 315.970158 -56.766714)
		(width 0.1651)
		(layer "B.Cu")
		(net "PCIE_IOM_B_TO_COMP_B_20_DP")
	)
	(segment
		(start 361.304078 -31.463488)
		(end 361.304078 -22.173946)
		(width 0.1651)
		(layer "B.Cu")
		(net "PCIE_IOM_B_TO_COMP_B_20_DP")
	)
	(segment
		(start 318.249046 -55.790846)
		(end 318.314578 -55.627524)
		(width 0.1651)
		(layer "B.Cu")
		(net "PCIE_IOM_B_TO_COMP_B_20_DP")
	)
	(segment
		(start 316.491112 -56.40832)
		(end 316.654434 -56.473852)
		(width 0.1651)
		(layer "B.Cu")
		(net "PCIE_IOM_B_TO_COMP_B_20_DP")
	)
	(segment
		(start 315.351668 -56.896254)
		(end 315.51499 -56.961786)
		(width 0.1651)
		(layer "B.Cu")
		(net "PCIE_IOM_B_TO_COMP_B_20_DP")
	)
	(segment
		(start 315.970158 -56.766714)
		(end 316.03569 -56.603392)
		(width 0.1651)
		(layer "B.Cu")
		(net "PCIE_IOM_B_TO_COMP_B_20_DP")
	)
	(segment
		(start 318.933322 -55.497984)
		(end 341.649304 -45.769784)
		(width 0.1651)
		(layer "B.Cu")
		(net "PCIE_IOM_B_TO_COMP_B_20_DP")
	)
	(segment
		(start 287.279842 -69.053964)
		(end 314.830968 -57.254648)
		(width 0.1651)
		(layer "B.Cu")
		(net "PCIE_IOM_B_TO_COMP_B_20_DP")
	)
	(segment
		(start 280.484834 -70.053962)
		(end 283.706062 -70.053962)
		(width 0.1651)
		(layer "B.Cu")
		(net "PCIE_IOM_B_TO_COMP_B_20_DP")
	)
	(segment
		(start 314.830968 -57.254648)
		(end 314.896246 -57.091326)
		(width 0.1651)
		(layer "B.Cu")
		(net "PCIE_IOM_B_TO_COMP_B_20_DP")
	)
	(segment
		(start 317.630556 -55.920386)
		(end 317.793878 -55.985918)
		(width 0.1651)
		(layer "B.Cu")
		(net "PCIE_IOM_B_TO_COMP_B_20_DP")
	)
	(segment
		(start 317.793878 -55.985918)
		(end 318.249046 -55.790846)
		(width 0.1651)
		(layer "B.Cu")
		(net "PCIE_IOM_B_TO_COMP_B_20_DP")
	)
	(arc
		(start 279.985216 -69.661278)
		(mid 279.991311 -69.739962)
		(end 280.03246 -69.807328)
		(width 0.1651)
		(layer "B.Cu")
		(net "PCIE_IOM_B_TO_COMP_B_20_DP")
	)
	(arc
		(start 362.18368 -21.504148)
		(mid 362.301321 -21.455419)
		(end 362.35005 -21.337778)
		(width 0.1651)
		(layer "B.Cu")
		(net "PCIE_IOM_B_TO_COMP_B_20_DP")
	)
	(arc
		(start 280.076402 -69.537326)
		(mid 280.01592 -69.588349)
		(end 279.985216 -69.661278)
		(width 0.1651)
		(layer "B.Cu")
		(net "PCIE_IOM_B_TO_COMP_B_20_DP")
	)
	(arc
		(start 280.133552 -69.90842)
		(mid 280.294722 -70.01611)
		(end 280.484834 -70.053962)
		(width 0.1651)
		(layer "B.Cu")
		(net "PCIE_IOM_B_TO_COMP_B_20_DP")
	)
	(arc
		(start 361.304078 -22.173946)
		(mid 361.500257 -21.700327)
		(end 361.973876 -21.504148)
		(width 0.1651)
		(layer "B.Cu")
		(net "PCIE_IOM_B_TO_COMP_B_20_DP")
	)
	(segment
		(start 279.721818 -69.910198)
		(end 279.926796 -70.115176)
		(width 0.1651)
		(layer "B.Cu")
		(net "PCIE_IOM_B_TO_COMP_B_20_DN")
	)
	(segment
		(start 362.35005 -21.962618)
		(end 362.35005 -22.350222)
		(width 0.1651)
		(layer "B.Cu")
		(net "PCIE_IOM_B_TO_COMP_B_20_DN")
	)
	(segment
		(start 359.585768 -34.704274)
		(end 361.596178 -31.548832)
		(width 0.1651)
		(layer "B.Cu")
		(net "PCIE_IOM_B_TO_COMP_B_20_DN")
	)
	(segment
		(start 361.596178 -31.548832)
		(end 361.596178 -22.173946)
		(width 0.1651)
		(layer "B.Cu")
		(net "PCIE_IOM_B_TO_COMP_B_20_DN")
	)
	(segment
		(start 284.827218 -69.346064)
		(end 287.339786 -69.346064)
		(width 0.1651)
		(layer "B.Cu")
		(net "PCIE_IOM_B_TO_COMP_B_20_DN")
	)
	(segment
		(start 279.566116 -69.836538)
		(end 279.58161 -69.839078)
		(width 0.1651)
		(layer "B.Cu")
		(net "PCIE_IOM_B_TO_COMP_B_20_DN")
	)
	(segment
		(start 361.973876 -21.796248)
		(end 362.18368 -21.796248)
		(width 0.1651)
		(layer "B.Cu")
		(net "PCIE_IOM_B_TO_COMP_B_20_DN")
	)
	(segment
		(start 280.484326 -70.346062)
		(end 283.82722 -70.346062)
		(width 0.1651)
		(layer "B.Cu")
		(net "PCIE_IOM_B_TO_COMP_B_20_DN")
	)
	(segment
		(start 287.339786 -69.346064)
		(end 341.78621 -46.029118)
		(width 0.1651)
		(layer "B.Cu")
		(net "PCIE_IOM_B_TO_COMP_B_20_DN")
	)
	(segment
		(start 278.750014 -70.200012)
		(end 279.410668 -69.86143)
		(width 0.1651)
		(layer "B.Cu")
		(net "PCIE_IOM_B_TO_COMP_B_20_DN")
	)
	(segment
		(start 283.82722 -70.346062)
		(end 284.827218 -69.346064)
		(width 0.1651)
		(layer "B.Cu")
		(net "PCIE_IOM_B_TO_COMP_B_20_DN")
	)
	(segment
		(start 341.78621 -46.029118)
		(end 359.585768 -34.704274)
		(width 0.1651)
		(layer "B.Cu")
		(net "PCIE_IOM_B_TO_COMP_B_20_DN")
	)
	(arc
		(start 361.596178 -22.173946)
		(mid 361.706803 -21.906873)
		(end 361.973876 -21.796248)
		(width 0.1651)
		(layer "B.Cu")
		(net "PCIE_IOM_B_TO_COMP_B_20_DN")
	)
	(arc
		(start 279.926796 -70.115176)
		(mid 280.182593 -70.286094)
		(end 280.484326 -70.346062)
		(width 0.1651)
		(layer "B.Cu")
		(net "PCIE_IOM_B_TO_COMP_B_20_DN")
	)
	(arc
		(start 279.410668 -69.86143)
		(mid 279.486415 -69.836667)
		(end 279.566116 -69.836538)
		(width 0.1651)
		(layer "B.Cu")
		(net "PCIE_IOM_B_TO_COMP_B_20_DN")
	)
	(arc
		(start 279.58161 -69.839078)
		(mid 279.657362 -69.863508)
		(end 279.721818 -69.910198)
		(width 0.1651)
		(layer "B.Cu")
		(net "PCIE_IOM_B_TO_COMP_B_20_DN")
	)
	(arc
		(start 362.18368 -21.796248)
		(mid 362.301321 -21.844977)
		(end 362.35005 -21.962618)
		(width 0.1651)
		(layer "B.Cu")
		(net "PCIE_IOM_B_TO_COMP_B_20_DN")
	)
	(segment
		(start 359.50398 -31.298134)
		(end 359.50398 -23.173944)
		(width 0.1651)
		(layer "B.Cu")
		(net "PCIE_IOM_B_TO_COMP_B_19_DP")
	)
	(segment
		(start 292.243256 -63.743332)
		(end 292.698678 -63.54826)
		(width 0.1651)
		(layer "B.Cu")
		(net "PCIE_IOM_B_TO_COMP_B_19_DP")
	)
	(segment
		(start 293.219378 -63.189866)
		(end 293.3827 -63.255398)
		(width 0.1651)
		(layer "B.Cu")
		(net "PCIE_IOM_B_TO_COMP_B_19_DP")
	)
	(segment
		(start 295.661588 -62.27953)
		(end 296.116756 -62.084458)
		(width 0.1651)
		(layer "B.Cu")
		(net "PCIE_IOM_B_TO_COMP_B_19_DP")
	)
	(segment
		(start 347.816678 -39.93642)
		(end 358.222042 -33.310576)
		(width 0.1651)
		(layer "B.Cu")
		(net "PCIE_IOM_B_TO_COMP_B_19_DP")
	)
	(segment
		(start 347.779848 -39.959788)
		(end 347.816678 -39.93642)
		(width 0.1651)
		(layer "B.Cu")
		(net "PCIE_IOM_B_TO_COMP_B_19_DP")
	)
	(segment
		(start 284.70606 -65.053972)
		(end 285.8008 -65.053972)
		(width 0.1651)
		(layer "B.Cu")
		(net "PCIE_IOM_B_TO_COMP_B_19_DP")
	)
	(segment
		(start 360.173778 -22.504146)
		(end 360.383582 -22.504146)
		(width 0.1651)
		(layer "B.Cu")
		(net "PCIE_IOM_B_TO_COMP_B_19_DP")
	)
	(segment
		(start 280.484834 -66.05397)
		(end 283.706062 -66.05397)
		(width 0.1651)
		(layer "B.Cu")
		(net "PCIE_IOM_B_TO_COMP_B_19_DP")
	)
	(segment
		(start 358.222042 -33.310576)
		(end 359.50398 -31.298134)
		(width 0.1651)
		(layer "B.Cu")
		(net "PCIE_IOM_B_TO_COMP_B_19_DP")
	)
	(segment
		(start 296.116756 -62.084458)
		(end 296.182288 -61.921136)
		(width 0.1651)
		(layer "B.Cu")
		(net "PCIE_IOM_B_TO_COMP_B_19_DP")
	)
	(segment
		(start 294.522144 -62.767464)
		(end 294.977312 -62.572392)
		(width 0.1651)
		(layer "B.Cu")
		(net "PCIE_IOM_B_TO_COMP_B_19_DP")
	)
	(segment
		(start 296.637456 -61.726064)
		(end 296.801032 -61.791596)
		(width 0.1651)
		(layer "B.Cu")
		(net "PCIE_IOM_B_TO_COMP_B_19_DP")
	)
	(segment
		(start 280.75001 -65.200022)
		(end 280.076402 -65.537334)
		(width 0.1651)
		(layer "B.Cu")
		(net "PCIE_IOM_B_TO_COMP_B_19_DP")
	)
	(segment
		(start 292.763956 -63.384938)
		(end 293.219378 -63.189866)
		(width 0.1651)
		(layer "B.Cu")
		(net "PCIE_IOM_B_TO_COMP_B_19_DP")
	)
	(segment
		(start 292.698678 -63.54826)
		(end 292.763956 -63.384938)
		(width 0.1651)
		(layer "B.Cu")
		(net "PCIE_IOM_B_TO_COMP_B_19_DP")
	)
	(segment
		(start 296.801032 -61.791596)
		(end 347.779594 -39.959788)
		(width 0.1651)
		(layer "B.Cu")
		(net "PCIE_IOM_B_TO_COMP_B_19_DP")
	)
	(segment
		(start 293.837868 -63.060326)
		(end 293.9034 -62.897004)
		(width 0.1651)
		(layer "B.Cu")
		(net "PCIE_IOM_B_TO_COMP_B_19_DP")
	)
	(segment
		(start 295.042844 -62.40907)
		(end 295.498266 -62.213998)
		(width 0.1651)
		(layer "B.Cu")
		(net "PCIE_IOM_B_TO_COMP_B_19_DP")
	)
	(segment
		(start 293.3827 -63.255398)
		(end 293.837868 -63.060326)
		(width 0.1651)
		(layer "B.Cu")
		(net "PCIE_IOM_B_TO_COMP_B_19_DP")
	)
	(segment
		(start 293.9034 -62.897004)
		(end 294.358822 -62.701932)
		(width 0.1651)
		(layer "B.Cu")
		(net "PCIE_IOM_B_TO_COMP_B_19_DP")
	)
	(segment
		(start 294.358822 -62.701932)
		(end 294.522144 -62.767464)
		(width 0.1651)
		(layer "B.Cu")
		(net "PCIE_IOM_B_TO_COMP_B_19_DP")
	)
	(segment
		(start 285.8008 -65.053972)
		(end 292.243256 -63.743332)
		(width 0.1651)
		(layer "B.Cu")
		(net "PCIE_IOM_B_TO_COMP_B_19_DP")
	)
	(segment
		(start 280.03246 -65.807336)
		(end 280.133552 -65.908428)
		(width 0.1651)
		(layer "B.Cu")
		(net "PCIE_IOM_B_TO_COMP_B_19_DP")
	)
	(segment
		(start 347.779594 -39.959788)
		(end 347.779848 -39.959788)
		(width 0.1651)
		(layer "B.Cu")
		(net "PCIE_IOM_B_TO_COMP_B_19_DP")
	)
	(segment
		(start 296.182288 -61.921136)
		(end 296.637456 -61.726064)
		(width 0.1651)
		(layer "B.Cu")
		(net "PCIE_IOM_B_TO_COMP_B_19_DP")
	)
	(segment
		(start 294.977312 -62.572392)
		(end 295.042844 -62.40907)
		(width 0.1651)
		(layer "B.Cu")
		(net "PCIE_IOM_B_TO_COMP_B_19_DP")
	)
	(segment
		(start 295.498266 -62.213998)
		(end 295.661588 -62.27953)
		(width 0.1651)
		(layer "B.Cu")
		(net "PCIE_IOM_B_TO_COMP_B_19_DP")
	)
	(segment
		(start 283.706062 -66.05397)
		(end 284.70606 -65.053972)
		(width 0.1651)
		(layer "B.Cu")
		(net "PCIE_IOM_B_TO_COMP_B_19_DP")
	)
	(segment
		(start 360.549952 -22.337776)
		(end 360.549952 -21.950172)
		(width 0.1651)
		(layer "B.Cu")
		(net "PCIE_IOM_B_TO_COMP_B_19_DP")
	)
	(arc
		(start 280.076402 -65.537334)
		(mid 280.01592 -65.588357)
		(end 279.985216 -65.661286)
		(width 0.1651)
		(layer "B.Cu")
		(net "PCIE_IOM_B_TO_COMP_B_19_DP")
	)
	(arc
		(start 359.50398 -23.173944)
		(mid 359.700159 -22.700325)
		(end 360.173778 -22.504146)
		(width 0.1651)
		(layer "B.Cu")
		(net "PCIE_IOM_B_TO_COMP_B_19_DP")
	)
	(arc
		(start 280.133552 -65.908428)
		(mid 280.294722 -66.016118)
		(end 280.484834 -66.05397)
		(width 0.1651)
		(layer "B.Cu")
		(net "PCIE_IOM_B_TO_COMP_B_19_DP")
	)
	(arc
		(start 360.383582 -22.504146)
		(mid 360.501223 -22.455417)
		(end 360.549952 -22.337776)
		(width 0.1651)
		(layer "B.Cu")
		(net "PCIE_IOM_B_TO_COMP_B_19_DP")
	)
	(arc
		(start 279.985216 -65.661286)
		(mid 279.991311 -65.73997)
		(end 280.03246 -65.807336)
		(width 0.1651)
		(layer "B.Cu")
		(net "PCIE_IOM_B_TO_COMP_B_19_DP")
	)
	(segment
		(start 292.332918 -64.022986)
		(end 347.917008 -40.218868)
		(width 0.1651)
		(layer "B.Cu")
		(net "PCIE_IOM_B_TO_COMP_B_19_DN")
	)
	(segment
		(start 280.484326 -66.34607)
		(end 283.82722 -66.34607)
		(width 0.1651)
		(layer "B.Cu")
		(net "PCIE_IOM_B_TO_COMP_B_19_DN")
	)
	(segment
		(start 279.721818 -65.910206)
		(end 279.926796 -66.115184)
		(width 0.1651)
		(layer "B.Cu")
		(net "PCIE_IOM_B_TO_COMP_B_19_DN")
	)
	(segment
		(start 278.750014 -66.20002)
		(end 279.410668 -65.861438)
		(width 0.1651)
		(layer "B.Cu")
		(net "PCIE_IOM_B_TO_COMP_B_19_DN")
	)
	(segment
		(start 358.433624 -33.522158)
		(end 359.79608 -31.383478)
		(width 0.1651)
		(layer "B.Cu")
		(net "PCIE_IOM_B_TO_COMP_B_19_DN")
	)
	(segment
		(start 283.82722 -66.34607)
		(end 284.827218 -65.346072)
		(width 0.1651)
		(layer "B.Cu")
		(net "PCIE_IOM_B_TO_COMP_B_19_DN")
	)
	(segment
		(start 285.830264 -65.346072)
		(end 292.332918 -64.02324)
		(width 0.1651)
		(layer "B.Cu")
		(net "PCIE_IOM_B_TO_COMP_B_19_DN")
	)
	(segment
		(start 279.566116 -65.836546)
		(end 279.58161 -65.839086)
		(width 0.1651)
		(layer "B.Cu")
		(net "PCIE_IOM_B_TO_COMP_B_19_DN")
	)
	(segment
		(start 292.332918 -64.02324)
		(end 292.332918 -64.022986)
		(width 0.1651)
		(layer "B.Cu")
		(net "PCIE_IOM_B_TO_COMP_B_19_DN")
	)
	(segment
		(start 347.973396 -40.183054)
		(end 358.433624 -33.522158)
		(width 0.1651)
		(layer "B.Cu")
		(net "PCIE_IOM_B_TO_COMP_B_19_DN")
	)
	(segment
		(start 360.173778 -22.796246)
		(end 360.383582 -22.796246)
		(width 0.1651)
		(layer "B.Cu")
		(net "PCIE_IOM_B_TO_COMP_B_19_DN")
	)
	(segment
		(start 359.79608 -31.383478)
		(end 359.79608 -23.173944)
		(width 0.1651)
		(layer "B.Cu")
		(net "PCIE_IOM_B_TO_COMP_B_19_DN")
	)
	(segment
		(start 347.917008 -40.218868)
		(end 347.973396 -40.183054)
		(width 0.1651)
		(layer "B.Cu")
		(net "PCIE_IOM_B_TO_COMP_B_19_DN")
	)
	(segment
		(start 284.827218 -65.346072)
		(end 285.830264 -65.346072)
		(width 0.1651)
		(layer "B.Cu")
		(net "PCIE_IOM_B_TO_COMP_B_19_DN")
	)
	(segment
		(start 360.549952 -22.962616)
		(end 360.549952 -23.35022)
		(width 0.1651)
		(layer "B.Cu")
		(net "PCIE_IOM_B_TO_COMP_B_19_DN")
	)
	(arc
		(start 279.58161 -65.839086)
		(mid 279.657362 -65.863516)
		(end 279.721818 -65.910206)
		(width 0.1651)
		(layer "B.Cu")
		(net "PCIE_IOM_B_TO_COMP_B_19_DN")
	)
	(arc
		(start 360.383582 -22.796246)
		(mid 360.501223 -22.844975)
		(end 360.549952 -22.962616)
		(width 0.1651)
		(layer "B.Cu")
		(net "PCIE_IOM_B_TO_COMP_B_19_DN")
	)
	(arc
		(start 279.410668 -65.861438)
		(mid 279.486415 -65.836675)
		(end 279.566116 -65.836546)
		(width 0.1651)
		(layer "B.Cu")
		(net "PCIE_IOM_B_TO_COMP_B_19_DN")
	)
	(arc
		(start 279.926796 -66.115184)
		(mid 280.182593 -66.286102)
		(end 280.484326 -66.34607)
		(width 0.1651)
		(layer "B.Cu")
		(net "PCIE_IOM_B_TO_COMP_B_19_DN")
	)
	(arc
		(start 359.79608 -23.173944)
		(mid 359.906705 -22.906871)
		(end 360.173778 -22.796246)
		(width 0.1651)
		(layer "B.Cu")
		(net "PCIE_IOM_B_TO_COMP_B_19_DN")
	)
	(segment
		(start 305.158648 -56.303672)
		(end 305.613816 -56.1086)
		(width 0.1651)
		(layer "B.Cu")
		(net "PCIE_IOM_B_TO_COMP_B_18_DP")
	)
	(segment
		(start 301.197518 -58.13552)
		(end 302.814482 -57.443116)
		(width 0.1651)
		(layer "B.Cu")
		(net "PCIE_IOM_B_TO_COMP_B_18_DP")
	)
	(segment
		(start 358.750108 -21.337778)
		(end 358.750108 -20.950174)
		(width 0.1651)
		(layer "B.Cu")
		(net "PCIE_IOM_B_TO_COMP_B_18_DP")
	)
	(segment
		(start 306.23256 -55.97906)
		(end 306.298092 -55.815738)
		(width 0.1651)
		(layer "B.Cu")
		(net "PCIE_IOM_B_TO_COMP_B_18_DP")
	)
	(segment
		(start 357.704136 -30.986222)
		(end 357.704136 -22.173946)
		(width 0.1651)
		(layer "B.Cu")
		(net "PCIE_IOM_B_TO_COMP_B_18_DP")
	)
	(segment
		(start 304.474372 -56.596788)
		(end 304.637948 -56.662066)
		(width 0.1651)
		(layer "B.Cu")
		(net "PCIE_IOM_B_TO_COMP_B_18_DP")
	)
	(segment
		(start 358.373934 -21.504148)
		(end 358.583738 -21.504148)
		(width 0.1651)
		(layer "B.Cu")
		(net "PCIE_IOM_B_TO_COMP_B_18_DP")
	)
	(segment
		(start 306.916836 -55.686198)
		(end 347.11132 -38.471856)
		(width 0.1651)
		(layer "B.Cu")
		(net "PCIE_IOM_B_TO_COMP_B_18_DP")
	)
	(segment
		(start 356.917244 -32.224472)
		(end 357.704136 -30.986222)
		(width 0.1651)
		(layer "B.Cu")
		(net "PCIE_IOM_B_TO_COMP_B_18_DP")
	)
	(segment
		(start 304.019204 -56.791606)
		(end 304.474372 -56.596788)
		(width 0.1651)
		(layer "B.Cu")
		(net "PCIE_IOM_B_TO_COMP_B_18_DP")
	)
	(segment
		(start 347.11132 -38.471856)
		(end 356.917244 -32.224472)
		(width 0.1651)
		(layer "B.Cu")
		(net "PCIE_IOM_B_TO_COMP_B_18_DP")
	)
	(segment
		(start 283.706062 -62.053978)
		(end 284.70606 -61.05398)
		(width 0.1651)
		(layer "B.Cu")
		(net "PCIE_IOM_B_TO_COMP_B_18_DP")
	)
	(segment
		(start 303.335182 -57.084722)
		(end 303.498504 -57.15)
		(width 0.1651)
		(layer "B.Cu")
		(net "PCIE_IOM_B_TO_COMP_B_18_DP")
	)
	(segment
		(start 303.498504 -57.15)
		(end 303.953672 -56.955182)
		(width 0.1651)
		(layer "B.Cu")
		(net "PCIE_IOM_B_TO_COMP_B_18_DP")
	)
	(segment
		(start 302.87976 -57.279794)
		(end 303.335182 -57.084722)
		(width 0.1651)
		(layer "B.Cu")
		(net "PCIE_IOM_B_TO_COMP_B_18_DP")
	)
	(segment
		(start 306.298092 -55.815738)
		(end 306.75326 -55.620666)
		(width 0.1651)
		(layer "B.Cu")
		(net "PCIE_IOM_B_TO_COMP_B_18_DP")
	)
	(segment
		(start 305.777392 -56.174132)
		(end 306.23256 -55.97906)
		(width 0.1651)
		(layer "B.Cu")
		(net "PCIE_IOM_B_TO_COMP_B_18_DP")
	)
	(segment
		(start 306.75326 -55.620666)
		(end 306.916836 -55.686198)
		(width 0.1651)
		(layer "B.Cu")
		(net "PCIE_IOM_B_TO_COMP_B_18_DP")
	)
	(segment
		(start 280.484834 -62.053978)
		(end 283.706062 -62.053978)
		(width 0.1651)
		(layer "B.Cu")
		(net "PCIE_IOM_B_TO_COMP_B_18_DP")
	)
	(segment
		(start 280.03246 -61.807344)
		(end 280.133552 -61.908436)
		(width 0.1651)
		(layer "B.Cu")
		(net "PCIE_IOM_B_TO_COMP_B_18_DP")
	)
	(segment
		(start 304.637948 -56.662066)
		(end 305.093116 -56.466994)
		(width 0.1651)
		(layer "B.Cu")
		(net "PCIE_IOM_B_TO_COMP_B_18_DP")
	)
	(segment
		(start 305.613816 -56.1086)
		(end 305.777392 -56.174132)
		(width 0.1651)
		(layer "B.Cu")
		(net "PCIE_IOM_B_TO_COMP_B_18_DP")
	)
	(segment
		(start 303.953672 -56.955182)
		(end 304.019204 -56.791606)
		(width 0.1651)
		(layer "B.Cu")
		(net "PCIE_IOM_B_TO_COMP_B_18_DP")
	)
	(segment
		(start 280.75001 -61.20003)
		(end 280.076402 -61.537342)
		(width 0.1651)
		(layer "B.Cu")
		(net "PCIE_IOM_B_TO_COMP_B_18_DP")
	)
	(segment
		(start 287.46704 -61.05398)
		(end 301.197518 -58.13552)
		(width 0.1651)
		(layer "B.Cu")
		(net "PCIE_IOM_B_TO_COMP_B_18_DP")
	)
	(segment
		(start 284.70606 -61.05398)
		(end 287.46704 -61.05398)
		(width 0.1651)
		(layer "B.Cu")
		(net "PCIE_IOM_B_TO_COMP_B_18_DP")
	)
	(segment
		(start 305.093116 -56.466994)
		(end 305.158648 -56.303672)
		(width 0.1651)
		(layer "B.Cu")
		(net "PCIE_IOM_B_TO_COMP_B_18_DP")
	)
	(segment
		(start 302.814482 -57.443116)
		(end 302.87976 -57.279794)
		(width 0.1651)
		(layer "B.Cu")
		(net "PCIE_IOM_B_TO_COMP_B_18_DP")
	)
	(arc
		(start 358.583738 -21.504148)
		(mid 358.701379 -21.455419)
		(end 358.750108 -21.337778)
		(width 0.1651)
		(layer "B.Cu")
		(net "PCIE_IOM_B_TO_COMP_B_18_DP")
	)
	(arc
		(start 280.133552 -61.908436)
		(mid 280.294722 -62.016126)
		(end 280.484834 -62.053978)
		(width 0.1651)
		(layer "B.Cu")
		(net "PCIE_IOM_B_TO_COMP_B_18_DP")
	)
	(arc
		(start 280.076402 -61.537342)
		(mid 280.01592 -61.588365)
		(end 279.985216 -61.661294)
		(width 0.1651)
		(layer "B.Cu")
		(net "PCIE_IOM_B_TO_COMP_B_18_DP")
	)
	(arc
		(start 357.704136 -22.173946)
		(mid 357.900315 -21.700327)
		(end 358.373934 -21.504148)
		(width 0.1651)
		(layer "B.Cu")
		(net "PCIE_IOM_B_TO_COMP_B_18_DP")
	)
	(arc
		(start 279.985216 -61.661294)
		(mid 279.991311 -61.739978)
		(end 280.03246 -61.807344)
		(width 0.1651)
		(layer "B.Cu")
		(net "PCIE_IOM_B_TO_COMP_B_18_DP")
	)
	(segment
		(start 278.750014 -62.200028)
		(end 279.410668 -61.861446)
		(width 0.1651)
		(layer "B.Cu")
		(net "PCIE_IOM_B_TO_COMP_B_18_DN")
	)
	(segment
		(start 279.566116 -61.836554)
		(end 279.58161 -61.839094)
		(width 0.1651)
		(layer "B.Cu")
		(net "PCIE_IOM_B_TO_COMP_B_18_DN")
	)
	(segment
		(start 284.827218 -61.34608)
		(end 287.497774 -61.34608)
		(width 0.1651)
		(layer "B.Cu")
		(net "PCIE_IOM_B_TO_COMP_B_18_DN")
	)
	(segment
		(start 279.721818 -61.910214)
		(end 279.926796 -62.115192)
		(width 0.1651)
		(layer "B.Cu")
		(net "PCIE_IOM_B_TO_COMP_B_18_DN")
	)
	(segment
		(start 347.248226 -38.73119)
		(end 357.12908 -32.436054)
		(width 0.1651)
		(layer "B.Cu")
		(net "PCIE_IOM_B_TO_COMP_B_18_DN")
	)
	(segment
		(start 301.286418 -58.415428)
		(end 347.248226 -38.73119)
		(width 0.1651)
		(layer "B.Cu")
		(net "PCIE_IOM_B_TO_COMP_B_18_DN")
	)
	(segment
		(start 358.750108 -21.962618)
		(end 358.750108 -22.350222)
		(width 0.1651)
		(layer "B.Cu")
		(net "PCIE_IOM_B_TO_COMP_B_18_DN")
	)
	(segment
		(start 358.373934 -21.796248)
		(end 358.583738 -21.796248)
		(width 0.1651)
		(layer "B.Cu")
		(net "PCIE_IOM_B_TO_COMP_B_18_DN")
	)
	(segment
		(start 283.82722 -62.346078)
		(end 284.827218 -61.34608)
		(width 0.1651)
		(layer "B.Cu")
		(net "PCIE_IOM_B_TO_COMP_B_18_DN")
	)
	(segment
		(start 357.996236 -31.071312)
		(end 357.996236 -22.173946)
		(width 0.1651)
		(layer "B.Cu")
		(net "PCIE_IOM_B_TO_COMP_B_18_DN")
	)
	(segment
		(start 357.12908 -32.436054)
		(end 357.996236 -31.071312)
		(width 0.1651)
		(layer "B.Cu")
		(net "PCIE_IOM_B_TO_COMP_B_18_DN")
	)
	(segment
		(start 287.497774 -61.34608)
		(end 301.286418 -58.415428)
		(width 0.1651)
		(layer "B.Cu")
		(net "PCIE_IOM_B_TO_COMP_B_18_DN")
	)
	(segment
		(start 280.484326 -62.346078)
		(end 283.82722 -62.346078)
		(width 0.1651)
		(layer "B.Cu")
		(net "PCIE_IOM_B_TO_COMP_B_18_DN")
	)
	(arc
		(start 279.926796 -62.115192)
		(mid 280.182593 -62.28611)
		(end 280.484326 -62.346078)
		(width 0.1651)
		(layer "B.Cu")
		(net "PCIE_IOM_B_TO_COMP_B_18_DN")
	)
	(arc
		(start 357.996236 -22.173946)
		(mid 358.106861 -21.906873)
		(end 358.373934 -21.796248)
		(width 0.1651)
		(layer "B.Cu")
		(net "PCIE_IOM_B_TO_COMP_B_18_DN")
	)
	(arc
		(start 279.58161 -61.839094)
		(mid 279.657362 -61.863524)
		(end 279.721818 -61.910214)
		(width 0.1651)
		(layer "B.Cu")
		(net "PCIE_IOM_B_TO_COMP_B_18_DN")
	)
	(arc
		(start 279.410668 -61.861446)
		(mid 279.486415 -61.836683)
		(end 279.566116 -61.836554)
		(width 0.1651)
		(layer "B.Cu")
		(net "PCIE_IOM_B_TO_COMP_B_18_DN")
	)
	(arc
		(start 358.583738 -21.796248)
		(mid 358.701379 -21.844977)
		(end 358.750108 -21.962618)
		(width 0.1651)
		(layer "B.Cu")
		(net "PCIE_IOM_B_TO_COMP_B_18_DN")
	)
	(segment
		(start 287.305242 -56.723026)
		(end 287.394904 -56.588406)
		(width 0.1651)
		(layer "B.Cu")
		(net "PCIE_IOM_B_TO_COMP_B_17_DP")
	)
	(segment
		(start 293.445692 -55.494174)
		(end 355.672898 -31.170372)
		(width 0.1651)
		(layer "B.Cu")
		(net "PCIE_IOM_B_TO_COMP_B_17_DP")
	)
	(segment
		(start 290.406074 -56.102758)
		(end 290.891722 -56.005476)
		(width 0.1651)
		(layer "B.Cu")
		(net "PCIE_IOM_B_TO_COMP_B_17_DP")
	)
	(segment
		(start 293.444676 -55.494936)
		(end 293.445692 -55.494682)
		(width 0.1651)
		(layer "B.Cu")
		(net "PCIE_IOM_B_TO_COMP_B_17_DP")
	)
	(segment
		(start 355.904038 -30.862016)
		(end 355.904038 -23.173944)
		(width 0.1651)
		(layer "B.Cu")
		(net "PCIE_IOM_B_TO_COMP_B_17_DP")
	)
	(segment
		(start 288.590482 -56.349392)
		(end 289.07613 -56.25211)
		(width 0.1651)
		(layer "B.Cu")
		(net "PCIE_IOM_B_TO_COMP_B_17_DP")
	)
	(segment
		(start 289.21075 -56.341772)
		(end 289.696398 -56.244744)
		(width 0.1651)
		(layer "B.Cu")
		(net "PCIE_IOM_B_TO_COMP_B_17_DP")
	)
	(segment
		(start 285.650432 -57.053988)
		(end 287.305242 -56.723026)
		(width 0.1651)
		(layer "B.Cu")
		(net "PCIE_IOM_B_TO_COMP_B_17_DP")
	)
	(segment
		(start 287.880552 -56.491378)
		(end 288.015172 -56.58104)
		(width 0.1651)
		(layer "B.Cu")
		(net "PCIE_IOM_B_TO_COMP_B_17_DP")
	)
	(segment
		(start 356.573836 -22.504146)
		(end 356.78364 -22.504146)
		(width 0.1651)
		(layer "B.Cu")
		(net "PCIE_IOM_B_TO_COMP_B_17_DP")
	)
	(segment
		(start 290.891722 -56.005476)
		(end 290.981384 -55.87111)
		(width 0.1651)
		(layer "B.Cu")
		(net "PCIE_IOM_B_TO_COMP_B_17_DP")
	)
	(segment
		(start 288.015172 -56.58104)
		(end 288.50082 -56.483758)
		(width 0.1651)
		(layer "B.Cu")
		(net "PCIE_IOM_B_TO_COMP_B_17_DP")
	)
	(segment
		(start 293.445692 -55.494682)
		(end 293.445692 -55.494174)
		(width 0.1651)
		(layer "B.Cu")
		(net "PCIE_IOM_B_TO_COMP_B_17_DP")
	)
	(segment
		(start 280.75001 -57.200038)
		(end 280.076402 -57.53735)
		(width 0.1651)
		(layer "B.Cu")
		(net "PCIE_IOM_B_TO_COMP_B_17_DP")
	)
	(segment
		(start 290.981384 -55.87111)
		(end 291.467286 -55.773828)
		(width 0.1651)
		(layer "B.Cu")
		(net "PCIE_IOM_B_TO_COMP_B_17_DP")
	)
	(segment
		(start 291.601652 -55.86349)
		(end 293.444676 -55.494936)
		(width 0.1651)
		(layer "B.Cu")
		(net "PCIE_IOM_B_TO_COMP_B_17_DP")
	)
	(segment
		(start 283.706062 -58.053986)
		(end 284.70606 -57.053988)
		(width 0.1651)
		(layer "B.Cu")
		(net "PCIE_IOM_B_TO_COMP_B_17_DP")
	)
	(segment
		(start 284.70606 -57.053988)
		(end 285.650432 -57.053988)
		(width 0.1651)
		(layer "B.Cu")
		(net "PCIE_IOM_B_TO_COMP_B_17_DP")
	)
	(segment
		(start 280.484834 -58.053986)
		(end 283.706062 -58.053986)
		(width 0.1651)
		(layer "B.Cu")
		(net "PCIE_IOM_B_TO_COMP_B_17_DP")
	)
	(segment
		(start 355.672898 -31.170372)
		(end 355.904038 -30.862016)
		(width 0.1651)
		(layer "B.Cu")
		(net "PCIE_IOM_B_TO_COMP_B_17_DP")
	)
	(segment
		(start 291.467286 -55.773828)
		(end 291.601652 -55.86349)
		(width 0.1651)
		(layer "B.Cu")
		(net "PCIE_IOM_B_TO_COMP_B_17_DP")
	)
	(segment
		(start 356.95001 -22.337776)
		(end 356.95001 -21.950172)
		(width 0.1651)
		(layer "B.Cu")
		(net "PCIE_IOM_B_TO_COMP_B_17_DP")
	)
	(segment
		(start 288.50082 -56.483758)
		(end 288.590482 -56.349392)
		(width 0.1651)
		(layer "B.Cu")
		(net "PCIE_IOM_B_TO_COMP_B_17_DP")
	)
	(segment
		(start 289.78606 -56.110124)
		(end 290.271708 -56.013096)
		(width 0.1651)
		(layer "B.Cu")
		(net "PCIE_IOM_B_TO_COMP_B_17_DP")
	)
	(segment
		(start 280.03246 -57.807352)
		(end 280.133552 -57.908444)
		(width 0.1651)
		(layer "B.Cu")
		(net "PCIE_IOM_B_TO_COMP_B_17_DP")
	)
	(segment
		(start 289.696398 -56.244744)
		(end 289.78606 -56.110124)
		(width 0.1651)
		(layer "B.Cu")
		(net "PCIE_IOM_B_TO_COMP_B_17_DP")
	)
	(segment
		(start 287.394904 -56.588406)
		(end 287.880552 -56.491378)
		(width 0.1651)
		(layer "B.Cu")
		(net "PCIE_IOM_B_TO_COMP_B_17_DP")
	)
	(segment
		(start 290.271708 -56.013096)
		(end 290.406074 -56.102758)
		(width 0.1651)
		(layer "B.Cu")
		(net "PCIE_IOM_B_TO_COMP_B_17_DP")
	)
	(segment
		(start 289.07613 -56.25211)
		(end 289.21075 -56.341772)
		(width 0.1651)
		(layer "B.Cu")
		(net "PCIE_IOM_B_TO_COMP_B_17_DP")
	)
	(arc
		(start 356.78364 -22.504146)
		(mid 356.901281 -22.455417)
		(end 356.95001 -22.337776)
		(width 0.1651)
		(layer "B.Cu")
		(net "PCIE_IOM_B_TO_COMP_B_17_DP")
	)
	(arc
		(start 279.985216 -57.661302)
		(mid 279.991311 -57.739986)
		(end 280.03246 -57.807352)
		(width 0.1651)
		(layer "B.Cu")
		(net "PCIE_IOM_B_TO_COMP_B_17_DP")
	)
	(arc
		(start 280.076402 -57.53735)
		(mid 280.01592 -57.588373)
		(end 279.985216 -57.661302)
		(width 0.1651)
		(layer "B.Cu")
		(net "PCIE_IOM_B_TO_COMP_B_17_DP")
	)
	(arc
		(start 355.904038 -23.173944)
		(mid 356.100217 -22.700325)
		(end 356.573836 -22.504146)
		(width 0.1651)
		(layer "B.Cu")
		(net "PCIE_IOM_B_TO_COMP_B_17_DP")
	)
	(arc
		(start 280.133552 -57.908444)
		(mid 280.294722 -58.016134)
		(end 280.484834 -58.053986)
		(width 0.1651)
		(layer "B.Cu")
		(net "PCIE_IOM_B_TO_COMP_B_17_DP")
	)
	(segment
		(start 293.534592 -55.773574)
		(end 355.856794 -31.41218)
		(width 0.1651)
		(layer "B.Cu")
		(net "PCIE_IOM_B_TO_COMP_B_17_DN")
	)
	(segment
		(start 283.82722 -58.346086)
		(end 284.827218 -57.346088)
		(width 0.1651)
		(layer "B.Cu")
		(net "PCIE_IOM_B_TO_COMP_B_17_DN")
	)
	(segment
		(start 279.721818 -57.910222)
		(end 279.926796 -58.1152)
		(width 0.1651)
		(layer "B.Cu")
		(net "PCIE_IOM_B_TO_COMP_B_17_DN")
	)
	(segment
		(start 278.750014 -58.200036)
		(end 279.410668 -57.861454)
		(width 0.1651)
		(layer "B.Cu")
		(net "PCIE_IOM_B_TO_COMP_B_17_DN")
	)
	(segment
		(start 356.196138 -30.959552)
		(end 356.196138 -23.173944)
		(width 0.1651)
		(layer "B.Cu")
		(net "PCIE_IOM_B_TO_COMP_B_17_DN")
	)
	(segment
		(start 279.566116 -57.836562)
		(end 279.58161 -57.839102)
		(width 0.1651)
		(layer "B.Cu")
		(net "PCIE_IOM_B_TO_COMP_B_17_DN")
	)
	(segment
		(start 356.95001 -22.962616)
		(end 356.95001 -23.35022)
		(width 0.1651)
		(layer "B.Cu")
		(net "PCIE_IOM_B_TO_COMP_B_17_DN")
	)
	(segment
		(start 280.484326 -58.346086)
		(end 283.82722 -58.346086)
		(width 0.1651)
		(layer "B.Cu")
		(net "PCIE_IOM_B_TO_COMP_B_17_DN")
	)
	(segment
		(start 284.827218 -57.346088)
		(end 285.679388 -57.346088)
		(width 0.1651)
		(layer "B.Cu")
		(net "PCIE_IOM_B_TO_COMP_B_17_DN")
	)
	(segment
		(start 293.508938 -55.780178)
		(end 293.534592 -55.773574)
		(width 0.1651)
		(layer "B.Cu")
		(net "PCIE_IOM_B_TO_COMP_B_17_DN")
	)
	(segment
		(start 355.856794 -31.41218)
		(end 356.196138 -30.959552)
		(width 0.1651)
		(layer "B.Cu")
		(net "PCIE_IOM_B_TO_COMP_B_17_DN")
	)
	(segment
		(start 356.573836 -22.796246)
		(end 356.78364 -22.796246)
		(width 0.1651)
		(layer "B.Cu")
		(net "PCIE_IOM_B_TO_COMP_B_17_DN")
	)
	(segment
		(start 285.679388 -57.346088)
		(end 293.508938 -55.780178)
		(width 0.1651)
		(layer "B.Cu")
		(net "PCIE_IOM_B_TO_COMP_B_17_DN")
	)
	(arc
		(start 356.78364 -22.796246)
		(mid 356.901281 -22.844975)
		(end 356.95001 -22.962616)
		(width 0.1651)
		(layer "B.Cu")
		(net "PCIE_IOM_B_TO_COMP_B_17_DN")
	)
	(arc
		(start 356.196138 -23.173944)
		(mid 356.306763 -22.906871)
		(end 356.573836 -22.796246)
		(width 0.1651)
		(layer "B.Cu")
		(net "PCIE_IOM_B_TO_COMP_B_17_DN")
	)
	(arc
		(start 279.926796 -58.1152)
		(mid 280.182593 -58.286118)
		(end 280.484326 -58.346086)
		(width 0.1651)
		(layer "B.Cu")
		(net "PCIE_IOM_B_TO_COMP_B_17_DN")
	)
	(arc
		(start 279.410668 -57.861454)
		(mid 279.486415 -57.836691)
		(end 279.566116 -57.836562)
		(width 0.1651)
		(layer "B.Cu")
		(net "PCIE_IOM_B_TO_COMP_B_17_DN")
	)
	(arc
		(start 279.58161 -57.839102)
		(mid 279.657362 -57.863532)
		(end 279.721818 -57.910222)
		(width 0.1651)
		(layer "B.Cu")
		(net "PCIE_IOM_B_TO_COMP_B_17_DN")
	)
	(segment
		(start 290.576508 -50.038254)
		(end 290.734496 -50.073306)
		(width 0.1651)
		(layer "B.Cu")
		(net "PCIE_IOM_B_TO_COMP_B_16_DP")
	)
	(segment
		(start 280.484834 -54.053994)
		(end 283.706062 -54.053994)
		(width 0.1651)
		(layer "B.Cu")
		(net "PCIE_IOM_B_TO_COMP_B_16_DP")
	)
	(segment
		(start 290.12388 -50.46218)
		(end 290.158932 -50.304446)
		(width 0.1651)
		(layer "B.Cu")
		(net "PCIE_IOM_B_TO_COMP_B_16_DP")
	)
	(segment
		(start 289.548316 -50.69332)
		(end 289.70605 -50.728372)
		(width 0.1651)
		(layer "B.Cu")
		(net "PCIE_IOM_B_TO_COMP_B_16_DP")
	)
	(segment
		(start 291.152072 -49.807114)
		(end 291.187124 -49.64938)
		(width 0.1651)
		(layer "B.Cu")
		(net "PCIE_IOM_B_TO_COMP_B_16_DP")
	)
	(segment
		(start 325.930006 -27.651456)
		(end 353.659186 -21.504148)
		(width 0.1651)
		(layer "B.Cu")
		(net "PCIE_IOM_B_TO_COMP_B_16_DP")
	)
	(segment
		(start 290.158932 -50.304446)
		(end 290.576508 -50.038254)
		(width 0.1651)
		(layer "B.Cu")
		(net "PCIE_IOM_B_TO_COMP_B_16_DP")
	)
	(segment
		(start 288.520124 -51.348386)
		(end 288.677858 -51.383438)
		(width 0.1651)
		(layer "B.Cu")
		(net "PCIE_IOM_B_TO_COMP_B_16_DP")
	)
	(segment
		(start 289.130486 -50.959512)
		(end 289.548316 -50.69332)
		(width 0.1651)
		(layer "B.Cu")
		(net "PCIE_IOM_B_TO_COMP_B_16_DP")
	)
	(segment
		(start 290.734496 -50.073306)
		(end 291.152072 -49.807114)
		(width 0.1651)
		(layer "B.Cu")
		(net "PCIE_IOM_B_TO_COMP_B_16_DP")
	)
	(segment
		(start 289.70605 -50.728372)
		(end 290.12388 -50.46218)
		(width 0.1651)
		(layer "B.Cu")
		(net "PCIE_IOM_B_TO_COMP_B_16_DP")
	)
	(segment
		(start 353.659186 -21.504148)
		(end 354.983542 -21.504148)
		(width 0.1651)
		(layer "B.Cu")
		(net "PCIE_IOM_B_TO_COMP_B_16_DP")
	)
	(segment
		(start 291.604954 -49.383188)
		(end 291.762688 -49.41824)
		(width 0.1651)
		(layer "B.Cu")
		(net "PCIE_IOM_B_TO_COMP_B_16_DP")
	)
	(segment
		(start 288.677858 -51.383438)
		(end 289.095688 -51.117246)
		(width 0.1651)
		(layer "B.Cu")
		(net "PCIE_IOM_B_TO_COMP_B_16_DP")
	)
	(segment
		(start 291.187124 -49.64938)
		(end 291.604954 -49.383188)
		(width 0.1651)
		(layer "B.Cu")
		(net "PCIE_IOM_B_TO_COMP_B_16_DP")
	)
	(segment
		(start 288.102294 -51.614578)
		(end 288.520124 -51.348386)
		(width 0.1651)
		(layer "B.Cu")
		(net "PCIE_IOM_B_TO_COMP_B_16_DP")
	)
	(segment
		(start 284.70606 -53.053996)
		(end 286.055562 -53.053996)
		(width 0.1651)
		(layer "B.Cu")
		(net "PCIE_IOM_B_TO_COMP_B_16_DP")
	)
	(segment
		(start 288.067242 -51.772312)
		(end 288.102294 -51.614578)
		(width 0.1651)
		(layer "B.Cu")
		(net "PCIE_IOM_B_TO_COMP_B_16_DP")
	)
	(segment
		(start 283.706062 -54.053994)
		(end 284.70606 -53.053996)
		(width 0.1651)
		(layer "B.Cu")
		(net "PCIE_IOM_B_TO_COMP_B_16_DP")
	)
	(segment
		(start 280.03246 -53.80736)
		(end 280.133552 -53.908452)
		(width 0.1651)
		(layer "B.Cu")
		(net "PCIE_IOM_B_TO_COMP_B_16_DP")
	)
	(segment
		(start 289.095688 -51.117246)
		(end 289.130486 -50.959512)
		(width 0.1651)
		(layer "B.Cu")
		(net "PCIE_IOM_B_TO_COMP_B_16_DP")
	)
	(segment
		(start 280.75001 -53.200046)
		(end 280.076402 -53.537358)
		(width 0.1651)
		(layer "B.Cu")
		(net "PCIE_IOM_B_TO_COMP_B_16_DP")
	)
	(segment
		(start 291.762688 -49.41824)
		(end 325.930006 -27.651456)
		(width 0.1651)
		(layer "B.Cu")
		(net "PCIE_IOM_B_TO_COMP_B_16_DP")
	)
	(segment
		(start 286.055562 -53.053996)
		(end 288.067242 -51.772312)
		(width 0.1651)
		(layer "B.Cu")
		(net "PCIE_IOM_B_TO_COMP_B_16_DP")
	)
	(segment
		(start 355.149912 -21.337778)
		(end 355.149912 -20.950174)
		(width 0.1651)
		(layer "B.Cu")
		(net "PCIE_IOM_B_TO_COMP_B_16_DP")
	)
	(arc
		(start 280.133552 -53.908452)
		(mid 280.294722 -54.016142)
		(end 280.484834 -54.053994)
		(width 0.1651)
		(layer "B.Cu")
		(net "PCIE_IOM_B_TO_COMP_B_16_DP")
	)
	(arc
		(start 354.983542 -21.504148)
		(mid 355.101183 -21.455419)
		(end 355.149912 -21.337778)
		(width 0.1651)
		(layer "B.Cu")
		(net "PCIE_IOM_B_TO_COMP_B_16_DP")
	)
	(arc
		(start 279.985216 -53.66131)
		(mid 279.991311 -53.739994)
		(end 280.03246 -53.80736)
		(width 0.1651)
		(layer "B.Cu")
		(net "PCIE_IOM_B_TO_COMP_B_16_DP")
	)
	(arc
		(start 280.076402 -53.537358)
		(mid 280.01592 -53.588381)
		(end 279.985216 -53.66131)
		(width 0.1651)
		(layer "B.Cu")
		(net "PCIE_IOM_B_TO_COMP_B_16_DP")
	)
	(segment
		(start 353.69119 -21.796248)
		(end 326.043544 -27.925522)
		(width 0.1651)
		(layer "B.Cu")
		(net "PCIE_IOM_B_TO_COMP_B_16_DN")
	)
	(segment
		(start 286.140906 -53.346096)
		(end 284.827218 -53.346096)
		(width 0.1651)
		(layer "B.Cu")
		(net "PCIE_IOM_B_TO_COMP_B_16_DN")
	)
	(segment
		(start 279.410668 -53.861462)
		(end 278.750014 -54.200044)
		(width 0.1651)
		(layer "B.Cu")
		(net "PCIE_IOM_B_TO_COMP_B_16_DN")
	)
	(segment
		(start 326.043544 -27.925522)
		(end 286.140906 -53.346096)
		(width 0.1651)
		(layer "B.Cu")
		(net "PCIE_IOM_B_TO_COMP_B_16_DN")
	)
	(segment
		(start 284.827218 -53.346096)
		(end 283.82722 -54.346094)
		(width 0.1651)
		(layer "B.Cu")
		(net "PCIE_IOM_B_TO_COMP_B_16_DN")
	)
	(segment
		(start 279.58161 -53.83911)
		(end 279.566116 -53.83657)
		(width 0.1651)
		(layer "B.Cu")
		(net "PCIE_IOM_B_TO_COMP_B_16_DN")
	)
	(segment
		(start 354.983542 -21.796248)
		(end 353.69119 -21.796248)
		(width 0.1651)
		(layer "B.Cu")
		(net "PCIE_IOM_B_TO_COMP_B_16_DN")
	)
	(segment
		(start 355.149912 -22.350222)
		(end 355.149912 -21.962618)
		(width 0.1651)
		(layer "B.Cu")
		(net "PCIE_IOM_B_TO_COMP_B_16_DN")
	)
	(segment
		(start 279.926796 -54.115208)
		(end 279.721818 -53.91023)
		(width 0.1651)
		(layer "B.Cu")
		(net "PCIE_IOM_B_TO_COMP_B_16_DN")
	)
	(segment
		(start 283.82722 -54.346094)
		(end 280.484326 -54.346094)
		(width 0.1651)
		(layer "B.Cu")
		(net "PCIE_IOM_B_TO_COMP_B_16_DN")
	)
	(arc
		(start 355.149912 -21.962618)
		(mid 355.101183 -21.844977)
		(end 354.983542 -21.796248)
		(width 0.1651)
		(layer "B.Cu")
		(net "PCIE_IOM_B_TO_COMP_B_16_DN")
	)
	(arc
		(start 279.721818 -53.91023)
		(mid 279.657352 -53.863558)
		(end 279.58161 -53.83911)
		(width 0.1651)
		(layer "B.Cu")
		(net "PCIE_IOM_B_TO_COMP_B_16_DN")
	)
	(arc
		(start 279.566116 -53.83657)
		(mid 279.486406 -53.836643)
		(end 279.410668 -53.861462)
		(width 0.1651)
		(layer "B.Cu")
		(net "PCIE_IOM_B_TO_COMP_B_16_DN")
	)
	(arc
		(start 280.484326 -54.346094)
		(mid 280.182612 -54.286079)
		(end 279.926796 -54.115208)
		(width 0.1651)
		(layer "B.Cu")
		(net "PCIE_IOM_B_TO_COMP_B_16_DN")
	)
	(segment
		(start 272.808954 -65.623186)
		(end 276.823424 -86.020148)
		(width 0.1651)
		(layer "B.Cu")
		(net "PCIE_IOM_B_TO_COMP_B_15_DP")
	)
	(segment
		(start 278.349964 -88.416892)
		(end 280.743152 -89.942162)
		(width 0.1651)
		(layer "B.Cu")
		(net "PCIE_IOM_B_TO_COMP_B_15_DP")
	)
	(segment
		(start 280.75001 -49.200054)
		(end 280.089356 -49.538636)
		(width 0.1651)
		(layer "B.Cu")
		(net "PCIE_IOM_B_TO_COMP_B_15_DP")
	)
	(segment
		(start 279.933908 -49.563528)
		(end 279.918414 -49.560988)
		(width 0.1651)
		(layer "B.Cu")
		(net "PCIE_IOM_B_TO_COMP_B_15_DP")
	)
	(segment
		(start 303.421542 -85.442298)
		(end 357.260398 -51.142138)
		(width 0.1651)
		(layer "B.Cu")
		(net "PCIE_IOM_B_TO_COMP_B_15_DP")
	)
	(segment
		(start 276.111462 -50.730658)
		(end 272.886678 -65.273174)
		(width 0.1651)
		(layer "B.Cu")
		(net "PCIE_IOM_B_TO_COMP_B_15_DP")
	)
	(segment
		(start 279.088088 -49.083976)
		(end 277.654258 -49.083976)
		(width 0.1651)
		(layer "B.Cu")
		(net "PCIE_IOM_B_TO_COMP_B_15_DP")
	)
	(segment
		(start 375.206768 -35.475418)
		(end 377.796044 -31.414212)
		(width 0.1651)
		(layer "B.Cu")
		(net "PCIE_IOM_B_TO_COMP_B_15_DP")
	)
	(segment
		(start 357.260398 -51.142138)
		(end 361.805982 -44.013628)
		(width 0.1651)
		(layer "B.Cu")
		(net "PCIE_IOM_B_TO_COMP_B_15_DP")
	)
	(segment
		(start 279.778206 -49.489868)
		(end 279.573228 -49.28489)
		(width 0.1651)
		(layer "B.Cu")
		(net "PCIE_IOM_B_TO_COMP_B_15_DP")
	)
	(segment
		(start 272.887186 -65.273428)
		(end 272.808954 -65.623186)
		(width 0.1651)
		(layer "B.Cu")
		(net "PCIE_IOM_B_TO_COMP_B_15_DP")
	)
	(segment
		(start 361.805982 -44.013628)
		(end 375.206768 -35.475418)
		(width 0.1651)
		(layer "B.Cu")
		(net "PCIE_IOM_B_TO_COMP_B_15_DP")
	)
	(segment
		(start 276.823424 -49.613566)
		(end 276.111462 -50.730658)
		(width 0.1651)
		(layer "B.Cu")
		(net "PCIE_IOM_B_TO_COMP_B_15_DP")
	)
	(segment
		(start 376.750072 -21.337778)
		(end 376.750072 -20.950174)
		(width 0.1651)
		(layer "B.Cu")
		(net "PCIE_IOM_B_TO_COMP_B_15_DP")
	)
	(segment
		(start 280.743152 -89.942162)
		(end 281.931618 -90.20556)
		(width 0.1651)
		(layer "B.Cu")
		(net "PCIE_IOM_B_TO_COMP_B_15_DP")
	)
	(segment
		(start 377.295918 -21.504148)
		(end 376.916442 -21.504148)
		(width 0.1651)
		(layer "B.Cu")
		(net "PCIE_IOM_B_TO_COMP_B_15_DP")
	)
	(segment
		(start 276.823424 -86.020148)
		(end 278.349964 -88.416892)
		(width 0.1651)
		(layer "B.Cu")
		(net "PCIE_IOM_B_TO_COMP_B_15_DP")
	)
	(segment
		(start 281.931618 -90.20556)
		(end 303.421542 -85.442298)
		(width 0.1651)
		(layer "B.Cu")
		(net "PCIE_IOM_B_TO_COMP_B_15_DP")
	)
	(segment
		(start 377.796044 -31.414212)
		(end 377.796044 -22.004274)
		(width 0.1651)
		(layer "B.Cu")
		(net "PCIE_IOM_B_TO_COMP_B_15_DP")
	)
	(segment
		(start 272.886678 -65.273174)
		(end 272.887186 -65.273428)
		(width 0.1651)
		(layer "B.Cu")
		(net "PCIE_IOM_B_TO_COMP_B_15_DP")
	)
	(segment
		(start 277.654258 -49.083976)
		(end 276.823424 -49.613566)
		(width 0.1651)
		(layer "B.Cu")
		(net "PCIE_IOM_B_TO_COMP_B_15_DP")
	)
	(arc
		(start 279.573228 -49.28489)
		(mid 279.499897 -49.221209)
		(end 279.418288 -49.168558)
		(width 0.1651)
		(layer "B.Cu")
		(net "PCIE_IOM_B_TO_COMP_B_15_DP")
	)
	(arc
		(start 376.916442 -21.504148)
		(mid 376.798801 -21.455419)
		(end 376.750072 -21.337778)
		(width 0.1651)
		(layer "B.Cu")
		(net "PCIE_IOM_B_TO_COMP_B_15_DP")
	)
	(arc
		(start 279.418288 -49.168558)
		(mid 279.258523 -49.105446)
		(end 279.088088 -49.083976)
		(width 0.1651)
		(layer "B.Cu")
		(net "PCIE_IOM_B_TO_COMP_B_15_DP")
	)
	(arc
		(start 279.918414 -49.560988)
		(mid 279.842662 -49.536558)
		(end 279.778206 -49.489868)
		(width 0.1651)
		(layer "B.Cu")
		(net "PCIE_IOM_B_TO_COMP_B_15_DP")
	)
	(arc
		(start 280.089356 -49.538636)
		(mid 280.013609 -49.563399)
		(end 279.933908 -49.563528)
		(width 0.1651)
		(layer "B.Cu")
		(net "PCIE_IOM_B_TO_COMP_B_15_DP")
	)
	(arc
		(start 377.796044 -22.004274)
		(mid 377.64956 -21.650632)
		(end 377.295918 -21.504148)
		(width 0.1651)
		(layer "B.Cu")
		(net "PCIE_IOM_B_TO_COMP_B_15_DP")
	)
	(segment
		(start 277.035006 -49.825148)
		(end 276.385528 -50.844196)
		(width 0.1651)
		(layer "B.Cu")
		(net "PCIE_IOM_B_TO_COMP_B_15_DN")
	)
	(segment
		(start 273.172682 -65.335912)
		(end 273.172428 -65.336928)
		(width 0.1651)
		(layer "B.Cu")
		(net "PCIE_IOM_B_TO_COMP_B_15_DN")
	)
	(segment
		(start 305.96586 -83.339178)
		(end 306.123848 -83.37423)
		(width 0.1651)
		(layer "B.Cu")
		(net "PCIE_IOM_B_TO_COMP_B_15_DN")
	)
	(segment
		(start 303.491646 -84.915502)
		(end 303.909476 -84.64931)
		(width 0.1651)
		(layer "B.Cu")
		(net "PCIE_IOM_B_TO_COMP_B_15_DN")
	)
	(segment
		(start 306.994052 -82.684112)
		(end 307.15204 -82.719164)
		(width 0.1651)
		(layer "B.Cu")
		(net "PCIE_IOM_B_TO_COMP_B_15_DN")
	)
	(segment
		(start 273.680174 -63.575184)
		(end 273.572986 -64.0588)
		(width 0.1651)
		(layer "B.Cu")
		(net "PCIE_IOM_B_TO_COMP_B_15_DN")
	)
	(segment
		(start 329.257152 -68.500752)
		(end 329.674728 -68.23456)
		(width 0.1651)
		(layer "B.Cu")
		(net "PCIE_IOM_B_TO_COMP_B_15_DN")
	)
	(segment
		(start 377.503944 -31.328868)
		(end 377.503944 -22.004274)
		(width 0.1651)
		(layer "B.Cu")
		(net "PCIE_IOM_B_TO_COMP_B_15_DN")
	)
	(segment
		(start 303.456594 -85.07349)
		(end 303.491646 -84.915502)
		(width 0.1651)
		(layer "B.Cu")
		(net "PCIE_IOM_B_TO_COMP_B_15_DN")
	)
	(segment
		(start 276.354794 -81.481676)
		(end 276.450552 -81.967578)
		(width 0.1651)
		(layer "B.Cu")
		(net "PCIE_IOM_B_TO_COMP_B_15_DN")
	)
	(segment
		(start 304.519838 -84.260436)
		(end 304.937668 -83.994244)
		(width 0.1651)
		(layer "B.Cu")
		(net "PCIE_IOM_B_TO_COMP_B_15_DN")
	)
	(segment
		(start 273.30908 -65.249044)
		(end 273.172682 -65.335912)
		(width 0.1651)
		(layer "B.Cu")
		(net "PCIE_IOM_B_TO_COMP_B_15_DN")
	)
	(segment
		(start 331.8891 -66.95948)
		(end 357.048816 -50.930556)
		(width 0.1651)
		(layer "B.Cu")
		(net "PCIE_IOM_B_TO_COMP_B_15_DN")
	)
	(segment
		(start 321.930014 -73.304146)
		(end 322.34759 -73.038208)
		(width 0.1651)
		(layer "B.Cu")
		(net "PCIE_IOM_B_TO_COMP_B_15_DN")
	)
	(segment
		(start 273.857212 -62.248542)
		(end 273.94408 -62.38494)
		(width 0.1651)
		(layer "B.Cu")
		(net "PCIE_IOM_B_TO_COMP_B_15_DN")
	)
	(segment
		(start 281.931618 -89.906348)
		(end 303.308004 -85.167978)
		(width 0.1651)
		(layer "B.Cu")
		(net "PCIE_IOM_B_TO_COMP_B_15_DN")
	)
	(segment
		(start 274.535138 -72.235822)
		(end 274.437094 -72.382126)
		(width 0.1651)
		(layer "B.Cu")
		(net "PCIE_IOM_B_TO_COMP_B_15_DN")
	)
	(segment
		(start 280.85669 -89.668096)
		(end 281.931618 -89.906348)
		(width 0.1651)
		(layer "B.Cu")
		(net "PCIE_IOM_B_TO_COMP_B_15_DN")
	)
	(segment
		(start 305.513232 -83.763104)
		(end 305.548284 -83.60537)
		(width 0.1651)
		(layer "B.Cu")
		(net "PCIE_IOM_B_TO_COMP_B_15_DN")
	)
	(segment
		(start 276.211284 -80.751426)
		(end 276.112986 -80.897476)
		(width 0.1651)
		(layer "B.Cu")
		(net "PCIE_IOM_B_TO_COMP_B_15_DN")
	)
	(segment
		(start 273.107658 -65.626996)
		(end 273.575272 -68.003166)
		(width 0.1651)
		(layer "B.Cu")
		(net "PCIE_IOM_B_TO_COMP_B_15_DN")
	)
	(segment
		(start 274.29587 -71.01967)
		(end 274.197826 -71.165974)
		(width 0.1651)
		(layer "B.Cu")
		(net "PCIE_IOM_B_TO_COMP_B_15_DN")
	)
	(segment
		(start 276.833584 -83.91398)
		(end 276.929342 -84.399882)
		(width 0.1651)
		(layer "B.Cu")
		(net "PCIE_IOM_B_TO_COMP_B_15_DN")
	)
	(segment
		(start 331.278484 -67.348354)
		(end 331.313536 -67.19062)
		(width 0.1651)
		(layer "B.Cu")
		(net "PCIE_IOM_B_TO_COMP_B_15_DN")
	)
	(segment
		(start 319.715642 -74.57948)
		(end 319.873376 -74.614532)
		(width 0.1651)
		(layer "B.Cu")
		(net "PCIE_IOM_B_TO_COMP_B_15_DN")
	)
	(segment
		(start 322.34759 -73.038208)
		(end 322.382642 -72.88022)
		(width 0.1651)
		(layer "B.Cu")
		(net "PCIE_IOM_B_TO_COMP_B_15_DN")
	)
	(segment
		(start 276.594316 -82.697828)
		(end 276.68982 -83.18373)
		(width 0.1651)
		(layer "B.Cu")
		(net "PCIE_IOM_B_TO_COMP_B_15_DN")
	)
	(segment
		(start 307.15204 -82.719164)
		(end 319.263014 -75.003406)
		(width 0.1651)
		(layer "B.Cu")
		(net "PCIE_IOM_B_TO_COMP_B_15_DN")
	)
	(segment
		(start 276.208744 -81.383378)
		(end 276.354794 -81.481676)
		(width 0.1651)
		(layer "B.Cu")
		(net "PCIE_IOM_B_TO_COMP_B_15_DN")
	)
	(segment
		(start 330.285344 -67.845686)
		(end 330.70292 -67.579494)
		(width 0.1651)
		(layer "B.Cu")
		(net "PCIE_IOM_B_TO_COMP_B_15_DN")
	)
	(segment
		(start 305.548284 -83.60537)
		(end 305.96586 -83.339178)
		(width 0.1651)
		(layer "B.Cu")
		(net "PCIE_IOM_B_TO_COMP_B_15_DN")
	)
	(segment
		(start 273.836892 -62.868556)
		(end 273.700494 -62.955424)
		(width 0.1651)
		(layer "B.Cu")
		(net "PCIE_IOM_B_TO_COMP_B_15_DN")
	)
	(segment
		(start 304.06721 -84.684362)
		(end 304.48504 -84.41817)
		(width 0.1651)
		(layer "B.Cu")
		(net "PCIE_IOM_B_TO_COMP_B_15_DN")
	)
	(segment
		(start 277.739602 -49.376076)
		(end 277.035006 -49.825148)
		(width 0.1651)
		(layer "B.Cu")
		(net "PCIE_IOM_B_TO_COMP_B_15_DN")
	)
	(segment
		(start 278.750014 -50.200052)
		(end 279.423622 -49.86274)
		(width 0.1651)
		(layer "B.Cu")
		(net "PCIE_IOM_B_TO_COMP_B_15_DN")
	)
	(segment
		(start 276.385528 -50.844196)
		(end 274.121118 -61.058298)
		(width 0.1651)
		(layer "B.Cu")
		(net "PCIE_IOM_B_TO_COMP_B_15_DN")
	)
	(segment
		(start 330.70292 -67.579494)
		(end 330.860908 -67.614546)
		(width 0.1651)
		(layer "B.Cu")
		(net "PCIE_IOM_B_TO_COMP_B_15_DN")
	)
	(segment
		(start 279.467564 -49.592738)
		(end 279.366472 -49.491646)
		(width 0.1651)
		(layer "B.Cu")
		(net "PCIE_IOM_B_TO_COMP_B_15_DN")
	)
	(segment
		(start 275.969476 -80.167226)
		(end 276.115526 -80.26527)
		(width 0.1651)
		(layer "B.Cu")
		(net "PCIE_IOM_B_TO_COMP_B_15_DN")
	)
	(segment
		(start 276.591776 -83.32978)
		(end 276.687534 -83.815936)
		(width 0.1651)
		(layer "B.Cu")
		(net "PCIE_IOM_B_TO_COMP_B_15_DN")
	)
	(segment
		(start 329.674728 -68.23456)
		(end 329.832716 -68.269612)
		(width 0.1651)
		(layer "B.Cu")
		(net "PCIE_IOM_B_TO_COMP_B_15_DN")
	)
	(segment
		(start 273.416268 -64.765428)
		(end 273.30908 -65.249044)
		(width 0.1651)
		(layer "B.Cu")
		(net "PCIE_IOM_B_TO_COMP_B_15_DN")
	)
	(segment
		(start 276.687534 -83.815936)
		(end 276.833584 -83.91398)
		(width 0.1651)
		(layer "B.Cu")
		(net "PCIE_IOM_B_TO_COMP_B_15_DN")
	)
	(segment
		(start 304.937668 -83.994244)
		(end 305.095402 -84.029296)
		(width 0.1651)
		(layer "B.Cu")
		(net "PCIE_IOM_B_TO_COMP_B_15_DN")
	)
	(segment
		(start 306.576476 -82.950304)
		(end 306.994052 -82.684112)
		(width 0.1651)
		(layer "B.Cu")
		(net "PCIE_IOM_B_TO_COMP_B_15_DN")
	)
	(segment
		(start 273.814794 -69.219572)
		(end 273.960844 -69.317616)
		(width 0.1651)
		(layer "B.Cu")
		(net "PCIE_IOM_B_TO_COMP_B_15_DN")
	)
	(segment
		(start 274.29333 -71.651876)
		(end 274.439634 -71.74992)
		(width 0.1651)
		(layer "B.Cu")
		(net "PCIE_IOM_B_TO_COMP_B_15_DN")
	)
	(segment
		(start 273.575272 -68.003166)
		(end 273.721576 -68.101464)
		(width 0.1651)
		(layer "B.Cu")
		(net "PCIE_IOM_B_TO_COMP_B_15_DN")
	)
	(segment
		(start 303.308004 -85.167978)
		(end 303.456594 -85.07349)
		(width 0.1651)
		(layer "B.Cu")
		(net "PCIE_IOM_B_TO_COMP_B_15_DN")
	)
	(segment
		(start 320.291206 -74.34834)
		(end 320.326258 -74.190352)
		(width 0.1651)
		(layer "B.Cu")
		(net "PCIE_IOM_B_TO_COMP_B_15_DN")
	)
	(segment
		(start 273.960844 -69.317616)
		(end 274.056602 -69.803518)
		(width 0.1651)
		(layer "B.Cu")
		(net "PCIE_IOM_B_TO_COMP_B_15_DN")
	)
	(segment
		(start 276.112986 -80.897476)
		(end 276.208744 -81.383378)
		(width 0.1651)
		(layer "B.Cu")
		(net "PCIE_IOM_B_TO_COMP_B_15_DN")
	)
	(segment
		(start 278.561546 -88.20531)
		(end 280.85669 -89.668096)
		(width 0.1651)
		(layer "B.Cu")
		(net "PCIE_IOM_B_TO_COMP_B_15_DN")
	)
	(segment
		(start 274.197826 -71.165974)
		(end 274.29333 -71.651876)
		(width 0.1651)
		(layer "B.Cu")
		(net "PCIE_IOM_B_TO_COMP_B_15_DN")
	)
	(segment
		(start 331.731366 -66.924428)
		(end 331.8891 -66.95948)
		(width 0.1651)
		(layer "B.Cu")
		(net "PCIE_IOM_B_TO_COMP_B_15_DN")
	)
	(segment
		(start 273.9644 -61.76518)
		(end 273.857212 -62.248542)
		(width 0.1651)
		(layer "B.Cu")
		(net "PCIE_IOM_B_TO_COMP_B_15_DN")
	)
	(segment
		(start 274.054062 -70.435724)
		(end 274.200112 -70.533768)
		(width 0.1651)
		(layer "B.Cu")
		(net "PCIE_IOM_B_TO_COMP_B_15_DN")
	)
	(segment
		(start 319.263014 -75.003406)
		(end 319.297812 -74.845672)
		(width 0.1651)
		(layer "B.Cu")
		(net "PCIE_IOM_B_TO_COMP_B_15_DN")
	)
	(segment
		(start 331.313536 -67.19062)
		(end 331.731366 -66.924428)
		(width 0.1651)
		(layer "B.Cu")
		(net "PCIE_IOM_B_TO_COMP_B_15_DN")
	)
	(segment
		(start 305.095402 -84.029296)
		(end 305.513232 -83.763104)
		(width 0.1651)
		(layer "B.Cu")
		(net "PCIE_IOM_B_TO_COMP_B_15_DN")
	)
	(segment
		(start 330.860908 -67.614546)
		(end 331.278484 -67.348354)
		(width 0.1651)
		(layer "B.Cu")
		(net "PCIE_IOM_B_TO_COMP_B_15_DN")
	)
	(segment
		(start 273.436588 -64.145668)
		(end 273.329654 -64.628014)
		(width 0.1651)
		(layer "B.Cu")
		(net "PCIE_IOM_B_TO_COMP_B_15_DN")
	)
	(segment
		(start 274.056602 -69.803518)
		(end 273.958304 -69.949568)
		(width 0.1651)
		(layer "B.Cu")
		(net "PCIE_IOM_B_TO_COMP_B_15_DN")
	)
	(segment
		(start 330.250292 -68.00342)
		(end 330.285344 -67.845686)
		(width 0.1651)
		(layer "B.Cu")
		(net "PCIE_IOM_B_TO_COMP_B_15_DN")
	)
	(segment
		(start 322.800472 -72.614028)
		(end 322.958206 -72.64908)
		(width 0.1651)
		(layer "B.Cu")
		(net "PCIE_IOM_B_TO_COMP_B_15_DN")
	)
	(segment
		(start 322.958206 -72.64908)
		(end 329.2221 -68.658486)
		(width 0.1651)
		(layer "B.Cu")
		(net "PCIE_IOM_B_TO_COMP_B_15_DN")
	)
	(segment
		(start 319.297812 -74.845672)
		(end 319.715642 -74.57948)
		(width 0.1651)
		(layer "B.Cu")
		(net "PCIE_IOM_B_TO_COMP_B_15_DN")
	)
	(segment
		(start 273.572986 -64.0588)
		(end 273.436588 -64.145668)
		(width 0.1651)
		(layer "B.Cu")
		(net "PCIE_IOM_B_TO_COMP_B_15_DN")
	)
	(segment
		(start 306.123848 -83.37423)
		(end 306.541424 -83.108038)
		(width 0.1651)
		(layer "B.Cu")
		(net "PCIE_IOM_B_TO_COMP_B_15_DN")
	)
	(segment
		(start 276.450552 -81.967578)
		(end 276.352508 -82.113628)
		(width 0.1651)
		(layer "B.Cu")
		(net "PCIE_IOM_B_TO_COMP_B_15_DN")
	)
	(segment
		(start 276.68982 -83.18373)
		(end 276.591776 -83.32978)
		(width 0.1651)
		(layer "B.Cu")
		(net "PCIE_IOM_B_TO_COMP_B_15_DN")
	)
	(segment
		(start 329.832716 -68.269612)
		(end 330.250292 -68.00342)
		(width 0.1651)
		(layer "B.Cu")
		(net "PCIE_IOM_B_TO_COMP_B_15_DN")
	)
	(segment
		(start 303.909476 -84.64931)
		(end 304.06721 -84.684362)
		(width 0.1651)
		(layer "B.Cu")
		(net "PCIE_IOM_B_TO_COMP_B_15_DN")
	)
	(segment
		(start 274.437094 -72.382126)
		(end 275.969476 -80.167226)
		(width 0.1651)
		(layer "B.Cu")
		(net "PCIE_IOM_B_TO_COMP_B_15_DN")
	)
	(segment
		(start 304.48504 -84.41817)
		(end 304.519838 -84.260436)
		(width 0.1651)
		(layer "B.Cu")
		(net "PCIE_IOM_B_TO_COMP_B_15_DN")
	)
	(segment
		(start 374.995186 -35.263836)
		(end 377.503944 -31.328868)
		(width 0.1651)
		(layer "B.Cu")
		(net "PCIE_IOM_B_TO_COMP_B_15_DN")
	)
	(segment
		(start 273.3294 -64.629284)
		(end 273.416268 -64.765428)
		(width 0.1651)
		(layer "B.Cu")
		(net "PCIE_IOM_B_TO_COMP_B_15_DN")
	)
	(segment
		(start 306.541424 -83.108038)
		(end 306.576476 -82.950304)
		(width 0.1651)
		(layer "B.Cu")
		(net "PCIE_IOM_B_TO_COMP_B_15_DN")
	)
	(segment
		(start 274.121118 -61.058298)
		(end 274.207986 -61.194696)
		(width 0.1651)
		(layer "B.Cu")
		(net "PCIE_IOM_B_TO_COMP_B_15_DN")
	)
	(segment
		(start 321.319398 -73.693274)
		(end 321.35445 -73.535286)
		(width 0.1651)
		(layer "B.Cu")
		(net "PCIE_IOM_B_TO_COMP_B_15_DN")
	)
	(segment
		(start 322.382642 -72.88022)
		(end 322.800472 -72.614028)
		(width 0.1651)
		(layer "B.Cu")
		(net "PCIE_IOM_B_TO_COMP_B_15_DN")
	)
	(segment
		(start 273.94408 -62.38494)
		(end 273.836892 -62.868556)
		(width 0.1651)
		(layer "B.Cu")
		(net "PCIE_IOM_B_TO_COMP_B_15_DN")
	)
	(segment
		(start 321.772026 -73.269348)
		(end 321.930014 -73.304146)
		(width 0.1651)
		(layer "B.Cu")
		(net "PCIE_IOM_B_TO_COMP_B_15_DN")
	)
	(segment
		(start 277.099522 -85.909658)
		(end 278.561546 -88.20531)
		(width 0.1651)
		(layer "B.Cu")
		(net "PCIE_IOM_B_TO_COMP_B_15_DN")
	)
	(segment
		(start 279.088342 -49.376076)
		(end 277.739602 -49.376076)
		(width 0.1651)
		(layer "B.Cu")
		(net "PCIE_IOM_B_TO_COMP_B_15_DN")
	)
	(segment
		(start 276.352508 -82.113628)
		(end 276.448012 -82.599784)
		(width 0.1651)
		(layer "B.Cu")
		(net "PCIE_IOM_B_TO_COMP_B_15_DN")
	)
	(segment
		(start 273.700494 -62.955424)
		(end 273.593306 -63.43904)
		(width 0.1651)
		(layer "B.Cu")
		(net "PCIE_IOM_B_TO_COMP_B_15_DN")
	)
	(segment
		(start 376.750072 -21.962618)
		(end 376.750072 -22.350222)
		(width 0.1651)
		(layer "B.Cu")
		(net "PCIE_IOM_B_TO_COMP_B_15_DN")
	)
	(segment
		(start 274.100798 -61.678312)
		(end 273.9644 -61.76518)
		(width 0.1651)
		(layer "B.Cu")
		(net "PCIE_IOM_B_TO_COMP_B_15_DN")
	)
	(segment
		(start 273.329654 -64.628014)
		(end 273.3294 -64.629284)
		(width 0.1651)
		(layer "B.Cu")
		(net "PCIE_IOM_B_TO_COMP_B_15_DN")
	)
	(segment
		(start 377.295918 -21.796248)
		(end 376.916442 -21.796248)
		(width 0.1651)
		(layer "B.Cu")
		(net "PCIE_IOM_B_TO_COMP_B_15_DN")
	)
	(segment
		(start 320.326258 -74.190352)
		(end 320.743834 -73.924414)
		(width 0.1651)
		(layer "B.Cu")
		(net "PCIE_IOM_B_TO_COMP_B_15_DN")
	)
	(segment
		(start 273.172428 -65.336928)
		(end 273.107658 -65.626996)
		(width 0.1651)
		(layer "B.Cu")
		(net "PCIE_IOM_B_TO_COMP_B_15_DN")
	)
	(segment
		(start 276.831044 -84.546186)
		(end 277.099522 -85.909658)
		(width 0.1651)
		(layer "B.Cu")
		(net "PCIE_IOM_B_TO_COMP_B_15_DN")
	)
	(segment
		(start 274.207986 -61.194696)
		(end 274.100798 -61.678312)
		(width 0.1651)
		(layer "B.Cu")
		(net "PCIE_IOM_B_TO_COMP_B_15_DN")
	)
	(segment
		(start 273.719036 -68.733416)
		(end 273.814794 -69.219572)
		(width 0.1651)
		(layer "B.Cu")
		(net "PCIE_IOM_B_TO_COMP_B_15_DN")
	)
	(segment
		(start 276.115526 -80.26527)
		(end 276.211284 -80.751426)
		(width 0.1651)
		(layer "B.Cu")
		(net "PCIE_IOM_B_TO_COMP_B_15_DN")
	)
	(segment
		(start 329.2221 -68.658486)
		(end 329.257152 -68.500752)
		(width 0.1651)
		(layer "B.Cu")
		(net "PCIE_IOM_B_TO_COMP_B_15_DN")
	)
	(segment
		(start 273.958304 -69.949568)
		(end 274.054062 -70.435724)
		(width 0.1651)
		(layer "B.Cu")
		(net "PCIE_IOM_B_TO_COMP_B_15_DN")
	)
	(segment
		(start 357.048816 -50.930556)
		(end 361.5944 -43.802046)
		(width 0.1651)
		(layer "B.Cu")
		(net "PCIE_IOM_B_TO_COMP_B_15_DN")
	)
	(segment
		(start 321.35445 -73.535286)
		(end 321.772026 -73.269348)
		(width 0.1651)
		(layer "B.Cu")
		(net "PCIE_IOM_B_TO_COMP_B_15_DN")
	)
	(segment
		(start 276.929342 -84.399882)
		(end 276.831044 -84.546186)
		(width 0.1651)
		(layer "B.Cu")
		(net "PCIE_IOM_B_TO_COMP_B_15_DN")
	)
	(segment
		(start 276.448012 -82.599784)
		(end 276.594316 -82.697828)
		(width 0.1651)
		(layer "B.Cu")
		(net "PCIE_IOM_B_TO_COMP_B_15_DN")
	)
	(segment
		(start 361.5944 -43.802046)
		(end 374.995186 -35.263836)
		(width 0.1651)
		(layer "B.Cu")
		(net "PCIE_IOM_B_TO_COMP_B_15_DN")
	)
	(segment
		(start 273.721576 -68.101464)
		(end 273.81708 -68.587366)
		(width 0.1651)
		(layer "B.Cu")
		(net "PCIE_IOM_B_TO_COMP_B_15_DN")
	)
	(segment
		(start 274.439634 -71.74992)
		(end 274.535138 -72.235822)
		(width 0.1651)
		(layer "B.Cu")
		(net "PCIE_IOM_B_TO_COMP_B_15_DN")
	)
	(segment
		(start 274.200112 -70.533768)
		(end 274.29587 -71.01967)
		(width 0.1651)
		(layer "B.Cu")
		(net "PCIE_IOM_B_TO_COMP_B_15_DN")
	)
	(segment
		(start 273.81708 -68.587366)
		(end 273.719036 -68.733416)
		(width 0.1651)
		(layer "B.Cu")
		(net "PCIE_IOM_B_TO_COMP_B_15_DN")
	)
	(segment
		(start 320.901822 -73.959212)
		(end 321.319398 -73.693274)
		(width 0.1651)
		(layer "B.Cu")
		(net "PCIE_IOM_B_TO_COMP_B_15_DN")
	)
	(segment
		(start 320.743834 -73.924414)
		(end 320.901822 -73.959212)
		(width 0.1651)
		(layer "B.Cu")
		(net "PCIE_IOM_B_TO_COMP_B_15_DN")
	)
	(segment
		(start 319.873376 -74.614532)
		(end 320.291206 -74.34834)
		(width 0.1651)
		(layer "B.Cu")
		(net "PCIE_IOM_B_TO_COMP_B_15_DN")
	)
	(segment
		(start 273.593306 -63.43904)
		(end 273.680174 -63.575184)
		(width 0.1651)
		(layer "B.Cu")
		(net "PCIE_IOM_B_TO_COMP_B_15_DN")
	)
	(arc
		(start 279.423622 -49.86274)
		(mid 279.484104 -49.811717)
		(end 279.514808 -49.738788)
		(width 0.1651)
		(layer "B.Cu")
		(net "PCIE_IOM_B_TO_COMP_B_15_DN")
	)
	(arc
		(start 279.366472 -49.491646)
		(mid 279.324385 -49.455101)
		(end 279.277572 -49.424844)
		(width 0.1651)
		(layer "B.Cu")
		(net "PCIE_IOM_B_TO_COMP_B_15_DN")
	)
	(arc
		(start 279.514808 -49.738788)
		(mid 279.508713 -49.660104)
		(end 279.467564 -49.592738)
		(width 0.1651)
		(layer "B.Cu")
		(net "PCIE_IOM_B_TO_COMP_B_15_DN")
	)
	(arc
		(start 376.916442 -21.796248)
		(mid 376.798801 -21.844977)
		(end 376.750072 -21.962618)
		(width 0.1651)
		(layer "B.Cu")
		(net "PCIE_IOM_B_TO_COMP_B_15_DN")
	)
	(arc
		(start 279.277572 -49.424844)
		(mid 279.186029 -49.388546)
		(end 279.088342 -49.376076)
		(width 0.1651)
		(layer "B.Cu")
		(net "PCIE_IOM_B_TO_COMP_B_15_DN")
	)
	(arc
		(start 377.503944 -22.004274)
		(mid 377.443015 -21.857177)
		(end 377.295918 -21.796248)
		(width 0.1651)
		(layer "B.Cu")
		(net "PCIE_IOM_B_TO_COMP_B_15_DN")
	)
	(segment
		(start 274.539202 -49.594008)
		(end 270.762222 -66.634614)
		(width 0.1651)
		(layer "B.Cu")
		(net "PCIE_IOM_B_TO_COMP_B_14_DP")
	)
	(segment
		(start 276.991572 -45.747432)
		(end 274.539202 -49.594008)
		(width 0.1651)
		(layer "B.Cu")
		(net "PCIE_IOM_B_TO_COMP_B_14_DP")
	)
	(segment
		(start 279.778206 -45.489876)
		(end 279.573228 -45.284898)
		(width 0.1651)
		(layer "B.Cu")
		(net "PCIE_IOM_B_TO_COMP_B_14_DP")
	)
	(segment
		(start 279.088088 -45.083984)
		(end 278.03348 -45.083984)
		(width 0.1651)
		(layer "B.Cu")
		(net "PCIE_IOM_B_TO_COMP_B_14_DP")
	)
	(segment
		(start 363.56925 -44.955206)
		(end 363.568996 -44.955206)
		(width 0.1651)
		(layer "B.Cu")
		(net "PCIE_IOM_B_TO_COMP_B_14_DP")
	)
	(segment
		(start 379.595888 -31.668212)
		(end 379.595888 -23.00097)
		(width 0.1651)
		(layer "B.Cu")
		(net "PCIE_IOM_B_TO_COMP_B_14_DP")
	)
	(segment
		(start 306.754784 -86.648798)
		(end 358.052116 -53.33619)
		(width 0.1651)
		(layer "B.Cu")
		(net "PCIE_IOM_B_TO_COMP_B_14_DP")
	)
	(segment
		(start 363.568996 -44.955206)
		(end 376.499628 -36.534598)
		(width 0.1651)
		(layer "B.Cu")
		(net "PCIE_IOM_B_TO_COMP_B_14_DP")
	)
	(segment
		(start 376.499628 -36.534598)
		(end 379.595888 -31.668212)
		(width 0.1651)
		(layer "B.Cu")
		(net "PCIE_IOM_B_TO_COMP_B_14_DP")
	)
	(segment
		(start 278.03348 -45.083984)
		(end 276.991572 -45.747432)
		(width 0.1651)
		(layer "B.Cu")
		(net "PCIE_IOM_B_TO_COMP_B_14_DP")
	)
	(segment
		(start 277.192486 -89.602056)
		(end 280.13533 -91.477084)
		(width 0.1651)
		(layer "B.Cu")
		(net "PCIE_IOM_B_TO_COMP_B_14_DP")
	)
	(segment
		(start 378.549916 -22.337776)
		(end 378.549916 -21.950172)
		(width 0.1651)
		(layer "B.Cu")
		(net "PCIE_IOM_B_TO_COMP_B_14_DP")
	)
	(segment
		(start 358.052116 -53.33619)
		(end 363.56925 -44.955206)
		(width 0.1651)
		(layer "B.Cu")
		(net "PCIE_IOM_B_TO_COMP_B_14_DP")
	)
	(segment
		(start 280.75001 -45.200062)
		(end 280.089356 -45.538644)
		(width 0.1651)
		(layer "B.Cu")
		(net "PCIE_IOM_B_TO_COMP_B_14_DP")
	)
	(segment
		(start 270.762222 -66.634614)
		(end 275.143976 -86.387686)
		(width 0.1651)
		(layer "B.Cu")
		(net "PCIE_IOM_B_TO_COMP_B_14_DP")
	)
	(segment
		(start 279.933908 -45.563536)
		(end 279.918414 -45.560996)
		(width 0.1651)
		(layer "B.Cu")
		(net "PCIE_IOM_B_TO_COMP_B_14_DP")
	)
	(segment
		(start 280.13533 -91.477084)
		(end 282.047188 -91.90101)
		(width 0.1651)
		(layer "B.Cu")
		(net "PCIE_IOM_B_TO_COMP_B_14_DP")
	)
	(segment
		(start 275.143976 -86.387686)
		(end 277.192486 -89.602056)
		(width 0.1651)
		(layer "B.Cu")
		(net "PCIE_IOM_B_TO_COMP_B_14_DP")
	)
	(segment
		(start 282.047188 -91.90101)
		(end 306.754784 -86.648798)
		(width 0.1651)
		(layer "B.Cu")
		(net "PCIE_IOM_B_TO_COMP_B_14_DP")
	)
	(segment
		(start 379.099064 -22.504146)
		(end 378.716286 -22.504146)
		(width 0.1651)
		(layer "B.Cu")
		(net "PCIE_IOM_B_TO_COMP_B_14_DP")
	)
	(arc
		(start 279.573228 -45.284898)
		(mid 279.499897 -45.221217)
		(end 279.418288 -45.168566)
		(width 0.1651)
		(layer "B.Cu")
		(net "PCIE_IOM_B_TO_COMP_B_14_DP")
	)
	(arc
		(start 279.418288 -45.168566)
		(mid 279.258523 -45.105454)
		(end 279.088088 -45.083984)
		(width 0.1651)
		(layer "B.Cu")
		(net "PCIE_IOM_B_TO_COMP_B_14_DP")
	)
	(arc
		(start 379.595888 -23.00097)
		(mid 379.450372 -22.649662)
		(end 379.099064 -22.504146)
		(width 0.1651)
		(layer "B.Cu")
		(net "PCIE_IOM_B_TO_COMP_B_14_DP")
	)
	(arc
		(start 279.918414 -45.560996)
		(mid 279.842662 -45.536566)
		(end 279.778206 -45.489876)
		(width 0.1651)
		(layer "B.Cu")
		(net "PCIE_IOM_B_TO_COMP_B_14_DP")
	)
	(arc
		(start 280.089356 -45.538644)
		(mid 280.013609 -45.563407)
		(end 279.933908 -45.563536)
		(width 0.1651)
		(layer "B.Cu")
		(net "PCIE_IOM_B_TO_COMP_B_14_DP")
	)
	(arc
		(start 378.716286 -22.504146)
		(mid 378.598645 -22.455417)
		(end 378.549916 -22.337776)
		(width 0.1651)
		(layer "B.Cu")
		(net "PCIE_IOM_B_TO_COMP_B_14_DP")
	)
	(segment
		(start 322.22821 -76.10348)
		(end 322.191634 -76.275692)
		(width 0.1651)
		(layer "B.Cu")
		(net "PCIE_IOM_B_TO_COMP_B_14_DN")
	)
	(segment
		(start 291.768784 -89.408508)
		(end 291.672772 -89.556082)
		(width 0.1651)
		(layer "B.Cu")
		(net "PCIE_IOM_B_TO_COMP_B_14_DN")
	)
	(segment
		(start 324.307454 -74.753216)
		(end 324.270624 -74.925428)
		(width 0.1651)
		(layer "B.Cu")
		(net "PCIE_IOM_B_TO_COMP_B_14_DN")
	)
	(segment
		(start 274.881086 -83.854036)
		(end 274.773898 -83.37042)
		(width 0.1651)
		(layer "B.Cu")
		(net "PCIE_IOM_B_TO_COMP_B_14_DN")
	)
	(segment
		(start 308.548024 -84.987384)
		(end 308.13248 -85.257132)
		(width 0.1651)
		(layer "B.Cu")
		(net "PCIE_IOM_B_TO_COMP_B_14_DN")
	)
	(segment
		(start 324.722744 -74.483468)
		(end 324.307454 -74.753216)
		(width 0.1651)
		(layer "B.Cu")
		(net "PCIE_IOM_B_TO_COMP_B_14_DN")
	)
	(segment
		(start 336.145378 -67.065652)
		(end 335.730088 -67.3354)
		(width 0.1651)
		(layer "B.Cu")
		(net "PCIE_IOM_B_TO_COMP_B_14_DN")
	)
	(segment
		(start 307.680614 -85.699092)
		(end 307.508402 -85.662516)
		(width 0.1651)
		(layer "B.Cu")
		(net "PCIE_IOM_B_TO_COMP_B_14_DN")
	)
	(segment
		(start 309.172102 -84.582)
		(end 309.135526 -84.754212)
		(width 0.1651)
		(layer "B.Cu")
		(net "PCIE_IOM_B_TO_COMP_B_14_DN")
	)
	(segment
		(start 280.248868 -91.203018)
		(end 277.404068 -89.390474)
		(width 0.1651)
		(layer "B.Cu")
		(net "PCIE_IOM_B_TO_COMP_B_14_DN")
	)
	(segment
		(start 292.253162 -89.305638)
		(end 291.768784 -89.408508)
		(width 0.1651)
		(layer "B.Cu")
		(net "PCIE_IOM_B_TO_COMP_B_14_DN")
	)
	(segment
		(start 335.693258 -67.507358)
		(end 335.277968 -67.777106)
		(width 0.1651)
		(layer "B.Cu")
		(net "PCIE_IOM_B_TO_COMP_B_14_DN")
	)
	(segment
		(start 275.310854 -85.790532)
		(end 275.405342 -85.642196)
		(width 0.1651)
		(layer "B.Cu")
		(net "PCIE_IOM_B_TO_COMP_B_14_DN")
	)
	(segment
		(start 363.35843 -44.743624)
		(end 357.84155 -53.124354)
		(width 0.1651)
		(layer "B.Cu")
		(net "PCIE_IOM_B_TO_COMP_B_14_DN")
	)
	(segment
		(start 291.672772 -89.556082)
		(end 282.048458 -91.602052)
		(width 0.1651)
		(layer "B.Cu")
		(net "PCIE_IOM_B_TO_COMP_B_14_DN")
	)
	(segment
		(start 308.095904 -85.429344)
		(end 307.680614 -85.699092)
		(width 0.1651)
		(layer "B.Cu")
		(net "PCIE_IOM_B_TO_COMP_B_14_DN")
	)
	(segment
		(start 378.716286 -22.796246)
		(end 379.099064 -22.796246)
		(width 0.1651)
		(layer "B.Cu")
		(net "PCIE_IOM_B_TO_COMP_B_14_DN")
	)
	(segment
		(start 275.418042 -86.274148)
		(end 275.310854 -85.790532)
		(width 0.1651)
		(layer "B.Cu")
		(net "PCIE_IOM_B_TO_COMP_B_14_DN")
	)
	(segment
		(start 274.50542 -82.160364)
		(end 274.600162 -82.011774)
		(width 0.1651)
		(layer "B.Cu")
		(net "PCIE_IOM_B_TO_COMP_B_14_DN")
	)
	(segment
		(start 308.13248 -85.257132)
		(end 308.095904 -85.429344)
		(width 0.1651)
		(layer "B.Cu")
		(net "PCIE_IOM_B_TO_COMP_B_14_DN")
	)
	(segment
		(start 334.65389 -68.18249)
		(end 334.238346 -68.452238)
		(width 0.1651)
		(layer "B.Cu")
		(net "PCIE_IOM_B_TO_COMP_B_14_DN")
	)
	(segment
		(start 273.548602 -55.941722)
		(end 273.461734 -55.805324)
		(width 0.1651)
		(layer "B.Cu")
		(net "PCIE_IOM_B_TO_COMP_B_14_DN")
	)
	(segment
		(start 335.277968 -67.777106)
		(end 335.105756 -67.74053)
		(width 0.1651)
		(layer "B.Cu")
		(net "PCIE_IOM_B_TO_COMP_B_14_DN")
	)
	(segment
		(start 336.73288 -66.83248)
		(end 336.31759 -67.102228)
		(width 0.1651)
		(layer "B.Cu")
		(net "PCIE_IOM_B_TO_COMP_B_14_DN")
	)
	(segment
		(start 334.238346 -68.452238)
		(end 334.066388 -68.415662)
		(width 0.1651)
		(layer "B.Cu")
		(net "PCIE_IOM_B_TO_COMP_B_14_DN")
	)
	(segment
		(start 337.357212 -66.427096)
		(end 337.185 -66.39052)
		(width 0.1651)
		(layer "B.Cu")
		(net "PCIE_IOM_B_TO_COMP_B_14_DN")
	)
	(segment
		(start 322.6435 -75.833732)
		(end 322.22821 -76.10348)
		(width 0.1651)
		(layer "B.Cu")
		(net "PCIE_IOM_B_TO_COMP_B_14_DN")
	)
	(segment
		(start 273.72564 -54.61508)
		(end 274.813268 -49.707546)
		(width 0.1651)
		(layer "B.Cu")
		(net "PCIE_IOM_B_TO_COMP_B_14_DN")
	)
	(segment
		(start 271.061434 -66.634614)
		(end 272.777458 -58.892694)
		(width 0.1651)
		(layer "B.Cu")
		(net "PCIE_IOM_B_TO_COMP_B_14_DN")
	)
	(segment
		(start 321.604132 -76.508864)
		(end 321.188588 -76.778612)
		(width 0.1651)
		(layer "B.Cu")
		(net "PCIE_IOM_B_TO_COMP_B_14_DN")
	)
	(segment
		(start 310.627014 -83.637374)
		(end 310.211724 -83.907122)
		(width 0.1651)
		(layer "B.Cu")
		(net "PCIE_IOM_B_TO_COMP_B_14_DN")
	)
	(segment
		(start 310.799226 -83.67395)
		(end 310.627014 -83.637374)
		(width 0.1651)
		(layer "B.Cu")
		(net "PCIE_IOM_B_TO_COMP_B_14_DN")
	)
	(segment
		(start 273.177508 -57.615582)
		(end 273.284696 -57.131966)
		(width 0.1651)
		(layer "B.Cu")
		(net "PCIE_IOM_B_TO_COMP_B_14_DN")
	)
	(segment
		(start 309.135526 -84.754212)
		(end 308.719982 -85.02396)
		(width 0.1651)
		(layer "B.Cu")
		(net "PCIE_IOM_B_TO_COMP_B_14_DN")
	)
	(segment
		(start 275.029676 -83.948524)
		(end 274.881086 -83.854036)
		(width 0.1651)
		(layer "B.Cu")
		(net "PCIE_IOM_B_TO_COMP_B_14_DN")
	)
	(segment
		(start 277.203154 -45.959014)
		(end 278.118824 -45.376084)
		(width 0.1651)
		(layer "B.Cu")
		(net "PCIE_IOM_B_TO_COMP_B_14_DN")
	)
	(segment
		(start 273.041364 -57.70245)
		(end 273.177508 -57.615582)
		(width 0.1651)
		(layer "B.Cu")
		(net "PCIE_IOM_B_TO_COMP_B_14_DN")
	)
	(segment
		(start 307.092858 -85.932264)
		(end 307.056282 -86.104476)
		(width 0.1651)
		(layer "B.Cu")
		(net "PCIE_IOM_B_TO_COMP_B_14_DN")
	)
	(segment
		(start 273.441414 -56.425338)
		(end 273.548602 -55.941722)
		(width 0.1651)
		(layer "B.Cu")
		(net "PCIE_IOM_B_TO_COMP_B_14_DN")
	)
	(segment
		(start 324.270624 -74.925428)
		(end 323.855334 -75.195176)
		(width 0.1651)
		(layer "B.Cu")
		(net "PCIE_IOM_B_TO_COMP_B_14_DN")
	)
	(segment
		(start 273.305016 -56.511952)
		(end 273.441414 -56.425338)
		(width 0.1651)
		(layer "B.Cu")
		(net "PCIE_IOM_B_TO_COMP_B_14_DN")
	)
	(segment
		(start 292.400736 -89.401396)
		(end 292.253162 -89.305638)
		(width 0.1651)
		(layer "B.Cu")
		(net "PCIE_IOM_B_TO_COMP_B_14_DN")
	)
	(segment
		(start 379.303788 -31.583122)
		(end 379.303534 -31.583122)
		(width 0.1651)
		(layer "B.Cu")
		(net "PCIE_IOM_B_TO_COMP_B_14_DN")
	)
	(segment
		(start 334.690466 -68.010278)
		(end 334.65389 -68.18249)
		(width 0.1651)
		(layer "B.Cu")
		(net "PCIE_IOM_B_TO_COMP_B_14_DN")
	)
	(segment
		(start 273.812508 -54.751224)
		(end 273.72564 -54.61508)
		(width 0.1651)
		(layer "B.Cu")
		(net "PCIE_IOM_B_TO_COMP_B_14_DN")
	)
	(segment
		(start 279.423622 -45.862748)
		(end 278.750014 -46.20006)
		(width 0.1651)
		(layer "B.Cu")
		(net "PCIE_IOM_B_TO_COMP_B_14_DN")
	)
	(segment
		(start 323.231256 -75.60056)
		(end 322.815712 -75.870308)
		(width 0.1651)
		(layer "B.Cu")
		(net "PCIE_IOM_B_TO_COMP_B_14_DN")
	)
	(segment
		(start 307.056282 -86.104476)
		(end 306.640992 -86.374224)
		(width 0.1651)
		(layer "B.Cu")
		(net "PCIE_IOM_B_TO_COMP_B_14_DN")
	)
	(segment
		(start 275.298154 -85.15858)
		(end 275.149564 -85.064092)
		(width 0.1651)
		(layer "B.Cu")
		(net "PCIE_IOM_B_TO_COMP_B_14_DN")
	)
	(segment
		(start 292.885114 -89.298526)
		(end 292.400736 -89.401396)
		(width 0.1651)
		(layer "B.Cu")
		(net "PCIE_IOM_B_TO_COMP_B_14_DN")
	)
	(segment
		(start 274.761198 -82.738468)
		(end 274.612862 -82.643726)
		(width 0.1651)
		(layer "B.Cu")
		(net "PCIE_IOM_B_TO_COMP_B_14_DN")
	)
	(segment
		(start 273.568922 -55.321708)
		(end 273.70532 -55.23484)
		(width 0.1651)
		(layer "B.Cu")
		(net "PCIE_IOM_B_TO_COMP_B_14_DN")
	)
	(segment
		(start 310.211724 -83.907122)
		(end 310.175148 -84.07908)
		(width 0.1651)
		(layer "B.Cu")
		(net "PCIE_IOM_B_TO_COMP_B_14_DN")
	)
	(segment
		(start 273.70532 -55.23484)
		(end 273.812508 -54.751224)
		(width 0.1651)
		(layer "B.Cu")
		(net "PCIE_IOM_B_TO_COMP_B_14_DN")
	)
	(segment
		(start 273.021044 -58.32221)
		(end 272.934176 -58.186066)
		(width 0.1651)
		(layer "B.Cu")
		(net "PCIE_IOM_B_TO_COMP_B_14_DN")
	)
	(segment
		(start 274.612862 -82.643726)
		(end 274.50542 -82.160364)
		(width 0.1651)
		(layer "B.Cu")
		(net "PCIE_IOM_B_TO_COMP_B_14_DN")
	)
	(segment
		(start 274.813268 -49.707546)
		(end 277.203154 -45.959014)
		(width 0.1651)
		(layer "B.Cu")
		(net "PCIE_IOM_B_TO_COMP_B_14_DN")
	)
	(segment
		(start 378.549916 -23.35022)
		(end 378.549916 -22.962616)
		(width 0.1651)
		(layer "B.Cu")
		(net "PCIE_IOM_B_TO_COMP_B_14_DN")
	)
	(segment
		(start 323.683122 -75.1586)
		(end 323.267832 -75.428348)
		(width 0.1651)
		(layer "B.Cu")
		(net "PCIE_IOM_B_TO_COMP_B_14_DN")
	)
	(segment
		(start 379.303788 -23.00097)
		(end 379.303788 -31.583122)
		(width 0.1651)
		(layer "B.Cu")
		(net "PCIE_IOM_B_TO_COMP_B_14_DN")
	)
	(segment
		(start 274.49272 -81.528158)
		(end 274.344384 -81.43367)
		(width 0.1651)
		(layer "B.Cu")
		(net "PCIE_IOM_B_TO_COMP_B_14_DN")
	)
	(segment
		(start 292.981126 -89.150698)
		(end 292.885114 -89.298526)
		(width 0.1651)
		(layer "B.Cu")
		(net "PCIE_IOM_B_TO_COMP_B_14_DN")
	)
	(segment
		(start 274.773898 -83.37042)
		(end 274.868386 -83.22183)
		(width 0.1651)
		(layer "B.Cu")
		(net "PCIE_IOM_B_TO_COMP_B_14_DN")
	)
	(segment
		(start 333.650844 -68.68541)
		(end 333.614268 -68.857622)
		(width 0.1651)
		(layer "B.Cu")
		(net "PCIE_IOM_B_TO_COMP_B_14_DN")
	)
	(segment
		(start 321.152012 -76.950824)
		(end 310.799226 -83.67395)
		(width 0.1651)
		(layer "B.Cu")
		(net "PCIE_IOM_B_TO_COMP_B_14_DN")
	)
	(segment
		(start 357.84155 -53.124354)
		(end 337.357212 -66.427096)
		(width 0.1651)
		(layer "B.Cu")
		(net "PCIE_IOM_B_TO_COMP_B_14_DN")
	)
	(segment
		(start 335.105756 -67.74053)
		(end 334.690466 -68.010278)
		(width 0.1651)
		(layer "B.Cu")
		(net "PCIE_IOM_B_TO_COMP_B_14_DN")
	)
	(segment
		(start 324.894956 -74.520044)
		(end 324.722744 -74.483468)
		(width 0.1651)
		(layer "B.Cu")
		(net "PCIE_IOM_B_TO_COMP_B_14_DN")
	)
	(segment
		(start 306.640992 -86.374224)
		(end 293.613078 -89.143586)
		(width 0.1651)
		(layer "B.Cu")
		(net "PCIE_IOM_B_TO_COMP_B_14_DN")
	)
	(segment
		(start 321.776344 -76.54544)
		(end 321.604132 -76.508864)
		(width 0.1651)
		(layer "B.Cu")
		(net "PCIE_IOM_B_TO_COMP_B_14_DN")
	)
	(segment
		(start 275.136864 -84.43214)
		(end 275.029676 -83.948524)
		(width 0.1651)
		(layer "B.Cu")
		(net "PCIE_IOM_B_TO_COMP_B_14_DN")
	)
	(segment
		(start 376.28703 -36.324286)
		(end 363.35843 -44.743624)
		(width 0.1651)
		(layer "B.Cu")
		(net "PCIE_IOM_B_TO_COMP_B_14_DN")
	)
	(segment
		(start 309.759604 -84.348828)
		(end 309.587392 -84.312252)
		(width 0.1651)
		(layer "B.Cu")
		(net "PCIE_IOM_B_TO_COMP_B_14_DN")
	)
	(segment
		(start 310.175148 -84.07908)
		(end 309.759604 -84.348828)
		(width 0.1651)
		(layer "B.Cu")
		(net "PCIE_IOM_B_TO_COMP_B_14_DN")
	)
	(segment
		(start 277.404068 -89.390474)
		(end 275.418042 -86.274148)
		(width 0.1651)
		(layer "B.Cu")
		(net "PCIE_IOM_B_TO_COMP_B_14_DN")
	)
	(segment
		(start 323.267832 -75.428348)
		(end 323.231256 -75.60056)
		(width 0.1651)
		(layer "B.Cu")
		(net "PCIE_IOM_B_TO_COMP_B_14_DN")
	)
	(segment
		(start 275.405342 -85.642196)
		(end 275.298154 -85.15858)
		(width 0.1651)
		(layer "B.Cu")
		(net "PCIE_IOM_B_TO_COMP_B_14_DN")
	)
	(segment
		(start 322.815712 -75.870308)
		(end 322.6435 -75.833732)
		(width 0.1651)
		(layer "B.Cu")
		(net "PCIE_IOM_B_TO_COMP_B_14_DN")
	)
	(segment
		(start 321.188588 -76.778612)
		(end 321.152012 -76.950824)
		(width 0.1651)
		(layer "B.Cu")
		(net "PCIE_IOM_B_TO_COMP_B_14_DN")
	)
	(segment
		(start 293.613078 -89.143586)
		(end 293.465504 -89.047828)
		(width 0.1651)
		(layer "B.Cu")
		(net "PCIE_IOM_B_TO_COMP_B_14_DN")
	)
	(segment
		(start 335.730088 -67.3354)
		(end 335.693258 -67.507358)
		(width 0.1651)
		(layer "B.Cu")
		(net "PCIE_IOM_B_TO_COMP_B_14_DN")
	)
	(segment
		(start 272.934176 -58.186066)
		(end 273.041364 -57.70245)
		(width 0.1651)
		(layer "B.Cu")
		(net "PCIE_IOM_B_TO_COMP_B_14_DN")
	)
	(segment
		(start 336.769456 -66.660268)
		(end 336.73288 -66.83248)
		(width 0.1651)
		(layer "B.Cu")
		(net "PCIE_IOM_B_TO_COMP_B_14_DN")
	)
	(segment
		(start 308.719982 -85.02396)
		(end 308.548024 -84.987384)
		(width 0.1651)
		(layer "B.Cu")
		(net "PCIE_IOM_B_TO_COMP_B_14_DN")
	)
	(segment
		(start 293.465504 -89.047828)
		(end 292.981126 -89.150698)
		(width 0.1651)
		(layer "B.Cu")
		(net "PCIE_IOM_B_TO_COMP_B_14_DN")
	)
	(segment
		(start 275.042376 -84.580476)
		(end 275.136864 -84.43214)
		(width 0.1651)
		(layer "B.Cu")
		(net "PCIE_IOM_B_TO_COMP_B_14_DN")
	)
	(segment
		(start 282.048458 -91.602052)
		(end 280.248868 -91.203018)
		(width 0.1651)
		(layer "B.Cu")
		(net "PCIE_IOM_B_TO_COMP_B_14_DN")
	)
	(segment
		(start 322.191634 -76.275692)
		(end 321.776344 -76.54544)
		(width 0.1651)
		(layer "B.Cu")
		(net "PCIE_IOM_B_TO_COMP_B_14_DN")
	)
	(segment
		(start 279.366472 -45.491654)
		(end 279.467564 -45.592746)
		(width 0.1651)
		(layer "B.Cu")
		(net "PCIE_IOM_B_TO_COMP_B_14_DN")
	)
	(segment
		(start 307.508402 -85.662516)
		(end 307.092858 -85.932264)
		(width 0.1651)
		(layer "B.Cu")
		(net "PCIE_IOM_B_TO_COMP_B_14_DN")
	)
	(segment
		(start 273.284696 -57.131966)
		(end 273.197828 -56.995568)
		(width 0.1651)
		(layer "B.Cu")
		(net "PCIE_IOM_B_TO_COMP_B_14_DN")
	)
	(segment
		(start 272.777458 -58.892694)
		(end 272.913856 -58.805826)
		(width 0.1651)
		(layer "B.Cu")
		(net "PCIE_IOM_B_TO_COMP_B_14_DN")
	)
	(segment
		(start 273.461734 -55.805324)
		(end 273.568922 -55.321708)
		(width 0.1651)
		(layer "B.Cu")
		(net "PCIE_IOM_B_TO_COMP_B_14_DN")
	)
	(segment
		(start 278.118824 -45.376084)
		(end 279.088342 -45.376084)
		(width 0.1651)
		(layer "B.Cu")
		(net "PCIE_IOM_B_TO_COMP_B_14_DN")
	)
	(segment
		(start 272.913856 -58.805826)
		(end 273.021044 -58.32221)
		(width 0.1651)
		(layer "B.Cu")
		(net "PCIE_IOM_B_TO_COMP_B_14_DN")
	)
	(segment
		(start 274.600162 -82.011774)
		(end 274.49272 -81.528158)
		(width 0.1651)
		(layer "B.Cu")
		(net "PCIE_IOM_B_TO_COMP_B_14_DN")
	)
	(segment
		(start 275.149564 -85.064092)
		(end 275.042376 -84.580476)
		(width 0.1651)
		(layer "B.Cu")
		(net "PCIE_IOM_B_TO_COMP_B_14_DN")
	)
	(segment
		(start 273.197828 -56.995568)
		(end 273.305016 -56.511952)
		(width 0.1651)
		(layer "B.Cu")
		(net "PCIE_IOM_B_TO_COMP_B_14_DN")
	)
	(segment
		(start 274.344384 -81.43367)
		(end 271.061434 -66.634614)
		(width 0.1651)
		(layer "B.Cu")
		(net "PCIE_IOM_B_TO_COMP_B_14_DN")
	)
	(segment
		(start 274.868386 -83.22183)
		(end 274.761198 -82.738468)
		(width 0.1651)
		(layer "B.Cu")
		(net "PCIE_IOM_B_TO_COMP_B_14_DN")
	)
	(segment
		(start 334.066388 -68.415662)
		(end 333.650844 -68.68541)
		(width 0.1651)
		(layer "B.Cu")
		(net "PCIE_IOM_B_TO_COMP_B_14_DN")
	)
	(segment
		(start 333.614268 -68.857622)
		(end 324.894956 -74.520044)
		(width 0.1651)
		(layer "B.Cu")
		(net "PCIE_IOM_B_TO_COMP_B_14_DN")
	)
	(segment
		(start 309.587392 -84.312252)
		(end 309.172102 -84.582)
		(width 0.1651)
		(layer "B.Cu")
		(net "PCIE_IOM_B_TO_COMP_B_14_DN")
	)
	(segment
		(start 379.303534 -31.583122)
		(end 376.28703 -36.324286)
		(width 0.1651)
		(layer "B.Cu")
		(net "PCIE_IOM_B_TO_COMP_B_14_DN")
	)
	(segment
		(start 336.31759 -67.102228)
		(end 336.145378 -67.065652)
		(width 0.1651)
		(layer "B.Cu")
		(net "PCIE_IOM_B_TO_COMP_B_14_DN")
	)
	(segment
		(start 337.185 -66.39052)
		(end 336.769456 -66.660268)
		(width 0.1651)
		(layer "B.Cu")
		(net "PCIE_IOM_B_TO_COMP_B_14_DN")
	)
	(segment
		(start 323.855334 -75.195176)
		(end 323.683122 -75.1586)
		(width 0.1651)
		(layer "B.Cu")
		(net "PCIE_IOM_B_TO_COMP_B_14_DN")
	)
	(arc
		(start 279.088342 -45.376084)
		(mid 279.186036 -45.388528)
		(end 279.277572 -45.424852)
		(width 0.1651)
		(layer "B.Cu")
		(net "PCIE_IOM_B_TO_COMP_B_14_DN")
	)
	(arc
		(start 279.514808 -45.738796)
		(mid 279.484105 -45.811727)
		(end 279.423622 -45.862748)
		(width 0.1651)
		(layer "B.Cu")
		(net "PCIE_IOM_B_TO_COMP_B_14_DN")
	)
	(arc
		(start 379.099064 -22.796246)
		(mid 379.243826 -22.856208)
		(end 379.303788 -23.00097)
		(width 0.1651)
		(layer "B.Cu")
		(net "PCIE_IOM_B_TO_COMP_B_14_DN")
	)
	(arc
		(start 378.549916 -22.962616)
		(mid 378.598645 -22.844975)
		(end 378.716286 -22.796246)
		(width 0.1651)
		(layer "B.Cu")
		(net "PCIE_IOM_B_TO_COMP_B_14_DN")
	)
	(arc
		(start 279.277572 -45.424852)
		(mid 279.324398 -45.455092)
		(end 279.366472 -45.491654)
		(width 0.1651)
		(layer "B.Cu")
		(net "PCIE_IOM_B_TO_COMP_B_14_DN")
	)
	(arc
		(start 279.467564 -45.592746)
		(mid 279.508792 -45.660086)
		(end 279.514808 -45.738796)
		(width 0.1651)
		(layer "B.Cu")
		(net "PCIE_IOM_B_TO_COMP_B_14_DN")
	)
	(segment
		(start 313.833002 -87.017098)
		(end 282.971748 -93.859604)
		(width 0.1651)
		(layer "B.Cu")
		(net "PCIE_IOM_B_TO_COMP_B_13_DP")
	)
	(segment
		(start 269.033498 -66.413126)
		(end 269.033244 -66.413126)
		(width 0.1651)
		(layer "B.Cu")
		(net "PCIE_IOM_B_TO_COMP_B_13_DP")
	)
	(segment
		(start 380.516384 -21.504148)
		(end 380.893066 -21.504148)
		(width 0.1651)
		(layer "B.Cu")
		(net "PCIE_IOM_B_TO_COMP_B_13_DP")
	)
	(segment
		(start 276.80158 -41.820084)
		(end 277.958296 -41.083992)
		(width 0.1651)
		(layer "B.Cu")
		(net "PCIE_IOM_B_TO_COMP_B_13_DP")
	)
	(segment
		(start 279.356566 -93.05798)
		(end 275.569934 -90.646758)
		(width 0.1651)
		(layer "B.Cu")
		(net "PCIE_IOM_B_TO_COMP_B_13_DP")
	)
	(segment
		(start 380.350014 -20.950174)
		(end 380.350014 -21.337778)
		(width 0.1651)
		(layer "B.Cu")
		(net "PCIE_IOM_B_TO_COMP_B_13_DP")
	)
	(segment
		(start 381.395986 -22.007068)
		(end 381.395986 -31.79318)
		(width 0.1651)
		(layer "B.Cu")
		(net "PCIE_IOM_B_TO_COMP_B_13_DP")
	)
	(segment
		(start 275.569934 -90.646758)
		(end 273.474434 -87.353394)
		(width 0.1651)
		(layer "B.Cu")
		(net "PCIE_IOM_B_TO_COMP_B_13_DP")
	)
	(segment
		(start 269.033244 -66.413126)
		(end 273.248628 -47.403766)
		(width 0.1651)
		(layer "B.Cu")
		(net "PCIE_IOM_B_TO_COMP_B_13_DP")
	)
	(segment
		(start 280.089356 -41.538652)
		(end 280.75001 -41.20007)
		(width 0.1651)
		(layer "B.Cu")
		(net "PCIE_IOM_B_TO_COMP_B_13_DP")
	)
	(segment
		(start 273.474434 -87.353394)
		(end 268.931644 -66.87185)
		(width 0.1651)
		(layer "B.Cu")
		(net "PCIE_IOM_B_TO_COMP_B_13_DP")
	)
	(segment
		(start 282.971748 -93.859604)
		(end 279.356566 -93.05798)
		(width 0.1651)
		(layer "B.Cu")
		(net "PCIE_IOM_B_TO_COMP_B_13_DP")
	)
	(segment
		(start 268.931644 -66.87185)
		(end 269.033498 -66.413126)
		(width 0.1651)
		(layer "B.Cu")
		(net "PCIE_IOM_B_TO_COMP_B_13_DP")
	)
	(segment
		(start 273.248628 -47.403766)
		(end 276.80158 -41.820084)
		(width 0.1651)
		(layer "B.Cu")
		(net "PCIE_IOM_B_TO_COMP_B_13_DP")
	)
	(segment
		(start 381.395986 -31.79318)
		(end 372.365016 -45.95749)
		(width 0.1651)
		(layer "B.Cu")
		(net "PCIE_IOM_B_TO_COMP_B_13_DP")
	)
	(segment
		(start 372.365016 -45.95749)
		(end 313.833002 -87.017098)
		(width 0.1651)
		(layer "B.Cu")
		(net "PCIE_IOM_B_TO_COMP_B_13_DP")
	)
	(segment
		(start 277.958296 -41.083992)
		(end 279.088088 -41.083992)
		(width 0.1651)
		(layer "B.Cu")
		(net "PCIE_IOM_B_TO_COMP_B_13_DP")
	)
	(segment
		(start 279.573228 -41.284906)
		(end 279.778206 -41.489884)
		(width 0.1651)
		(layer "B.Cu")
		(net "PCIE_IOM_B_TO_COMP_B_13_DP")
	)
	(segment
		(start 279.918414 -41.561004)
		(end 279.933908 -41.563544)
		(width 0.1651)
		(layer "B.Cu")
		(net "PCIE_IOM_B_TO_COMP_B_13_DP")
	)
	(arc
		(start 380.893066 -21.504148)
		(mid 381.248684 -21.65145)
		(end 381.395986 -22.007068)
		(width 0.1651)
		(layer "B.Cu")
		(net "PCIE_IOM_B_TO_COMP_B_13_DP")
	)
	(arc
		(start 380.350014 -21.337778)
		(mid 380.398743 -21.455419)
		(end 380.516384 -21.504148)
		(width 0.1651)
		(layer "B.Cu")
		(net "PCIE_IOM_B_TO_COMP_B_13_DP")
	)
	(arc
		(start 279.933908 -41.563544)
		(mid 280.013618 -41.563471)
		(end 280.089356 -41.538652)
		(width 0.1651)
		(layer "B.Cu")
		(net "PCIE_IOM_B_TO_COMP_B_13_DP")
	)
	(arc
		(start 279.088088 -41.083992)
		(mid 279.25853 -41.105436)
		(end 279.418288 -41.168574)
		(width 0.1651)
		(layer "B.Cu")
		(net "PCIE_IOM_B_TO_COMP_B_13_DP")
	)
	(arc
		(start 279.418288 -41.168574)
		(mid 279.499871 -41.221259)
		(end 279.573228 -41.284906)
		(width 0.1651)
		(layer "B.Cu")
		(net "PCIE_IOM_B_TO_COMP_B_13_DP")
	)
	(arc
		(start 279.778206 -41.489884)
		(mid 279.842672 -41.536556)
		(end 279.918414 -41.561004)
		(width 0.1651)
		(layer "B.Cu")
		(net "PCIE_IOM_B_TO_COMP_B_13_DP")
	)
	(segment
		(start 269.692882 -65.31737)
		(end 269.80007 -64.833754)
		(width 0.1651)
		(layer "B.Cu")
		(net "PCIE_IOM_B_TO_COMP_B_13_DN")
	)
	(segment
		(start 295.07307 -90.877136)
		(end 294.589454 -90.984324)
		(width 0.1651)
		(layer "B.Cu")
		(net "PCIE_IOM_B_TO_COMP_B_13_DN")
	)
	(segment
		(start 303.206658 -88.956642)
		(end 303.11979 -89.09304)
		(width 0.1651)
		(layer "B.Cu")
		(net "PCIE_IOM_B_TO_COMP_B_13_DN")
	)
	(segment
		(start 314.118244 -86.459822)
		(end 313.71286 -86.744302)
		(width 0.1651)
		(layer "B.Cu")
		(net "PCIE_IOM_B_TO_COMP_B_13_DN")
	)
	(segment
		(start 270.084296 -63.023496)
		(end 270.220694 -62.936628)
		(width 0.1651)
		(layer "B.Cu")
		(net "PCIE_IOM_B_TO_COMP_B_13_DN")
	)
	(segment
		(start 273.705066 -86.46922)
		(end 273.597878 -85.985604)
		(width 0.1651)
		(layer "B.Cu")
		(net "PCIE_IOM_B_TO_COMP_B_13_DN")
	)
	(segment
		(start 314.146184 -86.300564)
		(end 314.118244 -86.459822)
		(width 0.1651)
		(layer "B.Cu")
		(net "PCIE_IOM_B_TO_COMP_B_13_DN")
	)
	(segment
		(start 273.181064 -84.68106)
		(end 273.073622 -84.197444)
		(width 0.1651)
		(layer "B.Cu")
		(net "PCIE_IOM_B_TO_COMP_B_13_DN")
	)
	(segment
		(start 278.043386 -41.376092)
		(end 279.088342 -41.376092)
		(width 0.1651)
		(layer "B.Cu")
		(net "PCIE_IOM_B_TO_COMP_B_13_DN")
	)
	(segment
		(start 279.366472 -41.491662)
		(end 279.467564 -41.592754)
		(width 0.1651)
		(layer "B.Cu")
		(net "PCIE_IOM_B_TO_COMP_B_13_DN")
	)
	(segment
		(start 295.159938 -90.740738)
		(end 295.07307 -90.877136)
		(width 0.1651)
		(layer "B.Cu")
		(net "PCIE_IOM_B_TO_COMP_B_13_DN")
	)
	(segment
		(start 277.013416 -42.03192)
		(end 278.043386 -41.376092)
		(width 0.1651)
		(layer "B.Cu")
		(net "PCIE_IOM_B_TO_COMP_B_13_DN")
	)
	(segment
		(start 272.805398 -82.987388)
		(end 272.899886 -82.838798)
		(width 0.1651)
		(layer "B.Cu")
		(net "PCIE_IOM_B_TO_COMP_B_13_DN")
	)
	(segment
		(start 283.455364 -93.453204)
		(end 282.971748 -93.560392)
		(width 0.1651)
		(layer "B.Cu")
		(net "PCIE_IOM_B_TO_COMP_B_13_DN")
	)
	(segment
		(start 295.643554 -90.63355)
		(end 295.159938 -90.740738)
		(width 0.1651)
		(layer "B.Cu")
		(net "PCIE_IOM_B_TO_COMP_B_13_DN")
	)
	(segment
		(start 305.016916 -88.672162)
		(end 304.880518 -88.585548)
		(width 0.1651)
		(layer "B.Cu")
		(net "PCIE_IOM_B_TO_COMP_B_13_DN")
	)
	(segment
		(start 279.423622 -41.862756)
		(end 278.750014 -42.200068)
		(width 0.1651)
		(layer "B.Cu")
		(net "PCIE_IOM_B_TO_COMP_B_13_DN")
	)
	(segment
		(start 279.470104 -92.783914)
		(end 275.78177 -90.434922)
		(width 0.1651)
		(layer "B.Cu")
		(net "PCIE_IOM_B_TO_COMP_B_13_DN")
	)
	(segment
		(start 287.812226 -92.486988)
		(end 287.66389 -92.3925)
		(width 0.1651)
		(layer "B.Cu")
		(net "PCIE_IOM_B_TO_COMP_B_13_DN")
	)
	(segment
		(start 315.144404 -85.60054)
		(end 315.116464 -85.759798)
		(width 0.1651)
		(layer "B.Cu")
		(net "PCIE_IOM_B_TO_COMP_B_13_DN")
	)
	(segment
		(start 272.792698 -82.355436)
		(end 272.644108 -82.260694)
		(width 0.1651)
		(layer "B.Cu")
		(net "PCIE_IOM_B_TO_COMP_B_13_DN")
	)
	(segment
		(start 269.292578 -66.594482)
		(end 269.428722 -66.507614)
		(width 0.1651)
		(layer "B.Cu")
		(net "PCIE_IOM_B_TO_COMP_B_13_DN")
	)
	(segment
		(start 269.82039 -64.21374)
		(end 269.956788 -64.127126)
		(width 0.1651)
		(layer "B.Cu")
		(net "PCIE_IOM_B_TO_COMP_B_13_DN")
	)
	(segment
		(start 295.779698 -90.720418)
		(end 295.643554 -90.63355)
		(width 0.1651)
		(layer "B.Cu")
		(net "PCIE_IOM_B_TO_COMP_B_13_DN")
	)
	(segment
		(start 273.168364 -84.049108)
		(end 273.061176 -83.565492)
		(width 0.1651)
		(layer "B.Cu")
		(net "PCIE_IOM_B_TO_COMP_B_13_DN")
	)
	(segment
		(start 304.397156 -88.692736)
		(end 304.310288 -88.82888)
		(width 0.1651)
		(layer "B.Cu")
		(net "PCIE_IOM_B_TO_COMP_B_13_DN")
	)
	(segment
		(start 287.66389 -92.3925)
		(end 287.180274 -92.499688)
		(width 0.1651)
		(layer "B.Cu")
		(net "PCIE_IOM_B_TO_COMP_B_13_DN")
	)
	(segment
		(start 316.707266 -84.643722)
		(end 316.548008 -84.615782)
		(width 0.1651)
		(layer "B.Cu")
		(net "PCIE_IOM_B_TO_COMP_B_13_DN")
	)
	(segment
		(start 273.3294 -84.775548)
		(end 273.181064 -84.68106)
		(width 0.1651)
		(layer "B.Cu")
		(net "PCIE_IOM_B_TO_COMP_B_13_DN")
	)
	(segment
		(start 306.20716 -88.408256)
		(end 306.070762 -88.321388)
		(width 0.1651)
		(layer "B.Cu")
		(net "PCIE_IOM_B_TO_COMP_B_13_DN")
	)
	(segment
		(start 269.536164 -66.023998)
		(end 269.449296 -65.8876)
		(width 0.1651)
		(layer "B.Cu")
		(net "PCIE_IOM_B_TO_COMP_B_13_DN")
	)
	(segment
		(start 380.516384 -21.796248)
		(end 380.893066 -21.796248)
		(width 0.1651)
		(layer "B.Cu")
		(net "PCIE_IOM_B_TO_COMP_B_13_DN")
	)
	(segment
		(start 269.713202 -64.697356)
		(end 269.82039 -64.21374)
		(width 0.1651)
		(layer "B.Cu")
		(net "PCIE_IOM_B_TO_COMP_B_13_DN")
	)
	(segment
		(start 313.71286 -86.744302)
		(end 306.20716 -88.408256)
		(width 0.1651)
		(layer "B.Cu")
		(net "PCIE_IOM_B_TO_COMP_B_13_DN")
	)
	(segment
		(start 316.14237 -84.900262)
		(end 316.11443 -85.05952)
		(width 0.1651)
		(layer "B.Cu")
		(net "PCIE_IOM_B_TO_COMP_B_13_DN")
	)
	(segment
		(start 292.779196 -91.26855)
		(end 292.692582 -91.404948)
		(width 0.1651)
		(layer "B.Cu")
		(net "PCIE_IOM_B_TO_COMP_B_13_DN")
	)
	(segment
		(start 286.60217 -92.755466)
		(end 286.45358 -92.660978)
		(width 0.1651)
		(layer "B.Cu")
		(net "PCIE_IOM_B_TO_COMP_B_13_DN")
	)
	(segment
		(start 270.220694 -62.936628)
		(end 270.327882 -62.453266)
		(width 0.1651)
		(layer "B.Cu")
		(net "PCIE_IOM_B_TO_COMP_B_13_DN")
	)
	(segment
		(start 273.522694 -47.517304)
		(end 277.013416 -42.03192)
		(width 0.1651)
		(layer "B.Cu")
		(net "PCIE_IOM_B_TO_COMP_B_13_DN")
	)
	(segment
		(start 273.7485 -87.239856)
		(end 273.610578 -86.61781)
		(width 0.1651)
		(layer "B.Cu")
		(net "PCIE_IOM_B_TO_COMP_B_13_DN")
	)
	(segment
		(start 372.149878 -45.751496)
		(end 316.707266 -84.643722)
		(width 0.1651)
		(layer "B.Cu")
		(net "PCIE_IOM_B_TO_COMP_B_13_DN")
	)
	(segment
		(start 304.310288 -88.82888)
		(end 303.826672 -88.936322)
		(width 0.1651)
		(layer "B.Cu")
		(net "PCIE_IOM_B_TO_COMP_B_13_DN")
	)
	(segment
		(start 272.899886 -82.838798)
		(end 272.792698 -82.355436)
		(width 0.1651)
		(layer "B.Cu")
		(net "PCIE_IOM_B_TO_COMP_B_13_DN")
	)
	(segment
		(start 292.692582 -91.404948)
		(end 287.812226 -92.486988)
		(width 0.1651)
		(layer "B.Cu")
		(net "PCIE_IOM_B_TO_COMP_B_13_DN")
	)
	(segment
		(start 283.549852 -93.304614)
		(end 283.455364 -93.453204)
		(width 0.1651)
		(layer "B.Cu")
		(net "PCIE_IOM_B_TO_COMP_B_13_DN")
	)
	(segment
		(start 315.116464 -85.759798)
		(end 314.71108 -86.044024)
		(width 0.1651)
		(layer "B.Cu")
		(net "PCIE_IOM_B_TO_COMP_B_13_DN")
	)
	(segment
		(start 293.969694 -91.004644)
		(end 293.882826 -91.141042)
		(width 0.1651)
		(layer "B.Cu")
		(net "PCIE_IOM_B_TO_COMP_B_13_DN")
	)
	(segment
		(start 275.78177 -90.434922)
		(end 273.7485 -87.239856)
		(width 0.1651)
		(layer "B.Cu")
		(net "PCIE_IOM_B_TO_COMP_B_13_DN")
	)
	(segment
		(start 269.449296 -65.8876)
		(end 269.556484 -65.404238)
		(width 0.1651)
		(layer "B.Cu")
		(net "PCIE_IOM_B_TO_COMP_B_13_DN")
	)
	(segment
		(start 269.428722 -66.507614)
		(end 269.536164 -66.023998)
		(width 0.1651)
		(layer "B.Cu")
		(net "PCIE_IOM_B_TO_COMP_B_13_DN")
	)
	(segment
		(start 296.833798 -90.369644)
		(end 296.350182 -90.476832)
		(width 0.1651)
		(layer "B.Cu")
		(net "PCIE_IOM_B_TO_COMP_B_13_DN")
	)
	(segment
		(start 380.350014 -22.350222)
		(end 380.350014 -21.962618)
		(width 0.1651)
		(layer "B.Cu")
		(net "PCIE_IOM_B_TO_COMP_B_13_DN")
	)
	(segment
		(start 294.453056 -90.897456)
		(end 293.969694 -91.004644)
		(width 0.1651)
		(layer "B.Cu")
		(net "PCIE_IOM_B_TO_COMP_B_13_DN")
	)
	(segment
		(start 303.690274 -88.849454)
		(end 303.206658 -88.956642)
		(width 0.1651)
		(layer "B.Cu")
		(net "PCIE_IOM_B_TO_COMP_B_13_DN")
	)
	(segment
		(start 304.880518 -88.585548)
		(end 304.397156 -88.692736)
		(width 0.1651)
		(layer "B.Cu")
		(net "PCIE_IOM_B_TO_COMP_B_13_DN")
	)
	(segment
		(start 316.11443 -85.05952)
		(end 315.709046 -85.344)
		(width 0.1651)
		(layer "B.Cu")
		(net "PCIE_IOM_B_TO_COMP_B_13_DN")
	)
	(segment
		(start 315.709046 -85.344)
		(end 315.549788 -85.31606)
		(width 0.1651)
		(layer "B.Cu")
		(net "PCIE_IOM_B_TO_COMP_B_13_DN")
	)
	(segment
		(start 285.875476 -92.916502)
		(end 285.392114 -93.02369)
		(width 0.1651)
		(layer "B.Cu")
		(net "PCIE_IOM_B_TO_COMP_B_13_DN")
	)
	(segment
		(start 303.11979 -89.09304)
		(end 302.636428 -89.200228)
		(width 0.1651)
		(layer "B.Cu")
		(net "PCIE_IOM_B_TO_COMP_B_13_DN")
	)
	(segment
		(start 270.241014 -62.316868)
		(end 273.522694 -47.517304)
		(width 0.1651)
		(layer "B.Cu")
		(net "PCIE_IOM_B_TO_COMP_B_13_DN")
	)
	(segment
		(start 269.956788 -64.127126)
		(end 270.063976 -63.64351)
		(width 0.1651)
		(layer "B.Cu")
		(net "PCIE_IOM_B_TO_COMP_B_13_DN")
	)
	(segment
		(start 273.073622 -84.197444)
		(end 273.168364 -84.049108)
		(width 0.1651)
		(layer "B.Cu")
		(net "PCIE_IOM_B_TO_COMP_B_13_DN")
	)
	(segment
		(start 286.45358 -92.660978)
		(end 285.970218 -92.768166)
		(width 0.1651)
		(layer "B.Cu")
		(net "PCIE_IOM_B_TO_COMP_B_13_DN")
	)
	(segment
		(start 296.263314 -90.61323)
		(end 295.779698 -90.720418)
		(width 0.1651)
		(layer "B.Cu")
		(net "PCIE_IOM_B_TO_COMP_B_13_DN")
	)
	(segment
		(start 302.016414 -89.220548)
		(end 301.929546 -89.356946)
		(width 0.1651)
		(layer "B.Cu")
		(net "PCIE_IOM_B_TO_COMP_B_13_DN")
	)
	(segment
		(start 293.882826 -91.141042)
		(end 293.39921 -91.24823)
		(width 0.1651)
		(layer "B.Cu")
		(net "PCIE_IOM_B_TO_COMP_B_13_DN")
	)
	(segment
		(start 293.262812 -91.161362)
		(end 292.779196 -91.26855)
		(width 0.1651)
		(layer "B.Cu")
		(net "PCIE_IOM_B_TO_COMP_B_13_DN")
	)
	(segment
		(start 269.80007 -64.833754)
		(end 269.713202 -64.697356)
		(width 0.1651)
		(layer "B.Cu")
		(net "PCIE_IOM_B_TO_COMP_B_13_DN")
	)
	(segment
		(start 284.181804 -93.292168)
		(end 284.033468 -93.197426)
		(width 0.1651)
		(layer "B.Cu")
		(net "PCIE_IOM_B_TO_COMP_B_13_DN")
	)
	(segment
		(start 282.971748 -93.560392)
		(end 279.470104 -92.783914)
		(width 0.1651)
		(layer "B.Cu")
		(net "PCIE_IOM_B_TO_COMP_B_13_DN")
	)
	(segment
		(start 285.392114 -93.02369)
		(end 285.243524 -92.929202)
		(width 0.1651)
		(layer "B.Cu")
		(net "PCIE_IOM_B_TO_COMP_B_13_DN")
	)
	(segment
		(start 285.970218 -92.768166)
		(end 285.875476 -92.916502)
		(width 0.1651)
		(layer "B.Cu")
		(net "PCIE_IOM_B_TO_COMP_B_13_DN")
	)
	(segment
		(start 381.103886 -22.007068)
		(end 381.103886 -31.707836)
		(width 0.1651)
		(layer "B.Cu")
		(net "PCIE_IOM_B_TO_COMP_B_13_DN")
	)
	(segment
		(start 287.180274 -92.499688)
		(end 287.085786 -92.648278)
		(width 0.1651)
		(layer "B.Cu")
		(net "PCIE_IOM_B_TO_COMP_B_13_DN")
	)
	(segment
		(start 314.551822 -86.016084)
		(end 314.146184 -86.300564)
		(width 0.1651)
		(layer "B.Cu")
		(net "PCIE_IOM_B_TO_COMP_B_13_DN")
	)
	(segment
		(start 272.644108 -82.260694)
		(end 269.23111 -66.87185)
		(width 0.1651)
		(layer "B.Cu")
		(net "PCIE_IOM_B_TO_COMP_B_13_DN")
	)
	(segment
		(start 302.636428 -89.200228)
		(end 302.50003 -89.11336)
		(width 0.1651)
		(layer "B.Cu")
		(net "PCIE_IOM_B_TO_COMP_B_13_DN")
	)
	(segment
		(start 273.436588 -85.259164)
		(end 273.3294 -84.775548)
		(width 0.1651)
		(layer "B.Cu")
		(net "PCIE_IOM_B_TO_COMP_B_13_DN")
	)
	(segment
		(start 273.610578 -86.61781)
		(end 273.705066 -86.46922)
		(width 0.1651)
		(layer "B.Cu")
		(net "PCIE_IOM_B_TO_COMP_B_13_DN")
	)
	(segment
		(start 306.070762 -88.321388)
		(end 305.5874 -88.42883)
		(width 0.1651)
		(layer "B.Cu")
		(net "PCIE_IOM_B_TO_COMP_B_13_DN")
	)
	(segment
		(start 305.5874 -88.42883)
		(end 305.500532 -88.564974)
		(width 0.1651)
		(layer "B.Cu")
		(net "PCIE_IOM_B_TO_COMP_B_13_DN")
	)
	(segment
		(start 269.977108 -63.507112)
		(end 270.084296 -63.023496)
		(width 0.1651)
		(layer "B.Cu")
		(net "PCIE_IOM_B_TO_COMP_B_13_DN")
	)
	(segment
		(start 284.66542 -93.184726)
		(end 284.181804 -93.292168)
		(width 0.1651)
		(layer "B.Cu")
		(net "PCIE_IOM_B_TO_COMP_B_13_DN")
	)
	(segment
		(start 285.243524 -92.929202)
		(end 284.759908 -93.03639)
		(width 0.1651)
		(layer "B.Cu")
		(net "PCIE_IOM_B_TO_COMP_B_13_DN")
	)
	(segment
		(start 314.71108 -86.044024)
		(end 314.551822 -86.016084)
		(width 0.1651)
		(layer "B.Cu")
		(net "PCIE_IOM_B_TO_COMP_B_13_DN")
	)
	(segment
		(start 296.350182 -90.476832)
		(end 296.263314 -90.61323)
		(width 0.1651)
		(layer "B.Cu")
		(net "PCIE_IOM_B_TO_COMP_B_13_DN")
	)
	(segment
		(start 293.39921 -91.24823)
		(end 293.262812 -91.161362)
		(width 0.1651)
		(layer "B.Cu")
		(net "PCIE_IOM_B_TO_COMP_B_13_DN")
	)
	(segment
		(start 316.548008 -84.615782)
		(end 316.14237 -84.900262)
		(width 0.1651)
		(layer "B.Cu")
		(net "PCIE_IOM_B_TO_COMP_B_13_DN")
	)
	(segment
		(start 302.50003 -89.11336)
		(end 302.016414 -89.220548)
		(width 0.1651)
		(layer "B.Cu")
		(net "PCIE_IOM_B_TO_COMP_B_13_DN")
	)
	(segment
		(start 284.033468 -93.197426)
		(end 283.549852 -93.304614)
		(width 0.1651)
		(layer "B.Cu")
		(net "PCIE_IOM_B_TO_COMP_B_13_DN")
	)
	(segment
		(start 301.929546 -89.356946)
		(end 296.969942 -90.456512)
		(width 0.1651)
		(layer "B.Cu")
		(net "PCIE_IOM_B_TO_COMP_B_13_DN")
	)
	(segment
		(start 287.085786 -92.648278)
		(end 286.60217 -92.755466)
		(width 0.1651)
		(layer "B.Cu")
		(net "PCIE_IOM_B_TO_COMP_B_13_DN")
	)
	(segment
		(start 296.969942 -90.456512)
		(end 296.833798 -90.369644)
		(width 0.1651)
		(layer "B.Cu")
		(net "PCIE_IOM_B_TO_COMP_B_13_DN")
	)
	(segment
		(start 273.061176 -83.565492)
		(end 272.912586 -83.471004)
		(width 0.1651)
		(layer "B.Cu")
		(net "PCIE_IOM_B_TO_COMP_B_13_DN")
	)
	(segment
		(start 273.449288 -85.891116)
		(end 273.3421 -85.4075)
		(width 0.1651)
		(layer "B.Cu")
		(net "PCIE_IOM_B_TO_COMP_B_13_DN")
	)
	(segment
		(start 315.549788 -85.31606)
		(end 315.144404 -85.60054)
		(width 0.1651)
		(layer "B.Cu")
		(net "PCIE_IOM_B_TO_COMP_B_13_DN")
	)
	(segment
		(start 269.556484 -65.404238)
		(end 269.692882 -65.31737)
		(width 0.1651)
		(layer "B.Cu")
		(net "PCIE_IOM_B_TO_COMP_B_13_DN")
	)
	(segment
		(start 269.23111 -66.87185)
		(end 269.292578 -66.594482)
		(width 0.1651)
		(layer "B.Cu")
		(net "PCIE_IOM_B_TO_COMP_B_13_DN")
	)
	(segment
		(start 294.589454 -90.984324)
		(end 294.453056 -90.897456)
		(width 0.1651)
		(layer "B.Cu")
		(net "PCIE_IOM_B_TO_COMP_B_13_DN")
	)
	(segment
		(start 305.500532 -88.564974)
		(end 305.016916 -88.672162)
		(width 0.1651)
		(layer "B.Cu")
		(net "PCIE_IOM_B_TO_COMP_B_13_DN")
	)
	(segment
		(start 303.826672 -88.936322)
		(end 303.690274 -88.849454)
		(width 0.1651)
		(layer "B.Cu")
		(net "PCIE_IOM_B_TO_COMP_B_13_DN")
	)
	(segment
		(start 270.327882 -62.453266)
		(end 270.241014 -62.316868)
		(width 0.1651)
		(layer "B.Cu")
		(net "PCIE_IOM_B_TO_COMP_B_13_DN")
	)
	(segment
		(start 273.3421 -85.4075)
		(end 273.436588 -85.259164)
		(width 0.1651)
		(layer "B.Cu")
		(net "PCIE_IOM_B_TO_COMP_B_13_DN")
	)
	(segment
		(start 284.759908 -93.03639)
		(end 284.66542 -93.184726)
		(width 0.1651)
		(layer "B.Cu")
		(net "PCIE_IOM_B_TO_COMP_B_13_DN")
	)
	(segment
		(start 272.912586 -83.471004)
		(end 272.805398 -82.987388)
		(width 0.1651)
		(layer "B.Cu")
		(net "PCIE_IOM_B_TO_COMP_B_13_DN")
	)
	(segment
		(start 381.103886 -31.707836)
		(end 372.149878 -45.751496)
		(width 0.1651)
		(layer "B.Cu")
		(net "PCIE_IOM_B_TO_COMP_B_13_DN")
	)
	(segment
		(start 273.597878 -85.985604)
		(end 273.449288 -85.891116)
		(width 0.1651)
		(layer "B.Cu")
		(net "PCIE_IOM_B_TO_COMP_B_13_DN")
	)
	(segment
		(start 270.063976 -63.64351)
		(end 269.977108 -63.507112)
		(width 0.1651)
		(layer "B.Cu")
		(net "PCIE_IOM_B_TO_COMP_B_13_DN")
	)
	(arc
		(start 380.893066 -21.796248)
		(mid 381.042138 -21.857996)
		(end 381.103886 -22.007068)
		(width 0.1651)
		(layer "B.Cu")
		(net "PCIE_IOM_B_TO_COMP_B_13_DN")
	)
	(arc
		(start 279.467564 -41.592754)
		(mid 279.508792 -41.660094)
		(end 279.514808 -41.738804)
		(width 0.1651)
		(layer "B.Cu")
		(net "PCIE_IOM_B_TO_COMP_B_13_DN")
	)
	(arc
		(start 279.514808 -41.738804)
		(mid 279.484105 -41.811735)
		(end 279.423622 -41.862756)
		(width 0.1651)
		(layer "B.Cu")
		(net "PCIE_IOM_B_TO_COMP_B_13_DN")
	)
	(arc
		(start 279.088342 -41.376092)
		(mid 279.18604 -41.388528)
		(end 279.277572 -41.42486)
		(width 0.1651)
		(layer "B.Cu")
		(net "PCIE_IOM_B_TO_COMP_B_13_DN")
	)
	(arc
		(start 380.350014 -21.962618)
		(mid 380.398743 -21.844977)
		(end 380.516384 -21.796248)
		(width 0.1651)
		(layer "B.Cu")
		(net "PCIE_IOM_B_TO_COMP_B_13_DN")
	)
	(arc
		(start 279.277572 -41.42486)
		(mid 279.324385 -41.455114)
		(end 279.366472 -41.491662)
		(width 0.1651)
		(layer "B.Cu")
		(net "PCIE_IOM_B_TO_COMP_B_13_DN")
	)
	(segment
		(start 372.819422 -48.252888)
		(end 383.196084 -31.977838)
		(width 0.1651)
		(layer "B.Cu")
		(net "PCIE_IOM_B_TO_COMP_B_12_DP")
	)
	(segment
		(start 278.260556 -94.459552)
		(end 283.369766 -95.59163)
		(width 0.1651)
		(layer "B.Cu")
		(net "PCIE_IOM_B_TO_COMP_B_12_DP")
	)
	(segment
		(start 267.116814 -66.745612)
		(end 267.11656 -66.745866)
		(width 0.1651)
		(layer "B.Cu")
		(net "PCIE_IOM_B_TO_COMP_B_12_DP")
	)
	(segment
		(start 279.778206 -37.489892)
		(end 279.573228 -37.284914)
		(width 0.1651)
		(layer "B.Cu")
		(net "PCIE_IOM_B_TO_COMP_B_12_DP")
	)
	(segment
		(start 279.088088 -37.084)
		(end 277.85441 -37.084)
		(width 0.1651)
		(layer "B.Cu")
		(net "PCIE_IOM_B_TO_COMP_B_12_DP")
	)
	(segment
		(start 276.677628 -37.832538)
		(end 271.845532 -45.418502)
		(width 0.1651)
		(layer "B.Cu")
		(net "PCIE_IOM_B_TO_COMP_B_12_DP")
	)
	(segment
		(start 280.75001 -37.200078)
		(end 280.089356 -37.53866)
		(width 0.1651)
		(layer "B.Cu")
		(net "PCIE_IOM_B_TO_COMP_B_12_DP")
	)
	(segment
		(start 266.936728 -67.558666)
		(end 271.20215 -86.909402)
		(width 0.1651)
		(layer "B.Cu")
		(net "PCIE_IOM_B_TO_COMP_B_12_DP")
	)
	(segment
		(start 315.485526 -88.472264)
		(end 372.819422 -48.252888)
		(width 0.1651)
		(layer "B.Cu")
		(net "PCIE_IOM_B_TO_COMP_B_12_DP")
	)
	(segment
		(start 271.20215 -86.909402)
		(end 274.47621 -92.048584)
		(width 0.1651)
		(layer "B.Cu")
		(net "PCIE_IOM_B_TO_COMP_B_12_DP")
	)
	(segment
		(start 382.150112 -22.337776)
		(end 382.150112 -21.950172)
		(width 0.1651)
		(layer "B.Cu")
		(net "PCIE_IOM_B_TO_COMP_B_12_DP")
	)
	(segment
		(start 274.475956 -92.048584)
		(end 278.260556 -94.459552)
		(width 0.1651)
		(layer "B.Cu")
		(net "PCIE_IOM_B_TO_COMP_B_12_DP")
	)
	(segment
		(start 382.696974 -22.504146)
		(end 382.316482 -22.504146)
		(width 0.1651)
		(layer "B.Cu")
		(net "PCIE_IOM_B_TO_COMP_B_12_DP")
	)
	(segment
		(start 277.85441 -37.084)
		(end 276.677628 -37.832538)
		(width 0.1651)
		(layer "B.Cu")
		(net "PCIE_IOM_B_TO_COMP_B_12_DP")
	)
	(segment
		(start 279.933908 -37.563552)
		(end 279.918414 -37.561012)
		(width 0.1651)
		(layer "B.Cu")
		(net "PCIE_IOM_B_TO_COMP_B_12_DP")
	)
	(segment
		(start 283.369766 -95.59163)
		(end 315.485526 -88.472264)
		(width 0.1651)
		(layer "B.Cu")
		(net "PCIE_IOM_B_TO_COMP_B_12_DP")
	)
	(segment
		(start 274.47621 -92.048584)
		(end 274.475956 -92.048584)
		(width 0.1651)
		(layer "B.Cu")
		(net "PCIE_IOM_B_TO_COMP_B_12_DP")
	)
	(segment
		(start 267.11656 -66.745866)
		(end 266.936728 -67.558666)
		(width 0.1651)
		(layer "B.Cu")
		(net "PCIE_IOM_B_TO_COMP_B_12_DP")
	)
	(segment
		(start 271.845532 -45.418502)
		(end 267.116814 -66.745612)
		(width 0.1651)
		(layer "B.Cu")
		(net "PCIE_IOM_B_TO_COMP_B_12_DP")
	)
	(segment
		(start 383.196084 -31.977838)
		(end 383.196084 -23.003256)
		(width 0.1651)
		(layer "B.Cu")
		(net "PCIE_IOM_B_TO_COMP_B_12_DP")
	)
	(arc
		(start 279.918414 -37.561012)
		(mid 279.842662 -37.536582)
		(end 279.778206 -37.489892)
		(width 0.1651)
		(layer "B.Cu")
		(net "PCIE_IOM_B_TO_COMP_B_12_DP")
	)
	(arc
		(start 279.418288 -37.168582)
		(mid 279.258523 -37.10547)
		(end 279.088088 -37.084)
		(width 0.1651)
		(layer "B.Cu")
		(net "PCIE_IOM_B_TO_COMP_B_12_DP")
	)
	(arc
		(start 382.316482 -22.504146)
		(mid 382.198841 -22.455417)
		(end 382.150112 -22.337776)
		(width 0.1651)
		(layer "B.Cu")
		(net "PCIE_IOM_B_TO_COMP_B_12_DP")
	)
	(arc
		(start 280.089356 -37.53866)
		(mid 280.013609 -37.563423)
		(end 279.933908 -37.563552)
		(width 0.1651)
		(layer "B.Cu")
		(net "PCIE_IOM_B_TO_COMP_B_12_DP")
	)
	(arc
		(start 279.573228 -37.284914)
		(mid 279.499897 -37.221233)
		(end 279.418288 -37.168582)
		(width 0.1651)
		(layer "B.Cu")
		(net "PCIE_IOM_B_TO_COMP_B_12_DP")
	)
	(arc
		(start 383.196084 -23.003256)
		(mid 383.049898 -22.650332)
		(end 382.696974 -22.504146)
		(width 0.1651)
		(layer "B.Cu")
		(net "PCIE_IOM_B_TO_COMP_B_12_DP")
	)
	(segment
		(start 288.88055 -94.070678)
		(end 283.369766 -95.292418)
		(width 0.1651)
		(layer "B.Cu")
		(net "PCIE_IOM_B_TO_COMP_B_12_DN")
	)
	(segment
		(start 291.87902 -93.278452)
		(end 291.395404 -93.38564)
		(width 0.1651)
		(layer "B.Cu")
		(net "PCIE_IOM_B_TO_COMP_B_12_DN")
	)
	(segment
		(start 311.881266 -88.854788)
		(end 311.794398 -88.990932)
		(width 0.1651)
		(layer "B.Cu")
		(net "PCIE_IOM_B_TO_COMP_B_12_DN")
	)
	(segment
		(start 305.508152 -90.267536)
		(end 305.02479 -90.374724)
		(width 0.1651)
		(layer "B.Cu")
		(net "PCIE_IOM_B_TO_COMP_B_12_DN")
	)
	(segment
		(start 289.458654 -93.815154)
		(end 288.975292 -93.922342)
		(width 0.1651)
		(layer "B.Cu")
		(net "PCIE_IOM_B_TO_COMP_B_12_DN")
	)
	(segment
		(start 290.668964 -93.546676)
		(end 290.185348 -93.653864)
		(width 0.1651)
		(layer "B.Cu")
		(net "PCIE_IOM_B_TO_COMP_B_12_DN")
	)
	(segment
		(start 314.881768 -88.306656)
		(end 314.74537 -88.219788)
		(width 0.1651)
		(layer "B.Cu")
		(net "PCIE_IOM_B_TO_COMP_B_12_DN")
	)
	(segment
		(start 312.984896 -88.72728)
		(end 312.50128 -88.834468)
		(width 0.1651)
		(layer "B.Cu")
		(net "PCIE_IOM_B_TO_COMP_B_12_DN")
	)
	(segment
		(start 277.9395 -37.3761)
		(end 279.088342 -37.3761)
		(width 0.1651)
		(layer "B.Cu")
		(net "PCIE_IOM_B_TO_COMP_B_12_DN")
	)
	(segment
		(start 293.089076 -93.010228)
		(end 292.605714 -93.117416)
		(width 0.1651)
		(layer "B.Cu")
		(net "PCIE_IOM_B_TO_COMP_B_12_DN")
	)
	(segment
		(start 318.098424 -86.282276)
		(end 317.692786 -86.566756)
		(width 0.1651)
		(layer "B.Cu")
		(net "PCIE_IOM_B_TO_COMP_B_12_DN")
	)
	(segment
		(start 314.262008 -88.326976)
		(end 314.17514 -88.463374)
		(width 0.1651)
		(layer "B.Cu")
		(net "PCIE_IOM_B_TO_COMP_B_12_DN")
	)
	(segment
		(start 292.02761 -93.37294)
		(end 291.87902 -93.278452)
		(width 0.1651)
		(layer "B.Cu")
		(net "PCIE_IOM_B_TO_COMP_B_12_DN")
	)
	(segment
		(start 311.794398 -88.990932)
		(end 311.310782 -89.098374)
		(width 0.1651)
		(layer "B.Cu")
		(net "PCIE_IOM_B_TO_COMP_B_12_DN")
	)
	(segment
		(start 318.126364 -86.123018)
		(end 318.098424 -86.282276)
		(width 0.1651)
		(layer "B.Cu")
		(net "PCIE_IOM_B_TO_COMP_B_12_DN")
	)
	(segment
		(start 310.691022 -89.118694)
		(end 310.604154 -89.254838)
		(width 0.1651)
		(layer "B.Cu")
		(net "PCIE_IOM_B_TO_COMP_B_12_DN")
	)
	(segment
		(start 270.824452 -83.259168)
		(end 270.676116 -83.164426)
		(width 0.1651)
		(layer "B.Cu")
		(net "PCIE_IOM_B_TO_COMP_B_12_DN")
	)
	(segment
		(start 303.127664 -90.795094)
		(end 302.644048 -90.902536)
		(width 0.1651)
		(layer "B.Cu")
		(net "PCIE_IOM_B_TO_COMP_B_12_DN")
	)
	(segment
		(start 315.365384 -88.199468)
		(end 314.881768 -88.306656)
		(width 0.1651)
		(layer "B.Cu")
		(net "PCIE_IOM_B_TO_COMP_B_12_DN")
	)
	(segment
		(start 318.691006 -85.866732)
		(end 318.531748 -85.838792)
		(width 0.1651)
		(layer "B.Cu")
		(net "PCIE_IOM_B_TO_COMP_B_12_DN")
	)
	(segment
		(start 267.375894 -66.927222)
		(end 267.512038 -66.840354)
		(width 0.1651)
		(layer "B.Cu")
		(net "PCIE_IOM_B_TO_COMP_B_12_DN")
	)
	(segment
		(start 305.02479 -90.374724)
		(end 304.937922 -90.511122)
		(width 0.1651)
		(layer "B.Cu")
		(net "PCIE_IOM_B_TO_COMP_B_12_DN")
	)
	(segment
		(start 270.836136 -83.891374)
		(end 270.930878 -83.743038)
		(width 0.1651)
		(layer "B.Cu")
		(net "PCIE_IOM_B_TO_COMP_B_12_DN")
	)
	(segment
		(start 271.091152 -84.469732)
		(end 270.942816 -84.37499)
		(width 0.1651)
		(layer "B.Cu")
		(net "PCIE_IOM_B_TO_COMP_B_12_DN")
	)
	(segment
		(start 267.775944 -65.65011)
		(end 267.883386 -65.166494)
		(width 0.1651)
		(layer "B.Cu")
		(net "PCIE_IOM_B_TO_COMP_B_12_DN")
	)
	(segment
		(start 276.88921 -38.044374)
		(end 277.9395 -37.3761)
		(width 0.1651)
		(layer "B.Cu")
		(net "PCIE_IOM_B_TO_COMP_B_12_DN")
	)
	(segment
		(start 271.10309 -85.101684)
		(end 271.197832 -84.953348)
		(width 0.1651)
		(layer "B.Cu")
		(net "PCIE_IOM_B_TO_COMP_B_12_DN")
	)
	(segment
		(start 301.453804 -91.166188)
		(end 301.366936 -91.302586)
		(width 0.1651)
		(layer "B.Cu")
		(net "PCIE_IOM_B_TO_COMP_B_12_DN")
	)
	(segment
		(start 316.535562 -87.239094)
		(end 316.129924 -87.523574)
		(width 0.1651)
		(layer "B.Cu")
		(net "PCIE_IOM_B_TO_COMP_B_12_DN")
	)
	(segment
		(start 317.128144 -86.823296)
		(end 317.100204 -86.982554)
		(width 0.1651)
		(layer "B.Cu")
		(net "PCIE_IOM_B_TO_COMP_B_12_DN")
	)
	(segment
		(start 312.364882 -88.7476)
		(end 311.881266 -88.854788)
		(width 0.1651)
		(layer "B.Cu")
		(net "PCIE_IOM_B_TO_COMP_B_12_DN")
	)
	(segment
		(start 289.607244 -93.909642)
		(end 289.458654 -93.815154)
		(width 0.1651)
		(layer "B.Cu")
		(net "PCIE_IOM_B_TO_COMP_B_12_DN")
	)
	(segment
		(start 270.664178 -82.532474)
		(end 270.557498 -82.048858)
		(width 0.1651)
		(layer "B.Cu")
		(net "PCIE_IOM_B_TO_COMP_B_12_DN")
	)
	(segment
		(start 267.37564 -66.927476)
		(end 267.375894 -66.927222)
		(width 0.1651)
		(layer "B.Cu")
		(net "PCIE_IOM_B_TO_COMP_B_12_DN")
	)
	(segment
		(start 301.93742 -91.059)
		(end 301.453804 -91.166188)
		(width 0.1651)
		(layer "B.Cu")
		(net "PCIE_IOM_B_TO_COMP_B_12_DN")
	)
	(segment
		(start 272.119598 -45.53204)
		(end 276.88921 -38.044374)
		(width 0.1651)
		(layer "B.Cu")
		(net "PCIE_IOM_B_TO_COMP_B_12_DN")
	)
	(segment
		(start 268.410944 -62.786006)
		(end 268.32433 -62.649608)
		(width 0.1651)
		(layer "B.Cu")
		(net "PCIE_IOM_B_TO_COMP_B_12_DN")
	)
	(segment
		(start 268.147038 -63.97625)
		(end 268.060424 -63.839852)
		(width 0.1651)
		(layer "B.Cu")
		(net "PCIE_IOM_B_TO_COMP_B_12_DN")
	)
	(segment
		(start 314.17514 -88.463374)
		(end 313.691524 -88.570562)
		(width 0.1651)
		(layer "B.Cu")
		(net "PCIE_IOM_B_TO_COMP_B_12_DN")
	)
	(segment
		(start 317.692786 -86.566756)
		(end 317.533528 -86.538816)
		(width 0.1651)
		(layer "B.Cu")
		(net "PCIE_IOM_B_TO_COMP_B_12_DN")
	)
	(segment
		(start 301.366936 -91.302586)
		(end 293.237666 -93.104716)
		(width 0.1651)
		(layer "B.Cu")
		(net "PCIE_IOM_B_TO_COMP_B_12_DN")
	)
	(segment
		(start 288.975292 -93.922342)
		(end 288.88055 -94.070678)
		(width 0.1651)
		(layer "B.Cu")
		(net "PCIE_IOM_B_TO_COMP_B_12_DN")
	)
	(segment
		(start 313.555126 -88.483694)
		(end 313.07151 -88.590882)
		(width 0.1651)
		(layer "B.Cu")
		(net "PCIE_IOM_B_TO_COMP_B_12_DN")
	)
	(segment
		(start 303.264062 -90.881962)
		(end 303.127664 -90.795094)
		(width 0.1651)
		(layer "B.Cu")
		(net "PCIE_IOM_B_TO_COMP_B_12_DN")
	)
	(segment
		(start 316.129924 -87.523574)
		(end 316.102238 -87.682578)
		(width 0.1651)
		(layer "B.Cu")
		(net "PCIE_IOM_B_TO_COMP_B_12_DN")
	)
	(segment
		(start 290.8173 -93.641418)
		(end 290.668964 -93.546676)
		(width 0.1651)
		(layer "B.Cu")
		(net "PCIE_IOM_B_TO_COMP_B_12_DN")
	)
	(segment
		(start 292.605714 -93.117416)
		(end 292.510972 -93.265752)
		(width 0.1651)
		(layer "B.Cu")
		(net "PCIE_IOM_B_TO_COMP_B_12_DN")
	)
	(segment
		(start 271.464532 -86.163912)
		(end 271.358106 -85.680042)
		(width 0.1651)
		(layer "B.Cu")
		(net "PCIE_IOM_B_TO_COMP_B_12_DN")
	)
	(segment
		(start 267.903706 -64.54648)
		(end 268.03985 -64.459866)
		(width 0.1651)
		(layer "B.Cu")
		(net "PCIE_IOM_B_TO_COMP_B_12_DN")
	)
	(segment
		(start 303.747424 -90.774774)
		(end 303.264062 -90.881962)
		(width 0.1651)
		(layer "B.Cu")
		(net "PCIE_IOM_B_TO_COMP_B_12_DN")
	)
	(segment
		(start 302.073564 -91.145868)
		(end 301.93742 -91.059)
		(width 0.1651)
		(layer "B.Cu")
		(net "PCIE_IOM_B_TO_COMP_B_12_DN")
	)
	(segment
		(start 267.532612 -66.22034)
		(end 267.6398 -65.736978)
		(width 0.1651)
		(layer "B.Cu")
		(net "PCIE_IOM_B_TO_COMP_B_12_DN")
	)
	(segment
		(start 313.07151 -88.590882)
		(end 312.984896 -88.72728)
		(width 0.1651)
		(layer "B.Cu")
		(net "PCIE_IOM_B_TO_COMP_B_12_DN")
	)
	(segment
		(start 312.50128 -88.834468)
		(end 312.364882 -88.7476)
		(width 0.1651)
		(layer "B.Cu")
		(net "PCIE_IOM_B_TO_COMP_B_12_DN")
	)
	(segment
		(start 314.74537 -88.219788)
		(end 314.262008 -88.326976)
		(width 0.1651)
		(layer "B.Cu")
		(net "PCIE_IOM_B_TO_COMP_B_12_DN")
	)
	(segment
		(start 290.09086 -93.802454)
		(end 289.607244 -93.909642)
		(width 0.1651)
		(layer "B.Cu")
		(net "PCIE_IOM_B_TO_COMP_B_12_DN")
	)
	(segment
		(start 311.174638 -89.011506)
		(end 310.691022 -89.118694)
		(width 0.1651)
		(layer "B.Cu")
		(net "PCIE_IOM_B_TO_COMP_B_12_DN")
	)
	(segment
		(start 270.409162 -81.954116)
		(end 267.23594 -67.558666)
		(width 0.1651)
		(layer "B.Cu")
		(net "PCIE_IOM_B_TO_COMP_B_12_DN")
	)
	(segment
		(start 271.20977 -85.5853)
		(end 271.10309 -85.101684)
		(width 0.1651)
		(layer "B.Cu")
		(net "PCIE_IOM_B_TO_COMP_B_12_DN")
	)
	(segment
		(start 304.937922 -90.511122)
		(end 304.454306 -90.61831)
		(width 0.1651)
		(layer "B.Cu")
		(net "PCIE_IOM_B_TO_COMP_B_12_DN")
	)
	(segment
		(start 271.197832 -84.953348)
		(end 271.091152 -84.469732)
		(width 0.1651)
		(layer "B.Cu")
		(net "PCIE_IOM_B_TO_COMP_B_12_DN")
	)
	(segment
		(start 382.903984 -23.003256)
		(end 382.903984 -31.892494)
		(width 0.1651)
		(layer "B.Cu")
		(net "PCIE_IOM_B_TO_COMP_B_12_DN")
	)
	(segment
		(start 268.167612 -63.356236)
		(end 268.303756 -63.269368)
		(width 0.1651)
		(layer "B.Cu")
		(net "PCIE_IOM_B_TO_COMP_B_12_DN")
	)
	(segment
		(start 313.691524 -88.570562)
		(end 313.555126 -88.483694)
		(width 0.1651)
		(layer "B.Cu")
		(net "PCIE_IOM_B_TO_COMP_B_12_DN")
	)
	(segment
		(start 267.512038 -66.840354)
		(end 267.61948 -66.356738)
		(width 0.1651)
		(layer "B.Cu")
		(net "PCIE_IOM_B_TO_COMP_B_12_DN")
	)
	(segment
		(start 279.366472 -37.49167)
		(end 279.467564 -37.592762)
		(width 0.1651)
		(layer "B.Cu")
		(net "PCIE_IOM_B_TO_COMP_B_12_DN")
	)
	(segment
		(start 271.358106 -85.680042)
		(end 271.20977 -85.5853)
		(width 0.1651)
		(layer "B.Cu")
		(net "PCIE_IOM_B_TO_COMP_B_12_DN")
	)
	(segment
		(start 274.687792 -91.837002)
		(end 271.47647 -86.795864)
		(width 0.1651)
		(layer "B.Cu")
		(net "PCIE_IOM_B_TO_COMP_B_12_DN")
	)
	(segment
		(start 292.510972 -93.265752)
		(end 292.02761 -93.37294)
		(width 0.1651)
		(layer "B.Cu")
		(net "PCIE_IOM_B_TO_COMP_B_12_DN")
	)
	(segment
		(start 303.834292 -90.63863)
		(end 303.747424 -90.774774)
		(width 0.1651)
		(layer "B.Cu")
		(net "PCIE_IOM_B_TO_COMP_B_12_DN")
	)
	(segment
		(start 267.61948 -66.356738)
		(end 267.532612 -66.22034)
		(width 0.1651)
		(layer "B.Cu")
		(net "PCIE_IOM_B_TO_COMP_B_12_DN")
	)
	(segment
		(start 270.569436 -82.68081)
		(end 270.664178 -82.532474)
		(width 0.1651)
		(layer "B.Cu")
		(net "PCIE_IOM_B_TO_COMP_B_12_DN")
	)
	(segment
		(start 278.374094 -94.185486)
		(end 274.687792 -91.837002)
		(width 0.1651)
		(layer "B.Cu")
		(net "PCIE_IOM_B_TO_COMP_B_12_DN")
	)
	(segment
		(start 268.32433 -62.649608)
		(end 272.119598 -45.53204)
		(width 0.1651)
		(layer "B.Cu")
		(net "PCIE_IOM_B_TO_COMP_B_12_DN")
	)
	(segment
		(start 279.423622 -37.862764)
		(end 278.750014 -38.200076)
		(width 0.1651)
		(layer "B.Cu")
		(net "PCIE_IOM_B_TO_COMP_B_12_DN")
	)
	(segment
		(start 382.316482 -22.796246)
		(end 382.696974 -22.796246)
		(width 0.1651)
		(layer "B.Cu")
		(net "PCIE_IOM_B_TO_COMP_B_12_DN")
	)
	(segment
		(start 302.644048 -90.902536)
		(end 302.55718 -91.03868)
		(width 0.1651)
		(layer "B.Cu")
		(net "PCIE_IOM_B_TO_COMP_B_12_DN")
	)
	(segment
		(start 270.930878 -83.743038)
		(end 270.824452 -83.259168)
		(width 0.1651)
		(layer "B.Cu")
		(net "PCIE_IOM_B_TO_COMP_B_12_DN")
	)
	(segment
		(start 305.64455 -90.354404)
		(end 305.508152 -90.267536)
		(width 0.1651)
		(layer "B.Cu")
		(net "PCIE_IOM_B_TO_COMP_B_12_DN")
	)
	(segment
		(start 271.47647 -86.795864)
		(end 271.36979 -86.312248)
		(width 0.1651)
		(layer "B.Cu")
		(net "PCIE_IOM_B_TO_COMP_B_12_DN")
	)
	(segment
		(start 316.69482 -87.267034)
		(end 316.535562 -87.239094)
		(width 0.1651)
		(layer "B.Cu")
		(net "PCIE_IOM_B_TO_COMP_B_12_DN")
	)
	(segment
		(start 283.369766 -95.292418)
		(end 278.374094 -94.185486)
		(width 0.1651)
		(layer "B.Cu")
		(net "PCIE_IOM_B_TO_COMP_B_12_DN")
	)
	(segment
		(start 268.03985 -64.459866)
		(end 268.147038 -63.97625)
		(width 0.1651)
		(layer "B.Cu")
		(net "PCIE_IOM_B_TO_COMP_B_12_DN")
	)
	(segment
		(start 291.395404 -93.38564)
		(end 291.300916 -93.53423)
		(width 0.1651)
		(layer "B.Cu")
		(net "PCIE_IOM_B_TO_COMP_B_12_DN")
	)
	(segment
		(start 267.6398 -65.736978)
		(end 267.775944 -65.65011)
		(width 0.1651)
		(layer "B.Cu")
		(net "PCIE_IOM_B_TO_COMP_B_12_DN")
	)
	(segment
		(start 317.100204 -86.982554)
		(end 316.69482 -87.267034)
		(width 0.1651)
		(layer "B.Cu")
		(net "PCIE_IOM_B_TO_COMP_B_12_DN")
	)
	(segment
		(start 304.454306 -90.61831)
		(end 304.317908 -90.531442)
		(width 0.1651)
		(layer "B.Cu")
		(net "PCIE_IOM_B_TO_COMP_B_12_DN")
	)
	(segment
		(start 268.060424 -63.839852)
		(end 268.167612 -63.356236)
		(width 0.1651)
		(layer "B.Cu")
		(net "PCIE_IOM_B_TO_COMP_B_12_DN")
	)
	(segment
		(start 382.150112 -23.35022)
		(end 382.150112 -22.962616)
		(width 0.1651)
		(layer "B.Cu")
		(net "PCIE_IOM_B_TO_COMP_B_12_DN")
	)
	(segment
		(start 290.185348 -93.653864)
		(end 290.09086 -93.802454)
		(width 0.1651)
		(layer "B.Cu")
		(net "PCIE_IOM_B_TO_COMP_B_12_DN")
	)
	(segment
		(start 267.883386 -65.166494)
		(end 267.796518 -65.030096)
		(width 0.1651)
		(layer "B.Cu")
		(net "PCIE_IOM_B_TO_COMP_B_12_DN")
	)
	(segment
		(start 316.102238 -87.682578)
		(end 315.365384 -88.199468)
		(width 0.1651)
		(layer "B.Cu")
		(net "PCIE_IOM_B_TO_COMP_B_12_DN")
	)
	(segment
		(start 317.533528 -86.538816)
		(end 317.128144 -86.823296)
		(width 0.1651)
		(layer "B.Cu")
		(net "PCIE_IOM_B_TO_COMP_B_12_DN")
	)
	(segment
		(start 270.676116 -83.164426)
		(end 270.569436 -82.68081)
		(width 0.1651)
		(layer "B.Cu")
		(net "PCIE_IOM_B_TO_COMP_B_12_DN")
	)
	(segment
		(start 304.317908 -90.531442)
		(end 303.834292 -90.63863)
		(width 0.1651)
		(layer "B.Cu")
		(net "PCIE_IOM_B_TO_COMP_B_12_DN")
	)
	(segment
		(start 268.303756 -63.269368)
		(end 268.410944 -62.786006)
		(width 0.1651)
		(layer "B.Cu")
		(net "PCIE_IOM_B_TO_COMP_B_12_DN")
	)
	(segment
		(start 372.604284 -48.046894)
		(end 318.691006 -85.866732)
		(width 0.1651)
		(layer "B.Cu")
		(net "PCIE_IOM_B_TO_COMP_B_12_DN")
	)
	(segment
		(start 318.531748 -85.838792)
		(end 318.126364 -86.123018)
		(width 0.1651)
		(layer "B.Cu")
		(net "PCIE_IOM_B_TO_COMP_B_12_DN")
	)
	(segment
		(start 270.557498 -82.048858)
		(end 270.409162 -81.954116)
		(width 0.1651)
		(layer "B.Cu")
		(net "PCIE_IOM_B_TO_COMP_B_12_DN")
	)
	(segment
		(start 291.300916 -93.53423)
		(end 290.8173 -93.641418)
		(width 0.1651)
		(layer "B.Cu")
		(net "PCIE_IOM_B_TO_COMP_B_12_DN")
	)
	(segment
		(start 310.604154 -89.254838)
		(end 305.64455 -90.354404)
		(width 0.1651)
		(layer "B.Cu")
		(net "PCIE_IOM_B_TO_COMP_B_12_DN")
	)
	(segment
		(start 293.237666 -93.104716)
		(end 293.089076 -93.010228)
		(width 0.1651)
		(layer "B.Cu")
		(net "PCIE_IOM_B_TO_COMP_B_12_DN")
	)
	(segment
		(start 382.903984 -31.892494)
		(end 372.604284 -48.046894)
		(width 0.1651)
		(layer "B.Cu")
		(net "PCIE_IOM_B_TO_COMP_B_12_DN")
	)
	(segment
		(start 302.55718 -91.03868)
		(end 302.073564 -91.145868)
		(width 0.1651)
		(layer "B.Cu")
		(net "PCIE_IOM_B_TO_COMP_B_12_DN")
	)
	(segment
		(start 271.36979 -86.312248)
		(end 271.464532 -86.163912)
		(width 0.1651)
		(layer "B.Cu")
		(net "PCIE_IOM_B_TO_COMP_B_12_DN")
	)
	(segment
		(start 267.796518 -65.030096)
		(end 267.903706 -64.54648)
		(width 0.1651)
		(layer "B.Cu")
		(net "PCIE_IOM_B_TO_COMP_B_12_DN")
	)
	(segment
		(start 267.23594 -67.558666)
		(end 267.37564 -66.927476)
		(width 0.1651)
		(layer "B.Cu")
		(net "PCIE_IOM_B_TO_COMP_B_12_DN")
	)
	(segment
		(start 270.942816 -84.37499)
		(end 270.836136 -83.891374)
		(width 0.1651)
		(layer "B.Cu")
		(net "PCIE_IOM_B_TO_COMP_B_12_DN")
	)
	(segment
		(start 311.310782 -89.098374)
		(end 311.174638 -89.011506)
		(width 0.1651)
		(layer "B.Cu")
		(net "PCIE_IOM_B_TO_COMP_B_12_DN")
	)
	(arc
		(start 382.150112 -22.962616)
		(mid 382.198841 -22.844975)
		(end 382.316482 -22.796246)
		(width 0.1651)
		(layer "B.Cu")
		(net "PCIE_IOM_B_TO_COMP_B_12_DN")
	)
	(arc
		(start 279.467564 -37.592762)
		(mid 279.508792 -37.660102)
		(end 279.514808 -37.738812)
		(width 0.1651)
		(layer "B.Cu")
		(net "PCIE_IOM_B_TO_COMP_B_12_DN")
	)
	(arc
		(start 279.088342 -37.3761)
		(mid 279.18604 -37.388536)
		(end 279.277572 -37.424868)
		(width 0.1651)
		(layer "B.Cu")
		(net "PCIE_IOM_B_TO_COMP_B_12_DN")
	)
	(arc
		(start 279.277572 -37.424868)
		(mid 279.324385 -37.455122)
		(end 279.366472 -37.49167)
		(width 0.1651)
		(layer "B.Cu")
		(net "PCIE_IOM_B_TO_COMP_B_12_DN")
	)
	(arc
		(start 279.514808 -37.738812)
		(mid 279.484105 -37.811743)
		(end 279.423622 -37.862764)
		(width 0.1651)
		(layer "B.Cu")
		(net "PCIE_IOM_B_TO_COMP_B_12_DN")
	)
	(arc
		(start 382.696974 -22.796246)
		(mid 382.843352 -22.856878)
		(end 382.903984 -23.003256)
		(width 0.1651)
		(layer "B.Cu")
		(net "PCIE_IOM_B_TO_COMP_B_12_DN")
	)
	(segment
		(start 279.918414 -177.860706)
		(end 279.933908 -177.863246)
		(width 0.1651)
		(layer "B.Cu")
		(net "PCIE_IOM_B_TO_COMP_B_11_DP")
	)
	(segment
		(start 370.212874 -62.487556)
		(end 286.001206 -184.987946)
		(width 0.1651)
		(layer "B.Cu")
		(net "PCIE_IOM_B_TO_COMP_B_11_DP")
	)
	(segment
		(start 384.995928 -21.995384)
		(end 384.995928 -34.204656)
		(width 0.1651)
		(layer "B.Cu")
		(net "PCIE_IOM_B_TO_COMP_B_11_DP")
	)
	(segment
		(start 281.567128 -187.398152)
		(end 279.523698 -186.745372)
		(width 0.1651)
		(layer "B.Cu")
		(net "PCIE_IOM_B_TO_COMP_B_11_DP")
	)
	(segment
		(start 384.116326 -21.504148)
		(end 384.504692 -21.504148)
		(width 0.1651)
		(layer "B.Cu")
		(net "PCIE_IOM_B_TO_COMP_B_11_DP")
	)
	(segment
		(start 279.573228 -177.584608)
		(end 279.778206 -177.789586)
		(width 0.1651)
		(layer "B.Cu")
		(net "PCIE_IOM_B_TO_COMP_B_11_DP")
	)
	(segment
		(start 278.386286 -177.381154)
		(end 279.088088 -177.383694)
		(width 0.1651)
		(layer "B.Cu")
		(net "PCIE_IOM_B_TO_COMP_B_11_DP")
	)
	(segment
		(start 277.57247 -177.835052)
		(end 278.386286 -177.381154)
		(width 0.1651)
		(layer "B.Cu")
		(net "PCIE_IOM_B_TO_COMP_B_11_DP")
	)
	(segment
		(start 383.949956 -20.950174)
		(end 383.949956 -21.337778)
		(width 0.1651)
		(layer "B.Cu")
		(net "PCIE_IOM_B_TO_COMP_B_11_DP")
	)
	(segment
		(start 384.995928 -34.204656)
		(end 377.962922 -44.36364)
		(width 0.1651)
		(layer "B.Cu")
		(net "PCIE_IOM_B_TO_COMP_B_11_DP")
	)
	(segment
		(start 280.089356 -177.838354)
		(end 280.75001 -177.499772)
		(width 0.1651)
		(layer "B.Cu")
		(net "PCIE_IOM_B_TO_COMP_B_11_DP")
	)
	(segment
		(start 276.727158 -184.495948)
		(end 276.726904 -184.495948)
		(width 0.1651)
		(layer "B.Cu")
		(net "PCIE_IOM_B_TO_COMP_B_11_DP")
	)
	(segment
		(start 283.948124 -186.638692)
		(end 281.567128 -187.398152)
		(width 0.1651)
		(layer "B.Cu")
		(net "PCIE_IOM_B_TO_COMP_B_11_DP")
	)
	(segment
		(start 276.726904 -184.495948)
		(end 275.973286 -181.638956)
		(width 0.1651)
		(layer "B.Cu")
		(net "PCIE_IOM_B_TO_COMP_B_11_DP")
	)
	(segment
		(start 377.962922 -44.36364)
		(end 370.212874 -62.487556)
		(width 0.1651)
		(layer "B.Cu")
		(net "PCIE_IOM_B_TO_COMP_B_11_DP")
	)
	(segment
		(start 275.973286 -181.638956)
		(end 277.57247 -177.835052)
		(width 0.1651)
		(layer "B.Cu")
		(net "PCIE_IOM_B_TO_COMP_B_11_DP")
	)
	(segment
		(start 286.001206 -184.987946)
		(end 283.948124 -186.638692)
		(width 0.1651)
		(layer "B.Cu")
		(net "PCIE_IOM_B_TO_COMP_B_11_DP")
	)
	(segment
		(start 279.523698 -186.745372)
		(end 276.727158 -184.495948)
		(width 0.1651)
		(layer "B.Cu")
		(net "PCIE_IOM_B_TO_COMP_B_11_DP")
	)
	(arc
		(start 383.949956 -21.337778)
		(mid 383.998685 -21.455419)
		(end 384.116326 -21.504148)
		(width 0.1651)
		(layer "B.Cu")
		(net "PCIE_IOM_B_TO_COMP_B_11_DP")
	)
	(arc
		(start 279.088088 -177.383694)
		(mid 279.25853 -177.405138)
		(end 279.418288 -177.468276)
		(width 0.1651)
		(layer "B.Cu")
		(net "PCIE_IOM_B_TO_COMP_B_11_DP")
	)
	(arc
		(start 279.418288 -177.468276)
		(mid 279.499871 -177.520961)
		(end 279.573228 -177.584608)
		(width 0.1651)
		(layer "B.Cu")
		(net "PCIE_IOM_B_TO_COMP_B_11_DP")
	)
	(arc
		(start 279.933908 -177.863246)
		(mid 280.013618 -177.863173)
		(end 280.089356 -177.838354)
		(width 0.1651)
		(layer "B.Cu")
		(net "PCIE_IOM_B_TO_COMP_B_11_DP")
	)
	(arc
		(start 279.778206 -177.789586)
		(mid 279.842672 -177.836258)
		(end 279.918414 -177.860706)
		(width 0.1651)
		(layer "B.Cu")
		(net "PCIE_IOM_B_TO_COMP_B_11_DP")
	)
	(arc
		(start 384.504692 -21.504148)
		(mid 384.852048 -21.648028)
		(end 384.995928 -21.995384)
		(width 0.1651)
		(layer "B.Cu")
		(net "PCIE_IOM_B_TO_COMP_B_11_DP")
	)
	(segment
		(start 305.376326 -156.287724)
		(end 305.095656 -156.695902)
		(width 0.1651)
		(layer "B.Cu")
		(net "PCIE_IOM_B_TO_COMP_B_11_DN")
	)
	(segment
		(start 298.10583 -166.863776)
		(end 297.825414 -167.271954)
		(width 0.1651)
		(layer "B.Cu")
		(net "PCIE_IOM_B_TO_COMP_B_11_DN")
	)
	(segment
		(start 312.438034 -145.813272)
		(end 312.467498 -145.972276)
		(width 0.1651)
		(layer "B.Cu")
		(net "PCIE_IOM_B_TO_COMP_B_11_DN")
	)
	(segment
		(start 287.292288 -182.39232)
		(end 287.011618 -182.800498)
		(width 0.1651)
		(layer "B.Cu")
		(net "PCIE_IOM_B_TO_COMP_B_11_DN")
	)
	(segment
		(start 279.423622 -178.162458)
		(end 278.750014 -178.49977)
		(width 0.1651)
		(layer "B.Cu")
		(net "PCIE_IOM_B_TO_COMP_B_11_DN")
	)
	(segment
		(start 289.08375 -179.786534)
		(end 289.113214 -179.945284)
		(width 0.1651)
		(layer "B.Cu")
		(net "PCIE_IOM_B_TO_COMP_B_11_DN")
	)
	(segment
		(start 325.46417 -127.065786)
		(end 325.30542 -127.094996)
		(width 0.1651)
		(layer "B.Cu")
		(net "PCIE_IOM_B_TO_COMP_B_11_DN")
	)
	(segment
		(start 333.90967 -114.560604)
		(end 333.629254 -114.968782)
		(width 0.1651)
		(layer "B.Cu")
		(net "PCIE_IOM_B_TO_COMP_B_11_DN")
	)
	(segment
		(start 287.011618 -182.800498)
		(end 287.041082 -182.959502)
		(width 0.1651)
		(layer "B.Cu")
		(net "PCIE_IOM_B_TO_COMP_B_11_DN")
	)
	(segment
		(start 288.832544 -180.353462)
		(end 288.67354 -180.382926)
		(width 0.1651)
		(layer "B.Cu")
		(net "PCIE_IOM_B_TO_COMP_B_11_DN")
	)
	(segment
		(start 297.37177 -167.712136)
		(end 297.403774 -167.88511)
		(width 0.1651)
		(layer "B.Cu")
		(net "PCIE_IOM_B_TO_COMP_B_11_DN")
	)
	(segment
		(start 289.52317 -179.348892)
		(end 289.364166 -179.378356)
		(width 0.1651)
		(layer "B.Cu")
		(net "PCIE_IOM_B_TO_COMP_B_11_DN")
	)
	(segment
		(start 298.52747 -166.250366)
		(end 298.354496 -166.28237)
		(width 0.1651)
		(layer "B.Cu")
		(net "PCIE_IOM_B_TO_COMP_B_11_DN")
	)
	(segment
		(start 281.567128 -187.09132)
		(end 279.664414 -186.483498)
		(width 0.1651)
		(layer "B.Cu")
		(net "PCIE_IOM_B_TO_COMP_B_11_DN")
	)
	(segment
		(start 324.614794 -128.09982)
		(end 324.334124 -128.507998)
		(width 0.1651)
		(layer "B.Cu")
		(net "PCIE_IOM_B_TO_COMP_B_11_DN")
	)
	(segment
		(start 288.141918 -181.358286)
		(end 287.982914 -181.38775)
		(width 0.1651)
		(layer "B.Cu")
		(net "PCIE_IOM_B_TO_COMP_B_11_DN")
	)
	(segment
		(start 369.955572 -62.345824)
		(end 334.784954 -113.507012)
		(width 0.1651)
		(layer "B.Cu")
		(net "PCIE_IOM_B_TO_COMP_B_11_DN")
	)
	(segment
		(start 314.099956 -143.3957)
		(end 313.819286 -143.803878)
		(width 0.1651)
		(layer "B.Cu")
		(net "PCIE_IOM_B_TO_COMP_B_11_DN")
	)
	(segment
		(start 312.71845 -145.405094)
		(end 312.438034 -145.813272)
		(width 0.1651)
		(layer "B.Cu")
		(net "PCIE_IOM_B_TO_COMP_B_11_DN")
	)
	(segment
		(start 323.672962 -129.671572)
		(end 323.392292 -130.07975)
		(width 0.1651)
		(layer "B.Cu")
		(net "PCIE_IOM_B_TO_COMP_B_11_DN")
	)
	(segment
		(start 313.56808 -144.37106)
		(end 313.409076 -144.400524)
		(width 0.1651)
		(layer "B.Cu")
		(net "PCIE_IOM_B_TO_COMP_B_11_DN")
	)
	(segment
		(start 306.476908 -154.686508)
		(end 306.317904 -154.715718)
		(width 0.1651)
		(layer "B.Cu")
		(net "PCIE_IOM_B_TO_COMP_B_11_DN")
	)
	(segment
		(start 313.84875 -143.962882)
		(end 313.56808 -144.37106)
		(width 0.1651)
		(layer "B.Cu")
		(net "PCIE_IOM_B_TO_COMP_B_11_DN")
	)
	(segment
		(start 295.999408 -169.928032)
		(end 289.52317 -179.348892)
		(width 0.1651)
		(layer "B.Cu")
		(net "PCIE_IOM_B_TO_COMP_B_11_DN")
	)
	(segment
		(start 332.926944 -115.990116)
		(end 332.958948 -116.16309)
		(width 0.1651)
		(layer "B.Cu")
		(net "PCIE_IOM_B_TO_COMP_B_11_DN")
	)
	(segment
		(start 306.037488 -155.123896)
		(end 306.066952 -155.2829)
		(width 0.1651)
		(layer "B.Cu")
		(net "PCIE_IOM_B_TO_COMP_B_11_DN")
	)
	(segment
		(start 279.366472 -177.791364)
		(end 279.467564 -177.892456)
		(width 0.1651)
		(layer "B.Cu")
		(net "PCIE_IOM_B_TO_COMP_B_11_DN")
	)
	(segment
		(start 296.95013 -168.325292)
		(end 296.66946 -168.73347)
		(width 0.1651)
		(layer "B.Cu")
		(net "PCIE_IOM_B_TO_COMP_B_11_DN")
	)
	(segment
		(start 304.246026 -157.729936)
		(end 303.965356 -158.138114)
		(width 0.1651)
		(layer "B.Cu")
		(net "PCIE_IOM_B_TO_COMP_B_11_DN")
	)
	(segment
		(start 296.66946 -168.73347)
		(end 296.701464 -168.906444)
		(width 0.1651)
		(layer "B.Cu")
		(net "PCIE_IOM_B_TO_COMP_B_11_DN")
	)
	(segment
		(start 313.12866 -144.808702)
		(end 313.158124 -144.967452)
		(width 0.1651)
		(layer "B.Cu")
		(net "PCIE_IOM_B_TO_COMP_B_11_DN")
	)
	(segment
		(start 285.784798 -184.787032)
		(end 283.806646 -186.377072)
		(width 0.1651)
		(layer "B.Cu")
		(net "PCIE_IOM_B_TO_COMP_B_11_DN")
	)
	(segment
		(start 333.629254 -114.968782)
		(end 333.661258 -115.141756)
		(width 0.1651)
		(layer "B.Cu")
		(net "PCIE_IOM_B_TO_COMP_B_11_DN")
	)
	(segment
		(start 304.40503 -157.700472)
		(end 304.246026 -157.729936)
		(width 0.1651)
		(layer "B.Cu")
		(net "PCIE_IOM_B_TO_COMP_B_11_DN")
	)
	(segment
		(start 297.825414 -167.271954)
		(end 297.652186 -167.303958)
		(width 0.1651)
		(layer "B.Cu")
		(net "PCIE_IOM_B_TO_COMP_B_11_DN")
	)
	(segment
		(start 296.421048 -169.314622)
		(end 296.24782 -169.34688)
		(width 0.1651)
		(layer "B.Cu")
		(net "PCIE_IOM_B_TO_COMP_B_11_DN")
	)
	(segment
		(start 305.786282 -155.691078)
		(end 305.627278 -155.720542)
		(width 0.1651)
		(layer "B.Cu")
		(net "PCIE_IOM_B_TO_COMP_B_11_DN")
	)
	(segment
		(start 322.982082 -130.676396)
		(end 314.258706 -143.366236)
		(width 0.1651)
		(layer "B.Cu")
		(net "PCIE_IOM_B_TO_COMP_B_11_DN")
	)
	(segment
		(start 289.364166 -179.378356)
		(end 289.08375 -179.786534)
		(width 0.1651)
		(layer "B.Cu")
		(net "PCIE_IOM_B_TO_COMP_B_11_DN")
	)
	(segment
		(start 333.661258 -115.141756)
		(end 333.380588 -115.549934)
		(width 0.1651)
		(layer "B.Cu")
		(net "PCIE_IOM_B_TO_COMP_B_11_DN")
	)
	(segment
		(start 278.46147 -177.673762)
		(end 279.087072 -177.675794)
		(width 0.1651)
		(layer "B.Cu")
		(net "PCIE_IOM_B_TO_COMP_B_11_DN")
	)
	(segment
		(start 283.806646 -186.377072)
		(end 281.567128 -187.09132)
		(width 0.1651)
		(layer "B.Cu")
		(net "PCIE_IOM_B_TO_COMP_B_11_DN")
	)
	(segment
		(start 312.877454 -145.37563)
		(end 312.71845 -145.405094)
		(width 0.1651)
		(layer "B.Cu")
		(net "PCIE_IOM_B_TO_COMP_B_11_DN")
	)
	(segment
		(start 324.082918 -129.07518)
		(end 323.923914 -129.10439)
		(width 0.1651)
		(layer "B.Cu")
		(net "PCIE_IOM_B_TO_COMP_B_11_DN")
	)
	(segment
		(start 313.158124 -144.967452)
		(end 312.877454 -145.37563)
		(width 0.1651)
		(layer "B.Cu")
		(net "PCIE_IOM_B_TO_COMP_B_11_DN")
	)
	(segment
		(start 305.095656 -156.695902)
		(end 304.936652 -156.725112)
		(width 0.1651)
		(layer "B.Cu")
		(net "PCIE_IOM_B_TO_COMP_B_11_DN")
	)
	(segment
		(start 323.233288 -130.109214)
		(end 322.952872 -130.517392)
		(width 0.1651)
		(layer "B.Cu")
		(net "PCIE_IOM_B_TO_COMP_B_11_DN")
	)
	(segment
		(start 334.784954 -113.507012)
		(end 334.61198 -113.539016)
		(width 0.1651)
		(layer "B.Cu")
		(net "PCIE_IOM_B_TO_COMP_B_11_DN")
	)
	(segment
		(start 289.113214 -179.945284)
		(end 288.832544 -180.353462)
		(width 0.1651)
		(layer "B.Cu")
		(net "PCIE_IOM_B_TO_COMP_B_11_DN")
	)
	(segment
		(start 325.02475 -127.503174)
		(end 325.054214 -127.662178)
		(width 0.1651)
		(layer "B.Cu")
		(net "PCIE_IOM_B_TO_COMP_B_11_DN")
	)
	(segment
		(start 313.409076 -144.400524)
		(end 313.12866 -144.808702)
		(width 0.1651)
		(layer "B.Cu")
		(net "PCIE_IOM_B_TO_COMP_B_11_DN")
	)
	(segment
		(start 333.207614 -115.581938)
		(end 332.926944 -115.990116)
		(width 0.1651)
		(layer "B.Cu")
		(net "PCIE_IOM_B_TO_COMP_B_11_DN")
	)
	(segment
		(start 311.776618 -146.976846)
		(end 306.476908 -154.686508)
		(width 0.1651)
		(layer "B.Cu")
		(net "PCIE_IOM_B_TO_COMP_B_11_DN")
	)
	(segment
		(start 303.965356 -158.138114)
		(end 303.99482 -158.297118)
		(width 0.1651)
		(layer "B.Cu")
		(net "PCIE_IOM_B_TO_COMP_B_11_DN")
	)
	(segment
		(start 297.652186 -167.303958)
		(end 297.37177 -167.712136)
		(width 0.1651)
		(layer "B.Cu")
		(net "PCIE_IOM_B_TO_COMP_B_11_DN")
	)
	(segment
		(start 288.422334 -180.950108)
		(end 288.141918 -181.358286)
		(width 0.1651)
		(layer "B.Cu")
		(net "PCIE_IOM_B_TO_COMP_B_11_DN")
	)
	(segment
		(start 324.773544 -128.070356)
		(end 324.614794 -128.09982)
		(width 0.1651)
		(layer "B.Cu")
		(net "PCIE_IOM_B_TO_COMP_B_11_DN")
	)
	(segment
		(start 279.087072 -177.675794)
		(end 279.088342 -177.675794)
		(width 0.1651)
		(layer "B.Cu")
		(net "PCIE_IOM_B_TO_COMP_B_11_DN")
	)
	(segment
		(start 323.643498 -129.512568)
		(end 323.672962 -129.671572)
		(width 0.1651)
		(layer "B.Cu")
		(net "PCIE_IOM_B_TO_COMP_B_11_DN")
	)
	(segment
		(start 311.747154 -146.818096)
		(end 311.776618 -146.976846)
		(width 0.1651)
		(layer "B.Cu")
		(net "PCIE_IOM_B_TO_COMP_B_11_DN")
	)
	(segment
		(start 287.041082 -182.959502)
		(end 285.784798 -184.787032)
		(width 0.1651)
		(layer "B.Cu")
		(net "PCIE_IOM_B_TO_COMP_B_11_DN")
	)
	(segment
		(start 305.346862 -156.12872)
		(end 305.376326 -156.287724)
		(width 0.1651)
		(layer "B.Cu")
		(net "PCIE_IOM_B_TO_COMP_B_11_DN")
	)
	(segment
		(start 324.334124 -128.507998)
		(end 324.363588 -128.667002)
		(width 0.1651)
		(layer "B.Cu")
		(net "PCIE_IOM_B_TO_COMP_B_11_DN")
	)
	(segment
		(start 298.073826 -166.690548)
		(end 298.10583 -166.863776)
		(width 0.1651)
		(layer "B.Cu")
		(net "PCIE_IOM_B_TO_COMP_B_11_DN")
	)
	(segment
		(start 312.467498 -145.972276)
		(end 312.186828 -146.380454)
		(width 0.1651)
		(layer "B.Cu")
		(net "PCIE_IOM_B_TO_COMP_B_11_DN")
	)
	(segment
		(start 334.363568 -114.120168)
		(end 334.082898 -114.528346)
		(width 0.1651)
		(layer "B.Cu")
		(net "PCIE_IOM_B_TO_COMP_B_11_DN")
	)
	(segment
		(start 383.949956 -22.350222)
		(end 383.949956 -21.962618)
		(width 0.1651)
		(layer "B.Cu")
		(net "PCIE_IOM_B_TO_COMP_B_11_DN")
	)
	(segment
		(start 334.082898 -114.528346)
		(end 333.90967 -114.560604)
		(width 0.1651)
		(layer "B.Cu")
		(net "PCIE_IOM_B_TO_COMP_B_11_DN")
	)
	(segment
		(start 325.30542 -127.094996)
		(end 325.02475 -127.503174)
		(width 0.1651)
		(layer "B.Cu")
		(net "PCIE_IOM_B_TO_COMP_B_11_DN")
	)
	(segment
		(start 334.33131 -113.947194)
		(end 334.363568 -114.120168)
		(width 0.1651)
		(layer "B.Cu")
		(net "PCIE_IOM_B_TO_COMP_B_11_DN")
	)
	(segment
		(start 324.363588 -128.667002)
		(end 324.082918 -129.07518)
		(width 0.1651)
		(layer "B.Cu")
		(net "PCIE_IOM_B_TO_COMP_B_11_DN")
	)
	(segment
		(start 304.655982 -157.13329)
		(end 304.685446 -157.292294)
		(width 0.1651)
		(layer "B.Cu")
		(net "PCIE_IOM_B_TO_COMP_B_11_DN")
	)
	(segment
		(start 333.380588 -115.549934)
		(end 333.207614 -115.581938)
		(width 0.1651)
		(layer "B.Cu")
		(net "PCIE_IOM_B_TO_COMP_B_11_DN")
	)
	(segment
		(start 276.281134 -181.660546)
		(end 277.803102 -178.041046)
		(width 0.1651)
		(layer "B.Cu")
		(net "PCIE_IOM_B_TO_COMP_B_11_DN")
	)
	(segment
		(start 296.24782 -169.34688)
		(end 295.967404 -169.755058)
		(width 0.1651)
		(layer "B.Cu")
		(net "PCIE_IOM_B_TO_COMP_B_11_DN")
	)
	(segment
		(start 298.354496 -166.28237)
		(end 298.073826 -166.690548)
		(width 0.1651)
		(layer "B.Cu")
		(net "PCIE_IOM_B_TO_COMP_B_11_DN")
	)
	(segment
		(start 332.958948 -116.16309)
		(end 325.46417 -127.065786)
		(width 0.1651)
		(layer "B.Cu")
		(net "PCIE_IOM_B_TO_COMP_B_11_DN")
	)
	(segment
		(start 287.451292 -182.362856)
		(end 287.292288 -182.39232)
		(width 0.1651)
		(layer "B.Cu")
		(net "PCIE_IOM_B_TO_COMP_B_11_DN")
	)
	(segment
		(start 295.967404 -169.755058)
		(end 295.999408 -169.928032)
		(width 0.1651)
		(layer "B.Cu")
		(net "PCIE_IOM_B_TO_COMP_B_11_DN")
	)
	(segment
		(start 322.952872 -130.517392)
		(end 322.982082 -130.676396)
		(width 0.1651)
		(layer "B.Cu")
		(net "PCIE_IOM_B_TO_COMP_B_11_DN")
	)
	(segment
		(start 312.027824 -146.409918)
		(end 311.747154 -146.818096)
		(width 0.1651)
		(layer "B.Cu")
		(net "PCIE_IOM_B_TO_COMP_B_11_DN")
	)
	(segment
		(start 304.936652 -156.725112)
		(end 304.655982 -157.13329)
		(width 0.1651)
		(layer "B.Cu")
		(net "PCIE_IOM_B_TO_COMP_B_11_DN")
	)
	(segment
		(start 297.123104 -168.293288)
		(end 296.95013 -168.325292)
		(width 0.1651)
		(layer "B.Cu")
		(net "PCIE_IOM_B_TO_COMP_B_11_DN")
	)
	(segment
		(start 288.39287 -180.791104)
		(end 288.422334 -180.950108)
		(width 0.1651)
		(layer "B.Cu")
		(net "PCIE_IOM_B_TO_COMP_B_11_DN")
	)
	(segment
		(start 323.923914 -129.10439)
		(end 323.643498 -129.512568)
		(width 0.1651)
		(layer "B.Cu")
		(net "PCIE_IOM_B_TO_COMP_B_11_DN")
	)
	(segment
		(start 334.61198 -113.539016)
		(end 334.33131 -113.947194)
		(width 0.1651)
		(layer "B.Cu")
		(net "PCIE_IOM_B_TO_COMP_B_11_DN")
	)
	(segment
		(start 384.116326 -21.796248)
		(end 384.504692 -21.796248)
		(width 0.1651)
		(layer "B.Cu")
		(net "PCIE_IOM_B_TO_COMP_B_11_DN")
	)
	(segment
		(start 297.403774 -167.88511)
		(end 297.123104 -168.293288)
		(width 0.1651)
		(layer "B.Cu")
		(net "PCIE_IOM_B_TO_COMP_B_11_DN")
	)
	(segment
		(start 287.702244 -181.795928)
		(end 287.731708 -181.954932)
		(width 0.1651)
		(layer "B.Cu")
		(net "PCIE_IOM_B_TO_COMP_B_11_DN")
	)
	(segment
		(start 287.982914 -181.38775)
		(end 287.702244 -181.795928)
		(width 0.1651)
		(layer "B.Cu")
		(net "PCIE_IOM_B_TO_COMP_B_11_DN")
	)
	(segment
		(start 276.985222 -184.328562)
		(end 276.281134 -181.660546)
		(width 0.1651)
		(layer "B.Cu")
		(net "PCIE_IOM_B_TO_COMP_B_11_DN")
	)
	(segment
		(start 323.392292 -130.07975)
		(end 323.233288 -130.109214)
		(width 0.1651)
		(layer "B.Cu")
		(net "PCIE_IOM_B_TO_COMP_B_11_DN")
	)
	(segment
		(start 305.627278 -155.720542)
		(end 305.346862 -156.12872)
		(width 0.1651)
		(layer "B.Cu")
		(net "PCIE_IOM_B_TO_COMP_B_11_DN")
	)
	(segment
		(start 325.054214 -127.662178)
		(end 324.773544 -128.070356)
		(width 0.1651)
		(layer "B.Cu")
		(net "PCIE_IOM_B_TO_COMP_B_11_DN")
	)
	(segment
		(start 287.731708 -181.954932)
		(end 287.451292 -182.362856)
		(width 0.1651)
		(layer "B.Cu")
		(net "PCIE_IOM_B_TO_COMP_B_11_DN")
	)
	(segment
		(start 377.705874 -44.221654)
		(end 369.955572 -62.345824)
		(width 0.1651)
		(layer "B.Cu")
		(net "PCIE_IOM_B_TO_COMP_B_11_DN")
	)
	(segment
		(start 288.67354 -180.382926)
		(end 288.39287 -180.791104)
		(width 0.1651)
		(layer "B.Cu")
		(net "PCIE_IOM_B_TO_COMP_B_11_DN")
	)
	(segment
		(start 384.703828 -34.113216)
		(end 377.705874 -44.221654)
		(width 0.1651)
		(layer "B.Cu")
		(net "PCIE_IOM_B_TO_COMP_B_11_DN")
	)
	(segment
		(start 384.703828 -21.995384)
		(end 384.703828 -34.113216)
		(width 0.1651)
		(layer "B.Cu")
		(net "PCIE_IOM_B_TO_COMP_B_11_DN")
	)
	(segment
		(start 304.685446 -157.292294)
		(end 304.40503 -157.700472)
		(width 0.1651)
		(layer "B.Cu")
		(net "PCIE_IOM_B_TO_COMP_B_11_DN")
	)
	(segment
		(start 303.99482 -158.297118)
		(end 298.52747 -166.250366)
		(width 0.1651)
		(layer "B.Cu")
		(net "PCIE_IOM_B_TO_COMP_B_11_DN")
	)
	(segment
		(start 279.664414 -186.483498)
		(end 276.985222 -184.328562)
		(width 0.1651)
		(layer "B.Cu")
		(net "PCIE_IOM_B_TO_COMP_B_11_DN")
	)
	(segment
		(start 306.066952 -155.2829)
		(end 305.786282 -155.691078)
		(width 0.1651)
		(layer "B.Cu")
		(net "PCIE_IOM_B_TO_COMP_B_11_DN")
	)
	(segment
		(start 306.317904 -154.715718)
		(end 306.037488 -155.123896)
		(width 0.1651)
		(layer "B.Cu")
		(net "PCIE_IOM_B_TO_COMP_B_11_DN")
	)
	(segment
		(start 314.258706 -143.366236)
		(end 314.099956 -143.3957)
		(width 0.1651)
		(layer "B.Cu")
		(net "PCIE_IOM_B_TO_COMP_B_11_DN")
	)
	(segment
		(start 313.819286 -143.803878)
		(end 313.84875 -143.962882)
		(width 0.1651)
		(layer "B.Cu")
		(net "PCIE_IOM_B_TO_COMP_B_11_DN")
	)
	(segment
		(start 312.186828 -146.380454)
		(end 312.027824 -146.409918)
		(width 0.1651)
		(layer "B.Cu")
		(net "PCIE_IOM_B_TO_COMP_B_11_DN")
	)
	(segment
		(start 296.701464 -168.906444)
		(end 296.421048 -169.314622)
		(width 0.1651)
		(layer "B.Cu")
		(net "PCIE_IOM_B_TO_COMP_B_11_DN")
	)
	(segment
		(start 277.803102 -178.041046)
		(end 278.46147 -177.673762)
		(width 0.1651)
		(layer "B.Cu")
		(net "PCIE_IOM_B_TO_COMP_B_11_DN")
	)
	(arc
		(start 279.514808 -178.038506)
		(mid 279.484105 -178.111437)
		(end 279.423622 -178.162458)
		(width 0.1651)
		(layer "B.Cu")
		(net "PCIE_IOM_B_TO_COMP_B_11_DN")
	)
	(arc
		(start 279.467564 -177.892456)
		(mid 279.508792 -177.959796)
		(end 279.514808 -178.038506)
		(width 0.1651)
		(layer "B.Cu")
		(net "PCIE_IOM_B_TO_COMP_B_11_DN")
	)
	(arc
		(start 383.949956 -21.962618)
		(mid 383.998685 -21.844977)
		(end 384.116326 -21.796248)
		(width 0.1651)
		(layer "B.Cu")
		(net "PCIE_IOM_B_TO_COMP_B_11_DN")
	)
	(arc
		(start 384.504692 -21.796248)
		(mid 384.645502 -21.854574)
		(end 384.703828 -21.995384)
		(width 0.1651)
		(layer "B.Cu")
		(net "PCIE_IOM_B_TO_COMP_B_11_DN")
	)
	(arc
		(start 279.088342 -177.675794)
		(mid 279.18604 -177.68823)
		(end 279.277572 -177.724562)
		(width 0.1651)
		(layer "B.Cu")
		(net "PCIE_IOM_B_TO_COMP_B_11_DN")
	)
	(arc
		(start 279.277572 -177.724562)
		(mid 279.324385 -177.754816)
		(end 279.366472 -177.791364)
		(width 0.1651)
		(layer "B.Cu")
		(net "PCIE_IOM_B_TO_COMP_B_11_DN")
	)
	(segment
		(start 385.750054 -21.950172)
		(end 385.750054 -22.337776)
		(width 0.1651)
		(layer "B.Cu")
		(net "PCIE_IOM_B_TO_COMP_B_10_DP")
	)
	(segment
		(start 284.799786 -188.044074)
		(end 283.154628 -188.568838)
		(width 0.1651)
		(layer "B.Cu")
		(net "PCIE_IOM_B_TO_COMP_B_10_DP")
	)
	(segment
		(start 280.089356 -173.838362)
		(end 280.75001 -173.49978)
		(width 0.1651)
		(layer "B.Cu")
		(net "PCIE_IOM_B_TO_COMP_B_10_DP")
	)
	(segment
		(start 283.154628 -188.568838)
		(end 281.472894 -189.105286)
		(width 0.1651)
		(layer "B.Cu")
		(net "PCIE_IOM_B_TO_COMP_B_10_DP")
	)
	(segment
		(start 385.916424 -22.504146)
		(end 386.286756 -22.504146)
		(width 0.1651)
		(layer "B.Cu")
		(net "PCIE_IOM_B_TO_COMP_B_10_DP")
	)
	(segment
		(start 278.755856 -188.237622)
		(end 275.079968 -185.281316)
		(width 0.1651)
		(layer "B.Cu")
		(net "PCIE_IOM_B_TO_COMP_B_10_DP")
	)
	(segment
		(start 386.796026 -34.415476)
		(end 379.37186 -45.13961)
		(width 0.1651)
		(layer "B.Cu")
		(net "PCIE_IOM_B_TO_COMP_B_10_DP")
	)
	(segment
		(start 275.079968 -185.281316)
		(end 274.093686 -181.54142)
		(width 0.1651)
		(layer "B.Cu")
		(net "PCIE_IOM_B_TO_COMP_B_10_DP")
	)
	(segment
		(start 279.918414 -173.860714)
		(end 279.933908 -173.863254)
		(width 0.1651)
		(layer "B.Cu")
		(net "PCIE_IOM_B_TO_COMP_B_10_DP")
	)
	(segment
		(start 278.386032 -173.381162)
		(end 279.088088 -173.383702)
		(width 0.1651)
		(layer "B.Cu")
		(net "PCIE_IOM_B_TO_COMP_B_10_DP")
	)
	(segment
		(start 281.472894 -189.105286)
		(end 278.755856 -188.237622)
		(width 0.1651)
		(layer "B.Cu")
		(net "PCIE_IOM_B_TO_COMP_B_10_DP")
	)
	(segment
		(start 274.093686 -181.54142)
		(end 277.260304 -174.009558)
		(width 0.1651)
		(layer "B.Cu")
		(net "PCIE_IOM_B_TO_COMP_B_10_DP")
	)
	(segment
		(start 287.55213 -185.83148)
		(end 284.799786 -188.044074)
		(width 0.1651)
		(layer "B.Cu")
		(net "PCIE_IOM_B_TO_COMP_B_10_DP")
	)
	(segment
		(start 379.37186 -45.13961)
		(end 371.368066 -63.860426)
		(width 0.1651)
		(layer "B.Cu")
		(net "PCIE_IOM_B_TO_COMP_B_10_DP")
	)
	(segment
		(start 371.368066 -63.860426)
		(end 287.55213 -185.83148)
		(width 0.1651)
		(layer "B.Cu")
		(net "PCIE_IOM_B_TO_COMP_B_10_DP")
	)
	(segment
		(start 279.573228 -173.584616)
		(end 279.778206 -173.789594)
		(width 0.1651)
		(layer "B.Cu")
		(net "PCIE_IOM_B_TO_COMP_B_10_DP")
	)
	(segment
		(start 277.260304 -174.009558)
		(end 278.386032 -173.381162)
		(width 0.1651)
		(layer "B.Cu")
		(net "PCIE_IOM_B_TO_COMP_B_10_DP")
	)
	(segment
		(start 386.796026 -23.013416)
		(end 386.796026 -34.415476)
		(width 0.1651)
		(layer "B.Cu")
		(net "PCIE_IOM_B_TO_COMP_B_10_DP")
	)
	(arc
		(start 386.286756 -22.504146)
		(mid 386.646864 -22.653308)
		(end 386.796026 -23.013416)
		(width 0.1651)
		(layer "B.Cu")
		(net "PCIE_IOM_B_TO_COMP_B_10_DP")
	)
	(arc
		(start 279.933908 -173.863254)
		(mid 280.013618 -173.863181)
		(end 280.089356 -173.838362)
		(width 0.1651)
		(layer "B.Cu")
		(net "PCIE_IOM_B_TO_COMP_B_10_DP")
	)
	(arc
		(start 385.750054 -22.337776)
		(mid 385.798783 -22.455417)
		(end 385.916424 -22.504146)
		(width 0.1651)
		(layer "B.Cu")
		(net "PCIE_IOM_B_TO_COMP_B_10_DP")
	)
	(arc
		(start 279.088088 -173.383702)
		(mid 279.25853 -173.405146)
		(end 279.418288 -173.468284)
		(width 0.1651)
		(layer "B.Cu")
		(net "PCIE_IOM_B_TO_COMP_B_10_DP")
	)
	(arc
		(start 279.778206 -173.789594)
		(mid 279.842672 -173.836266)
		(end 279.918414 -173.860714)
		(width 0.1651)
		(layer "B.Cu")
		(net "PCIE_IOM_B_TO_COMP_B_10_DP")
	)
	(arc
		(start 279.418288 -173.468284)
		(mid 279.499871 -173.520969)
		(end 279.573228 -173.584616)
		(width 0.1651)
		(layer "B.Cu")
		(net "PCIE_IOM_B_TO_COMP_B_10_DP")
	)
	(segment
		(start 284.65907 -187.7822)
		(end 281.472894 -188.798454)
		(width 0.1651)
		(layer "B.Cu")
		(net "PCIE_IOM_B_TO_COMP_B_10_DN")
	)
	(segment
		(start 277.490682 -174.215552)
		(end 278.46147 -173.67377)
		(width 0.1651)
		(layer "B.Cu")
		(net "PCIE_IOM_B_TO_COMP_B_10_DN")
	)
	(segment
		(start 334.601312 -116.646198)
		(end 334.320896 -117.05463)
		(width 0.1651)
		(layer "B.Cu")
		(net "PCIE_IOM_B_TO_COMP_B_10_DN")
	)
	(segment
		(start 297.516042 -170.595544)
		(end 297.5483 -170.768518)
		(width 0.1651)
		(layer "B.Cu")
		(net "PCIE_IOM_B_TO_COMP_B_10_DN")
	)
	(segment
		(start 325.18858 -130.54584)
		(end 324.90791 -130.954018)
		(width 0.1651)
		(layer "B.Cu")
		(net "PCIE_IOM_B_TO_COMP_B_10_DN")
	)
	(segment
		(start 336.42173 -114.198908)
		(end 336.141314 -114.607086)
		(width 0.1651)
		(layer "B.Cu")
		(net "PCIE_IOM_B_TO_COMP_B_10_DN")
	)
	(segment
		(start 313.291474 -147.85848)
		(end 300.0756 -167.090598)
		(width 0.1651)
		(layer "B.Cu")
		(net "PCIE_IOM_B_TO_COMP_B_10_DN")
	)
	(segment
		(start 274.401534 -181.56301)
		(end 277.490682 -174.215552)
		(width 0.1651)
		(layer "B.Cu")
		(net "PCIE_IOM_B_TO_COMP_B_10_DN")
	)
	(segment
		(start 298.498768 -169.165778)
		(end 298.218098 -169.573956)
		(width 0.1651)
		(layer "B.Cu")
		(net "PCIE_IOM_B_TO_COMP_B_10_DN")
	)
	(segment
		(start 342.494362 -105.36174)
		(end 342.213692 -105.769918)
		(width 0.1651)
		(layer "B.Cu")
		(net "PCIE_IOM_B_TO_COMP_B_10_DN")
	)
	(segment
		(start 335.011268 -116.049806)
		(end 335.040732 -116.208556)
		(width 0.1651)
		(layer "B.Cu")
		(net "PCIE_IOM_B_TO_COMP_B_10_DN")
	)
	(segment
		(start 298.671742 -169.133774)
		(end 298.498768 -169.165778)
		(width 0.1651)
		(layer "B.Cu")
		(net "PCIE_IOM_B_TO_COMP_B_10_DN")
	)
	(segment
		(start 298.218098 -169.573956)
		(end 298.250102 -169.74693)
		(width 0.1651)
		(layer "B.Cu")
		(net "PCIE_IOM_B_TO_COMP_B_10_DN")
	)
	(segment
		(start 343.44483 -103.759)
		(end 343.16416 -104.167178)
		(width 0.1651)
		(layer "B.Cu")
		(net "PCIE_IOM_B_TO_COMP_B_10_DN")
	)
	(segment
		(start 326.82053 -127.96901)
		(end 326.53986 -128.377188)
		(width 0.1651)
		(layer "B.Cu")
		(net "PCIE_IOM_B_TO_COMP_B_10_DN")
	)
	(segment
		(start 325.598536 -129.949194)
		(end 325.439532 -129.978658)
		(width 0.1651)
		(layer "B.Cu")
		(net "PCIE_IOM_B_TO_COMP_B_10_DN")
	)
	(segment
		(start 290.922456 -180.410612)
		(end 290.763452 -180.440076)
		(width 0.1651)
		(layer "B.Cu")
		(net "PCIE_IOM_B_TO_COMP_B_10_DN")
	)
	(segment
		(start 336.831686 -113.602262)
		(end 336.672682 -113.631726)
		(width 0.1651)
		(layer "B.Cu")
		(net "PCIE_IOM_B_TO_COMP_B_10_DN")
	)
	(segment
		(start 298.952158 -168.725596)
		(end 298.671742 -169.133774)
		(width 0.1651)
		(layer "B.Cu")
		(net "PCIE_IOM_B_TO_COMP_B_10_DN")
	)
	(segment
		(start 385.916424 -22.796246)
		(end 386.286756 -22.796246)
		(width 0.1651)
		(layer "B.Cu")
		(net "PCIE_IOM_B_TO_COMP_B_10_DN")
	)
	(segment
		(start 290.763452 -180.440076)
		(end 290.483036 -180.848508)
		(width 0.1651)
		(layer "B.Cu")
		(net "PCIE_IOM_B_TO_COMP_B_10_DN")
	)
	(segment
		(start 336.141314 -114.607086)
		(end 335.98231 -114.63655)
		(width 0.1651)
		(layer "B.Cu")
		(net "PCIE_IOM_B_TO_COMP_B_10_DN")
	)
	(segment
		(start 288.440876 -184.02173)
		(end 287.335468 -185.630566)
		(width 0.1651)
		(layer "B.Cu")
		(net "PCIE_IOM_B_TO_COMP_B_10_DN")
	)
	(segment
		(start 325.439532 -129.978658)
		(end 325.159116 -130.386836)
		(width 0.1651)
		(layer "B.Cu")
		(net "PCIE_IOM_B_TO_COMP_B_10_DN")
	)
	(segment
		(start 334.760316 -116.616734)
		(end 334.601312 -116.646198)
		(width 0.1651)
		(layer "B.Cu")
		(net "PCIE_IOM_B_TO_COMP_B_10_DN")
	)
	(segment
		(start 335.98231 -114.63655)
		(end 335.701894 -115.044982)
		(width 0.1651)
		(layer "B.Cu")
		(net "PCIE_IOM_B_TO_COMP_B_10_DN")
	)
	(segment
		(start 314.672472 -145.848832)
		(end 314.392056 -146.25701)
		(width 0.1651)
		(layer "B.Cu")
		(net "PCIE_IOM_B_TO_COMP_B_10_DN")
	)
	(segment
		(start 379.114812 -44.997624)
		(end 371.110764 -63.718694)
		(width 0.1651)
		(layer "B.Cu")
		(net "PCIE_IOM_B_TO_COMP_B_10_DN")
	)
	(segment
		(start 313.70143 -147.261834)
		(end 313.542426 -147.291298)
		(width 0.1651)
		(layer "B.Cu")
		(net "PCIE_IOM_B_TO_COMP_B_10_DN")
	)
	(segment
		(start 313.952636 -146.694652)
		(end 313.9821 -146.853656)
		(width 0.1651)
		(layer "B.Cu")
		(net "PCIE_IOM_B_TO_COMP_B_10_DN")
	)
	(segment
		(start 289.821874 -182.012082)
		(end 289.541458 -182.42026)
		(width 0.1651)
		(layer "B.Cu")
		(net "PCIE_IOM_B_TO_COMP_B_10_DN")
	)
	(segment
		(start 335.450688 -115.61191)
		(end 335.291684 -115.641374)
		(width 0.1651)
		(layer "B.Cu")
		(net "PCIE_IOM_B_TO_COMP_B_10_DN")
	)
	(segment
		(start 279.087072 -173.675802)
		(end 279.088342 -173.675802)
		(width 0.1651)
		(layer "B.Cu")
		(net "PCIE_IOM_B_TO_COMP_B_10_DN")
	)
	(segment
		(start 343.16416 -104.167178)
		(end 343.196418 -104.340152)
		(width 0.1651)
		(layer "B.Cu")
		(net "PCIE_IOM_B_TO_COMP_B_10_DN")
	)
	(segment
		(start 279.366472 -173.791372)
		(end 279.467564 -173.892464)
		(width 0.1651)
		(layer "B.Cu")
		(net "PCIE_IOM_B_TO_COMP_B_10_DN")
	)
	(segment
		(start 326.288908 -128.94437)
		(end 326.129904 -128.973834)
		(width 0.1651)
		(layer "B.Cu")
		(net "PCIE_IOM_B_TO_COMP_B_10_DN")
	)
	(segment
		(start 314.233052 -146.286474)
		(end 313.952636 -146.694652)
		(width 0.1651)
		(layer "B.Cu")
		(net "PCIE_IOM_B_TO_COMP_B_10_DN")
	)
	(segment
		(start 314.643008 -145.689828)
		(end 314.672472 -145.848832)
		(width 0.1651)
		(layer "B.Cu")
		(net "PCIE_IOM_B_TO_COMP_B_10_DN")
	)
	(segment
		(start 335.291684 -115.641374)
		(end 335.011268 -116.049806)
		(width 0.1651)
		(layer "B.Cu")
		(net "PCIE_IOM_B_TO_COMP_B_10_DN")
	)
	(segment
		(start 386.503926 -34.324036)
		(end 379.114812 -44.997624)
		(width 0.1651)
		(layer "B.Cu")
		(net "PCIE_IOM_B_TO_COMP_B_10_DN")
	)
	(segment
		(start 336.672682 -113.631726)
		(end 336.392266 -114.040158)
		(width 0.1651)
		(layer "B.Cu")
		(net "PCIE_IOM_B_TO_COMP_B_10_DN")
	)
	(segment
		(start 324.748906 -130.983482)
		(end 324.46849 -131.39166)
		(width 0.1651)
		(layer "B.Cu")
		(net "PCIE_IOM_B_TO_COMP_B_10_DN")
	)
	(segment
		(start 297.969686 -170.155362)
		(end 297.796712 -170.187366)
		(width 0.1651)
		(layer "B.Cu")
		(net "PCIE_IOM_B_TO_COMP_B_10_DN")
	)
	(segment
		(start 335.701894 -115.044982)
		(end 335.731358 -115.203732)
		(width 0.1651)
		(layer "B.Cu")
		(net "PCIE_IOM_B_TO_COMP_B_10_DN")
	)
	(segment
		(start 278.46147 -173.67377)
		(end 279.087072 -173.675802)
		(width 0.1651)
		(layer "B.Cu")
		(net "PCIE_IOM_B_TO_COMP_B_10_DN")
	)
	(segment
		(start 300.0756 -167.090598)
		(end 299.902626 -167.122602)
		(width 0.1651)
		(layer "B.Cu")
		(net "PCIE_IOM_B_TO_COMP_B_10_DN")
	)
	(segment
		(start 299.62221 -167.53078)
		(end 299.654214 -167.704008)
		(width 0.1651)
		(layer "B.Cu")
		(net "PCIE_IOM_B_TO_COMP_B_10_DN")
	)
	(segment
		(start 315.33338 -144.685004)
		(end 315.363098 -144.844008)
		(width 0.1651)
		(layer "B.Cu")
		(net "PCIE_IOM_B_TO_COMP_B_10_DN")
	)
	(segment
		(start 342.040718 -105.802176)
		(end 341.760302 -106.210354)
		(width 0.1651)
		(layer "B.Cu")
		(net "PCIE_IOM_B_TO_COMP_B_10_DN")
	)
	(segment
		(start 299.373798 -168.112186)
		(end 299.20057 -168.14419)
		(width 0.1651)
		(layer "B.Cu")
		(net "PCIE_IOM_B_TO_COMP_B_10_DN")
	)
	(segment
		(start 289.102038 -182.858156)
		(end 289.131502 -183.016906)
		(width 0.1651)
		(layer "B.Cu")
		(net "PCIE_IOM_B_TO_COMP_B_10_DN")
	)
	(segment
		(start 335.040732 -116.208556)
		(end 334.760316 -116.616734)
		(width 0.1651)
		(layer "B.Cu")
		(net "PCIE_IOM_B_TO_COMP_B_10_DN")
	)
	(segment
		(start 324.497954 -131.550664)
		(end 315.773054 -144.247362)
		(width 0.1651)
		(layer "B.Cu")
		(net "PCIE_IOM_B_TO_COMP_B_10_DN")
	)
	(segment
		(start 314.392056 -146.25701)
		(end 314.233052 -146.286474)
		(width 0.1651)
		(layer "B.Cu")
		(net "PCIE_IOM_B_TO_COMP_B_10_DN")
	)
	(segment
		(start 342.462358 -105.188766)
		(end 342.494362 -105.36174)
		(width 0.1651)
		(layer "B.Cu")
		(net "PCIE_IOM_B_TO_COMP_B_10_DN")
	)
	(segment
		(start 326.569578 -128.536192)
		(end 326.288908 -128.94437)
		(width 0.1651)
		(layer "B.Cu")
		(net "PCIE_IOM_B_TO_COMP_B_10_DN")
	)
	(segment
		(start 342.915748 -104.748584)
		(end 342.742774 -104.780588)
		(width 0.1651)
		(layer "B.Cu")
		(net "PCIE_IOM_B_TO_COMP_B_10_DN")
	)
	(segment
		(start 326.53986 -128.377188)
		(end 326.569578 -128.536192)
		(width 0.1651)
		(layer "B.Cu")
		(net "PCIE_IOM_B_TO_COMP_B_10_DN")
	)
	(segment
		(start 325.159116 -130.386836)
		(end 325.18858 -130.54584)
		(width 0.1651)
		(layer "B.Cu")
		(net "PCIE_IOM_B_TO_COMP_B_10_DN")
	)
	(segment
		(start 341.760302 -106.210354)
		(end 341.792306 -106.383328)
		(width 0.1651)
		(layer "B.Cu")
		(net "PCIE_IOM_B_TO_COMP_B_10_DN")
	)
	(segment
		(start 336.392266 -114.040158)
		(end 336.42173 -114.198908)
		(width 0.1651)
		(layer "B.Cu")
		(net "PCIE_IOM_B_TO_COMP_B_10_DN")
	)
	(segment
		(start 298.920154 -168.552368)
		(end 298.952158 -168.725596)
		(width 0.1651)
		(layer "B.Cu")
		(net "PCIE_IOM_B_TO_COMP_B_10_DN")
	)
	(segment
		(start 342.742774 -104.780588)
		(end 342.462358 -105.188766)
		(width 0.1651)
		(layer "B.Cu")
		(net "PCIE_IOM_B_TO_COMP_B_10_DN")
	)
	(segment
		(start 287.335468 -185.630566)
		(end 284.65907 -187.7822)
		(width 0.1651)
		(layer "B.Cu")
		(net "PCIE_IOM_B_TO_COMP_B_10_DN")
	)
	(segment
		(start 343.196418 -104.340152)
		(end 342.915748 -104.748584)
		(width 0.1651)
		(layer "B.Cu")
		(net "PCIE_IOM_B_TO_COMP_B_10_DN")
	)
	(segment
		(start 326.979534 -127.939546)
		(end 326.82053 -127.96901)
		(width 0.1651)
		(layer "B.Cu")
		(net "PCIE_IOM_B_TO_COMP_B_10_DN")
	)
	(segment
		(start 313.542426 -147.291298)
		(end 313.26201 -147.699476)
		(width 0.1651)
		(layer "B.Cu")
		(net "PCIE_IOM_B_TO_COMP_B_10_DN")
	)
	(segment
		(start 315.363098 -144.844008)
		(end 315.082428 -145.252186)
		(width 0.1651)
		(layer "B.Cu")
		(net "PCIE_IOM_B_TO_COMP_B_10_DN")
	)
	(segment
		(start 314.923424 -145.28165)
		(end 314.643008 -145.689828)
		(width 0.1651)
		(layer "B.Cu")
		(net "PCIE_IOM_B_TO_COMP_B_10_DN")
	)
	(segment
		(start 299.20057 -168.14419)
		(end 298.920154 -168.552368)
		(width 0.1651)
		(layer "B.Cu")
		(net "PCIE_IOM_B_TO_COMP_B_10_DN")
	)
	(segment
		(start 324.90791 -130.954018)
		(end 324.748906 -130.983482)
		(width 0.1651)
		(layer "B.Cu")
		(net "PCIE_IOM_B_TO_COMP_B_10_DN")
	)
	(segment
		(start 299.902626 -167.122602)
		(end 299.62221 -167.53078)
		(width 0.1651)
		(layer "B.Cu")
		(net "PCIE_IOM_B_TO_COMP_B_10_DN")
	)
	(segment
		(start 289.382454 -182.449724)
		(end 289.102038 -182.858156)
		(width 0.1651)
		(layer "B.Cu")
		(net "PCIE_IOM_B_TO_COMP_B_10_DN")
	)
	(segment
		(start 281.472894 -188.798454)
		(end 278.896572 -187.975748)
		(width 0.1651)
		(layer "B.Cu")
		(net "PCIE_IOM_B_TO_COMP_B_10_DN")
	)
	(segment
		(start 297.796712 -170.187366)
		(end 297.516042 -170.595544)
		(width 0.1651)
		(layer "B.Cu")
		(net "PCIE_IOM_B_TO_COMP_B_10_DN")
	)
	(segment
		(start 288.850832 -183.425084)
		(end 288.692082 -183.454548)
		(width 0.1651)
		(layer "B.Cu")
		(net "PCIE_IOM_B_TO_COMP_B_10_DN")
	)
	(segment
		(start 342.213692 -105.769918)
		(end 342.040718 -105.802176)
		(width 0.1651)
		(layer "B.Cu")
		(net "PCIE_IOM_B_TO_COMP_B_10_DN")
	)
	(segment
		(start 290.5125 -181.007258)
		(end 290.23183 -181.415436)
		(width 0.1651)
		(layer "B.Cu")
		(net "PCIE_IOM_B_TO_COMP_B_10_DN")
	)
	(segment
		(start 313.9821 -146.853656)
		(end 313.70143 -147.261834)
		(width 0.1651)
		(layer "B.Cu")
		(net "PCIE_IOM_B_TO_COMP_B_10_DN")
	)
	(segment
		(start 289.541458 -182.42026)
		(end 289.382454 -182.449724)
		(width 0.1651)
		(layer "B.Cu")
		(net "PCIE_IOM_B_TO_COMP_B_10_DN")
	)
	(segment
		(start 289.131502 -183.016906)
		(end 288.850832 -183.425084)
		(width 0.1651)
		(layer "B.Cu")
		(net "PCIE_IOM_B_TO_COMP_B_10_DN")
	)
	(segment
		(start 290.07308 -181.4449)
		(end 289.79241 -181.853332)
		(width 0.1651)
		(layer "B.Cu")
		(net "PCIE_IOM_B_TO_COMP_B_10_DN")
	)
	(segment
		(start 315.773054 -144.247362)
		(end 315.61405 -144.276826)
		(width 0.1651)
		(layer "B.Cu")
		(net "PCIE_IOM_B_TO_COMP_B_10_DN")
	)
	(segment
		(start 324.46849 -131.39166)
		(end 324.497954 -131.550664)
		(width 0.1651)
		(layer "B.Cu")
		(net "PCIE_IOM_B_TO_COMP_B_10_DN")
	)
	(segment
		(start 289.79241 -181.853332)
		(end 289.821874 -182.012082)
		(width 0.1651)
		(layer "B.Cu")
		(net "PCIE_IOM_B_TO_COMP_B_10_DN")
	)
	(segment
		(start 343.617804 -103.726996)
		(end 343.44483 -103.759)
		(width 0.1651)
		(layer "B.Cu")
		(net "PCIE_IOM_B_TO_COMP_B_10_DN")
	)
	(segment
		(start 341.792306 -106.383328)
		(end 336.831686 -113.602262)
		(width 0.1651)
		(layer "B.Cu")
		(net "PCIE_IOM_B_TO_COMP_B_10_DN")
	)
	(segment
		(start 315.61405 -144.276826)
		(end 315.33338 -144.685004)
		(width 0.1651)
		(layer "B.Cu")
		(net "PCIE_IOM_B_TO_COMP_B_10_DN")
	)
	(segment
		(start 279.423622 -174.162466)
		(end 278.750014 -174.499778)
		(width 0.1651)
		(layer "B.Cu")
		(net "PCIE_IOM_B_TO_COMP_B_10_DN")
	)
	(segment
		(start 288.692082 -183.454548)
		(end 288.411412 -183.86298)
		(width 0.1651)
		(layer "B.Cu")
		(net "PCIE_IOM_B_TO_COMP_B_10_DN")
	)
	(segment
		(start 290.483036 -180.848508)
		(end 290.5125 -181.007258)
		(width 0.1651)
		(layer "B.Cu")
		(net "PCIE_IOM_B_TO_COMP_B_10_DN")
	)
	(segment
		(start 290.23183 -181.415436)
		(end 290.07308 -181.4449)
		(width 0.1651)
		(layer "B.Cu")
		(net "PCIE_IOM_B_TO_COMP_B_10_DN")
	)
	(segment
		(start 334.35036 -117.21338)
		(end 326.979534 -127.939546)
		(width 0.1651)
		(layer "B.Cu")
		(net "PCIE_IOM_B_TO_COMP_B_10_DN")
	)
	(segment
		(start 288.411412 -183.86298)
		(end 288.440876 -184.02173)
		(width 0.1651)
		(layer "B.Cu")
		(net "PCIE_IOM_B_TO_COMP_B_10_DN")
	)
	(segment
		(start 298.250102 -169.74693)
		(end 297.969686 -170.155362)
		(width 0.1651)
		(layer "B.Cu")
		(net "PCIE_IOM_B_TO_COMP_B_10_DN")
	)
	(segment
		(start 326.129904 -128.973834)
		(end 325.849488 -129.382012)
		(width 0.1651)
		(layer "B.Cu")
		(net "PCIE_IOM_B_TO_COMP_B_10_DN")
	)
	(segment
		(start 371.110764 -63.718694)
		(end 343.617804 -103.726996)
		(width 0.1651)
		(layer "B.Cu")
		(net "PCIE_IOM_B_TO_COMP_B_10_DN")
	)
	(segment
		(start 299.654214 -167.704008)
		(end 299.373798 -168.112186)
		(width 0.1651)
		(layer "B.Cu")
		(net "PCIE_IOM_B_TO_COMP_B_10_DN")
	)
	(segment
		(start 325.849488 -129.382012)
		(end 325.878952 -129.541016)
		(width 0.1651)
		(layer "B.Cu")
		(net "PCIE_IOM_B_TO_COMP_B_10_DN")
	)
	(segment
		(start 385.750054 -23.35022)
		(end 385.750054 -22.962616)
		(width 0.1651)
		(layer "B.Cu")
		(net "PCIE_IOM_B_TO_COMP_B_10_DN")
	)
	(segment
		(start 334.320896 -117.05463)
		(end 334.35036 -117.21338)
		(width 0.1651)
		(layer "B.Cu")
		(net "PCIE_IOM_B_TO_COMP_B_10_DN")
	)
	(segment
		(start 313.26201 -147.699476)
		(end 313.291474 -147.85848)
		(width 0.1651)
		(layer "B.Cu")
		(net "PCIE_IOM_B_TO_COMP_B_10_DN")
	)
	(segment
		(start 335.731358 -115.203732)
		(end 335.450688 -115.61191)
		(width 0.1651)
		(layer "B.Cu")
		(net "PCIE_IOM_B_TO_COMP_B_10_DN")
	)
	(segment
		(start 325.878952 -129.541016)
		(end 325.598536 -129.949194)
		(width 0.1651)
		(layer "B.Cu")
		(net "PCIE_IOM_B_TO_COMP_B_10_DN")
	)
	(segment
		(start 278.896572 -187.975748)
		(end 275.338032 -185.113676)
		(width 0.1651)
		(layer "B.Cu")
		(net "PCIE_IOM_B_TO_COMP_B_10_DN")
	)
	(segment
		(start 297.5483 -170.768518)
		(end 290.922456 -180.410612)
		(width 0.1651)
		(layer "B.Cu")
		(net "PCIE_IOM_B_TO_COMP_B_10_DN")
	)
	(segment
		(start 315.082428 -145.252186)
		(end 314.923424 -145.28165)
		(width 0.1651)
		(layer "B.Cu")
		(net "PCIE_IOM_B_TO_COMP_B_10_DN")
	)
	(segment
		(start 386.503926 -23.013416)
		(end 386.503926 -34.324036)
		(width 0.1651)
		(layer "B.Cu")
		(net "PCIE_IOM_B_TO_COMP_B_10_DN")
	)
	(segment
		(start 275.338032 -185.113676)
		(end 274.401534 -181.56301)
		(width 0.1651)
		(layer "B.Cu")
		(net "PCIE_IOM_B_TO_COMP_B_10_DN")
	)
	(arc
		(start 279.277572 -173.72457)
		(mid 279.324385 -173.754824)
		(end 279.366472 -173.791372)
		(width 0.1651)
		(layer "B.Cu")
		(net "PCIE_IOM_B_TO_COMP_B_10_DN")
	)
	(arc
		(start 279.088342 -173.675802)
		(mid 279.18604 -173.688238)
		(end 279.277572 -173.72457)
		(width 0.1651)
		(layer "B.Cu")
		(net "PCIE_IOM_B_TO_COMP_B_10_DN")
	)
	(arc
		(start 279.467564 -173.892464)
		(mid 279.508792 -173.959804)
		(end 279.514808 -174.038514)
		(width 0.1651)
		(layer "B.Cu")
		(net "PCIE_IOM_B_TO_COMP_B_10_DN")
	)
	(arc
		(start 386.286756 -22.796246)
		(mid 386.440318 -22.859854)
		(end 386.503926 -23.013416)
		(width 0.1651)
		(layer "B.Cu")
		(net "PCIE_IOM_B_TO_COMP_B_10_DN")
	)
	(arc
		(start 385.750054 -22.962616)
		(mid 385.798783 -22.844975)
		(end 385.916424 -22.796246)
		(width 0.1651)
		(layer "B.Cu")
		(net "PCIE_IOM_B_TO_COMP_B_10_DN")
	)
	(arc
		(start 279.514808 -174.038514)
		(mid 279.484105 -174.111445)
		(end 279.423622 -174.162466)
		(width 0.1651)
		(layer "B.Cu")
		(net "PCIE_IOM_B_TO_COMP_B_10_DN")
	)
	(segment
		(start 235.726478 -27.054048)
		(end 236.525308 -27.054048)
		(width 0.1651)
		(layer "B.Cu")
		(net "PCIE_IOM_A_TO_COMP_A_9_DP")
	)
	(segment
		(start 252.642878 -60.212478)
		(end 247.507506 -86.631272)
		(width 0.1651)
		(layer "B.Cu")
		(net "PCIE_IOM_A_TO_COMP_A_9_DP")
	)
	(segment
		(start 237.389416 -169.83837)
		(end 238.05007 -169.499788)
		(width 0.1651)
		(layer "B.Cu")
		(net "PCIE_IOM_A_TO_COMP_A_9_DP")
	)
	(segment
		(start 142.87627 -32.022542)
		(end 143.472408 -32.424624)
		(width 0.1651)
		(layer "B.Cu")
		(net "PCIE_IOM_A_TO_COMP_A_9_DP")
	)
	(segment
		(start 237.525306 -28.054046)
		(end 241.024918 -28.054046)
		(width 0.1651)
		(layer "B.Cu")
		(net "PCIE_IOM_A_TO_COMP_A_9_DP")
	)
	(segment
		(start 247.406668 -33.277048)
		(end 252.642878 -60.212478)
		(width 0.1651)
		(layer "B.Cu")
		(net "PCIE_IOM_A_TO_COMP_A_9_DP")
	)
	(segment
		(start 237.218474 -169.860722)
		(end 237.233968 -169.863262)
		(width 0.1651)
		(layer "B.Cu")
		(net "PCIE_IOM_A_TO_COMP_A_9_DP")
	)
	(segment
		(start 243.00053 -29.054044)
		(end 245.697756 -30.743652)
		(width 0.1651)
		(layer "B.Cu")
		(net "PCIE_IOM_A_TO_COMP_A_9_DP")
	)
	(segment
		(start 142.595854 -22.173946)
		(end 142.595854 -31.596584)
		(width 0.1651)
		(layer "B.Cu")
		(net "PCIE_IOM_A_TO_COMP_A_9_DP")
	)
	(segment
		(start 247.507506 -86.631272)
		(end 245.266718 -89.953338)
		(width 0.1651)
		(layer "B.Cu")
		(net "PCIE_IOM_A_TO_COMP_A_9_DP")
	)
	(segment
		(start 231.511094 -102.627684)
		(end 223.812354 -142.230348)
		(width 0.1651)
		(layer "B.Cu")
		(net "PCIE_IOM_A_TO_COMP_A_9_DP")
	)
	(segment
		(start 241.024918 -28.054046)
		(end 241.163602 -28.192476)
		(width 0.1651)
		(layer "B.Cu")
		(net "PCIE_IOM_A_TO_COMP_A_9_DP")
	)
	(segment
		(start 226.596448 -156.552392)
		(end 234.845352 -168.783)
		(width 0.1651)
		(layer "B.Cu")
		(net "PCIE_IOM_A_TO_COMP_A_9_DP")
	)
	(segment
		(start 245.266718 -89.953338)
		(end 233.933238 -99.0346)
		(width 0.1651)
		(layer "B.Cu")
		(net "PCIE_IOM_A_TO_COMP_A_9_DP")
	)
	(segment
		(start 152.16378 -34.114232)
		(end 212.18144 -22.446996)
		(width 0.1651)
		(layer "B.Cu")
		(net "PCIE_IOM_A_TO_COMP_A_9_DP")
	)
	(segment
		(start 141.549882 -20.950174)
		(end 141.549882 -21.337778)
		(width 0.1651)
		(layer "B.Cu")
		(net "PCIE_IOM_A_TO_COMP_A_9_DP")
	)
	(segment
		(start 236.525308 -27.054048)
		(end 237.525306 -28.054046)
		(width 0.1651)
		(layer "B.Cu")
		(net "PCIE_IOM_A_TO_COMP_A_9_DP")
	)
	(segment
		(start 242.02517 -29.054044)
		(end 243.00053 -29.054044)
		(width 0.1651)
		(layer "B.Cu")
		(net "PCIE_IOM_A_TO_COMP_A_9_DP")
	)
	(segment
		(start 233.933238 -99.0346)
		(end 231.511094 -102.627684)
		(width 0.1651)
		(layer "B.Cu")
		(net "PCIE_IOM_A_TO_COMP_A_9_DP")
	)
	(segment
		(start 234.845352 -168.783)
		(end 235.621322 -169.380916)
		(width 0.1651)
		(layer "B.Cu")
		(net "PCIE_IOM_A_TO_COMP_A_9_DP")
	)
	(segment
		(start 141.716252 -21.504148)
		(end 141.926056 -21.504148)
		(width 0.1651)
		(layer "B.Cu")
		(net "PCIE_IOM_A_TO_COMP_A_9_DP")
	)
	(segment
		(start 212.18144 -22.446996)
		(end 235.726478 -27.054048)
		(width 0.1651)
		(layer "B.Cu")
		(net "PCIE_IOM_A_TO_COMP_A_9_DP")
	)
	(segment
		(start 235.621322 -169.380916)
		(end 236.388148 -169.38371)
		(width 0.1651)
		(layer "B.Cu")
		(net "PCIE_IOM_A_TO_COMP_A_9_DP")
	)
	(segment
		(start 223.812354 -142.230348)
		(end 226.596448 -156.552392)
		(width 0.1651)
		(layer "B.Cu")
		(net "PCIE_IOM_A_TO_COMP_A_9_DP")
	)
	(segment
		(start 143.472408 -32.424624)
		(end 152.16378 -34.114232)
		(width 0.1651)
		(layer "B.Cu")
		(net "PCIE_IOM_A_TO_COMP_A_9_DP")
	)
	(segment
		(start 245.697756 -30.743652)
		(end 247.406668 -33.277048)
		(width 0.1651)
		(layer "B.Cu")
		(net "PCIE_IOM_A_TO_COMP_A_9_DP")
	)
	(segment
		(start 236.873288 -169.584624)
		(end 237.078266 -169.789602)
		(width 0.1651)
		(layer "B.Cu")
		(net "PCIE_IOM_A_TO_COMP_A_9_DP")
	)
	(segment
		(start 142.595854 -31.596584)
		(end 142.87627 -32.022542)
		(width 0.1651)
		(layer "B.Cu")
		(net "PCIE_IOM_A_TO_COMP_A_9_DP")
	)
	(segment
		(start 241.163602 -28.192476)
		(end 242.02517 -29.054044)
		(width 0.1651)
		(layer "B.Cu")
		(net "PCIE_IOM_A_TO_COMP_A_9_DP")
	)
	(arc
		(start 236.718348 -169.468292)
		(mid 236.799931 -169.520977)
		(end 236.873288 -169.584624)
		(width 0.1651)
		(layer "B.Cu")
		(net "PCIE_IOM_A_TO_COMP_A_9_DP")
	)
	(arc
		(start 237.078266 -169.789602)
		(mid 237.142732 -169.836274)
		(end 237.218474 -169.860722)
		(width 0.1651)
		(layer "B.Cu")
		(net "PCIE_IOM_A_TO_COMP_A_9_DP")
	)
	(arc
		(start 236.388148 -169.38371)
		(mid 236.55859 -169.405154)
		(end 236.718348 -169.468292)
		(width 0.1651)
		(layer "B.Cu")
		(net "PCIE_IOM_A_TO_COMP_A_9_DP")
	)
	(arc
		(start 141.926056 -21.504148)
		(mid 142.399675 -21.700327)
		(end 142.595854 -22.173946)
		(width 0.1651)
		(layer "B.Cu")
		(net "PCIE_IOM_A_TO_COMP_A_9_DP")
	)
	(arc
		(start 141.549882 -21.337778)
		(mid 141.598611 -21.455419)
		(end 141.716252 -21.504148)
		(width 0.1651)
		(layer "B.Cu")
		(net "PCIE_IOM_A_TO_COMP_A_9_DP")
	)
	(arc
		(start 237.233968 -169.863262)
		(mid 237.313678 -169.863189)
		(end 237.389416 -169.83837)
		(width 0.1651)
		(layer "B.Cu")
		(net "PCIE_IOM_A_TO_COMP_A_9_DP")
	)
	(segment
		(start 234.629452 -168.985692)
		(end 235.521754 -169.673016)
		(width 0.1651)
		(layer "B.Cu")
		(net "PCIE_IOM_A_TO_COMP_A_9_DN")
	)
	(segment
		(start 232.632758 -166.229538)
		(end 232.791254 -166.260272)
		(width 0.1651)
		(layer "B.Cu")
		(net "PCIE_IOM_A_TO_COMP_A_9_DN")
	)
	(segment
		(start 235.521754 -169.673016)
		(end 236.388402 -169.67581)
		(width 0.1651)
		(layer "B.Cu")
		(net "PCIE_IOM_A_TO_COMP_A_9_DN")
	)
	(segment
		(start 236.40415 -27.346148)
		(end 237.404148 -28.346146)
		(width 0.1651)
		(layer "B.Cu")
		(net "PCIE_IOM_A_TO_COMP_A_9_DN")
	)
	(segment
		(start 212.181186 -22.744684)
		(end 235.69803 -27.346148)
		(width 0.1651)
		(layer "B.Cu")
		(net "PCIE_IOM_A_TO_COMP_A_9_DN")
	)
	(segment
		(start 152.16378 -34.41192)
		(end 212.181186 -22.744684)
		(width 0.1651)
		(layer "B.Cu")
		(net "PCIE_IOM_A_TO_COMP_A_9_DN")
	)
	(segment
		(start 142.303754 -22.173946)
		(end 142.303754 -31.684214)
		(width 0.1651)
		(layer "B.Cu")
		(net "PCIE_IOM_A_TO_COMP_A_9_DN")
	)
	(segment
		(start 223.514666 -142.230348)
		(end 226.320858 -156.666438)
		(width 0.1651)
		(layer "B.Cu")
		(net "PCIE_IOM_A_TO_COMP_A_9_DN")
	)
	(segment
		(start 233.47299 -167.271192)
		(end 233.750104 -167.681656)
		(width 0.1651)
		(layer "B.Cu")
		(net "PCIE_IOM_A_TO_COMP_A_9_DN")
	)
	(segment
		(start 247.231916 -86.517226)
		(end 245.049294 -89.753186)
		(width 0.1651)
		(layer "B.Cu")
		(net "PCIE_IOM_A_TO_COMP_A_9_DN")
	)
	(segment
		(start 236.666532 -169.79138)
		(end 236.767624 -169.892472)
		(width 0.1651)
		(layer "B.Cu")
		(net "PCIE_IOM_A_TO_COMP_A_9_DN")
	)
	(segment
		(start 232.355644 -165.81882)
		(end 232.632758 -166.229538)
		(width 0.1651)
		(layer "B.Cu")
		(net "PCIE_IOM_A_TO_COMP_A_9_DN")
	)
	(segment
		(start 234.603036 -168.946576)
		(end 234.629452 -168.985692)
		(width 0.1651)
		(layer "B.Cu")
		(net "PCIE_IOM_A_TO_COMP_A_9_DN")
	)
	(segment
		(start 234.154726 -168.281858)
		(end 234.603036 -168.946576)
		(width 0.1651)
		(layer "B.Cu")
		(net "PCIE_IOM_A_TO_COMP_A_9_DN")
	)
	(segment
		(start 231.951022 -165.218618)
		(end 232.109518 -165.249606)
		(width 0.1651)
		(layer "B.Cu")
		(net "PCIE_IOM_A_TO_COMP_A_9_DN")
	)
	(segment
		(start 241.904012 -29.346144)
		(end 242.916456 -29.346144)
		(width 0.1651)
		(layer "B.Cu")
		(net "PCIE_IOM_A_TO_COMP_A_9_DN")
	)
	(segment
		(start 233.715814 -98.834448)
		(end 231.235504 -102.513638)
		(width 0.1651)
		(layer "B.Cu")
		(net "PCIE_IOM_A_TO_COMP_A_9_DN")
	)
	(segment
		(start 231.673908 -164.8079)
		(end 231.951022 -165.218618)
		(width 0.1651)
		(layer "B.Cu")
		(net "PCIE_IOM_A_TO_COMP_A_9_DN")
	)
	(segment
		(start 252.34519 -60.212478)
		(end 247.231916 -86.517226)
		(width 0.1651)
		(layer "B.Cu")
		(net "PCIE_IOM_A_TO_COMP_A_9_DN")
	)
	(segment
		(start 143.358362 -32.700214)
		(end 152.16378 -34.41192)
		(width 0.1651)
		(layer "B.Cu")
		(net "PCIE_IOM_A_TO_COMP_A_9_DN")
	)
	(segment
		(start 232.791254 -166.260272)
		(end 233.068368 -166.67099)
		(width 0.1651)
		(layer "B.Cu")
		(net "PCIE_IOM_A_TO_COMP_A_9_DN")
	)
	(segment
		(start 142.303754 -31.684214)
		(end 142.664434 -32.232092)
		(width 0.1651)
		(layer "B.Cu")
		(net "PCIE_IOM_A_TO_COMP_A_9_DN")
	)
	(segment
		(start 233.719116 -167.840406)
		(end 233.995976 -168.251124)
		(width 0.1651)
		(layer "B.Cu")
		(net "PCIE_IOM_A_TO_COMP_A_9_DN")
	)
	(segment
		(start 245.049294 -89.753186)
		(end 233.715814 -98.834448)
		(width 0.1651)
		(layer "B.Cu")
		(net "PCIE_IOM_A_TO_COMP_A_9_DN")
	)
	(segment
		(start 233.995976 -168.251124)
		(end 234.154726 -168.281858)
		(width 0.1651)
		(layer "B.Cu")
		(net "PCIE_IOM_A_TO_COMP_A_9_DN")
	)
	(segment
		(start 231.235504 -102.513638)
		(end 223.514666 -142.230348)
		(width 0.1651)
		(layer "B.Cu")
		(net "PCIE_IOM_A_TO_COMP_A_9_DN")
	)
	(segment
		(start 233.03738 -166.829486)
		(end 233.31424 -167.240204)
		(width 0.1651)
		(layer "B.Cu")
		(net "PCIE_IOM_A_TO_COMP_A_9_DN")
	)
	(segment
		(start 233.068368 -166.67099)
		(end 233.03738 -166.829486)
		(width 0.1651)
		(layer "B.Cu")
		(net "PCIE_IOM_A_TO_COMP_A_9_DN")
	)
	(segment
		(start 142.664434 -32.232092)
		(end 143.358362 -32.700214)
		(width 0.1651)
		(layer "B.Cu")
		(net "PCIE_IOM_A_TO_COMP_A_9_DN")
	)
	(segment
		(start 232.386632 -165.66007)
		(end 232.355644 -165.81882)
		(width 0.1651)
		(layer "B.Cu")
		(net "PCIE_IOM_A_TO_COMP_A_9_DN")
	)
	(segment
		(start 226.320858 -156.666438)
		(end 231.704896 -164.649404)
		(width 0.1651)
		(layer "B.Cu")
		(net "PCIE_IOM_A_TO_COMP_A_9_DN")
	)
	(segment
		(start 235.69803 -27.346148)
		(end 236.40415 -27.346148)
		(width 0.1651)
		(layer "B.Cu")
		(net "PCIE_IOM_A_TO_COMP_A_9_DN")
	)
	(segment
		(start 141.549882 -22.350222)
		(end 141.549882 -21.962618)
		(width 0.1651)
		(layer "B.Cu")
		(net "PCIE_IOM_A_TO_COMP_A_9_DN")
	)
	(segment
		(start 141.716252 -21.796248)
		(end 141.926056 -21.796248)
		(width 0.1651)
		(layer "B.Cu")
		(net "PCIE_IOM_A_TO_COMP_A_9_DN")
	)
	(segment
		(start 233.31424 -167.240204)
		(end 233.47299 -167.271192)
		(width 0.1651)
		(layer "B.Cu")
		(net "PCIE_IOM_A_TO_COMP_A_9_DN")
	)
	(segment
		(start 231.704896 -164.649404)
		(end 231.673908 -164.8079)
		(width 0.1651)
		(layer "B.Cu")
		(net "PCIE_IOM_A_TO_COMP_A_9_DN")
	)
	(segment
		(start 236.723682 -170.162474)
		(end 236.050074 -170.499786)
		(width 0.1651)
		(layer "B.Cu")
		(net "PCIE_IOM_A_TO_COMP_A_9_DN")
	)
	(segment
		(start 240.904014 -28.346146)
		(end 241.904012 -29.346144)
		(width 0.1651)
		(layer "B.Cu")
		(net "PCIE_IOM_A_TO_COMP_A_9_DN")
	)
	(segment
		(start 247.131078 -33.391348)
		(end 252.34519 -60.212478)
		(width 0.1651)
		(layer "B.Cu")
		(net "PCIE_IOM_A_TO_COMP_A_9_DN")
	)
	(segment
		(start 237.404148 -28.346146)
		(end 240.904014 -28.346146)
		(width 0.1651)
		(layer "B.Cu")
		(net "PCIE_IOM_A_TO_COMP_A_9_DN")
	)
	(segment
		(start 242.916456 -29.346144)
		(end 245.489984 -30.958536)
		(width 0.1651)
		(layer "B.Cu")
		(net "PCIE_IOM_A_TO_COMP_A_9_DN")
	)
	(segment
		(start 245.489984 -30.958536)
		(end 247.131078 -33.391348)
		(width 0.1651)
		(layer "B.Cu")
		(net "PCIE_IOM_A_TO_COMP_A_9_DN")
	)
	(segment
		(start 233.750104 -167.681656)
		(end 233.719116 -167.840406)
		(width 0.1651)
		(layer "B.Cu")
		(net "PCIE_IOM_A_TO_COMP_A_9_DN")
	)
	(segment
		(start 232.109518 -165.249606)
		(end 232.386632 -165.66007)
		(width 0.1651)
		(layer "B.Cu")
		(net "PCIE_IOM_A_TO_COMP_A_9_DN")
	)
	(arc
		(start 236.767624 -169.892472)
		(mid 236.808852 -169.959812)
		(end 236.814868 -170.038522)
		(width 0.1651)
		(layer "B.Cu")
		(net "PCIE_IOM_A_TO_COMP_A_9_DN")
	)
	(arc
		(start 236.388402 -169.67581)
		(mid 236.4861 -169.688246)
		(end 236.577632 -169.724578)
		(width 0.1651)
		(layer "B.Cu")
		(net "PCIE_IOM_A_TO_COMP_A_9_DN")
	)
	(arc
		(start 141.549882 -21.962618)
		(mid 141.598611 -21.844977)
		(end 141.716252 -21.796248)
		(width 0.1651)
		(layer "B.Cu")
		(net "PCIE_IOM_A_TO_COMP_A_9_DN")
	)
	(arc
		(start 236.814868 -170.038522)
		(mid 236.784165 -170.111453)
		(end 236.723682 -170.162474)
		(width 0.1651)
		(layer "B.Cu")
		(net "PCIE_IOM_A_TO_COMP_A_9_DN")
	)
	(arc
		(start 236.577632 -169.724578)
		(mid 236.624445 -169.754832)
		(end 236.666532 -169.79138)
		(width 0.1651)
		(layer "B.Cu")
		(net "PCIE_IOM_A_TO_COMP_A_9_DN")
	)
	(arc
		(start 141.926056 -21.796248)
		(mid 142.193129 -21.906873)
		(end 142.303754 -22.173946)
		(width 0.1651)
		(layer "B.Cu")
		(net "PCIE_IOM_A_TO_COMP_A_9_DN")
	)
	(segment
		(start 236.873288 -165.584632)
		(end 237.078266 -165.78961)
		(width 0.1651)
		(layer "B.Cu")
		(net "PCIE_IOM_A_TO_COMP_A_8_DP")
	)
	(segment
		(start 225.55327 -142.335504)
		(end 226.713796 -148.30552)
		(width 0.1651)
		(layer "B.Cu")
		(net "PCIE_IOM_A_TO_COMP_A_8_DP")
	)
	(segment
		(start 249.071892 -87.191088)
		(end 246.526812 -90.965274)
		(width 0.1651)
		(layer "B.Cu")
		(net "PCIE_IOM_A_TO_COMP_A_8_DP")
	)
	(segment
		(start 235.339382 -99.9617)
		(end 233.16692 -103.181912)
		(width 0.1651)
		(layer "B.Cu")
		(net "PCIE_IOM_A_TO_COMP_A_8_DP")
	)
	(segment
		(start 144.38503 -22.504146)
		(end 155.128722 -20.351242)
		(width 0.1651)
		(layer "B.Cu")
		(net "PCIE_IOM_A_TO_COMP_A_8_DP")
	)
	(segment
		(start 143.34998 -21.950172)
		(end 143.34998 -22.337776)
		(width 0.1651)
		(layer "B.Cu")
		(net "PCIE_IOM_A_TO_COMP_A_8_DP")
	)
	(segment
		(start 236.17682 -165.383718)
		(end 236.388148 -165.383718)
		(width 0.1651)
		(layer "B.Cu")
		(net "PCIE_IOM_A_TO_COMP_A_8_DP")
	)
	(segment
		(start 184.545224 -26.197306)
		(end 212.32368 -20.37842)
		(width 0.1651)
		(layer "B.Cu")
		(net "PCIE_IOM_A_TO_COMP_A_8_DP")
	)
	(segment
		(start 235.621322 -165.380924)
		(end 236.17682 -165.383718)
		(width 0.1651)
		(layer "B.Cu")
		(net "PCIE_IOM_A_TO_COMP_A_8_DP")
	)
	(segment
		(start 212.32368 -20.37842)
		(end 224.132902 -22.724872)
		(width 0.1651)
		(layer "B.Cu")
		(net "PCIE_IOM_A_TO_COMP_A_8_DP")
	)
	(segment
		(start 236.525054 -25.054052)
		(end 237.525052 -26.05405)
		(width 0.1651)
		(layer "B.Cu")
		(net "PCIE_IOM_A_TO_COMP_A_8_DP")
	)
	(segment
		(start 235.086906 -164.96919)
		(end 235.621322 -165.380924)
		(width 0.1651)
		(layer "B.Cu")
		(net "PCIE_IOM_A_TO_COMP_A_8_DP")
	)
	(segment
		(start 248.865898 -32.21482)
		(end 248.865898 -32.214566)
		(width 0.1651)
		(layer "B.Cu")
		(net "PCIE_IOM_A_TO_COMP_A_8_DP")
	)
	(segment
		(start 242.02517 -27.054048)
		(end 242.926616 -27.054048)
		(width 0.1651)
		(layer "B.Cu")
		(net "PCIE_IOM_A_TO_COMP_A_8_DP")
	)
	(segment
		(start 235.855256 -25.054052)
		(end 236.525054 -25.054052)
		(width 0.1651)
		(layer "B.Cu")
		(net "PCIE_IOM_A_TO_COMP_A_8_DP")
	)
	(segment
		(start 248.865898 -32.214566)
		(end 254.312674 -60.227718)
		(width 0.1651)
		(layer "B.Cu")
		(net "PCIE_IOM_A_TO_COMP_A_8_DP")
	)
	(segment
		(start 226.713796 -148.30552)
		(end 227.874068 -154.275028)
		(width 0.1651)
		(layer "B.Cu")
		(net "PCIE_IOM_A_TO_COMP_A_8_DP")
	)
	(segment
		(start 242.926616 -27.054048)
		(end 247.183148 -29.719524)
		(width 0.1651)
		(layer "B.Cu")
		(net "PCIE_IOM_A_TO_COMP_A_8_DP")
	)
	(segment
		(start 227.874068 -154.275028)
		(end 235.086906 -164.96919)
		(width 0.1651)
		(layer "B.Cu")
		(net "PCIE_IOM_A_TO_COMP_A_8_DP")
	)
	(segment
		(start 237.218474 -165.86073)
		(end 237.233968 -165.86327)
		(width 0.1651)
		(layer "B.Cu")
		(net "PCIE_IOM_A_TO_COMP_A_8_DP")
	)
	(segment
		(start 237.525052 -26.05405)
		(end 241.025172 -26.05405)
		(width 0.1651)
		(layer "B.Cu")
		(net "PCIE_IOM_A_TO_COMP_A_8_DP")
	)
	(segment
		(start 224.132902 -22.724872)
		(end 235.855256 -25.054052)
		(width 0.1651)
		(layer "B.Cu")
		(net "PCIE_IOM_A_TO_COMP_A_8_DP")
	)
	(segment
		(start 247.183148 -29.719524)
		(end 248.865898 -32.21482)
		(width 0.1651)
		(layer "B.Cu")
		(net "PCIE_IOM_A_TO_COMP_A_8_DP")
	)
	(segment
		(start 246.526812 -90.965274)
		(end 235.339382 -99.9617)
		(width 0.1651)
		(layer "B.Cu")
		(net "PCIE_IOM_A_TO_COMP_A_8_DP")
	)
	(segment
		(start 233.16692 -103.181912)
		(end 225.55327 -142.335504)
		(width 0.1651)
		(layer "B.Cu")
		(net "PCIE_IOM_A_TO_COMP_A_8_DP")
	)
	(segment
		(start 155.128722 -20.351242)
		(end 184.545224 -26.197306)
		(width 0.1651)
		(layer "B.Cu")
		(net "PCIE_IOM_A_TO_COMP_A_8_DP")
	)
	(segment
		(start 143.51635 -22.504146)
		(end 144.38503 -22.504146)
		(width 0.1651)
		(layer "B.Cu")
		(net "PCIE_IOM_A_TO_COMP_A_8_DP")
	)
	(segment
		(start 254.312674 -60.227718)
		(end 249.071892 -87.191088)
		(width 0.1651)
		(layer "B.Cu")
		(net "PCIE_IOM_A_TO_COMP_A_8_DP")
	)
	(segment
		(start 241.025172 -26.05405)
		(end 242.02517 -27.054048)
		(width 0.1651)
		(layer "B.Cu")
		(net "PCIE_IOM_A_TO_COMP_A_8_DP")
	)
	(segment
		(start 237.389416 -165.838378)
		(end 238.05007 -165.499796)
		(width 0.1651)
		(layer "B.Cu")
		(net "PCIE_IOM_A_TO_COMP_A_8_DP")
	)
	(arc
		(start 236.388148 -165.383718)
		(mid 236.55859 -165.405162)
		(end 236.718348 -165.4683)
		(width 0.1651)
		(layer "B.Cu")
		(net "PCIE_IOM_A_TO_COMP_A_8_DP")
	)
	(arc
		(start 143.34998 -22.337776)
		(mid 143.398709 -22.455417)
		(end 143.51635 -22.504146)
		(width 0.1651)
		(layer "B.Cu")
		(net "PCIE_IOM_A_TO_COMP_A_8_DP")
	)
	(arc
		(start 237.233968 -165.86327)
		(mid 237.313678 -165.863197)
		(end 237.389416 -165.838378)
		(width 0.1651)
		(layer "B.Cu")
		(net "PCIE_IOM_A_TO_COMP_A_8_DP")
	)
	(arc
		(start 236.718348 -165.4683)
		(mid 236.799931 -165.520985)
		(end 236.873288 -165.584632)
		(width 0.1651)
		(layer "B.Cu")
		(net "PCIE_IOM_A_TO_COMP_A_8_DP")
	)
	(arc
		(start 237.078266 -165.78961)
		(mid 237.142732 -165.836282)
		(end 237.218474 -165.86073)
		(width 0.1651)
		(layer "B.Cu")
		(net "PCIE_IOM_A_TO_COMP_A_8_DP")
	)
	(segment
		(start 233.071924 -162.708844)
		(end 233.230674 -162.739578)
		(width 0.1651)
		(layer "B.Cu")
		(net "PCIE_IOM_A_TO_COMP_A_8_DN")
	)
	(segment
		(start 143.34998 -23.35022)
		(end 143.34998 -22.962616)
		(width 0.1651)
		(layer "B.Cu")
		(net "PCIE_IOM_A_TO_COMP_A_8_DN")
	)
	(segment
		(start 233.230674 -162.739578)
		(end 233.507534 -163.150296)
		(width 0.1651)
		(layer "B.Cu")
		(net "PCIE_IOM_A_TO_COMP_A_8_DN")
	)
	(segment
		(start 233.4768 -163.309046)
		(end 233.75366 -163.71951)
		(width 0.1651)
		(layer "B.Cu")
		(net "PCIE_IOM_A_TO_COMP_A_8_DN")
	)
	(segment
		(start 144.41424 -22.796246)
		(end 155.128976 -20.649184)
		(width 0.1651)
		(layer "B.Cu")
		(net "PCIE_IOM_A_TO_COMP_A_8_DN")
	)
	(segment
		(start 232.89133 -103.067612)
		(end 225.255582 -142.335504)
		(width 0.1651)
		(layer "B.Cu")
		(net "PCIE_IOM_A_TO_COMP_A_8_DN")
	)
	(segment
		(start 232.548938 -161.728912)
		(end 232.825798 -162.13963)
		(width 0.1651)
		(layer "B.Cu")
		(net "PCIE_IOM_A_TO_COMP_A_8_DN")
	)
	(segment
		(start 254.014986 -60.227718)
		(end 248.796302 -87.077042)
		(width 0.1651)
		(layer "B.Cu")
		(net "PCIE_IOM_A_TO_COMP_A_8_DN")
	)
	(segment
		(start 235.121704 -99.761548)
		(end 232.89133 -103.067612)
		(width 0.1651)
		(layer "B.Cu")
		(net "PCIE_IOM_A_TO_COMP_A_8_DN")
	)
	(segment
		(start 234.871006 -165.171882)
		(end 235.521754 -165.673024)
		(width 0.1651)
		(layer "B.Cu")
		(net "PCIE_IOM_A_TO_COMP_A_8_DN")
	)
	(segment
		(start 232.113328 -161.28746)
		(end 232.390188 -161.697924)
		(width 0.1651)
		(layer "B.Cu")
		(net "PCIE_IOM_A_TO_COMP_A_8_DN")
	)
	(segment
		(start 241.904012 -27.346148)
		(end 242.842542 -27.346148)
		(width 0.1651)
		(layer "B.Cu")
		(net "PCIE_IOM_A_TO_COMP_A_8_DN")
	)
	(segment
		(start 225.255582 -142.335504)
		(end 227.598478 -154.389074)
		(width 0.1651)
		(layer "B.Cu")
		(net "PCIE_IOM_A_TO_COMP_A_8_DN")
	)
	(segment
		(start 235.521754 -165.673024)
		(end 236.068616 -165.675818)
		(width 0.1651)
		(layer "B.Cu")
		(net "PCIE_IOM_A_TO_COMP_A_8_DN")
	)
	(segment
		(start 233.91241 -163.750498)
		(end 234.18927 -164.161216)
		(width 0.1651)
		(layer "B.Cu")
		(net "PCIE_IOM_A_TO_COMP_A_8_DN")
	)
	(segment
		(start 240.904014 -26.34615)
		(end 241.904012 -27.346148)
		(width 0.1651)
		(layer "B.Cu")
		(net "PCIE_IOM_A_TO_COMP_A_8_DN")
	)
	(segment
		(start 234.158536 -164.319712)
		(end 234.435396 -164.73043)
		(width 0.1651)
		(layer "B.Cu")
		(net "PCIE_IOM_A_TO_COMP_A_8_DN")
	)
	(segment
		(start 234.435396 -164.73043)
		(end 234.594146 -164.761164)
		(width 0.1651)
		(layer "B.Cu")
		(net "PCIE_IOM_A_TO_COMP_A_8_DN")
	)
	(segment
		(start 246.975376 -29.934408)
		(end 248.590308 -32.328866)
		(width 0.1651)
		(layer "B.Cu")
		(net "PCIE_IOM_A_TO_COMP_A_8_DN")
	)
	(segment
		(start 234.594146 -164.761164)
		(end 234.871006 -165.171882)
		(width 0.1651)
		(layer "B.Cu")
		(net "PCIE_IOM_A_TO_COMP_A_8_DN")
	)
	(segment
		(start 234.18927 -164.161216)
		(end 234.158536 -164.319712)
		(width 0.1651)
		(layer "B.Cu")
		(net "PCIE_IOM_A_TO_COMP_A_8_DN")
	)
	(segment
		(start 248.796302 -87.077042)
		(end 246.309134 -90.765122)
		(width 0.1651)
		(layer "B.Cu")
		(net "PCIE_IOM_A_TO_COMP_A_8_DN")
	)
	(segment
		(start 237.403894 -26.34615)
		(end 240.904014 -26.34615)
		(width 0.1651)
		(layer "B.Cu")
		(net "PCIE_IOM_A_TO_COMP_A_8_DN")
	)
	(segment
		(start 233.507534 -163.150296)
		(end 233.4768 -163.309046)
		(width 0.1651)
		(layer "B.Cu")
		(net "PCIE_IOM_A_TO_COMP_A_8_DN")
	)
	(segment
		(start 232.795064 -162.298126)
		(end 233.071924 -162.708844)
		(width 0.1651)
		(layer "B.Cu")
		(net "PCIE_IOM_A_TO_COMP_A_8_DN")
	)
	(segment
		(start 235.8263 -25.346152)
		(end 236.403896 -25.346152)
		(width 0.1651)
		(layer "B.Cu")
		(net "PCIE_IOM_A_TO_COMP_A_8_DN")
	)
	(segment
		(start 232.390188 -161.697924)
		(end 232.548938 -161.728912)
		(width 0.1651)
		(layer "B.Cu")
		(net "PCIE_IOM_A_TO_COMP_A_8_DN")
	)
	(segment
		(start 232.144062 -161.12871)
		(end 232.113328 -161.28746)
		(width 0.1651)
		(layer "B.Cu")
		(net "PCIE_IOM_A_TO_COMP_A_8_DN")
	)
	(segment
		(start 232.825798 -162.13963)
		(end 232.795064 -162.298126)
		(width 0.1651)
		(layer "B.Cu")
		(net "PCIE_IOM_A_TO_COMP_A_8_DN")
	)
	(segment
		(start 242.842542 -27.346148)
		(end 246.975376 -29.934408)
		(width 0.1651)
		(layer "B.Cu")
		(net "PCIE_IOM_A_TO_COMP_A_8_DN")
	)
	(segment
		(start 236.666532 -165.791388)
		(end 236.767624 -165.89248)
		(width 0.1651)
		(layer "B.Cu")
		(net "PCIE_IOM_A_TO_COMP_A_8_DN")
	)
	(segment
		(start 212.325204 -20.676616)
		(end 235.8263 -25.346152)
		(width 0.1651)
		(layer "B.Cu")
		(net "PCIE_IOM_A_TO_COMP_A_8_DN")
	)
	(segment
		(start 227.598478 -154.389074)
		(end 232.144062 -161.12871)
		(width 0.1651)
		(layer "B.Cu")
		(net "PCIE_IOM_A_TO_COMP_A_8_DN")
	)
	(segment
		(start 236.723682 -166.162482)
		(end 236.050074 -166.499794)
		(width 0.1651)
		(layer "B.Cu")
		(net "PCIE_IOM_A_TO_COMP_A_8_DN")
	)
	(segment
		(start 236.068616 -165.675818)
		(end 236.388402 -165.675818)
		(width 0.1651)
		(layer "B.Cu")
		(net "PCIE_IOM_A_TO_COMP_A_8_DN")
	)
	(segment
		(start 143.51635 -22.796246)
		(end 144.41424 -22.796246)
		(width 0.1651)
		(layer "B.Cu")
		(net "PCIE_IOM_A_TO_COMP_A_8_DN")
	)
	(segment
		(start 248.590308 -32.328866)
		(end 254.014986 -60.227718)
		(width 0.1651)
		(layer "B.Cu")
		(net "PCIE_IOM_A_TO_COMP_A_8_DN")
	)
	(segment
		(start 184.546748 -26.495502)
		(end 212.325204 -20.676616)
		(width 0.1651)
		(layer "B.Cu")
		(net "PCIE_IOM_A_TO_COMP_A_8_DN")
	)
	(segment
		(start 236.403896 -25.346152)
		(end 237.403894 -26.34615)
		(width 0.1651)
		(layer "B.Cu")
		(net "PCIE_IOM_A_TO_COMP_A_8_DN")
	)
	(segment
		(start 155.128976 -20.649184)
		(end 184.546748 -26.495502)
		(width 0.1651)
		(layer "B.Cu")
		(net "PCIE_IOM_A_TO_COMP_A_8_DN")
	)
	(segment
		(start 233.75366 -163.71951)
		(end 233.91241 -163.750498)
		(width 0.1651)
		(layer "B.Cu")
		(net "PCIE_IOM_A_TO_COMP_A_8_DN")
	)
	(segment
		(start 246.309134 -90.765122)
		(end 235.121704 -99.761548)
		(width 0.1651)
		(layer "B.Cu")
		(net "PCIE_IOM_A_TO_COMP_A_8_DN")
	)
	(arc
		(start 236.388402 -165.675818)
		(mid 236.4861 -165.688254)
		(end 236.577632 -165.724586)
		(width 0.1651)
		(layer "B.Cu")
		(net "PCIE_IOM_A_TO_COMP_A_8_DN")
	)
	(arc
		(start 236.814868 -166.03853)
		(mid 236.784165 -166.111461)
		(end 236.723682 -166.162482)
		(width 0.1651)
		(layer "B.Cu")
		(net "PCIE_IOM_A_TO_COMP_A_8_DN")
	)
	(arc
		(start 143.34998 -22.962616)
		(mid 143.398709 -22.844975)
		(end 143.51635 -22.796246)
		(width 0.1651)
		(layer "B.Cu")
		(net "PCIE_IOM_A_TO_COMP_A_8_DN")
	)
	(arc
		(start 236.577632 -165.724586)
		(mid 236.624445 -165.75484)
		(end 236.666532 -165.791388)
		(width 0.1651)
		(layer "B.Cu")
		(net "PCIE_IOM_A_TO_COMP_A_8_DN")
	)
	(arc
		(start 236.767624 -165.89248)
		(mid 236.808852 -165.95982)
		(end 236.814868 -166.03853)
		(width 0.1651)
		(layer "B.Cu")
		(net "PCIE_IOM_A_TO_COMP_A_8_DN")
	)
	(segment
		(start 108.983526 -21.504148)
		(end 108.63326 -21.504148)
		(width 0.1651)
		(layer "B.Cu")
		(net "PCIE_IOM_A_TO_COMP_A_23_DP")
	)
	(segment
		(start 235.117386 -83.346036)
		(end 236.329474 -83.346036)
		(width 0.1651)
		(layer "B.Cu")
		(net "PCIE_IOM_A_TO_COMP_A_23_DP")
	)
	(segment
		(start 237.449868 -81.924906)
		(end 237.332266 -81.807304)
		(width 0.1651)
		(layer "B.Cu")
		(net "PCIE_IOM_A_TO_COMP_A_23_DP")
	)
	(segment
		(start 206.009494 -85.925406)
		(end 235.117386 -83.346036)
		(width 0.1651)
		(layer "B.Cu")
		(net "PCIE_IOM_A_TO_COMP_A_23_DP")
	)
	(segment
		(start 236.918754 -83.101942)
		(end 237.449868 -82.570574)
		(width 0.1651)
		(layer "B.Cu")
		(net "PCIE_IOM_A_TO_COMP_A_23_DP")
	)
	(segment
		(start 237.332266 -81.807304)
		(end 237.33252 -81.807304)
		(width 0.1651)
		(layer "B.Cu")
		(net "PCIE_IOM_A_TO_COMP_A_23_DP")
	)
	(segment
		(start 109.149896 -20.950174)
		(end 109.149896 -21.337778)
		(width 0.1651)
		(layer "B.Cu")
		(net "PCIE_IOM_A_TO_COMP_A_23_DP")
	)
	(segment
		(start 107.8103 -30.16377)
		(end 109.084872 -36.240974)
		(width 0.1651)
		(layer "B.Cu")
		(net "PCIE_IOM_A_TO_COMP_A_23_DP")
	)
	(segment
		(start 123.336558 -57.771284)
		(end 148.110702 -74.145394)
		(width 0.1651)
		(layer "B.Cu")
		(net "PCIE_IOM_A_TO_COMP_A_23_DP")
	)
	(segment
		(start 109.084872 -36.24072)
		(end 123.336558 -57.771284)
		(width 0.1651)
		(layer "B.Cu")
		(net "PCIE_IOM_A_TO_COMP_A_23_DP")
	)
	(segment
		(start 109.084872 -36.240974)
		(end 109.084872 -36.24072)
		(width 0.1651)
		(layer "B.Cu")
		(net "PCIE_IOM_A_TO_COMP_A_23_DP")
	)
	(segment
		(start 237.376462 -81.537302)
		(end 238.05007 -81.19999)
		(width 0.1651)
		(layer "B.Cu")
		(net "PCIE_IOM_A_TO_COMP_A_23_DP")
	)
	(segment
		(start 107.8103 -22.327108)
		(end 107.8103 -30.16377)
		(width 0.1651)
		(layer "B.Cu")
		(net "PCIE_IOM_A_TO_COMP_A_23_DP")
	)
	(segment
		(start 148.110702 -74.145394)
		(end 206.009494 -85.925406)
		(width 0.1651)
		(layer "B.Cu")
		(net "PCIE_IOM_A_TO_COMP_A_23_DP")
	)
	(segment
		(start 237.52429 -82.390996)
		(end 237.52429 -82.104484)
		(width 0.1651)
		(layer "B.Cu")
		(net "PCIE_IOM_A_TO_COMP_A_23_DP")
	)
	(arc
		(start 237.301786 -81.765394)
		(mid 237.285179 -81.714646)
		(end 237.285276 -81.661254)
		(width 0.1651)
		(layer "B.Cu")
		(net "PCIE_IOM_A_TO_COMP_A_23_DP")
	)
	(arc
		(start 236.329474 -83.346036)
		(mid 236.648392 -83.282599)
		(end 236.918754 -83.101942)
		(width 0.1651)
		(layer "B.Cu")
		(net "PCIE_IOM_A_TO_COMP_A_23_DP")
	)
	(arc
		(start 109.149896 -21.337778)
		(mid 109.101167 -21.455419)
		(end 108.983526 -21.504148)
		(width 0.1651)
		(layer "B.Cu")
		(net "PCIE_IOM_A_TO_COMP_A_23_DP")
	)
	(arc
		(start 108.63326 -21.504148)
		(mid 108.051339 -21.745187)
		(end 107.8103 -22.327108)
		(width 0.1651)
		(layer "B.Cu")
		(net "PCIE_IOM_A_TO_COMP_A_23_DP")
	)
	(arc
		(start 237.449868 -82.570574)
		(mid 237.504974 -82.488197)
		(end 237.52429 -82.390996)
		(width 0.1651)
		(layer "B.Cu")
		(net "PCIE_IOM_A_TO_COMP_A_23_DP")
	)
	(arc
		(start 237.33252 -81.807304)
		(mid 237.315525 -81.787542)
		(end 237.301786 -81.765394)
		(width 0.1651)
		(layer "B.Cu")
		(net "PCIE_IOM_A_TO_COMP_A_23_DP")
	)
	(arc
		(start 237.52429 -82.104484)
		(mid 237.50494 -82.007297)
		(end 237.449868 -81.924906)
		(width 0.1651)
		(layer "B.Cu")
		(net "PCIE_IOM_A_TO_COMP_A_23_DP")
	)
	(arc
		(start 237.285276 -81.661254)
		(mid 237.315979 -81.588323)
		(end 237.376462 -81.537302)
		(width 0.1651)
		(layer "B.Cu")
		(net "PCIE_IOM_A_TO_COMP_A_23_DP")
	)
	(segment
		(start 138.900916 -67.708018)
		(end 139.314174 -67.981068)
		(width 0.1651)
		(layer "B.Cu")
		(net "PCIE_IOM_A_TO_COMP_A_23_DN")
	)
	(segment
		(start 109.359446 -36.126166)
		(end 123.547378 -57.560464)
		(width 0.1651)
		(layer "B.Cu")
		(net "PCIE_IOM_A_TO_COMP_A_23_DN")
	)
	(segment
		(start 236.88167 -81.839054)
		(end 236.866176 -81.836514)
		(width 0.1651)
		(layer "B.Cu")
		(net "PCIE_IOM_A_TO_COMP_A_23_DN")
	)
	(segment
		(start 237.23219 -82.306668)
		(end 237.23219 -82.188812)
		(width 0.1651)
		(layer "B.Cu")
		(net "PCIE_IOM_A_TO_COMP_A_23_DN")
	)
	(segment
		(start 136.834372 -66.2051)
		(end 136.86663 -66.363596)
		(width 0.1651)
		(layer "B.Cu")
		(net "PCIE_IOM_A_TO_COMP_A_23_DN")
	)
	(segment
		(start 148.224494 -73.870312)
		(end 203.596748 -85.136228)
		(width 0.1651)
		(layer "B.Cu")
		(net "PCIE_IOM_A_TO_COMP_A_23_DN")
	)
	(segment
		(start 226.089464 -83.852512)
		(end 226.582986 -83.808824)
		(width 0.1651)
		(layer "B.Cu")
		(net "PCIE_IOM_A_TO_COMP_A_23_DN")
	)
	(segment
		(start 135.245602 -65.29197)
		(end 135.403844 -65.259712)
		(width 0.1651)
		(layer "B.Cu")
		(net "PCIE_IOM_A_TO_COMP_A_23_DN")
	)
	(segment
		(start 215.88222 -84.632038)
		(end 216.375742 -84.58835)
		(width 0.1651)
		(layer "B.Cu")
		(net "PCIE_IOM_A_TO_COMP_A_23_DN")
	)
	(segment
		(start 229.11562 -83.469734)
		(end 229.608888 -83.426046)
		(width 0.1651)
		(layer "B.Cu")
		(net "PCIE_IOM_A_TO_COMP_A_23_DN")
	)
	(segment
		(start 139.314174 -67.981068)
		(end 139.472416 -67.94881)
		(width 0.1651)
		(layer "B.Cu")
		(net "PCIE_IOM_A_TO_COMP_A_23_DN")
	)
	(segment
		(start 229.608888 -83.426046)
		(end 229.73284 -83.529678)
		(width 0.1651)
		(layer "B.Cu")
		(net "PCIE_IOM_A_TO_COMP_A_23_DN")
	)
	(segment
		(start 205.443582 -85.384894)
		(end 205.54061 -85.531706)
		(width 0.1651)
		(layer "B.Cu")
		(net "PCIE_IOM_A_TO_COMP_A_23_DN")
	)
	(segment
		(start 229.73284 -83.529678)
		(end 235.104432 -83.053936)
		(width 0.1651)
		(layer "B.Cu")
		(net "PCIE_IOM_A_TO_COMP_A_23_DN")
	)
	(segment
		(start 136.421114 -65.93205)
		(end 136.834372 -66.2051)
		(width 0.1651)
		(layer "B.Cu")
		(net "PCIE_IOM_A_TO_COMP_A_23_DN")
	)
	(segment
		(start 229.011734 -83.593686)
		(end 229.11562 -83.469734)
		(width 0.1651)
		(layer "B.Cu")
		(net "PCIE_IOM_A_TO_COMP_A_23_DN")
	)
	(segment
		(start 235.104432 -83.053936)
		(end 236.32922 -83.053936)
		(width 0.1651)
		(layer "B.Cu")
		(net "PCIE_IOM_A_TO_COMP_A_23_DN")
	)
	(segment
		(start 218.238578 -84.548218)
		(end 218.351608 -84.413344)
		(width 0.1651)
		(layer "B.Cu")
		(net "PCIE_IOM_A_TO_COMP_A_23_DN")
	)
	(segment
		(start 218.980004 -84.482432)
		(end 225.368612 -83.91652)
		(width 0.1651)
		(layer "B.Cu")
		(net "PCIE_IOM_A_TO_COMP_A_23_DN")
	)
	(segment
		(start 225.368612 -83.91652)
		(end 225.472244 -83.792568)
		(width 0.1651)
		(layer "B.Cu")
		(net "PCIE_IOM_A_TO_COMP_A_23_DN")
	)
	(segment
		(start 217.003884 -84.657692)
		(end 217.116914 -84.522564)
		(width 0.1651)
		(layer "B.Cu")
		(net "PCIE_IOM_A_TO_COMP_A_23_DN")
	)
	(segment
		(start 137.851388 -66.877438)
		(end 137.8839 -67.03568)
		(width 0.1651)
		(layer "B.Cu")
		(net "PCIE_IOM_A_TO_COMP_A_23_DN")
	)
	(segment
		(start 203.74356 -85.0392)
		(end 204.228954 -85.137752)
		(width 0.1651)
		(layer "B.Cu")
		(net "PCIE_IOM_A_TO_COMP_A_23_DN")
	)
	(segment
		(start 228.394514 -83.533488)
		(end 228.518466 -83.637374)
		(width 0.1651)
		(layer "B.Cu")
		(net "PCIE_IOM_A_TO_COMP_A_23_DN")
	)
	(segment
		(start 227.79736 -83.701382)
		(end 227.901246 -83.57743)
		(width 0.1651)
		(layer "B.Cu")
		(net "PCIE_IOM_A_TO_COMP_A_23_DN")
	)
	(segment
		(start 225.472244 -83.792568)
		(end 225.965766 -83.74888)
		(width 0.1651)
		(layer "B.Cu")
		(net "PCIE_IOM_A_TO_COMP_A_23_DN")
	)
	(segment
		(start 227.18014 -83.641184)
		(end 227.304092 -83.74507)
		(width 0.1651)
		(layer "B.Cu")
		(net "PCIE_IOM_A_TO_COMP_A_23_DN")
	)
	(segment
		(start 205.54061 -85.531706)
		(end 206.026004 -85.630512)
		(width 0.1651)
		(layer "B.Cu")
		(net "PCIE_IOM_A_TO_COMP_A_23_DN")
	)
	(segment
		(start 135.84936 -65.691258)
		(end 136.262618 -65.964308)
		(width 0.1651)
		(layer "B.Cu")
		(net "PCIE_IOM_A_TO_COMP_A_23_DN")
	)
	(segment
		(start 216.510616 -84.70138)
		(end 217.003884 -84.657692)
		(width 0.1651)
		(layer "B.Cu")
		(net "PCIE_IOM_A_TO_COMP_A_23_DN")
	)
	(segment
		(start 217.610436 -84.478876)
		(end 217.74531 -84.591906)
		(width 0.1651)
		(layer "B.Cu")
		(net "PCIE_IOM_A_TO_COMP_A_23_DN")
	)
	(segment
		(start 139.472416 -67.94881)
		(end 139.885674 -68.22186)
		(width 0.1651)
		(layer "B.Cu")
		(net "PCIE_IOM_A_TO_COMP_A_23_DN")
	)
	(segment
		(start 138.296904 -67.308984)
		(end 138.4554 -67.276472)
		(width 0.1651)
		(layer "B.Cu")
		(net "PCIE_IOM_A_TO_COMP_A_23_DN")
	)
	(segment
		(start 108.983526 -21.796248)
		(end 108.63326 -21.796248)
		(width 0.1651)
		(layer "B.Cu")
		(net "PCIE_IOM_A_TO_COMP_A_23_DN")
	)
	(segment
		(start 136.86663 -66.363596)
		(end 137.279888 -66.636646)
		(width 0.1651)
		(layer "B.Cu")
		(net "PCIE_IOM_A_TO_COMP_A_23_DN")
	)
	(segment
		(start 217.74531 -84.591906)
		(end 218.238578 -84.548218)
		(width 0.1651)
		(layer "B.Cu")
		(net "PCIE_IOM_A_TO_COMP_A_23_DN")
	)
	(segment
		(start 214.53475 -84.876386)
		(end 214.647526 -84.741512)
		(width 0.1651)
		(layer "B.Cu")
		(net "PCIE_IOM_A_TO_COMP_A_23_DN")
	)
	(segment
		(start 137.279888 -66.636646)
		(end 137.43813 -66.604388)
		(width 0.1651)
		(layer "B.Cu")
		(net "PCIE_IOM_A_TO_COMP_A_23_DN")
	)
	(segment
		(start 204.325982 -85.284564)
		(end 204.811376 -85.38337)
		(width 0.1651)
		(layer "B.Cu")
		(net "PCIE_IOM_A_TO_COMP_A_23_DN")
	)
	(segment
		(start 136.262618 -65.964308)
		(end 136.421114 -65.93205)
		(width 0.1651)
		(layer "B.Cu")
		(net "PCIE_IOM_A_TO_COMP_A_23_DN")
	)
	(segment
		(start 226.582986 -83.808824)
		(end 226.686618 -83.684872)
		(width 0.1651)
		(layer "B.Cu")
		(net "PCIE_IOM_A_TO_COMP_A_23_DN")
	)
	(segment
		(start 217.116914 -84.522564)
		(end 217.610436 -84.478876)
		(width 0.1651)
		(layer "B.Cu")
		(net "PCIE_IOM_A_TO_COMP_A_23_DN")
	)
	(segment
		(start 226.686618 -83.684872)
		(end 227.18014 -83.641184)
		(width 0.1651)
		(layer "B.Cu")
		(net "PCIE_IOM_A_TO_COMP_A_23_DN")
	)
	(segment
		(start 204.811376 -85.38337)
		(end 204.958188 -85.286342)
		(width 0.1651)
		(layer "B.Cu")
		(net "PCIE_IOM_A_TO_COMP_A_23_DN")
	)
	(segment
		(start 135.403844 -65.259712)
		(end 135.817102 -65.532762)
		(width 0.1651)
		(layer "B.Cu")
		(net "PCIE_IOM_A_TO_COMP_A_23_DN")
	)
	(segment
		(start 228.518466 -83.637374)
		(end 229.011734 -83.593686)
		(width 0.1651)
		(layer "B.Cu")
		(net "PCIE_IOM_A_TO_COMP_A_23_DN")
	)
	(segment
		(start 225.965766 -83.74888)
		(end 226.089464 -83.852512)
		(width 0.1651)
		(layer "B.Cu")
		(net "PCIE_IOM_A_TO_COMP_A_23_DN")
	)
	(segment
		(start 206.026004 -85.630512)
		(end 206.026004 -85.630258)
		(width 0.1651)
		(layer "B.Cu")
		(net "PCIE_IOM_A_TO_COMP_A_23_DN")
	)
	(segment
		(start 227.901246 -83.57743)
		(end 228.394514 -83.533488)
		(width 0.1651)
		(layer "B.Cu")
		(net "PCIE_IOM_A_TO_COMP_A_23_DN")
	)
	(segment
		(start 227.304092 -83.74507)
		(end 227.79736 -83.701382)
		(width 0.1651)
		(layer "B.Cu")
		(net "PCIE_IOM_A_TO_COMP_A_23_DN")
	)
	(segment
		(start 123.547378 -57.560464)
		(end 135.245602 -65.29197)
		(width 0.1651)
		(layer "B.Cu")
		(net "PCIE_IOM_A_TO_COMP_A_23_DN")
	)
	(segment
		(start 135.817102 -65.532762)
		(end 135.84936 -65.691258)
		(width 0.1651)
		(layer "B.Cu")
		(net "PCIE_IOM_A_TO_COMP_A_23_DN")
	)
	(segment
		(start 137.43813 -66.604388)
		(end 137.851388 -66.877438)
		(width 0.1651)
		(layer "B.Cu")
		(net "PCIE_IOM_A_TO_COMP_A_23_DN")
	)
	(segment
		(start 139.885674 -68.22186)
		(end 139.917932 -68.380356)
		(width 0.1651)
		(layer "B.Cu")
		(net "PCIE_IOM_A_TO_COMP_A_23_DN")
	)
	(segment
		(start 215.275922 -84.8106)
		(end 215.76919 -84.766912)
		(width 0.1651)
		(layer "B.Cu")
		(net "PCIE_IOM_A_TO_COMP_A_23_DN")
	)
	(segment
		(start 138.4554 -67.276472)
		(end 138.868658 -67.549776)
		(width 0.1651)
		(layer "B.Cu")
		(net "PCIE_IOM_A_TO_COMP_A_23_DN")
	)
	(segment
		(start 137.8839 -67.03568)
		(end 138.296904 -67.308984)
		(width 0.1651)
		(layer "B.Cu")
		(net "PCIE_IOM_A_TO_COMP_A_23_DN")
	)
	(segment
		(start 139.917932 -68.380356)
		(end 148.224494 -73.870312)
		(width 0.1651)
		(layer "B.Cu")
		(net "PCIE_IOM_A_TO_COMP_A_23_DN")
	)
	(segment
		(start 236.711998 -82.895186)
		(end 237.18393 -82.423254)
		(width 0.1651)
		(layer "B.Cu")
		(net "PCIE_IOM_A_TO_COMP_A_23_DN")
	)
	(segment
		(start 218.84513 -84.369656)
		(end 218.980004 -84.482432)
		(width 0.1651)
		(layer "B.Cu")
		(net "PCIE_IOM_A_TO_COMP_A_23_DN")
	)
	(segment
		(start 236.710728 -81.861406)
		(end 236.050074 -82.199988)
		(width 0.1651)
		(layer "B.Cu")
		(net "PCIE_IOM_A_TO_COMP_A_23_DN")
	)
	(segment
		(start 206.026004 -85.630258)
		(end 214.53475 -84.876386)
		(width 0.1651)
		(layer "B.Cu")
		(net "PCIE_IOM_A_TO_COMP_A_23_DN")
	)
	(segment
		(start 204.228954 -85.137752)
		(end 204.325982 -85.284564)
		(width 0.1651)
		(layer "B.Cu")
		(net "PCIE_IOM_A_TO_COMP_A_23_DN")
	)
	(segment
		(start 138.868658 -67.549776)
		(end 138.900916 -67.708018)
		(width 0.1651)
		(layer "B.Cu")
		(net "PCIE_IOM_A_TO_COMP_A_23_DN")
	)
	(segment
		(start 204.958188 -85.286342)
		(end 205.443582 -85.384894)
		(width 0.1651)
		(layer "B.Cu")
		(net "PCIE_IOM_A_TO_COMP_A_23_DN")
	)
	(segment
		(start 203.596748 -85.136228)
		(end 203.74356 -85.0392)
		(width 0.1651)
		(layer "B.Cu")
		(net "PCIE_IOM_A_TO_COMP_A_23_DN")
	)
	(segment
		(start 218.351608 -84.413344)
		(end 218.84513 -84.369656)
		(width 0.1651)
		(layer "B.Cu")
		(net "PCIE_IOM_A_TO_COMP_A_23_DN")
	)
	(segment
		(start 108.1024 -30.13329)
		(end 109.359446 -36.126166)
		(width 0.1651)
		(layer "B.Cu")
		(net "PCIE_IOM_A_TO_COMP_A_23_DN")
	)
	(segment
		(start 109.149896 -22.350222)
		(end 109.149896 -21.962618)
		(width 0.1651)
		(layer "B.Cu")
		(net "PCIE_IOM_A_TO_COMP_A_23_DN")
	)
	(segment
		(start 215.76919 -84.766912)
		(end 215.88222 -84.632038)
		(width 0.1651)
		(layer "B.Cu")
		(net "PCIE_IOM_A_TO_COMP_A_23_DN")
	)
	(segment
		(start 216.375742 -84.58835)
		(end 216.510616 -84.70138)
		(width 0.1651)
		(layer "B.Cu")
		(net "PCIE_IOM_A_TO_COMP_A_23_DN")
	)
	(segment
		(start 214.647526 -84.741512)
		(end 215.141048 -84.697824)
		(width 0.1651)
		(layer "B.Cu")
		(net "PCIE_IOM_A_TO_COMP_A_23_DN")
	)
	(segment
		(start 237.18393 -82.072226)
		(end 237.021878 -81.910174)
		(width 0.1651)
		(layer "B.Cu")
		(net "PCIE_IOM_A_TO_COMP_A_23_DN")
	)
	(segment
		(start 215.141048 -84.697824)
		(end 215.275922 -84.8106)
		(width 0.1651)
		(layer "B.Cu")
		(net "PCIE_IOM_A_TO_COMP_A_23_DN")
	)
	(segment
		(start 108.1024 -22.327108)
		(end 108.1024 -30.13329)
		(width 0.1651)
		(layer "B.Cu")
		(net "PCIE_IOM_A_TO_COMP_A_23_DN")
	)
	(arc
		(start 237.18393 -82.423254)
		(mid 237.219671 -82.369764)
		(end 237.23219 -82.306668)
		(width 0.1651)
		(layer "B.Cu")
		(net "PCIE_IOM_A_TO_COMP_A_23_DN")
	)
	(arc
		(start 108.63326 -21.796248)
		(mid 108.257885 -21.951733)
		(end 108.1024 -22.327108)
		(width 0.1651)
		(layer "B.Cu")
		(net "PCIE_IOM_A_TO_COMP_A_23_DN")
	)
	(arc
		(start 109.149896 -21.962618)
		(mid 109.101167 -21.844977)
		(end 108.983526 -21.796248)
		(width 0.1651)
		(layer "B.Cu")
		(net "PCIE_IOM_A_TO_COMP_A_23_DN")
	)
	(arc
		(start 237.021878 -81.910174)
		(mid 236.957412 -81.863502)
		(end 236.88167 -81.839054)
		(width 0.1651)
		(layer "B.Cu")
		(net "PCIE_IOM_A_TO_COMP_A_23_DN")
	)
	(arc
		(start 236.32922 -83.053936)
		(mid 236.536425 -83.012685)
		(end 236.711998 -82.895186)
		(width 0.1651)
		(layer "B.Cu")
		(net "PCIE_IOM_A_TO_COMP_A_23_DN")
	)
	(arc
		(start 237.23219 -82.188812)
		(mid 237.219642 -82.125728)
		(end 237.18393 -82.072226)
		(width 0.1651)
		(layer "B.Cu")
		(net "PCIE_IOM_A_TO_COMP_A_23_DN")
	)
	(arc
		(start 236.866176 -81.836514)
		(mid 236.786466 -81.836587)
		(end 236.710728 -81.861406)
		(width 0.1651)
		(layer "B.Cu")
		(net "PCIE_IOM_A_TO_COMP_A_23_DN")
	)
	(segment
		(start 237.52429 -78.391004)
		(end 237.52429 -78.104492)
		(width 0.1651)
		(layer "B.Cu")
		(net "PCIE_IOM_A_TO_COMP_A_22_DP")
	)
	(segment
		(start 110.783624 -22.504146)
		(end 110.433358 -22.504146)
		(width 0.1651)
		(layer "B.Cu")
		(net "PCIE_IOM_A_TO_COMP_A_22_DP")
	)
	(segment
		(start 110.949994 -21.950172)
		(end 110.949994 -22.337776)
		(width 0.1651)
		(layer "B.Cu")
		(net "PCIE_IOM_A_TO_COMP_A_22_DP")
	)
	(segment
		(start 110.824772 -36.00323)
		(end 123.472956 -55.112666)
		(width 0.1651)
		(layer "B.Cu")
		(net "PCIE_IOM_A_TO_COMP_A_22_DP")
	)
	(segment
		(start 123.472956 -55.112666)
		(end 150.53691 -73.02627)
		(width 0.1651)
		(layer "B.Cu")
		(net "PCIE_IOM_A_TO_COMP_A_22_DP")
	)
	(segment
		(start 235.587032 -79.346044)
		(end 236.329474 -79.346044)
		(width 0.1651)
		(layer "B.Cu")
		(net "PCIE_IOM_A_TO_COMP_A_22_DP")
	)
	(segment
		(start 237.376462 -77.53731)
		(end 238.05007 -77.199998)
		(width 0.1651)
		(layer "B.Cu")
		(net "PCIE_IOM_A_TO_COMP_A_22_DP")
	)
	(segment
		(start 203.801218 -83.605624)
		(end 235.587032 -79.346044)
		(width 0.1651)
		(layer "B.Cu")
		(net "PCIE_IOM_A_TO_COMP_A_22_DP")
	)
	(segment
		(start 237.449868 -77.924914)
		(end 237.332266 -77.807312)
		(width 0.1651)
		(layer "B.Cu")
		(net "PCIE_IOM_A_TO_COMP_A_22_DP")
	)
	(segment
		(start 109.904022 -23.033482)
		(end 109.904022 -31.614618)
		(width 0.1651)
		(layer "B.Cu")
		(net "PCIE_IOM_A_TO_COMP_A_22_DP")
	)
	(segment
		(start 236.918754 -79.10195)
		(end 237.449868 -78.570582)
		(width 0.1651)
		(layer "B.Cu")
		(net "PCIE_IOM_A_TO_COMP_A_22_DP")
	)
	(segment
		(start 109.904022 -31.614618)
		(end 110.824772 -36.00323)
		(width 0.1651)
		(layer "B.Cu")
		(net "PCIE_IOM_A_TO_COMP_A_22_DP")
	)
	(segment
		(start 150.53691 -73.02627)
		(end 203.801218 -83.605624)
		(width 0.1651)
		(layer "B.Cu")
		(net "PCIE_IOM_A_TO_COMP_A_22_DP")
	)
	(segment
		(start 237.332266 -77.807312)
		(end 237.33252 -77.807312)
		(width 0.1651)
		(layer "B.Cu")
		(net "PCIE_IOM_A_TO_COMP_A_22_DP")
	)
	(arc
		(start 237.33252 -77.807312)
		(mid 237.315525 -77.78755)
		(end 237.301786 -77.765402)
		(width 0.1651)
		(layer "B.Cu")
		(net "PCIE_IOM_A_TO_COMP_A_22_DP")
	)
	(arc
		(start 237.301786 -77.765402)
		(mid 237.285179 -77.714654)
		(end 237.285276 -77.661262)
		(width 0.1651)
		(layer "B.Cu")
		(net "PCIE_IOM_A_TO_COMP_A_22_DP")
	)
	(arc
		(start 237.52429 -78.104492)
		(mid 237.50494 -78.007305)
		(end 237.449868 -77.924914)
		(width 0.1651)
		(layer "B.Cu")
		(net "PCIE_IOM_A_TO_COMP_A_22_DP")
	)
	(arc
		(start 236.329474 -79.346044)
		(mid 236.648392 -79.282607)
		(end 236.918754 -79.10195)
		(width 0.1651)
		(layer "B.Cu")
		(net "PCIE_IOM_A_TO_COMP_A_22_DP")
	)
	(arc
		(start 237.449868 -78.570582)
		(mid 237.504974 -78.488205)
		(end 237.52429 -78.391004)
		(width 0.1651)
		(layer "B.Cu")
		(net "PCIE_IOM_A_TO_COMP_A_22_DP")
	)
	(arc
		(start 237.285276 -77.661262)
		(mid 237.315979 -77.588331)
		(end 237.376462 -77.53731)
		(width 0.1651)
		(layer "B.Cu")
		(net "PCIE_IOM_A_TO_COMP_A_22_DP")
	)
	(arc
		(start 110.949994 -22.337776)
		(mid 110.901265 -22.455417)
		(end 110.783624 -22.504146)
		(width 0.1651)
		(layer "B.Cu")
		(net "PCIE_IOM_A_TO_COMP_A_22_DP")
	)
	(arc
		(start 110.433358 -22.504146)
		(mid 110.059061 -22.659185)
		(end 109.904022 -23.033482)
		(width 0.1651)
		(layer "B.Cu")
		(net "PCIE_IOM_A_TO_COMP_A_22_DP")
	)
	(segment
		(start 204.89926 -83.037934)
		(end 205.039214 -83.144868)
		(width 0.1651)
		(layer "B.Cu")
		(net "PCIE_IOM_A_TO_COMP_A_22_DN")
	)
	(segment
		(start 205.636876 -82.939128)
		(end 206.127858 -82.873342)
		(width 0.1651)
		(layer "B.Cu")
		(net "PCIE_IOM_A_TO_COMP_A_22_DN")
	)
	(segment
		(start 215.214962 -81.781142)
		(end 215.321642 -81.641188)
		(width 0.1651)
		(layer "B.Cu")
		(net "PCIE_IOM_A_TO_COMP_A_22_DN")
	)
	(segment
		(start 231.451404 -79.605378)
		(end 231.942386 -79.539592)
		(width 0.1651)
		(layer "B.Cu")
		(net "PCIE_IOM_A_TO_COMP_A_22_DN")
	)
	(segment
		(start 223.282002 -80.700118)
		(end 223.772984 -80.634332)
		(width 0.1651)
		(layer "B.Cu")
		(net "PCIE_IOM_A_TO_COMP_A_22_DN")
	)
	(segment
		(start 234.947968 -79.021686)
		(end 235.076492 -79.11973)
		(width 0.1651)
		(layer "B.Cu")
		(net "PCIE_IOM_A_TO_COMP_A_22_DN")
	)
	(segment
		(start 236.711998 -78.895194)
		(end 237.18393 -78.423262)
		(width 0.1651)
		(layer "B.Cu")
		(net "PCIE_IOM_A_TO_COMP_A_22_DN")
	)
	(segment
		(start 234.45724 -79.087472)
		(end 234.947968 -79.021686)
		(width 0.1651)
		(layer "B.Cu")
		(net "PCIE_IOM_A_TO_COMP_A_22_DN")
	)
	(segment
		(start 206.75854 -82.914236)
		(end 206.865474 -82.774536)
		(width 0.1651)
		(layer "B.Cu")
		(net "PCIE_IOM_A_TO_COMP_A_22_DN")
	)
	(segment
		(start 221.356174 -80.958182)
		(end 221.454218 -80.829658)
		(width 0.1651)
		(layer "B.Cu")
		(net "PCIE_IOM_A_TO_COMP_A_22_DN")
	)
	(segment
		(start 216.44356 -81.61655)
		(end 216.55024 -81.476596)
		(width 0.1651)
		(layer "B.Cu")
		(net "PCIE_IOM_A_TO_COMP_A_22_DN")
	)
	(segment
		(start 235.076492 -79.11973)
		(end 235.567474 -79.053944)
		(width 0.1651)
		(layer "B.Cu")
		(net "PCIE_IOM_A_TO_COMP_A_22_DN")
	)
	(segment
		(start 110.196122 -31.584138)
		(end 111.099346 -35.888422)
		(width 0.1651)
		(layer "B.Cu")
		(net "PCIE_IOM_A_TO_COMP_A_22_DN")
	)
	(segment
		(start 237.23219 -78.306676)
		(end 237.23219 -78.18882)
		(width 0.1651)
		(layer "B.Cu")
		(net "PCIE_IOM_A_TO_COMP_A_22_DN")
	)
	(segment
		(start 203.810616 -83.30946)
		(end 204.301598 -83.243674)
		(width 0.1651)
		(layer "B.Cu")
		(net "PCIE_IOM_A_TO_COMP_A_22_DN")
	)
	(segment
		(start 150.650194 -72.750934)
		(end 203.810616 -83.30946)
		(width 0.1651)
		(layer "B.Cu")
		(net "PCIE_IOM_A_TO_COMP_A_22_DN")
	)
	(segment
		(start 214.584026 -81.739994)
		(end 214.72398 -81.846928)
		(width 0.1651)
		(layer "B.Cu")
		(net "PCIE_IOM_A_TO_COMP_A_22_DN")
	)
	(segment
		(start 225.570288 -80.278224)
		(end 225.698812 -80.376268)
		(width 0.1651)
		(layer "B.Cu")
		(net "PCIE_IOM_A_TO_COMP_A_22_DN")
	)
	(segment
		(start 110.196122 -23.033482)
		(end 110.196122 -31.584138)
		(width 0.1651)
		(layer "B.Cu")
		(net "PCIE_IOM_A_TO_COMP_A_22_DN")
	)
	(segment
		(start 231.32288 -79.507334)
		(end 231.451404 -79.605378)
		(width 0.1651)
		(layer "B.Cu")
		(net "PCIE_IOM_A_TO_COMP_A_22_DN")
	)
	(segment
		(start 234.359196 -79.215742)
		(end 234.45724 -79.087472)
		(width 0.1651)
		(layer "B.Cu")
		(net "PCIE_IOM_A_TO_COMP_A_22_DN")
	)
	(segment
		(start 205.529942 -83.079082)
		(end 205.636876 -82.939128)
		(width 0.1651)
		(layer "B.Cu")
		(net "PCIE_IOM_A_TO_COMP_A_22_DN")
	)
	(segment
		(start 223.871028 -80.505808)
		(end 224.36201 -80.440022)
		(width 0.1651)
		(layer "B.Cu")
		(net "PCIE_IOM_A_TO_COMP_A_22_DN")
	)
	(segment
		(start 221.454218 -80.829658)
		(end 221.9452 -80.763872)
		(width 0.1651)
		(layer "B.Cu")
		(net "PCIE_IOM_A_TO_COMP_A_22_DN")
	)
	(segment
		(start 205.039214 -83.144868)
		(end 205.529942 -83.079082)
		(width 0.1651)
		(layer "B.Cu")
		(net "PCIE_IOM_A_TO_COMP_A_22_DN")
	)
	(segment
		(start 213.495382 -82.01152)
		(end 213.986364 -81.945734)
		(width 0.1651)
		(layer "B.Cu")
		(net "PCIE_IOM_A_TO_COMP_A_22_DN")
	)
	(segment
		(start 231.942386 -79.539592)
		(end 232.04043 -79.411322)
		(width 0.1651)
		(layer "B.Cu")
		(net "PCIE_IOM_A_TO_COMP_A_22_DN")
	)
	(segment
		(start 222.073724 -80.86217)
		(end 222.564706 -80.796384)
		(width 0.1651)
		(layer "B.Cu")
		(net "PCIE_IOM_A_TO_COMP_A_22_DN")
	)
	(segment
		(start 232.04043 -79.411322)
		(end 232.531412 -79.345536)
		(width 0.1651)
		(layer "B.Cu")
		(net "PCIE_IOM_A_TO_COMP_A_22_DN")
	)
	(segment
		(start 217.041222 -81.41081)
		(end 217.181176 -81.517744)
		(width 0.1651)
		(layer "B.Cu")
		(net "PCIE_IOM_A_TO_COMP_A_22_DN")
	)
	(segment
		(start 212.757766 -82.110326)
		(end 212.8647 -81.970372)
		(width 0.1651)
		(layer "B.Cu")
		(net "PCIE_IOM_A_TO_COMP_A_22_DN")
	)
	(segment
		(start 206.267558 -82.980022)
		(end 206.75854 -82.914236)
		(width 0.1651)
		(layer "B.Cu")
		(net "PCIE_IOM_A_TO_COMP_A_22_DN")
	)
	(segment
		(start 204.301598 -83.243674)
		(end 204.408278 -83.10372)
		(width 0.1651)
		(layer "B.Cu")
		(net "PCIE_IOM_A_TO_COMP_A_22_DN")
	)
	(segment
		(start 110.783624 -22.796246)
		(end 110.433358 -22.796246)
		(width 0.1651)
		(layer "B.Cu")
		(net "PCIE_IOM_A_TO_COMP_A_22_DN")
	)
	(segment
		(start 223.772984 -80.634332)
		(end 223.871028 -80.505808)
		(width 0.1651)
		(layer "B.Cu")
		(net "PCIE_IOM_A_TO_COMP_A_22_DN")
	)
	(segment
		(start 225.698812 -80.376268)
		(end 230.733854 -79.701644)
		(width 0.1651)
		(layer "B.Cu")
		(net "PCIE_IOM_A_TO_COMP_A_22_DN")
	)
	(segment
		(start 222.564706 -80.796384)
		(end 222.66275 -80.66786)
		(width 0.1651)
		(layer "B.Cu")
		(net "PCIE_IOM_A_TO_COMP_A_22_DN")
	)
	(segment
		(start 215.952578 -81.682336)
		(end 216.44356 -81.61655)
		(width 0.1651)
		(layer "B.Cu")
		(net "PCIE_IOM_A_TO_COMP_A_22_DN")
	)
	(segment
		(start 230.733854 -79.701644)
		(end 230.831898 -79.57312)
		(width 0.1651)
		(layer "B.Cu")
		(net "PCIE_IOM_A_TO_COMP_A_22_DN")
	)
	(segment
		(start 213.986364 -81.945734)
		(end 214.093298 -81.80578)
		(width 0.1651)
		(layer "B.Cu")
		(net "PCIE_IOM_A_TO_COMP_A_22_DN")
	)
	(segment
		(start 123.683776 -54.901846)
		(end 150.650194 -72.750934)
		(width 0.1651)
		(layer "B.Cu")
		(net "PCIE_IOM_A_TO_COMP_A_22_DN")
	)
	(segment
		(start 224.36201 -80.440022)
		(end 224.490534 -80.53832)
		(width 0.1651)
		(layer "B.Cu")
		(net "PCIE_IOM_A_TO_COMP_A_22_DN")
	)
	(segment
		(start 206.127858 -82.873342)
		(end 206.267558 -82.980022)
		(width 0.1651)
		(layer "B.Cu")
		(net "PCIE_IOM_A_TO_COMP_A_22_DN")
	)
	(segment
		(start 221.9452 -80.763872)
		(end 222.073724 -80.86217)
		(width 0.1651)
		(layer "B.Cu")
		(net "PCIE_IOM_A_TO_COMP_A_22_DN")
	)
	(segment
		(start 232.659682 -79.44358)
		(end 233.150664 -79.377794)
		(width 0.1651)
		(layer "B.Cu")
		(net "PCIE_IOM_A_TO_COMP_A_22_DN")
	)
	(segment
		(start 215.812624 -81.575402)
		(end 215.952578 -81.682336)
		(width 0.1651)
		(layer "B.Cu")
		(net "PCIE_IOM_A_TO_COMP_A_22_DN")
	)
	(segment
		(start 225.07956 -80.34401)
		(end 225.570288 -80.278224)
		(width 0.1651)
		(layer "B.Cu")
		(net "PCIE_IOM_A_TO_COMP_A_22_DN")
	)
	(segment
		(start 224.490534 -80.53832)
		(end 224.981262 -80.472534)
		(width 0.1651)
		(layer "B.Cu")
		(net "PCIE_IOM_A_TO_COMP_A_22_DN")
	)
	(segment
		(start 230.831898 -79.57312)
		(end 231.32288 -79.507334)
		(width 0.1651)
		(layer "B.Cu")
		(net "PCIE_IOM_A_TO_COMP_A_22_DN")
	)
	(segment
		(start 204.408278 -83.10372)
		(end 204.89926 -83.037934)
		(width 0.1651)
		(layer "B.Cu")
		(net "PCIE_IOM_A_TO_COMP_A_22_DN")
	)
	(segment
		(start 237.18393 -78.072234)
		(end 237.021878 -77.910182)
		(width 0.1651)
		(layer "B.Cu")
		(net "PCIE_IOM_A_TO_COMP_A_22_DN")
	)
	(segment
		(start 233.248708 -79.24927)
		(end 233.73969 -79.183484)
		(width 0.1651)
		(layer "B.Cu")
		(net "PCIE_IOM_A_TO_COMP_A_22_DN")
	)
	(segment
		(start 222.66275 -80.66786)
		(end 223.153732 -80.602074)
		(width 0.1651)
		(layer "B.Cu")
		(net "PCIE_IOM_A_TO_COMP_A_22_DN")
	)
	(segment
		(start 216.55024 -81.476596)
		(end 217.041222 -81.41081)
		(width 0.1651)
		(layer "B.Cu")
		(net "PCIE_IOM_A_TO_COMP_A_22_DN")
	)
	(segment
		(start 224.981262 -80.472534)
		(end 225.07956 -80.34401)
		(width 0.1651)
		(layer "B.Cu")
		(net "PCIE_IOM_A_TO_COMP_A_22_DN")
	)
	(segment
		(start 223.153732 -80.602074)
		(end 223.282002 -80.700118)
		(width 0.1651)
		(layer "B.Cu")
		(net "PCIE_IOM_A_TO_COMP_A_22_DN")
	)
	(segment
		(start 215.321642 -81.641188)
		(end 215.812624 -81.575402)
		(width 0.1651)
		(layer "B.Cu")
		(net "PCIE_IOM_A_TO_COMP_A_22_DN")
	)
	(segment
		(start 212.8647 -81.970372)
		(end 213.355682 -81.904586)
		(width 0.1651)
		(layer "B.Cu")
		(net "PCIE_IOM_A_TO_COMP_A_22_DN")
	)
	(segment
		(start 214.72398 -81.846928)
		(end 215.214962 -81.781142)
		(width 0.1651)
		(layer "B.Cu")
		(net "PCIE_IOM_A_TO_COMP_A_22_DN")
	)
	(segment
		(start 214.093298 -81.80578)
		(end 214.584026 -81.739994)
		(width 0.1651)
		(layer "B.Cu")
		(net "PCIE_IOM_A_TO_COMP_A_22_DN")
	)
	(segment
		(start 236.710728 -77.861414)
		(end 236.050074 -78.199996)
		(width 0.1651)
		(layer "B.Cu")
		(net "PCIE_IOM_A_TO_COMP_A_22_DN")
	)
	(segment
		(start 213.355682 -81.904586)
		(end 213.495382 -82.01152)
		(width 0.1651)
		(layer "B.Cu")
		(net "PCIE_IOM_A_TO_COMP_A_22_DN")
	)
	(segment
		(start 207.356202 -82.70875)
		(end 207.496156 -82.81543)
		(width 0.1651)
		(layer "B.Cu")
		(net "PCIE_IOM_A_TO_COMP_A_22_DN")
	)
	(segment
		(start 110.949994 -23.35022)
		(end 110.949994 -22.962616)
		(width 0.1651)
		(layer "B.Cu")
		(net "PCIE_IOM_A_TO_COMP_A_22_DN")
	)
	(segment
		(start 111.099346 -35.888422)
		(end 123.683776 -54.901846)
		(width 0.1651)
		(layer "B.Cu")
		(net "PCIE_IOM_A_TO_COMP_A_22_DN")
	)
	(segment
		(start 206.865474 -82.774536)
		(end 207.356202 -82.70875)
		(width 0.1651)
		(layer "B.Cu")
		(net "PCIE_IOM_A_TO_COMP_A_22_DN")
	)
	(segment
		(start 235.567474 -79.053944)
		(end 236.32922 -79.053944)
		(width 0.1651)
		(layer "B.Cu")
		(net "PCIE_IOM_A_TO_COMP_A_22_DN")
	)
	(segment
		(start 233.73969 -79.183484)
		(end 233.868214 -79.281528)
		(width 0.1651)
		(layer "B.Cu")
		(net "PCIE_IOM_A_TO_COMP_A_22_DN")
	)
	(segment
		(start 236.88167 -77.839062)
		(end 236.866176 -77.836522)
		(width 0.1651)
		(layer "B.Cu")
		(net "PCIE_IOM_A_TO_COMP_A_22_DN")
	)
	(segment
		(start 233.150664 -79.377794)
		(end 233.248708 -79.24927)
		(width 0.1651)
		(layer "B.Cu")
		(net "PCIE_IOM_A_TO_COMP_A_22_DN")
	)
	(segment
		(start 232.531412 -79.345536)
		(end 232.659682 -79.44358)
		(width 0.1651)
		(layer "B.Cu")
		(net "PCIE_IOM_A_TO_COMP_A_22_DN")
	)
	(segment
		(start 217.181176 -81.517744)
		(end 221.356174 -80.958182)
		(width 0.1651)
		(layer "B.Cu")
		(net "PCIE_IOM_A_TO_COMP_A_22_DN")
	)
	(segment
		(start 233.868214 -79.281528)
		(end 234.359196 -79.215742)
		(width 0.1651)
		(layer "B.Cu")
		(net "PCIE_IOM_A_TO_COMP_A_22_DN")
	)
	(segment
		(start 207.496156 -82.81543)
		(end 212.757766 -82.110326)
		(width 0.1651)
		(layer "B.Cu")
		(net "PCIE_IOM_A_TO_COMP_A_22_DN")
	)
	(arc
		(start 236.32922 -79.053944)
		(mid 236.536425 -79.012693)
		(end 236.711998 -78.895194)
		(width 0.1651)
		(layer "B.Cu")
		(net "PCIE_IOM_A_TO_COMP_A_22_DN")
	)
	(arc
		(start 237.23219 -78.18882)
		(mid 237.219642 -78.125736)
		(end 237.18393 -78.072234)
		(width 0.1651)
		(layer "B.Cu")
		(net "PCIE_IOM_A_TO_COMP_A_22_DN")
	)
	(arc
		(start 237.021878 -77.910182)
		(mid 236.957412 -77.86351)
		(end 236.88167 -77.839062)
		(width 0.1651)
		(layer "B.Cu")
		(net "PCIE_IOM_A_TO_COMP_A_22_DN")
	)
	(arc
		(start 110.949994 -22.962616)
		(mid 110.901265 -22.844975)
		(end 110.783624 -22.796246)
		(width 0.1651)
		(layer "B.Cu")
		(net "PCIE_IOM_A_TO_COMP_A_22_DN")
	)
	(arc
		(start 236.866176 -77.836522)
		(mid 236.786466 -77.836595)
		(end 236.710728 -77.861414)
		(width 0.1651)
		(layer "B.Cu")
		(net "PCIE_IOM_A_TO_COMP_A_22_DN")
	)
	(arc
		(start 237.18393 -78.423262)
		(mid 237.219671 -78.369772)
		(end 237.23219 -78.306676)
		(width 0.1651)
		(layer "B.Cu")
		(net "PCIE_IOM_A_TO_COMP_A_22_DN")
	)
	(arc
		(start 110.433358 -22.796246)
		(mid 110.265607 -22.865731)
		(end 110.196122 -23.033482)
		(width 0.1651)
		(layer "B.Cu")
		(net "PCIE_IOM_A_TO_COMP_A_22_DN")
	)
	(segment
		(start 124.615448 -53.421534)
		(end 125.093984 -54.146958)
		(width 0.1651)
		(layer "B.Cu")
		(net "PCIE_IOM_A_TO_COMP_A_21_DP")
	)
	(segment
		(start 236.918754 -75.101958)
		(end 237.449868 -74.57059)
		(width 0.1651)
		(layer "B.Cu")
		(net "PCIE_IOM_A_TO_COMP_A_21_DP")
	)
	(segment
		(start 237.376462 -73.537318)
		(end 238.05007 -73.200006)
		(width 0.1651)
		(layer "B.Cu")
		(net "PCIE_IOM_A_TO_COMP_A_21_DP")
	)
	(segment
		(start 112.750092 -20.950174)
		(end 112.750092 -21.337778)
		(width 0.1651)
		(layer "B.Cu")
		(net "PCIE_IOM_A_TO_COMP_A_21_DP")
	)
	(segment
		(start 237.449868 -73.924922)
		(end 237.332266 -73.80732)
		(width 0.1651)
		(layer "B.Cu")
		(net "PCIE_IOM_A_TO_COMP_A_21_DP")
	)
	(segment
		(start 111.70412 -30.920436)
		(end 112.60582 -35.21456)
		(width 0.1651)
		(layer "B.Cu")
		(net "PCIE_IOM_A_TO_COMP_A_21_DP")
	)
	(segment
		(start 151.165814 -71.528178)
		(end 200.459848 -81.318862)
		(width 0.1651)
		(layer "B.Cu")
		(net "PCIE_IOM_A_TO_COMP_A_21_DP")
	)
	(segment
		(start 237.52429 -74.391012)
		(end 237.52429 -74.1045)
		(width 0.1651)
		(layer "B.Cu")
		(net "PCIE_IOM_A_TO_COMP_A_21_DP")
	)
	(segment
		(start 235.056172 -75.346052)
		(end 236.329474 -75.346052)
		(width 0.1651)
		(layer "B.Cu")
		(net "PCIE_IOM_A_TO_COMP_A_21_DP")
	)
	(segment
		(start 237.332266 -73.80732)
		(end 237.33252 -73.80732)
		(width 0.1651)
		(layer "B.Cu")
		(net "PCIE_IOM_A_TO_COMP_A_21_DP")
	)
	(segment
		(start 111.70412 -22.033484)
		(end 111.70412 -30.920436)
		(width 0.1651)
		(layer "B.Cu")
		(net "PCIE_IOM_A_TO_COMP_A_21_DP")
	)
	(segment
		(start 112.60582 -35.21456)
		(end 124.615448 -53.421534)
		(width 0.1651)
		(layer "B.Cu")
		(net "PCIE_IOM_A_TO_COMP_A_21_DP")
	)
	(segment
		(start 125.093984 -54.146958)
		(end 151.165814 -71.528178)
		(width 0.1651)
		(layer "B.Cu")
		(net "PCIE_IOM_A_TO_COMP_A_21_DP")
	)
	(segment
		(start 200.459848 -81.318862)
		(end 235.056172 -75.346052)
		(width 0.1651)
		(layer "B.Cu")
		(net "PCIE_IOM_A_TO_COMP_A_21_DP")
	)
	(segment
		(start 112.583722 -21.504148)
		(end 112.233456 -21.504148)
		(width 0.1651)
		(layer "B.Cu")
		(net "PCIE_IOM_A_TO_COMP_A_21_DP")
	)
	(arc
		(start 237.449868 -74.57059)
		(mid 237.504974 -74.488213)
		(end 237.52429 -74.391012)
		(width 0.1651)
		(layer "B.Cu")
		(net "PCIE_IOM_A_TO_COMP_A_21_DP")
	)
	(arc
		(start 237.301786 -73.76541)
		(mid 237.285179 -73.714662)
		(end 237.285276 -73.66127)
		(width 0.1651)
		(layer "B.Cu")
		(net "PCIE_IOM_A_TO_COMP_A_21_DP")
	)
	(arc
		(start 237.285276 -73.66127)
		(mid 237.315979 -73.588339)
		(end 237.376462 -73.537318)
		(width 0.1651)
		(layer "B.Cu")
		(net "PCIE_IOM_A_TO_COMP_A_21_DP")
	)
	(arc
		(start 112.233456 -21.504148)
		(mid 111.859159 -21.659187)
		(end 111.70412 -22.033484)
		(width 0.1651)
		(layer "B.Cu")
		(net "PCIE_IOM_A_TO_COMP_A_21_DP")
	)
	(arc
		(start 237.33252 -73.80732)
		(mid 237.315525 -73.787558)
		(end 237.301786 -73.76541)
		(width 0.1651)
		(layer "B.Cu")
		(net "PCIE_IOM_A_TO_COMP_A_21_DP")
	)
	(arc
		(start 237.52429 -74.1045)
		(mid 237.50494 -74.007313)
		(end 237.449868 -73.924922)
		(width 0.1651)
		(layer "B.Cu")
		(net "PCIE_IOM_A_TO_COMP_A_21_DP")
	)
	(arc
		(start 112.750092 -21.337778)
		(mid 112.701363 -21.455419)
		(end 112.583722 -21.504148)
		(width 0.1651)
		(layer "B.Cu")
		(net "PCIE_IOM_A_TO_COMP_A_21_DP")
	)
	(arc
		(start 236.329474 -75.346052)
		(mid 236.648392 -75.282615)
		(end 236.918754 -75.101958)
		(width 0.1651)
		(layer "B.Cu")
		(net "PCIE_IOM_A_TO_COMP_A_21_DP")
	)
	(segment
		(start 191.320674 -79.078836)
		(end 191.418718 -79.22514)
		(width 0.1651)
		(layer "B.Cu")
		(net "PCIE_IOM_A_TO_COMP_A_21_DN")
	)
	(segment
		(start 203.447904 -80.390492)
		(end 203.935838 -80.306164)
		(width 0.1651)
		(layer "B.Cu")
		(net "PCIE_IOM_A_TO_COMP_A_21_DN")
	)
	(segment
		(start 237.23219 -74.306684)
		(end 237.23219 -74.188828)
		(width 0.1651)
		(layer "B.Cu")
		(net "PCIE_IOM_A_TO_COMP_A_21_DN")
	)
	(segment
		(start 190.688722 -79.080106)
		(end 190.835026 -78.982316)
		(width 0.1651)
		(layer "B.Cu")
		(net "PCIE_IOM_A_TO_COMP_A_21_DN")
	)
	(segment
		(start 197.147434 -80.236314)
		(end 197.245478 -80.382618)
		(width 0.1651)
		(layer "B.Cu")
		(net "PCIE_IOM_A_TO_COMP_A_21_DN")
	)
	(segment
		(start 210.4771 -79.292958)
		(end 214.554054 -78.589124)
		(width 0.1651)
		(layer "B.Cu")
		(net "PCIE_IOM_A_TO_COMP_A_21_DN")
	)
	(segment
		(start 203.935838 -80.306164)
		(end 204.067918 -80.399382)
		(width 0.1651)
		(layer "B.Cu")
		(net "PCIE_IOM_A_TO_COMP_A_21_DN")
	)
	(segment
		(start 200.951846 -80.937354)
		(end 201.04481 -80.805274)
		(width 0.1651)
		(layer "B.Cu")
		(net "PCIE_IOM_A_TO_COMP_A_21_DN")
	)
	(segment
		(start 201.04481 -80.805274)
		(end 201.532998 -80.7212)
		(width 0.1651)
		(layer "B.Cu")
		(net "PCIE_IOM_A_TO_COMP_A_21_DN")
	)
	(segment
		(start 189.472824 -78.838552)
		(end 189.619128 -78.740762)
		(width 0.1651)
		(layer "B.Cu")
		(net "PCIE_IOM_A_TO_COMP_A_21_DN")
	)
	(segment
		(start 216.33688 -78.165452)
		(end 216.46896 -78.258416)
		(width 0.1651)
		(layer "B.Cu")
		(net "PCIE_IOM_A_TO_COMP_A_21_DN")
	)
	(segment
		(start 124.859288 -53.260498)
		(end 125.305312 -53.936646)
		(width 0.1651)
		(layer "B.Cu")
		(net "PCIE_IOM_A_TO_COMP_A_21_DN")
	)
	(segment
		(start 236.88167 -73.83907)
		(end 236.866176 -73.83653)
		(width 0.1651)
		(layer "B.Cu")
		(net "PCIE_IOM_A_TO_COMP_A_21_DN")
	)
	(segment
		(start 196.515482 -80.237584)
		(end 196.661786 -80.139794)
		(width 0.1651)
		(layer "B.Cu")
		(net "PCIE_IOM_A_TO_COMP_A_21_DN")
	)
	(segment
		(start 111.99622 -30.889956)
		(end 112.880394 -35.100006)
		(width 0.1651)
		(layer "B.Cu")
		(net "PCIE_IOM_A_TO_COMP_A_21_DN")
	)
	(segment
		(start 191.904366 -79.32166)
		(end 192.05067 -79.22387)
		(width 0.1651)
		(layer "B.Cu")
		(net "PCIE_IOM_A_TO_COMP_A_21_DN")
	)
	(segment
		(start 151.279606 -71.252842)
		(end 189.472824 -78.838552)
		(width 0.1651)
		(layer "B.Cu")
		(net "PCIE_IOM_A_TO_COMP_A_21_DN")
	)
	(segment
		(start 202.734418 -80.513682)
		(end 202.866498 -80.6069)
		(width 0.1651)
		(layer "B.Cu")
		(net "PCIE_IOM_A_TO_COMP_A_21_DN")
	)
	(segment
		(start 202.24623 -80.59801)
		(end 202.734418 -80.513682)
		(width 0.1651)
		(layer "B.Cu")
		(net "PCIE_IOM_A_TO_COMP_A_21_DN")
	)
	(segment
		(start 198.461122 -80.623918)
		(end 200.463658 -81.021682)
		(width 0.1651)
		(layer "B.Cu")
		(net "PCIE_IOM_A_TO_COMP_A_21_DN")
	)
	(segment
		(start 198.363332 -80.477614)
		(end 198.461122 -80.623918)
		(width 0.1651)
		(layer "B.Cu")
		(net "PCIE_IOM_A_TO_COMP_A_21_DN")
	)
	(segment
		(start 202.153266 -80.73009)
		(end 202.24623 -80.59801)
		(width 0.1651)
		(layer "B.Cu")
		(net "PCIE_IOM_A_TO_COMP_A_21_DN")
	)
	(segment
		(start 209.27568 -79.500222)
		(end 209.763614 -79.416148)
		(width 0.1651)
		(layer "B.Cu")
		(net "PCIE_IOM_A_TO_COMP_A_21_DN")
	)
	(segment
		(start 190.20282 -78.983586)
		(end 190.688722 -79.080106)
		(width 0.1651)
		(layer "B.Cu")
		(net "PCIE_IOM_A_TO_COMP_A_21_DN")
	)
	(segment
		(start 196.661786 -80.139794)
		(end 197.147434 -80.236314)
		(width 0.1651)
		(layer "B.Cu")
		(net "PCIE_IOM_A_TO_COMP_A_21_DN")
	)
	(segment
		(start 214.647272 -78.457044)
		(end 215.13546 -78.372716)
		(width 0.1651)
		(layer "B.Cu")
		(net "PCIE_IOM_A_TO_COMP_A_21_DN")
	)
	(segment
		(start 214.554054 -78.589124)
		(end 214.647272 -78.457044)
		(width 0.1651)
		(layer "B.Cu")
		(net "PCIE_IOM_A_TO_COMP_A_21_DN")
	)
	(segment
		(start 216.46896 -78.258416)
		(end 216.956894 -78.174342)
		(width 0.1651)
		(layer "B.Cu")
		(net "PCIE_IOM_A_TO_COMP_A_21_DN")
	)
	(segment
		(start 196.02958 -80.141064)
		(end 196.515482 -80.237584)
		(width 0.1651)
		(layer "B.Cu")
		(net "PCIE_IOM_A_TO_COMP_A_21_DN")
	)
	(segment
		(start 208.07426 -79.70774)
		(end 208.562194 -79.623412)
		(width 0.1651)
		(layer "B.Cu")
		(net "PCIE_IOM_A_TO_COMP_A_21_DN")
	)
	(segment
		(start 190.835026 -78.982316)
		(end 191.320674 -79.078836)
		(width 0.1651)
		(layer "B.Cu")
		(net "PCIE_IOM_A_TO_COMP_A_21_DN")
	)
	(segment
		(start 237.18393 -74.072242)
		(end 237.021878 -73.91019)
		(width 0.1651)
		(layer "B.Cu")
		(net "PCIE_IOM_A_TO_COMP_A_21_DN")
	)
	(segment
		(start 209.1436 -79.407004)
		(end 209.27568 -79.500222)
		(width 0.1651)
		(layer "B.Cu")
		(net "PCIE_IOM_A_TO_COMP_A_21_DN")
	)
	(segment
		(start 217.67038 -78.051152)
		(end 235.031026 -75.053952)
		(width 0.1651)
		(layer "B.Cu")
		(net "PCIE_IOM_A_TO_COMP_A_21_DN")
	)
	(segment
		(start 216.956894 -78.174342)
		(end 217.050112 -78.042262)
		(width 0.1651)
		(layer "B.Cu")
		(net "PCIE_IOM_A_TO_COMP_A_21_DN")
	)
	(segment
		(start 112.750092 -22.350222)
		(end 112.750092 -21.962618)
		(width 0.1651)
		(layer "B.Cu")
		(net "PCIE_IOM_A_TO_COMP_A_21_DN")
	)
	(segment
		(start 195.93179 -79.99476)
		(end 196.02958 -80.141064)
		(width 0.1651)
		(layer "B.Cu")
		(net "PCIE_IOM_A_TO_COMP_A_21_DN")
	)
	(segment
		(start 217.5383 -77.957934)
		(end 217.67038 -78.051152)
		(width 0.1651)
		(layer "B.Cu")
		(net "PCIE_IOM_A_TO_COMP_A_21_DN")
	)
	(segment
		(start 195.299584 -79.99603)
		(end 195.445888 -79.89824)
		(width 0.1651)
		(layer "B.Cu")
		(net "PCIE_IOM_A_TO_COMP_A_21_DN")
	)
	(segment
		(start 215.13546 -78.372716)
		(end 215.26754 -78.465934)
		(width 0.1651)
		(layer "B.Cu")
		(net "PCIE_IOM_A_TO_COMP_A_21_DN")
	)
	(segment
		(start 204.067918 -80.399382)
		(end 207.360774 -79.83093)
		(width 0.1651)
		(layer "B.Cu")
		(net "PCIE_IOM_A_TO_COMP_A_21_DN")
	)
	(segment
		(start 215.755474 -78.381606)
		(end 215.848692 -78.249526)
		(width 0.1651)
		(layer "B.Cu")
		(net "PCIE_IOM_A_TO_COMP_A_21_DN")
	)
	(segment
		(start 235.031026 -75.053952)
		(end 236.32922 -75.053952)
		(width 0.1651)
		(layer "B.Cu")
		(net "PCIE_IOM_A_TO_COMP_A_21_DN")
	)
	(segment
		(start 200.463658 -81.021682)
		(end 200.951846 -80.937354)
		(width 0.1651)
		(layer "B.Cu")
		(net "PCIE_IOM_A_TO_COMP_A_21_DN")
	)
	(segment
		(start 202.866498 -80.6069)
		(end 203.354686 -80.522572)
		(width 0.1651)
		(layer "B.Cu")
		(net "PCIE_IOM_A_TO_COMP_A_21_DN")
	)
	(segment
		(start 207.453992 -79.69885)
		(end 207.94218 -79.614522)
		(width 0.1651)
		(layer "B.Cu")
		(net "PCIE_IOM_A_TO_COMP_A_21_DN")
	)
	(segment
		(start 215.26754 -78.465934)
		(end 215.755474 -78.381606)
		(width 0.1651)
		(layer "B.Cu")
		(net "PCIE_IOM_A_TO_COMP_A_21_DN")
	)
	(segment
		(start 195.445888 -79.89824)
		(end 195.93179 -79.99476)
		(width 0.1651)
		(layer "B.Cu")
		(net "PCIE_IOM_A_TO_COMP_A_21_DN")
	)
	(segment
		(start 197.87743 -80.381094)
		(end 198.363332 -80.477614)
		(width 0.1651)
		(layer "B.Cu")
		(net "PCIE_IOM_A_TO_COMP_A_21_DN")
	)
	(segment
		(start 215.848692 -78.249526)
		(end 216.33688 -78.165452)
		(width 0.1651)
		(layer "B.Cu")
		(net "PCIE_IOM_A_TO_COMP_A_21_DN")
	)
	(segment
		(start 189.619128 -78.740762)
		(end 190.10503 -78.837282)
		(width 0.1651)
		(layer "B.Cu")
		(net "PCIE_IOM_A_TO_COMP_A_21_DN")
	)
	(segment
		(start 209.856832 -79.284068)
		(end 210.34502 -79.19974)
		(width 0.1651)
		(layer "B.Cu")
		(net "PCIE_IOM_A_TO_COMP_A_21_DN")
	)
	(segment
		(start 209.763614 -79.416148)
		(end 209.856832 -79.284068)
		(width 0.1651)
		(layer "B.Cu")
		(net "PCIE_IOM_A_TO_COMP_A_21_DN")
	)
	(segment
		(start 190.10503 -78.837282)
		(end 190.20282 -78.983586)
		(width 0.1651)
		(layer "B.Cu")
		(net "PCIE_IOM_A_TO_COMP_A_21_DN")
	)
	(segment
		(start 236.711998 -74.895202)
		(end 237.18393 -74.42327)
		(width 0.1651)
		(layer "B.Cu")
		(net "PCIE_IOM_A_TO_COMP_A_21_DN")
	)
	(segment
		(start 192.536572 -79.32039)
		(end 192.634362 -79.466694)
		(width 0.1651)
		(layer "B.Cu")
		(net "PCIE_IOM_A_TO_COMP_A_21_DN")
	)
	(segment
		(start 192.05067 -79.22387)
		(end 192.536572 -79.32039)
		(width 0.1651)
		(layer "B.Cu")
		(net "PCIE_IOM_A_TO_COMP_A_21_DN")
	)
	(segment
		(start 111.99622 -22.033484)
		(end 111.99622 -30.889956)
		(width 0.1651)
		(layer "B.Cu")
		(net "PCIE_IOM_A_TO_COMP_A_21_DN")
	)
	(segment
		(start 210.34502 -79.19974)
		(end 210.4771 -79.292958)
		(width 0.1651)
		(layer "B.Cu")
		(net "PCIE_IOM_A_TO_COMP_A_21_DN")
	)
	(segment
		(start 207.94218 -79.614522)
		(end 208.07426 -79.70774)
		(width 0.1651)
		(layer "B.Cu")
		(net "PCIE_IOM_A_TO_COMP_A_21_DN")
	)
	(segment
		(start 197.731126 -80.478884)
		(end 197.87743 -80.381094)
		(width 0.1651)
		(layer "B.Cu")
		(net "PCIE_IOM_A_TO_COMP_A_21_DN")
	)
	(segment
		(start 112.880394 -35.100006)
		(end 124.859288 -53.260498)
		(width 0.1651)
		(layer "B.Cu")
		(net "PCIE_IOM_A_TO_COMP_A_21_DN")
	)
	(segment
		(start 112.583722 -21.796248)
		(end 112.233456 -21.796248)
		(width 0.1651)
		(layer "B.Cu")
		(net "PCIE_IOM_A_TO_COMP_A_21_DN")
	)
	(segment
		(start 197.245478 -80.382618)
		(end 197.731126 -80.478884)
		(width 0.1651)
		(layer "B.Cu")
		(net "PCIE_IOM_A_TO_COMP_A_21_DN")
	)
	(segment
		(start 217.050112 -78.042262)
		(end 217.5383 -77.957934)
		(width 0.1651)
		(layer "B.Cu")
		(net "PCIE_IOM_A_TO_COMP_A_21_DN")
	)
	(segment
		(start 192.634362 -79.466694)
		(end 195.299584 -79.99603)
		(width 0.1651)
		(layer "B.Cu")
		(net "PCIE_IOM_A_TO_COMP_A_21_DN")
	)
	(segment
		(start 125.305312 -53.936646)
		(end 151.279606 -71.252842)
		(width 0.1651)
		(layer "B.Cu")
		(net "PCIE_IOM_A_TO_COMP_A_21_DN")
	)
	(segment
		(start 201.665078 -80.814164)
		(end 202.153266 -80.73009)
		(width 0.1651)
		(layer "B.Cu")
		(net "PCIE_IOM_A_TO_COMP_A_21_DN")
	)
	(segment
		(start 236.710728 -73.861422)
		(end 236.050074 -74.200004)
		(width 0.1651)
		(layer "B.Cu")
		(net "PCIE_IOM_A_TO_COMP_A_21_DN")
	)
	(segment
		(start 203.354686 -80.522572)
		(end 203.447904 -80.390492)
		(width 0.1651)
		(layer "B.Cu")
		(net "PCIE_IOM_A_TO_COMP_A_21_DN")
	)
	(segment
		(start 191.418718 -79.22514)
		(end 191.904366 -79.32166)
		(width 0.1651)
		(layer "B.Cu")
		(net "PCIE_IOM_A_TO_COMP_A_21_DN")
	)
	(segment
		(start 208.562194 -79.623412)
		(end 208.655412 -79.491332)
		(width 0.1651)
		(layer "B.Cu")
		(net "PCIE_IOM_A_TO_COMP_A_21_DN")
	)
	(segment
		(start 201.532998 -80.7212)
		(end 201.665078 -80.814164)
		(width 0.1651)
		(layer "B.Cu")
		(net "PCIE_IOM_A_TO_COMP_A_21_DN")
	)
	(segment
		(start 208.655412 -79.491332)
		(end 209.1436 -79.407004)
		(width 0.1651)
		(layer "B.Cu")
		(net "PCIE_IOM_A_TO_COMP_A_21_DN")
	)
	(segment
		(start 207.360774 -79.83093)
		(end 207.453992 -79.69885)
		(width 0.1651)
		(layer "B.Cu")
		(net "PCIE_IOM_A_TO_COMP_A_21_DN")
	)
	(arc
		(start 112.233456 -21.796248)
		(mid 112.065705 -21.865733)
		(end 111.99622 -22.033484)
		(width 0.1651)
		(layer "B.Cu")
		(net "PCIE_IOM_A_TO_COMP_A_21_DN")
	)
	(arc
		(start 236.866176 -73.83653)
		(mid 236.786466 -73.836603)
		(end 236.710728 -73.861422)
		(width 0.1651)
		(layer "B.Cu")
		(net "PCIE_IOM_A_TO_COMP_A_21_DN")
	)
	(arc
		(start 237.18393 -74.42327)
		(mid 237.219671 -74.36978)
		(end 237.23219 -74.306684)
		(width 0.1651)
		(layer "B.Cu")
		(net "PCIE_IOM_A_TO_COMP_A_21_DN")
	)
	(arc
		(start 236.32922 -75.053952)
		(mid 236.536425 -75.012701)
		(end 236.711998 -74.895202)
		(width 0.1651)
		(layer "B.Cu")
		(net "PCIE_IOM_A_TO_COMP_A_21_DN")
	)
	(arc
		(start 237.021878 -73.91019)
		(mid 236.957412 -73.863518)
		(end 236.88167 -73.83907)
		(width 0.1651)
		(layer "B.Cu")
		(net "PCIE_IOM_A_TO_COMP_A_21_DN")
	)
	(arc
		(start 112.750092 -21.962618)
		(mid 112.701363 -21.844977)
		(end 112.583722 -21.796248)
		(width 0.1651)
		(layer "B.Cu")
		(net "PCIE_IOM_A_TO_COMP_A_21_DN")
	)
	(arc
		(start 237.23219 -74.188828)
		(mid 237.219642 -74.125744)
		(end 237.18393 -74.072242)
		(width 0.1651)
		(layer "B.Cu")
		(net "PCIE_IOM_A_TO_COMP_A_21_DN")
	)
	(segment
		(start 114.549936 -21.950172)
		(end 114.549936 -22.337776)
		(width 0.1651)
		(layer "B.Cu")
		(net "PCIE_IOM_A_TO_COMP_A_20_DP")
	)
	(segment
		(start 203.200762 -78.46187)
		(end 235.26369 -71.34606)
		(width 0.1651)
		(layer "B.Cu")
		(net "PCIE_IOM_A_TO_COMP_A_20_DP")
	)
	(segment
		(start 237.376462 -69.537326)
		(end 238.05007 -69.200014)
		(width 0.1651)
		(layer "B.Cu")
		(net "PCIE_IOM_A_TO_COMP_A_20_DP")
	)
	(segment
		(start 164.603176 -70.79615)
		(end 203.200762 -78.46187)
		(width 0.1651)
		(layer "B.Cu")
		(net "PCIE_IOM_A_TO_COMP_A_20_DP")
	)
	(segment
		(start 114.276886 -34.730436)
		(end 126.31166 -53.006498)
		(width 0.1651)
		(layer "B.Cu")
		(net "PCIE_IOM_A_TO_COMP_A_20_DP")
	)
	(segment
		(start 114.383566 -22.504146)
		(end 114.0333 -22.504146)
		(width 0.1651)
		(layer "B.Cu")
		(net "PCIE_IOM_A_TO_COMP_A_20_DP")
	)
	(segment
		(start 148.294598 -67.557142)
		(end 164.603176 -70.79615)
		(width 0.1651)
		(layer "B.Cu")
		(net "PCIE_IOM_A_TO_COMP_A_20_DP")
	)
	(segment
		(start 236.918754 -71.101966)
		(end 237.449868 -70.570598)
		(width 0.1651)
		(layer "B.Cu")
		(net "PCIE_IOM_A_TO_COMP_A_20_DP")
	)
	(segment
		(start 113.503964 -31.048198)
		(end 114.276886 -34.730436)
		(width 0.1651)
		(layer "B.Cu")
		(net "PCIE_IOM_A_TO_COMP_A_20_DP")
	)
	(segment
		(start 235.26369 -71.34606)
		(end 236.329474 -71.34606)
		(width 0.1651)
		(layer "B.Cu")
		(net "PCIE_IOM_A_TO_COMP_A_20_DP")
	)
	(segment
		(start 237.449868 -69.92493)
		(end 237.332266 -69.807328)
		(width 0.1651)
		(layer "B.Cu")
		(net "PCIE_IOM_A_TO_COMP_A_20_DP")
	)
	(segment
		(start 113.503964 -23.033482)
		(end 113.503964 -31.048198)
		(width 0.1651)
		(layer "B.Cu")
		(net "PCIE_IOM_A_TO_COMP_A_20_DP")
	)
	(segment
		(start 237.332266 -69.807328)
		(end 237.33252 -69.807328)
		(width 0.1651)
		(layer "B.Cu")
		(net "PCIE_IOM_A_TO_COMP_A_20_DP")
	)
	(segment
		(start 126.31166 -53.006498)
		(end 148.294598 -67.557142)
		(width 0.1651)
		(layer "B.Cu")
		(net "PCIE_IOM_A_TO_COMP_A_20_DP")
	)
	(segment
		(start 237.52429 -70.39102)
		(end 237.52429 -70.104508)
		(width 0.1651)
		(layer "B.Cu")
		(net "PCIE_IOM_A_TO_COMP_A_20_DP")
	)
	(arc
		(start 237.285276 -69.661278)
		(mid 237.315979 -69.588347)
		(end 237.376462 -69.537326)
		(width 0.1651)
		(layer "B.Cu")
		(net "PCIE_IOM_A_TO_COMP_A_20_DP")
	)
	(arc
		(start 237.449868 -70.570598)
		(mid 237.504974 -70.488221)
		(end 237.52429 -70.39102)
		(width 0.1651)
		(layer "B.Cu")
		(net "PCIE_IOM_A_TO_COMP_A_20_DP")
	)
	(arc
		(start 236.329474 -71.34606)
		(mid 236.648392 -71.282623)
		(end 236.918754 -71.101966)
		(width 0.1651)
		(layer "B.Cu")
		(net "PCIE_IOM_A_TO_COMP_A_20_DP")
	)
	(arc
		(start 237.33252 -69.807328)
		(mid 237.315525 -69.787566)
		(end 237.301786 -69.765418)
		(width 0.1651)
		(layer "B.Cu")
		(net "PCIE_IOM_A_TO_COMP_A_20_DP")
	)
	(arc
		(start 114.549936 -22.337776)
		(mid 114.501207 -22.455417)
		(end 114.383566 -22.504146)
		(width 0.1651)
		(layer "B.Cu")
		(net "PCIE_IOM_A_TO_COMP_A_20_DP")
	)
	(arc
		(start 237.301786 -69.765418)
		(mid 237.285179 -69.71467)
		(end 237.285276 -69.661278)
		(width 0.1651)
		(layer "B.Cu")
		(net "PCIE_IOM_A_TO_COMP_A_20_DP")
	)
	(arc
		(start 114.0333 -22.504146)
		(mid 113.659003 -22.659185)
		(end 113.503964 -23.033482)
		(width 0.1651)
		(layer "B.Cu")
		(net "PCIE_IOM_A_TO_COMP_A_20_DP")
	)
	(arc
		(start 237.52429 -70.104508)
		(mid 237.50494 -70.007321)
		(end 237.449868 -69.92493)
		(width 0.1651)
		(layer "B.Cu")
		(net "PCIE_IOM_A_TO_COMP_A_20_DP")
	)
	(segment
		(start 231.21747 -71.827644)
		(end 231.353868 -71.914512)
		(width 0.1651)
		(layer "B.Cu")
		(net "PCIE_IOM_A_TO_COMP_A_20_DN")
	)
	(segment
		(start 204.891132 -77.787246)
		(end 204.98562 -77.63891)
		(width 0.1651)
		(layer "B.Cu")
		(net "PCIE_IOM_A_TO_COMP_A_20_DN")
	)
	(segment
		(start 114.55146 -34.616136)
		(end 126.522988 -52.795678)
		(width 0.1651)
		(layer "B.Cu")
		(net "PCIE_IOM_A_TO_COMP_A_20_DN")
	)
	(segment
		(start 199.609964 -77.450696)
		(end 199.74433 -77.36078)
		(width 0.1651)
		(layer "B.Cu")
		(net "PCIE_IOM_A_TO_COMP_A_20_DN")
	)
	(segment
		(start 206.101188 -77.518768)
		(end 206.195676 -77.370178)
		(width 0.1651)
		(layer "B.Cu")
		(net "PCIE_IOM_A_TO_COMP_A_20_DN")
	)
	(segment
		(start 215.216994 -75.495658)
		(end 215.303862 -75.359514)
		(width 0.1651)
		(layer "B.Cu")
		(net "PCIE_IOM_A_TO_COMP_A_20_DN")
	)
	(segment
		(start 201.426064 -77.69479)
		(end 201.515726 -77.829156)
		(width 0.1651)
		(layer "B.Cu")
		(net "PCIE_IOM_A_TO_COMP_A_20_DN")
	)
	(segment
		(start 225.218498 -73.276206)
		(end 229.456996 -72.33539)
		(width 0.1651)
		(layer "B.Cu")
		(net "PCIE_IOM_A_TO_COMP_A_20_DN")
	)
	(segment
		(start 203.19746 -78.163166)
		(end 203.681076 -78.055978)
		(width 0.1651)
		(layer "B.Cu")
		(net "PCIE_IOM_A_TO_COMP_A_20_DN")
	)
	(segment
		(start 237.23219 -70.306692)
		(end 237.23219 -70.188836)
		(width 0.1651)
		(layer "B.Cu")
		(net "PCIE_IOM_A_TO_COMP_A_20_DN")
	)
	(segment
		(start 204.98562 -77.63891)
		(end 205.469236 -77.531468)
		(width 0.1651)
		(layer "B.Cu")
		(net "PCIE_IOM_A_TO_COMP_A_20_DN")
	)
	(segment
		(start 214.733632 -75.6031)
		(end 215.216994 -75.495658)
		(width 0.1651)
		(layer "B.Cu")
		(net "PCIE_IOM_A_TO_COMP_A_20_DN")
	)
	(segment
		(start 206.195676 -77.370178)
		(end 206.679292 -77.26299)
		(width 0.1651)
		(layer "B.Cu")
		(net "PCIE_IOM_A_TO_COMP_A_20_DN")
	)
	(segment
		(start 202.135994 -77.83576)
		(end 202.621896 -77.93228)
		(width 0.1651)
		(layer "B.Cu")
		(net "PCIE_IOM_A_TO_COMP_A_20_DN")
	)
	(segment
		(start 208.037684 -77.089)
		(end 212.836506 -76.023978)
		(width 0.1651)
		(layer "B.Cu")
		(net "PCIE_IOM_A_TO_COMP_A_20_DN")
	)
	(segment
		(start 206.827628 -77.357478)
		(end 207.311244 -77.25029)
		(width 0.1651)
		(layer "B.Cu")
		(net "PCIE_IOM_A_TO_COMP_A_20_DN")
	)
	(segment
		(start 231.353868 -71.914512)
		(end 235.231432 -71.05396)
		(width 0.1651)
		(layer "B.Cu")
		(net "PCIE_IOM_A_TO_COMP_A_20_DN")
	)
	(segment
		(start 214.113618 -75.623674)
		(end 214.597234 -75.516232)
		(width 0.1651)
		(layer "B.Cu")
		(net "PCIE_IOM_A_TO_COMP_A_20_DN")
	)
	(segment
		(start 114.383566 -22.796246)
		(end 114.0333 -22.796246)
		(width 0.1651)
		(layer "B.Cu")
		(net "PCIE_IOM_A_TO_COMP_A_20_DN")
	)
	(segment
		(start 236.88167 -69.839078)
		(end 236.866176 -69.836538)
		(width 0.1651)
		(layer "B.Cu")
		(net "PCIE_IOM_A_TO_COMP_A_20_DN")
	)
	(segment
		(start 236.710728 -69.86143)
		(end 236.050074 -70.200012)
		(width 0.1651)
		(layer "B.Cu")
		(net "PCIE_IOM_A_TO_COMP_A_20_DN")
	)
	(segment
		(start 201.515726 -77.829156)
		(end 202.001628 -77.925676)
		(width 0.1651)
		(layer "B.Cu")
		(net "PCIE_IOM_A_TO_COMP_A_20_DN")
	)
	(segment
		(start 215.787478 -75.252072)
		(end 215.923876 -75.33894)
		(width 0.1651)
		(layer "B.Cu")
		(net "PCIE_IOM_A_TO_COMP_A_20_DN")
	)
	(segment
		(start 230.027226 -72.091804)
		(end 230.163624 -72.178672)
		(width 0.1651)
		(layer "B.Cu")
		(net "PCIE_IOM_A_TO_COMP_A_20_DN")
	)
	(segment
		(start 200.319894 -77.591666)
		(end 200.805796 -77.688186)
		(width 0.1651)
		(layer "B.Cu")
		(net "PCIE_IOM_A_TO_COMP_A_20_DN")
	)
	(segment
		(start 222.798386 -73.813162)
		(end 223.282002 -73.705974)
		(width 0.1651)
		(layer "B.Cu")
		(net "PCIE_IOM_A_TO_COMP_A_20_DN")
	)
	(segment
		(start 126.522988 -52.795678)
		(end 148.407882 -67.281806)
		(width 0.1651)
		(layer "B.Cu")
		(net "PCIE_IOM_A_TO_COMP_A_20_DN")
	)
	(segment
		(start 206.679292 -77.26299)
		(end 206.827628 -77.357478)
		(width 0.1651)
		(layer "B.Cu")
		(net "PCIE_IOM_A_TO_COMP_A_20_DN")
	)
	(segment
		(start 236.711998 -70.89521)
		(end 237.18393 -70.423278)
		(width 0.1651)
		(layer "B.Cu")
		(net "PCIE_IOM_A_TO_COMP_A_20_DN")
	)
	(segment
		(start 200.805796 -77.688186)
		(end 200.940162 -77.59827)
		(width 0.1651)
		(layer "B.Cu")
		(net "PCIE_IOM_A_TO_COMP_A_20_DN")
	)
	(segment
		(start 225.070162 -73.181718)
		(end 225.218498 -73.276206)
		(width 0.1651)
		(layer "B.Cu")
		(net "PCIE_IOM_A_TO_COMP_A_20_DN")
	)
	(segment
		(start 113.796064 -23.033482)
		(end 113.796064 -31.017718)
		(width 0.1651)
		(layer "B.Cu")
		(net "PCIE_IOM_A_TO_COMP_A_20_DN")
	)
	(segment
		(start 222.166434 -73.826116)
		(end 222.65005 -73.718674)
		(width 0.1651)
		(layer "B.Cu")
		(net "PCIE_IOM_A_TO_COMP_A_20_DN")
	)
	(segment
		(start 215.303862 -75.359514)
		(end 215.787478 -75.252072)
		(width 0.1651)
		(layer "B.Cu")
		(net "PCIE_IOM_A_TO_COMP_A_20_DN")
	)
	(segment
		(start 205.617572 -77.625956)
		(end 206.101188 -77.518768)
		(width 0.1651)
		(layer "B.Cu")
		(net "PCIE_IOM_A_TO_COMP_A_20_DN")
	)
	(segment
		(start 222.071946 -73.974452)
		(end 222.166434 -73.826116)
		(width 0.1651)
		(layer "B.Cu")
		(net "PCIE_IOM_A_TO_COMP_A_20_DN")
	)
	(segment
		(start 164.660072 -70.509638)
		(end 199.609964 -77.450696)
		(width 0.1651)
		(layer "B.Cu")
		(net "PCIE_IOM_A_TO_COMP_A_20_DN")
	)
	(segment
		(start 204.407516 -77.894688)
		(end 204.891132 -77.787246)
		(width 0.1651)
		(layer "B.Cu")
		(net "PCIE_IOM_A_TO_COMP_A_20_DN")
	)
	(segment
		(start 207.405732 -77.1017)
		(end 207.889348 -76.994512)
		(width 0.1651)
		(layer "B.Cu")
		(net "PCIE_IOM_A_TO_COMP_A_20_DN")
	)
	(segment
		(start 212.923374 -75.887834)
		(end 213.40699 -75.780392)
		(width 0.1651)
		(layer "B.Cu")
		(net "PCIE_IOM_A_TO_COMP_A_20_DN")
	)
	(segment
		(start 200.940162 -77.59827)
		(end 201.426064 -77.69479)
		(width 0.1651)
		(layer "B.Cu")
		(net "PCIE_IOM_A_TO_COMP_A_20_DN")
	)
	(segment
		(start 200.230232 -77.4573)
		(end 200.319894 -77.591666)
		(width 0.1651)
		(layer "B.Cu")
		(net "PCIE_IOM_A_TO_COMP_A_20_DN")
	)
	(segment
		(start 114.549936 -23.35022)
		(end 114.549936 -22.962616)
		(width 0.1651)
		(layer "B.Cu")
		(net "PCIE_IOM_A_TO_COMP_A_20_DN")
	)
	(segment
		(start 214.597234 -75.516232)
		(end 214.733632 -75.6031)
		(width 0.1651)
		(layer "B.Cu")
		(net "PCIE_IOM_A_TO_COMP_A_20_DN")
	)
	(segment
		(start 113.796064 -31.017718)
		(end 114.55146 -34.616136)
		(width 0.1651)
		(layer "B.Cu")
		(net "PCIE_IOM_A_TO_COMP_A_20_DN")
	)
	(segment
		(start 202.001628 -77.925676)
		(end 202.135994 -77.83576)
		(width 0.1651)
		(layer "B.Cu")
		(net "PCIE_IOM_A_TO_COMP_A_20_DN")
	)
	(segment
		(start 215.923876 -75.33894)
		(end 222.071946 -73.974452)
		(width 0.1651)
		(layer "B.Cu")
		(net "PCIE_IOM_A_TO_COMP_A_20_DN")
	)
	(segment
		(start 237.18393 -70.07225)
		(end 237.021878 -69.910198)
		(width 0.1651)
		(layer "B.Cu")
		(net "PCIE_IOM_A_TO_COMP_A_20_DN")
	)
	(segment
		(start 148.407882 -67.281806)
		(end 164.660072 -70.509638)
		(width 0.1651)
		(layer "B.Cu")
		(net "PCIE_IOM_A_TO_COMP_A_20_DN")
	)
	(segment
		(start 203.681076 -78.055978)
		(end 203.775564 -77.907388)
		(width 0.1651)
		(layer "B.Cu")
		(net "PCIE_IOM_A_TO_COMP_A_20_DN")
	)
	(segment
		(start 223.37649 -73.557384)
		(end 223.860106 -73.450196)
		(width 0.1651)
		(layer "B.Cu")
		(net "PCIE_IOM_A_TO_COMP_A_20_DN")
	)
	(segment
		(start 224.008442 -73.544684)
		(end 224.492058 -73.437496)
		(width 0.1651)
		(layer "B.Cu")
		(net "PCIE_IOM_A_TO_COMP_A_20_DN")
	)
	(segment
		(start 205.469236 -77.531468)
		(end 205.617572 -77.625956)
		(width 0.1651)
		(layer "B.Cu")
		(net "PCIE_IOM_A_TO_COMP_A_20_DN")
	)
	(segment
		(start 202.711558 -78.066646)
		(end 203.19746 -78.163166)
		(width 0.1651)
		(layer "B.Cu")
		(net "PCIE_IOM_A_TO_COMP_A_20_DN")
	)
	(segment
		(start 213.40699 -75.780392)
		(end 213.543388 -75.86726)
		(width 0.1651)
		(layer "B.Cu")
		(net "PCIE_IOM_A_TO_COMP_A_20_DN")
	)
	(segment
		(start 224.492058 -73.437496)
		(end 224.586546 -73.288906)
		(width 0.1651)
		(layer "B.Cu")
		(net "PCIE_IOM_A_TO_COMP_A_20_DN")
	)
	(segment
		(start 207.889348 -76.994512)
		(end 208.037684 -77.089)
		(width 0.1651)
		(layer "B.Cu")
		(net "PCIE_IOM_A_TO_COMP_A_20_DN")
	)
	(segment
		(start 230.64724 -72.07123)
		(end 230.734108 -71.935086)
		(width 0.1651)
		(layer "B.Cu")
		(net "PCIE_IOM_A_TO_COMP_A_20_DN")
	)
	(segment
		(start 199.74433 -77.36078)
		(end 200.230232 -77.4573)
		(width 0.1651)
		(layer "B.Cu")
		(net "PCIE_IOM_A_TO_COMP_A_20_DN")
	)
	(segment
		(start 212.836506 -76.023978)
		(end 212.923374 -75.887834)
		(width 0.1651)
		(layer "B.Cu")
		(net "PCIE_IOM_A_TO_COMP_A_20_DN")
	)
	(segment
		(start 223.860106 -73.450196)
		(end 224.008442 -73.544684)
		(width 0.1651)
		(layer "B.Cu")
		(net "PCIE_IOM_A_TO_COMP_A_20_DN")
	)
	(segment
		(start 224.586546 -73.288906)
		(end 225.070162 -73.181718)
		(width 0.1651)
		(layer "B.Cu")
		(net "PCIE_IOM_A_TO_COMP_A_20_DN")
	)
	(segment
		(start 229.456996 -72.33539)
		(end 229.543864 -72.199246)
		(width 0.1651)
		(layer "B.Cu")
		(net "PCIE_IOM_A_TO_COMP_A_20_DN")
	)
	(segment
		(start 230.734108 -71.935086)
		(end 231.21747 -71.827644)
		(width 0.1651)
		(layer "B.Cu")
		(net "PCIE_IOM_A_TO_COMP_A_20_DN")
	)
	(segment
		(start 223.282002 -73.705974)
		(end 223.37649 -73.557384)
		(width 0.1651)
		(layer "B.Cu")
		(net "PCIE_IOM_A_TO_COMP_A_20_DN")
	)
	(segment
		(start 214.02675 -75.759818)
		(end 214.113618 -75.623674)
		(width 0.1651)
		(layer "B.Cu")
		(net "PCIE_IOM_A_TO_COMP_A_20_DN")
	)
	(segment
		(start 230.163624 -72.178672)
		(end 230.64724 -72.07123)
		(width 0.1651)
		(layer "B.Cu")
		(net "PCIE_IOM_A_TO_COMP_A_20_DN")
	)
	(segment
		(start 203.775564 -77.907388)
		(end 204.25918 -77.799946)
		(width 0.1651)
		(layer "B.Cu")
		(net "PCIE_IOM_A_TO_COMP_A_20_DN")
	)
	(segment
		(start 235.231432 -71.05396)
		(end 236.32922 -71.05396)
		(width 0.1651)
		(layer "B.Cu")
		(net "PCIE_IOM_A_TO_COMP_A_20_DN")
	)
	(segment
		(start 222.65005 -73.718674)
		(end 222.798386 -73.813162)
		(width 0.1651)
		(layer "B.Cu")
		(net "PCIE_IOM_A_TO_COMP_A_20_DN")
	)
	(segment
		(start 207.311244 -77.25029)
		(end 207.405732 -77.1017)
		(width 0.1651)
		(layer "B.Cu")
		(net "PCIE_IOM_A_TO_COMP_A_20_DN")
	)
	(segment
		(start 202.621896 -77.93228)
		(end 202.711558 -78.066646)
		(width 0.1651)
		(layer "B.Cu")
		(net "PCIE_IOM_A_TO_COMP_A_20_DN")
	)
	(segment
		(start 204.25918 -77.799946)
		(end 204.407516 -77.894688)
		(width 0.1651)
		(layer "B.Cu")
		(net "PCIE_IOM_A_TO_COMP_A_20_DN")
	)
	(segment
		(start 229.543864 -72.199246)
		(end 230.027226 -72.091804)
		(width 0.1651)
		(layer "B.Cu")
		(net "PCIE_IOM_A_TO_COMP_A_20_DN")
	)
	(segment
		(start 213.543388 -75.86726)
		(end 214.02675 -75.759818)
		(width 0.1651)
		(layer "B.Cu")
		(net "PCIE_IOM_A_TO_COMP_A_20_DN")
	)
	(arc
		(start 237.021878 -69.910198)
		(mid 236.957412 -69.863526)
		(end 236.88167 -69.839078)
		(width 0.1651)
		(layer "B.Cu")
		(net "PCIE_IOM_A_TO_COMP_A_20_DN")
	)
	(arc
		(start 237.23219 -70.188836)
		(mid 237.219642 -70.125752)
		(end 237.18393 -70.07225)
		(width 0.1651)
		(layer "B.Cu")
		(net "PCIE_IOM_A_TO_COMP_A_20_DN")
	)
	(arc
		(start 114.549936 -22.962616)
		(mid 114.501207 -22.844975)
		(end 114.383566 -22.796246)
		(width 0.1651)
		(layer "B.Cu")
		(net "PCIE_IOM_A_TO_COMP_A_20_DN")
	)
	(arc
		(start 237.18393 -70.423278)
		(mid 237.219671 -70.369788)
		(end 237.23219 -70.306692)
		(width 0.1651)
		(layer "B.Cu")
		(net "PCIE_IOM_A_TO_COMP_A_20_DN")
	)
	(arc
		(start 114.0333 -22.796246)
		(mid 113.865549 -22.865731)
		(end 113.796064 -23.033482)
		(width 0.1651)
		(layer "B.Cu")
		(net "PCIE_IOM_A_TO_COMP_A_20_DN")
	)
	(arc
		(start 236.32922 -71.05396)
		(mid 236.536425 -71.012709)
		(end 236.711998 -70.89521)
		(width 0.1651)
		(layer "B.Cu")
		(net "PCIE_IOM_A_TO_COMP_A_20_DN")
	)
	(arc
		(start 236.866176 -69.836538)
		(mid 236.786466 -69.836611)
		(end 236.710728 -69.86143)
		(width 0.1651)
		(layer "B.Cu")
		(net "PCIE_IOM_A_TO_COMP_A_20_DN")
	)
	(segment
		(start 122.061224 -42.50309)
		(end 124.311156 -46.23054)
		(width 0.1651)
		(layer "B.Cu")
		(net "PCIE_IOM_A_TO_COMP_A_19_DP")
	)
	(segment
		(start 234.3912 -67.346068)
		(end 236.446568 -67.346068)
		(width 0.1651)
		(layer "B.Cu")
		(net "PCIE_IOM_A_TO_COMP_A_19_DP")
	)
	(segment
		(start 174.413418 -61.081412)
		(end 201.482452 -55.410608)
		(width 0.1651)
		(layer "B.Cu")
		(net "PCIE_IOM_A_TO_COMP_A_19_DP")
	)
	(segment
		(start 236.836458 -67.18427)
		(end 237.449868 -66.570606)
		(width 0.1651)
		(layer "B.Cu")
		(net "PCIE_IOM_A_TO_COMP_A_19_DP")
	)
	(segment
		(start 237.449868 -65.924938)
		(end 237.332266 -65.807336)
		(width 0.1651)
		(layer "B.Cu")
		(net "PCIE_IOM_A_TO_COMP_A_19_DP")
	)
	(segment
		(start 115.304062 -22.033484)
		(end 115.304062 -30.920436)
		(width 0.1651)
		(layer "B.Cu")
		(net "PCIE_IOM_A_TO_COMP_A_19_DP")
	)
	(segment
		(start 120.716294 -41.613328)
		(end 122.061224 -42.50309)
		(width 0.1651)
		(layer "B.Cu")
		(net "PCIE_IOM_A_TO_COMP_A_19_DP")
	)
	(segment
		(start 224.452434 -59.878468)
		(end 234.3912 -67.346068)
		(width 0.1651)
		(layer "B.Cu")
		(net "PCIE_IOM_A_TO_COMP_A_19_DP")
	)
	(segment
		(start 141.357604 -54.357016)
		(end 174.413418 -61.081412)
		(width 0.1651)
		(layer "B.Cu")
		(net "PCIE_IOM_A_TO_COMP_A_19_DP")
	)
	(segment
		(start 116.183664 -21.504148)
		(end 115.833398 -21.504148)
		(width 0.1651)
		(layer "B.Cu")
		(net "PCIE_IOM_A_TO_COMP_A_19_DP")
	)
	(segment
		(start 124.311156 -46.23054)
		(end 126.654052 -50.112168)
		(width 0.1651)
		(layer "B.Cu")
		(net "PCIE_IOM_A_TO_COMP_A_19_DP")
	)
	(segment
		(start 115.304062 -30.920436)
		(end 116.067078 -34.552382)
		(width 0.1651)
		(layer "B.Cu")
		(net "PCIE_IOM_A_TO_COMP_A_19_DP")
	)
	(segment
		(start 126.654052 -50.112168)
		(end 141.357604 -54.357016)
		(width 0.1651)
		(layer "B.Cu")
		(net "PCIE_IOM_A_TO_COMP_A_19_DP")
	)
	(segment
		(start 201.482452 -55.410608)
		(end 224.452434 -59.878468)
		(width 0.1651)
		(layer "B.Cu")
		(net "PCIE_IOM_A_TO_COMP_A_19_DP")
	)
	(segment
		(start 116.067078 -34.552382)
		(end 120.716294 -41.613328)
		(width 0.1651)
		(layer "B.Cu")
		(net "PCIE_IOM_A_TO_COMP_A_19_DP")
	)
	(segment
		(start 237.376462 -65.537334)
		(end 238.05007 -65.200022)
		(width 0.1651)
		(layer "B.Cu")
		(net "PCIE_IOM_A_TO_COMP_A_19_DP")
	)
	(segment
		(start 237.332266 -65.807336)
		(end 237.33252 -65.807336)
		(width 0.1651)
		(layer "B.Cu")
		(net "PCIE_IOM_A_TO_COMP_A_19_DP")
	)
	(segment
		(start 116.350034 -20.950174)
		(end 116.350034 -21.337778)
		(width 0.1651)
		(layer "B.Cu")
		(net "PCIE_IOM_A_TO_COMP_A_19_DP")
	)
	(segment
		(start 237.52429 -66.391028)
		(end 237.52429 -66.104516)
		(width 0.1651)
		(layer "B.Cu")
		(net "PCIE_IOM_A_TO_COMP_A_19_DP")
	)
	(arc
		(start 237.33252 -65.807336)
		(mid 237.315525 -65.787574)
		(end 237.301786 -65.765426)
		(width 0.1651)
		(layer "B.Cu")
		(net "PCIE_IOM_A_TO_COMP_A_19_DP")
	)
	(arc
		(start 237.449868 -66.570606)
		(mid 237.504974 -66.488229)
		(end 237.52429 -66.391028)
		(width 0.1651)
		(layer "B.Cu")
		(net "PCIE_IOM_A_TO_COMP_A_19_DP")
	)
	(arc
		(start 236.447838 -67.346068)
		(mid 236.658159 -67.303629)
		(end 236.836458 -67.18427)
		(width 0.1651)
		(layer "B.Cu")
		(net "PCIE_IOM_A_TO_COMP_A_19_DP")
	)
	(arc
		(start 237.52429 -66.104516)
		(mid 237.50494 -66.007329)
		(end 237.449868 -65.924938)
		(width 0.1651)
		(layer "B.Cu")
		(net "PCIE_IOM_A_TO_COMP_A_19_DP")
	)
	(arc
		(start 237.301786 -65.765426)
		(mid 237.285179 -65.714678)
		(end 237.285276 -65.661286)
		(width 0.1651)
		(layer "B.Cu")
		(net "PCIE_IOM_A_TO_COMP_A_19_DP")
	)
	(arc
		(start 115.833398 -21.504148)
		(mid 115.459101 -21.659187)
		(end 115.304062 -22.033484)
		(width 0.1651)
		(layer "B.Cu")
		(net "PCIE_IOM_A_TO_COMP_A_19_DP")
	)
	(arc
		(start 116.350034 -21.337778)
		(mid 116.301305 -21.455419)
		(end 116.183664 -21.504148)
		(width 0.1651)
		(layer "B.Cu")
		(net "PCIE_IOM_A_TO_COMP_A_19_DP")
	)
	(arc
		(start 237.285276 -65.661286)
		(mid 237.315979 -65.588355)
		(end 237.376462 -65.537334)
		(width 0.1651)
		(layer "B.Cu")
		(net "PCIE_IOM_A_TO_COMP_A_19_DP")
	)
	(arc
		(start 236.446568 -67.346068)
		(mid 236.447203 -67.346069)
		(end 236.447838 -67.346068)
		(width 0.1651)
		(layer "B.Cu")
		(net "PCIE_IOM_A_TO_COMP_A_19_DP")
	)
	(segment
		(start 232.31475 -65.277492)
		(end 232.710736 -65.574926)
		(width 0.1651)
		(layer "B.Cu")
		(net "PCIE_IOM_A_TO_COMP_A_19_DN")
	)
	(segment
		(start 205.032102 -55.676546)
		(end 205.130654 -55.822342)
		(width 0.1651)
		(layer "B.Cu")
		(net "PCIE_IOM_A_TO_COMP_A_19_DN")
	)
	(segment
		(start 215.480646 -57.835546)
		(end 215.966802 -57.930034)
		(width 0.1651)
		(layer "B.Cu")
		(net "PCIE_IOM_A_TO_COMP_A_19_DN")
	)
	(segment
		(start 213.047072 -57.362344)
		(end 213.533228 -57.456832)
		(width 0.1651)
		(layer "B.Cu")
		(net "PCIE_IOM_A_TO_COMP_A_19_DN")
	)
	(segment
		(start 116.183664 -21.796248)
		(end 115.833398 -21.796248)
		(width 0.1651)
		(layer "B.Cu")
		(net "PCIE_IOM_A_TO_COMP_A_19_DN")
	)
	(segment
		(start 225.13036 -59.87923)
		(end 225.526346 -60.176664)
		(width 0.1651)
		(layer "B.Cu")
		(net "PCIE_IOM_A_TO_COMP_A_19_DN")
	)
	(segment
		(start 126.84506 -49.863248)
		(end 141.427454 -54.073044)
		(width 0.1651)
		(layer "B.Cu")
		(net "PCIE_IOM_A_TO_COMP_A_19_DN")
	)
	(segment
		(start 116.350034 -22.350222)
		(end 116.350034 -21.962618)
		(width 0.1651)
		(layer "B.Cu")
		(net "PCIE_IOM_A_TO_COMP_A_19_DN")
	)
	(segment
		(start 232.733342 -65.734946)
		(end 233.129328 -66.032634)
		(width 0.1651)
		(layer "B.Cu")
		(net "PCIE_IOM_A_TO_COMP_A_19_DN")
	)
	(segment
		(start 174.412656 -60.782962)
		(end 201.48042 -55.112412)
		(width 0.1651)
		(layer "B.Cu")
		(net "PCIE_IOM_A_TO_COMP_A_19_DN")
	)
	(segment
		(start 204.545946 -55.581804)
		(end 205.032102 -55.676546)
		(width 0.1651)
		(layer "B.Cu")
		(net "PCIE_IOM_A_TO_COMP_A_19_DN")
	)
	(segment
		(start 236.629702 -66.977514)
		(end 237.18393 -66.423286)
		(width 0.1651)
		(layer "B.Cu")
		(net "PCIE_IOM_A_TO_COMP_A_19_DN")
	)
	(segment
		(start 141.427454 -54.073044)
		(end 174.412656 -60.782962)
		(width 0.1651)
		(layer "B.Cu")
		(net "PCIE_IOM_A_TO_COMP_A_19_DN")
	)
	(segment
		(start 228.473254 -62.534038)
		(end 231.179878 -64.567816)
		(width 0.1651)
		(layer "B.Cu")
		(net "PCIE_IOM_A_TO_COMP_A_19_DN")
	)
	(segment
		(start 212.462618 -57.121806)
		(end 212.948774 -57.216294)
		(width 0.1651)
		(layer "B.Cu")
		(net "PCIE_IOM_A_TO_COMP_A_19_DN")
	)
	(segment
		(start 216.697306 -58.072274)
		(end 224.574354 -59.604402)
		(width 0.1651)
		(layer "B.Cu")
		(net "PCIE_IOM_A_TO_COMP_A_19_DN")
	)
	(segment
		(start 231.179878 -64.567816)
		(end 231.339898 -64.544956)
		(width 0.1651)
		(layer "B.Cu")
		(net "PCIE_IOM_A_TO_COMP_A_19_DN")
	)
	(segment
		(start 203.815442 -55.439818)
		(end 203.91374 -55.585614)
		(width 0.1651)
		(layer "B.Cu")
		(net "PCIE_IOM_A_TO_COMP_A_19_DN")
	)
	(segment
		(start 116.341652 -34.438082)
		(end 117.328696 -35.936936)
		(width 0.1651)
		(layer "B.Cu")
		(net "PCIE_IOM_A_TO_COMP_A_19_DN")
	)
	(segment
		(start 226.91979 -61.366654)
		(end 227.07981 -61.344048)
		(width 0.1651)
		(layer "B.Cu")
		(net "PCIE_IOM_A_TO_COMP_A_19_DN")
	)
	(segment
		(start 213.679278 -57.35828)
		(end 214.165434 -57.453022)
		(width 0.1651)
		(layer "B.Cu")
		(net "PCIE_IOM_A_TO_COMP_A_19_DN")
	)
	(segment
		(start 216.598754 -57.926224)
		(end 216.697306 -58.072274)
		(width 0.1651)
		(layer "B.Cu")
		(net "PCIE_IOM_A_TO_COMP_A_19_DN")
	)
	(segment
		(start 203.183236 -55.443628)
		(end 203.329286 -55.34533)
		(width 0.1651)
		(layer "B.Cu")
		(net "PCIE_IOM_A_TO_COMP_A_19_DN")
	)
	(segment
		(start 201.966576 -55.2069)
		(end 202.112626 -55.108602)
		(width 0.1651)
		(layer "B.Cu")
		(net "PCIE_IOM_A_TO_COMP_A_19_DN")
	)
	(segment
		(start 228.054408 -62.07633)
		(end 228.450394 -62.374018)
		(width 0.1651)
		(layer "B.Cu")
		(net "PCIE_IOM_A_TO_COMP_A_19_DN")
	)
	(segment
		(start 225.944938 -60.634372)
		(end 226.104958 -60.611512)
		(width 0.1651)
		(layer "B.Cu")
		(net "PCIE_IOM_A_TO_COMP_A_19_DN")
	)
	(segment
		(start 202.598782 -55.20309)
		(end 202.69708 -55.34914)
		(width 0.1651)
		(layer "B.Cu")
		(net "PCIE_IOM_A_TO_COMP_A_19_DN")
	)
	(segment
		(start 214.263732 -57.598818)
		(end 214.749888 -57.69356)
		(width 0.1651)
		(layer "B.Cu")
		(net "PCIE_IOM_A_TO_COMP_A_19_DN")
	)
	(segment
		(start 231.758744 -65.002664)
		(end 232.15473 -65.300098)
		(width 0.1651)
		(layer "B.Cu")
		(net "PCIE_IOM_A_TO_COMP_A_19_DN")
	)
	(segment
		(start 212.948774 -57.216294)
		(end 213.047072 -57.362344)
		(width 0.1651)
		(layer "B.Cu")
		(net "PCIE_IOM_A_TO_COMP_A_19_DN")
	)
	(segment
		(start 115.596162 -22.033484)
		(end 115.596162 -30.889956)
		(width 0.1651)
		(layer "B.Cu")
		(net "PCIE_IOM_A_TO_COMP_A_19_DN")
	)
	(segment
		(start 234.488736 -67.053968)
		(end 236.44606 -67.053968)
		(width 0.1651)
		(layer "B.Cu")
		(net "PCIE_IOM_A_TO_COMP_A_19_DN")
	)
	(segment
		(start 214.749888 -57.69356)
		(end 214.895938 -57.595008)
		(width 0.1651)
		(layer "B.Cu")
		(net "PCIE_IOM_A_TO_COMP_A_19_DN")
	)
	(segment
		(start 236.710728 -65.861438)
		(end 236.050074 -66.20002)
		(width 0.1651)
		(layer "B.Cu")
		(net "PCIE_IOM_A_TO_COMP_A_19_DN")
	)
	(segment
		(start 202.69708 -55.34914)
		(end 203.183236 -55.443628)
		(width 0.1651)
		(layer "B.Cu")
		(net "PCIE_IOM_A_TO_COMP_A_19_DN")
	)
	(segment
		(start 227.07981 -61.344048)
		(end 227.475796 -61.641482)
		(width 0.1651)
		(layer "B.Cu")
		(net "PCIE_IOM_A_TO_COMP_A_19_DN")
	)
	(segment
		(start 213.533228 -57.456832)
		(end 213.679278 -57.35828)
		(width 0.1651)
		(layer "B.Cu")
		(net "PCIE_IOM_A_TO_COMP_A_19_DN")
	)
	(segment
		(start 233.129328 -66.032634)
		(end 233.289348 -66.009774)
		(width 0.1651)
		(layer "B.Cu")
		(net "PCIE_IOM_A_TO_COMP_A_19_DN")
	)
	(segment
		(start 233.708194 -66.467482)
		(end 234.488736 -67.053968)
		(width 0.1651)
		(layer "B.Cu")
		(net "PCIE_IOM_A_TO_COMP_A_19_DN")
	)
	(segment
		(start 224.97034 -59.901836)
		(end 225.13036 -59.87923)
		(width 0.1651)
		(layer "B.Cu")
		(net "PCIE_IOM_A_TO_COMP_A_19_DN")
	)
	(segment
		(start 233.685334 -66.307462)
		(end 233.708194 -66.467482)
		(width 0.1651)
		(layer "B.Cu")
		(net "PCIE_IOM_A_TO_COMP_A_19_DN")
	)
	(segment
		(start 228.450394 -62.374018)
		(end 228.473254 -62.534038)
		(width 0.1651)
		(layer "B.Cu")
		(net "PCIE_IOM_A_TO_COMP_A_19_DN")
	)
	(segment
		(start 232.15473 -65.300098)
		(end 232.31475 -65.277492)
		(width 0.1651)
		(layer "B.Cu")
		(net "PCIE_IOM_A_TO_COMP_A_19_DN")
	)
	(segment
		(start 216.112598 -57.831736)
		(end 216.598754 -57.926224)
		(width 0.1651)
		(layer "B.Cu")
		(net "PCIE_IOM_A_TO_COMP_A_19_DN")
	)
	(segment
		(start 237.18393 -66.072258)
		(end 237.021878 -65.910206)
		(width 0.1651)
		(layer "B.Cu")
		(net "PCIE_IOM_A_TO_COMP_A_19_DN")
	)
	(segment
		(start 203.329286 -55.34533)
		(end 203.815442 -55.439818)
		(width 0.1651)
		(layer "B.Cu")
		(net "PCIE_IOM_A_TO_COMP_A_19_DN")
	)
	(segment
		(start 122.277378 -42.295826)
		(end 126.84506 -49.863248)
		(width 0.1651)
		(layer "B.Cu")
		(net "PCIE_IOM_A_TO_COMP_A_19_DN")
	)
	(segment
		(start 117.328696 -35.936936)
		(end 120.927622 -41.402508)
		(width 0.1651)
		(layer "B.Cu")
		(net "PCIE_IOM_A_TO_COMP_A_19_DN")
	)
	(segment
		(start 120.927622 -41.402508)
		(end 122.277378 -42.295826)
		(width 0.1651)
		(layer "B.Cu")
		(net "PCIE_IOM_A_TO_COMP_A_19_DN")
	)
	(segment
		(start 231.735884 -64.842644)
		(end 231.758744 -65.002664)
		(width 0.1651)
		(layer "B.Cu")
		(net "PCIE_IOM_A_TO_COMP_A_19_DN")
	)
	(segment
		(start 226.104958 -60.611512)
		(end 226.500944 -60.9092)
		(width 0.1651)
		(layer "B.Cu")
		(net "PCIE_IOM_A_TO_COMP_A_19_DN")
	)
	(segment
		(start 212.316568 -57.220104)
		(end 212.462618 -57.121806)
		(width 0.1651)
		(layer "B.Cu")
		(net "PCIE_IOM_A_TO_COMP_A_19_DN")
	)
	(segment
		(start 205.130654 -55.822342)
		(end 205.61681 -55.917084)
		(width 0.1651)
		(layer "B.Cu")
		(net "PCIE_IOM_A_TO_COMP_A_19_DN")
	)
	(segment
		(start 232.710736 -65.574926)
		(end 232.733342 -65.734946)
		(width 0.1651)
		(layer "B.Cu")
		(net "PCIE_IOM_A_TO_COMP_A_19_DN")
	)
	(segment
		(start 203.91374 -55.585614)
		(end 204.40015 -55.680356)
		(width 0.1651)
		(layer "B.Cu")
		(net "PCIE_IOM_A_TO_COMP_A_19_DN")
	)
	(segment
		(start 224.574354 -59.604402)
		(end 224.97034 -59.901836)
		(width 0.1651)
		(layer "B.Cu")
		(net "PCIE_IOM_A_TO_COMP_A_19_DN")
	)
	(segment
		(start 227.475796 -61.641482)
		(end 227.498402 -61.801502)
		(width 0.1651)
		(layer "B.Cu")
		(net "PCIE_IOM_A_TO_COMP_A_19_DN")
	)
	(segment
		(start 206.248762 -55.91302)
		(end 206.347314 -56.05907)
		(width 0.1651)
		(layer "B.Cu")
		(net "PCIE_IOM_A_TO_COMP_A_19_DN")
	)
	(segment
		(start 237.23219 -66.3067)
		(end 237.23219 -66.188844)
		(width 0.1651)
		(layer "B.Cu")
		(net "PCIE_IOM_A_TO_COMP_A_19_DN")
	)
	(segment
		(start 227.894388 -62.09919)
		(end 228.054408 -62.07633)
		(width 0.1651)
		(layer "B.Cu")
		(net "PCIE_IOM_A_TO_COMP_A_19_DN")
	)
	(segment
		(start 225.548952 -60.336684)
		(end 225.944938 -60.634372)
		(width 0.1651)
		(layer "B.Cu")
		(net "PCIE_IOM_A_TO_COMP_A_19_DN")
	)
	(segment
		(start 205.61681 -55.917084)
		(end 205.762606 -55.818532)
		(width 0.1651)
		(layer "B.Cu")
		(net "PCIE_IOM_A_TO_COMP_A_19_DN")
	)
	(segment
		(start 215.382094 -57.689496)
		(end 215.480646 -57.835546)
		(width 0.1651)
		(layer "B.Cu")
		(net "PCIE_IOM_A_TO_COMP_A_19_DN")
	)
	(segment
		(start 227.498402 -61.801502)
		(end 227.894388 -62.09919)
		(width 0.1651)
		(layer "B.Cu")
		(net "PCIE_IOM_A_TO_COMP_A_19_DN")
	)
	(segment
		(start 214.895938 -57.595008)
		(end 215.382094 -57.689496)
		(width 0.1651)
		(layer "B.Cu")
		(net "PCIE_IOM_A_TO_COMP_A_19_DN")
	)
	(segment
		(start 214.165434 -57.453022)
		(end 214.263732 -57.598818)
		(width 0.1651)
		(layer "B.Cu")
		(net "PCIE_IOM_A_TO_COMP_A_19_DN")
	)
	(segment
		(start 202.112626 -55.108602)
		(end 202.598782 -55.20309)
		(width 0.1651)
		(layer "B.Cu")
		(net "PCIE_IOM_A_TO_COMP_A_19_DN")
	)
	(segment
		(start 204.40015 -55.680356)
		(end 204.545946 -55.581804)
		(width 0.1651)
		(layer "B.Cu")
		(net "PCIE_IOM_A_TO_COMP_A_19_DN")
	)
	(segment
		(start 236.88167 -65.839086)
		(end 236.866176 -65.836546)
		(width 0.1651)
		(layer "B.Cu")
		(net "PCIE_IOM_A_TO_COMP_A_19_DN")
	)
	(segment
		(start 231.339898 -64.544956)
		(end 231.735884 -64.842644)
		(width 0.1651)
		(layer "B.Cu")
		(net "PCIE_IOM_A_TO_COMP_A_19_DN")
	)
	(segment
		(start 206.347314 -56.05907)
		(end 212.316568 -57.220104)
		(width 0.1651)
		(layer "B.Cu")
		(net "PCIE_IOM_A_TO_COMP_A_19_DN")
	)
	(segment
		(start 115.596162 -30.889956)
		(end 116.341652 -34.438082)
		(width 0.1651)
		(layer "B.Cu")
		(net "PCIE_IOM_A_TO_COMP_A_19_DN")
	)
	(segment
		(start 233.289348 -66.009774)
		(end 233.685334 -66.307462)
		(width 0.1651)
		(layer "B.Cu")
		(net "PCIE_IOM_A_TO_COMP_A_19_DN")
	)
	(segment
		(start 205.762606 -55.818532)
		(end 206.248762 -55.91302)
		(width 0.1651)
		(layer "B.Cu")
		(net "PCIE_IOM_A_TO_COMP_A_19_DN")
	)
	(segment
		(start 225.526346 -60.176664)
		(end 225.548952 -60.336684)
		(width 0.1651)
		(layer "B.Cu")
		(net "PCIE_IOM_A_TO_COMP_A_19_DN")
	)
	(segment
		(start 201.48042 -55.112412)
		(end 201.966576 -55.2069)
		(width 0.1651)
		(layer "B.Cu")
		(net "PCIE_IOM_A_TO_COMP_A_19_DN")
	)
	(segment
		(start 226.500944 -60.9092)
		(end 226.523804 -61.06922)
		(width 0.1651)
		(layer "B.Cu")
		(net "PCIE_IOM_A_TO_COMP_A_19_DN")
	)
	(segment
		(start 226.523804 -61.06922)
		(end 226.91979 -61.366654)
		(width 0.1651)
		(layer "B.Cu")
		(net "PCIE_IOM_A_TO_COMP_A_19_DN")
	)
	(segment
		(start 215.966802 -57.930034)
		(end 216.112598 -57.831736)
		(width 0.1651)
		(layer "B.Cu")
		(net "PCIE_IOM_A_TO_COMP_A_19_DN")
	)
	(arc
		(start 237.021878 -65.910206)
		(mid 236.957412 -65.863534)
		(end 236.88167 -65.839086)
		(width 0.1651)
		(layer "B.Cu")
		(net "PCIE_IOM_A_TO_COMP_A_19_DN")
	)
	(arc
		(start 116.350034 -21.962618)
		(mid 116.301305 -21.844977)
		(end 116.183664 -21.796248)
		(width 0.1651)
		(layer "B.Cu")
		(net "PCIE_IOM_A_TO_COMP_A_19_DN")
	)
	(arc
		(start 236.44606 -67.053968)
		(mid 236.545487 -67.034004)
		(end 236.629702 -66.977514)
		(width 0.1651)
		(layer "B.Cu")
		(net "PCIE_IOM_A_TO_COMP_A_19_DN")
	)
	(arc
		(start 237.18393 -66.423286)
		(mid 237.219671 -66.369796)
		(end 237.23219 -66.3067)
		(width 0.1651)
		(layer "B.Cu")
		(net "PCIE_IOM_A_TO_COMP_A_19_DN")
	)
	(arc
		(start 115.833398 -21.796248)
		(mid 115.665647 -21.865733)
		(end 115.596162 -22.033484)
		(width 0.1651)
		(layer "B.Cu")
		(net "PCIE_IOM_A_TO_COMP_A_19_DN")
	)
	(arc
		(start 237.23219 -66.188844)
		(mid 237.219642 -66.12576)
		(end 237.18393 -66.072258)
		(width 0.1651)
		(layer "B.Cu")
		(net "PCIE_IOM_A_TO_COMP_A_19_DN")
	)
	(arc
		(start 236.866176 -65.836546)
		(mid 236.786466 -65.836619)
		(end 236.710728 -65.861438)
		(width 0.1651)
		(layer "B.Cu")
		(net "PCIE_IOM_A_TO_COMP_A_19_DN")
	)
	(segment
		(start 202.213718 -53.620416)
		(end 229.500176 -59.050936)
		(width 0.1651)
		(layer "B.Cu")
		(net "PCIE_IOM_A_TO_COMP_A_18_DP")
	)
	(segment
		(start 117.103906 -23.033482)
		(end 117.103906 -31.04515)
		(width 0.1651)
		(layer "B.Cu")
		(net "PCIE_IOM_A_TO_COMP_A_18_DP")
	)
	(segment
		(start 235.024676 -63.306452)
		(end 236.424724 -63.306452)
		(width 0.1651)
		(layer "B.Cu")
		(net "PCIE_IOM_A_TO_COMP_A_18_DP")
	)
	(segment
		(start 237.332266 -61.807344)
		(end 237.33252 -61.807344)
		(width 0.1651)
		(layer "B.Cu")
		(net "PCIE_IOM_A_TO_COMP_A_18_DP")
	)
	(segment
		(start 236.918754 -63.101982)
		(end 237.449868 -62.570614)
		(width 0.1651)
		(layer "B.Cu")
		(net "PCIE_IOM_A_TO_COMP_A_18_DP")
	)
	(segment
		(start 139.61872 -52.175918)
		(end 175.656748 -59.182508)
		(width 0.1651)
		(layer "B.Cu")
		(net "PCIE_IOM_A_TO_COMP_A_18_DP")
	)
	(segment
		(start 175.656748 -59.182508)
		(end 202.213718 -53.620416)
		(width 0.1651)
		(layer "B.Cu")
		(net "PCIE_IOM_A_TO_COMP_A_18_DP")
	)
	(segment
		(start 117.783864 -34.283142)
		(end 119.732552 -37.24021)
		(width 0.1651)
		(layer "B.Cu")
		(net "PCIE_IOM_A_TO_COMP_A_18_DP")
	)
	(segment
		(start 237.376462 -61.537342)
		(end 238.05007 -61.20003)
		(width 0.1651)
		(layer "B.Cu")
		(net "PCIE_IOM_A_TO_COMP_A_18_DP")
	)
	(segment
		(start 237.449868 -61.924946)
		(end 237.332266 -61.807344)
		(width 0.1651)
		(layer "B.Cu")
		(net "PCIE_IOM_A_TO_COMP_A_18_DP")
	)
	(segment
		(start 119.732552 -37.24021)
		(end 121.682764 -40.199818)
		(width 0.1651)
		(layer "B.Cu")
		(net "PCIE_IOM_A_TO_COMP_A_18_DP")
	)
	(segment
		(start 117.983508 -22.504146)
		(end 117.633242 -22.504146)
		(width 0.1651)
		(layer "B.Cu")
		(net "PCIE_IOM_A_TO_COMP_A_18_DP")
	)
	(segment
		(start 121.682764 -40.199818)
		(end 139.61872 -52.175918)
		(width 0.1651)
		(layer "B.Cu")
		(net "PCIE_IOM_A_TO_COMP_A_18_DP")
	)
	(segment
		(start 237.52429 -62.391036)
		(end 237.52429 -62.104524)
		(width 0.1651)
		(layer "B.Cu")
		(net "PCIE_IOM_A_TO_COMP_A_18_DP")
	)
	(segment
		(start 229.500176 -59.050936)
		(end 235.024676 -63.306452)
		(width 0.1651)
		(layer "B.Cu")
		(net "PCIE_IOM_A_TO_COMP_A_18_DP")
	)
	(segment
		(start 117.103906 -31.04515)
		(end 117.783864 -34.283142)
		(width 0.1651)
		(layer "B.Cu")
		(net "PCIE_IOM_A_TO_COMP_A_18_DP")
	)
	(segment
		(start 118.149878 -21.950172)
		(end 118.149878 -22.337776)
		(width 0.1651)
		(layer "B.Cu")
		(net "PCIE_IOM_A_TO_COMP_A_18_DP")
	)
	(arc
		(start 117.633242 -22.504146)
		(mid 117.258945 -22.659185)
		(end 117.103906 -23.033482)
		(width 0.1651)
		(layer "B.Cu")
		(net "PCIE_IOM_A_TO_COMP_A_18_DP")
	)
	(arc
		(start 237.449868 -62.570614)
		(mid 237.504974 -62.488237)
		(end 237.52429 -62.391036)
		(width 0.1651)
		(layer "B.Cu")
		(net "PCIE_IOM_A_TO_COMP_A_18_DP")
	)
	(arc
		(start 236.424724 -63.306452)
		(mid 236.692057 -63.253312)
		(end 236.918754 -63.101982)
		(width 0.1651)
		(layer "B.Cu")
		(net "PCIE_IOM_A_TO_COMP_A_18_DP")
	)
	(arc
		(start 118.149878 -22.337776)
		(mid 118.101149 -22.455417)
		(end 117.983508 -22.504146)
		(width 0.1651)
		(layer "B.Cu")
		(net "PCIE_IOM_A_TO_COMP_A_18_DP")
	)
	(arc
		(start 237.301786 -61.765434)
		(mid 237.285179 -61.714686)
		(end 237.285276 -61.661294)
		(width 0.1651)
		(layer "B.Cu")
		(net "PCIE_IOM_A_TO_COMP_A_18_DP")
	)
	(arc
		(start 237.33252 -61.807344)
		(mid 237.315525 -61.787582)
		(end 237.301786 -61.765434)
		(width 0.1651)
		(layer "B.Cu")
		(net "PCIE_IOM_A_TO_COMP_A_18_DP")
	)
	(arc
		(start 237.52429 -62.104524)
		(mid 237.50494 -62.007337)
		(end 237.449868 -61.924946)
		(width 0.1651)
		(layer "B.Cu")
		(net "PCIE_IOM_A_TO_COMP_A_18_DP")
	)
	(arc
		(start 237.285276 -61.661294)
		(mid 237.315979 -61.588363)
		(end 237.376462 -61.537342)
		(width 0.1651)
		(layer "B.Cu")
		(net "PCIE_IOM_A_TO_COMP_A_18_DP")
	)
	(segment
		(start 202.212194 -53.32222)
		(end 203.751942 -53.628544)
		(width 0.1651)
		(layer "B.Cu")
		(net "PCIE_IOM_A_TO_COMP_A_18_DN")
	)
	(segment
		(start 219.870782 -56.83631)
		(end 224.852992 -57.827926)
		(width 0.1651)
		(layer "B.Cu")
		(net "PCIE_IOM_A_TO_COMP_A_18_DN")
	)
	(segment
		(start 215.57361 -55.981092)
		(end 215.707976 -55.89143)
		(width 0.1651)
		(layer "B.Cu")
		(net "PCIE_IOM_A_TO_COMP_A_18_DN")
	)
	(segment
		(start 118.058438 -34.168842)
		(end 121.894346 -39.989506)
		(width 0.1651)
		(layer "B.Cu")
		(net "PCIE_IOM_A_TO_COMP_A_18_DN")
	)
	(segment
		(start 207.398874 -54.354476)
		(end 207.545178 -54.256686)
		(width 0.1651)
		(layer "B.Cu")
		(net "PCIE_IOM_A_TO_COMP_A_18_DN")
	)
	(segment
		(start 175.654716 -58.884312)
		(end 197.359524 -54.338474)
		(width 0.1651)
		(layer "B.Cu")
		(net "PCIE_IOM_A_TO_COMP_A_18_DN")
	)
	(segment
		(start 117.396006 -31.01467)
		(end 118.058438 -34.168842)
		(width 0.1651)
		(layer "B.Cu")
		(net "PCIE_IOM_A_TO_COMP_A_18_DN")
	)
	(segment
		(start 218.67495 -56.598566)
		(end 219.160852 -56.695086)
		(width 0.1651)
		(layer "B.Cu")
		(net "PCIE_IOM_A_TO_COMP_A_18_DN")
	)
	(segment
		(start 236.94771 -62.65926)
		(end 237.183676 -62.423294)
		(width 0.1651)
		(layer "B.Cu")
		(net "PCIE_IOM_A_TO_COMP_A_18_DN")
	)
	(segment
		(start 203.751942 -53.628544)
		(end 203.898246 -53.530754)
		(width 0.1651)
		(layer "B.Cu")
		(net "PCIE_IOM_A_TO_COMP_A_18_DN")
	)
	(segment
		(start 216.903808 -56.129428)
		(end 217.389456 -56.225948)
		(width 0.1651)
		(layer "B.Cu")
		(net "PCIE_IOM_A_TO_COMP_A_18_DN")
	)
	(segment
		(start 199.15378 -53.835554)
		(end 199.3011 -53.93182)
		(width 0.1651)
		(layer "B.Cu")
		(net "PCIE_IOM_A_TO_COMP_A_18_DN")
	)
	(segment
		(start 205.697328 -54.015894)
		(end 206.18323 -54.112414)
		(width 0.1651)
		(layer "B.Cu")
		(net "PCIE_IOM_A_TO_COMP_A_18_DN")
	)
	(segment
		(start 226.758754 -58.207402)
		(end 227.244656 -58.303922)
		(width 0.1651)
		(layer "B.Cu")
		(net "PCIE_IOM_A_TO_COMP_A_18_DN")
	)
	(segment
		(start 218.099386 -56.367426)
		(end 218.585288 -56.463946)
		(width 0.1651)
		(layer "B.Cu")
		(net "PCIE_IOM_A_TO_COMP_A_18_DN")
	)
	(segment
		(start 226.048824 -58.065924)
		(end 226.18319 -57.976262)
		(width 0.1651)
		(layer "B.Cu")
		(net "PCIE_IOM_A_TO_COMP_A_18_DN")
	)
	(segment
		(start 226.18319 -57.976262)
		(end 226.669092 -58.072782)
		(width 0.1651)
		(layer "B.Cu")
		(net "PCIE_IOM_A_TO_COMP_A_18_DN")
	)
	(segment
		(start 200.514204 -53.67782)
		(end 202.212194 -53.32222)
		(width 0.1651)
		(layer "B.Cu")
		(net "PCIE_IOM_A_TO_COMP_A_18_DN")
	)
	(segment
		(start 237.183676 -62.423294)
		(end 237.18393 -62.423294)
		(width 0.1651)
		(layer "B.Cu")
		(net "PCIE_IOM_A_TO_COMP_A_18_DN")
	)
	(segment
		(start 117.396006 -23.033482)
		(end 117.396006 -31.01467)
		(width 0.1651)
		(layer "B.Cu")
		(net "PCIE_IOM_A_TO_COMP_A_18_DN")
	)
	(segment
		(start 227.954586 -58.445146)
		(end 228.440234 -58.54192)
		(width 0.1651)
		(layer "B.Cu")
		(net "PCIE_IOM_A_TO_COMP_A_18_DN")
	)
	(segment
		(start 224.987358 -57.738264)
		(end 225.47326 -57.834784)
		(width 0.1651)
		(layer "B.Cu")
		(net "PCIE_IOM_A_TO_COMP_A_18_DN")
	)
	(segment
		(start 198.668894 -53.937154)
		(end 199.15378 -53.835554)
		(width 0.1651)
		(layer "B.Cu")
		(net "PCIE_IOM_A_TO_COMP_A_18_DN")
	)
	(segment
		(start 204.481684 -53.773832)
		(end 204.967586 -53.870606)
		(width 0.1651)
		(layer "B.Cu")
		(net "PCIE_IOM_A_TO_COMP_A_18_DN")
	)
	(segment
		(start 219.78112 -56.701944)
		(end 219.870782 -56.83631)
		(width 0.1651)
		(layer "B.Cu")
		(net "PCIE_IOM_A_TO_COMP_A_18_DN")
	)
	(segment
		(start 197.359524 -54.338474)
		(end 197.45579 -54.191154)
		(width 0.1651)
		(layer "B.Cu")
		(net "PCIE_IOM_A_TO_COMP_A_18_DN")
	)
	(segment
		(start 236.711998 -62.895226)
		(end 236.94771 -62.65926)
		(width 0.1651)
		(layer "B.Cu")
		(net "PCIE_IOM_A_TO_COMP_A_18_DN")
	)
	(segment
		(start 237.23219 -62.306708)
		(end 237.23219 -62.188852)
		(width 0.1651)
		(layer "B.Cu")
		(net "PCIE_IOM_A_TO_COMP_A_18_DN")
	)
	(segment
		(start 205.11389 -53.772816)
		(end 205.599538 -53.869336)
		(width 0.1651)
		(layer "B.Cu")
		(net "PCIE_IOM_A_TO_COMP_A_18_DN")
	)
	(segment
		(start 216.28354 -56.12257)
		(end 216.769188 -56.21909)
		(width 0.1651)
		(layer "B.Cu")
		(net "PCIE_IOM_A_TO_COMP_A_18_DN")
	)
	(segment
		(start 225.562922 -57.969404)
		(end 226.048824 -58.065924)
		(width 0.1651)
		(layer "B.Cu")
		(net "PCIE_IOM_A_TO_COMP_A_18_DN")
	)
	(segment
		(start 203.898246 -53.530754)
		(end 204.383894 -53.627528)
		(width 0.1651)
		(layer "B.Cu")
		(net "PCIE_IOM_A_TO_COMP_A_18_DN")
	)
	(segment
		(start 237.18393 -62.072266)
		(end 237.021878 -61.910214)
		(width 0.1651)
		(layer "B.Cu")
		(net "PCIE_IOM_A_TO_COMP_A_18_DN")
	)
	(segment
		(start 215.707976 -55.89143)
		(end 216.193624 -55.98795)
		(width 0.1651)
		(layer "B.Cu")
		(net "PCIE_IOM_A_TO_COMP_A_18_DN")
	)
	(segment
		(start 229.624382 -58.777632)
		(end 235.124244 -63.014352)
		(width 0.1651)
		(layer "B.Cu")
		(net "PCIE_IOM_A_TO_COMP_A_18_DN")
	)
	(segment
		(start 207.545178 -54.256686)
		(end 208.03108 -54.353206)
		(width 0.1651)
		(layer "B.Cu")
		(net "PCIE_IOM_A_TO_COMP_A_18_DN")
	)
	(segment
		(start 204.383894 -53.627528)
		(end 204.481684 -53.773832)
		(width 0.1651)
		(layer "B.Cu")
		(net "PCIE_IOM_A_TO_COMP_A_18_DN")
	)
	(segment
		(start 197.940422 -54.089808)
		(end 198.087742 -54.186074)
		(width 0.1651)
		(layer "B.Cu")
		(net "PCIE_IOM_A_TO_COMP_A_18_DN")
	)
	(segment
		(start 217.96502 -56.457088)
		(end 218.099386 -56.367426)
		(width 0.1651)
		(layer "B.Cu")
		(net "PCIE_IOM_A_TO_COMP_A_18_DN")
	)
	(segment
		(start 236.88167 -61.839094)
		(end 236.866176 -61.836554)
		(width 0.1651)
		(layer "B.Cu")
		(net "PCIE_IOM_A_TO_COMP_A_18_DN")
	)
	(segment
		(start 204.967586 -53.870606)
		(end 205.11389 -53.772816)
		(width 0.1651)
		(layer "B.Cu")
		(net "PCIE_IOM_A_TO_COMP_A_18_DN")
	)
	(segment
		(start 228.440234 -58.54192)
		(end 228.574854 -58.452258)
		(width 0.1651)
		(layer "B.Cu")
		(net "PCIE_IOM_A_TO_COMP_A_18_DN")
	)
	(segment
		(start 229.060502 -58.548778)
		(end 229.150418 -58.683144)
		(width 0.1651)
		(layer "B.Cu")
		(net "PCIE_IOM_A_TO_COMP_A_18_DN")
	)
	(segment
		(start 139.732004 -51.900328)
		(end 175.654716 -58.884312)
		(width 0.1651)
		(layer "B.Cu")
		(net "PCIE_IOM_A_TO_COMP_A_18_DN")
	)
	(segment
		(start 205.599538 -53.869336)
		(end 205.697328 -54.015894)
		(width 0.1651)
		(layer "B.Cu")
		(net "PCIE_IOM_A_TO_COMP_A_18_DN")
	)
	(segment
		(start 225.47326 -57.834784)
		(end 225.562922 -57.969404)
		(width 0.1651)
		(layer "B.Cu")
		(net "PCIE_IOM_A_TO_COMP_A_18_DN")
	)
	(segment
		(start 227.379022 -58.21426)
		(end 227.86467 -58.31078)
		(width 0.1651)
		(layer "B.Cu")
		(net "PCIE_IOM_A_TO_COMP_A_18_DN")
	)
	(segment
		(start 118.149878 -23.35022)
		(end 118.149878 -22.962616)
		(width 0.1651)
		(layer "B.Cu")
		(net "PCIE_IOM_A_TO_COMP_A_18_DN")
	)
	(segment
		(start 198.572628 -54.084474)
		(end 198.668894 -53.937154)
		(width 0.1651)
		(layer "B.Cu")
		(net "PCIE_IOM_A_TO_COMP_A_18_DN")
	)
	(segment
		(start 218.585288 -56.463946)
		(end 218.67495 -56.598566)
		(width 0.1651)
		(layer "B.Cu")
		(net "PCIE_IOM_A_TO_COMP_A_18_DN")
	)
	(segment
		(start 117.983508 -22.796246)
		(end 117.633242 -22.796246)
		(width 0.1651)
		(layer "B.Cu")
		(net "PCIE_IOM_A_TO_COMP_A_18_DN")
	)
	(segment
		(start 208.12887 -54.499764)
		(end 215.57361 -55.981092)
		(width 0.1651)
		(layer "B.Cu")
		(net "PCIE_IOM_A_TO_COMP_A_18_DN")
	)
	(segment
		(start 216.769188 -56.21909)
		(end 216.903808 -56.129428)
		(width 0.1651)
		(layer "B.Cu")
		(net "PCIE_IOM_A_TO_COMP_A_18_DN")
	)
	(segment
		(start 227.86467 -58.31078)
		(end 227.954586 -58.445146)
		(width 0.1651)
		(layer "B.Cu")
		(net "PCIE_IOM_A_TO_COMP_A_18_DN")
	)
	(segment
		(start 197.45579 -54.191154)
		(end 197.940422 -54.089808)
		(width 0.1651)
		(layer "B.Cu")
		(net "PCIE_IOM_A_TO_COMP_A_18_DN")
	)
	(segment
		(start 198.087742 -54.186074)
		(end 198.572628 -54.084474)
		(width 0.1651)
		(layer "B.Cu")
		(net "PCIE_IOM_A_TO_COMP_A_18_DN")
	)
	(segment
		(start 226.669092 -58.072782)
		(end 226.758754 -58.207402)
		(width 0.1651)
		(layer "B.Cu")
		(net "PCIE_IOM_A_TO_COMP_A_18_DN")
	)
	(segment
		(start 219.160852 -56.695086)
		(end 219.295218 -56.605424)
		(width 0.1651)
		(layer "B.Cu")
		(net "PCIE_IOM_A_TO_COMP_A_18_DN")
	)
	(segment
		(start 199.785732 -53.830474)
		(end 199.881998 -53.683154)
		(width 0.1651)
		(layer "B.Cu")
		(net "PCIE_IOM_A_TO_COMP_A_18_DN")
	)
	(segment
		(start 229.150418 -58.683144)
		(end 229.624382 -58.777632)
		(width 0.1651)
		(layer "B.Cu")
		(net "PCIE_IOM_A_TO_COMP_A_18_DN")
	)
	(segment
		(start 217.479372 -56.360568)
		(end 217.96502 -56.457088)
		(width 0.1651)
		(layer "B.Cu")
		(net "PCIE_IOM_A_TO_COMP_A_18_DN")
	)
	(segment
		(start 235.124244 -63.014352)
		(end 236.424724 -63.014352)
		(width 0.1651)
		(layer "B.Cu")
		(net "PCIE_IOM_A_TO_COMP_A_18_DN")
	)
	(segment
		(start 217.389456 -56.225948)
		(end 217.479372 -56.360568)
		(width 0.1651)
		(layer "B.Cu")
		(net "PCIE_IOM_A_TO_COMP_A_18_DN")
	)
	(segment
		(start 206.18323 -54.112414)
		(end 206.329534 -54.014624)
		(width 0.1651)
		(layer "B.Cu")
		(net "PCIE_IOM_A_TO_COMP_A_18_DN")
	)
	(segment
		(start 200.366884 -53.581554)
		(end 200.514204 -53.67782)
		(width 0.1651)
		(layer "B.Cu")
		(net "PCIE_IOM_A_TO_COMP_A_18_DN")
	)
	(segment
		(start 206.329534 -54.014624)
		(end 206.815436 -54.111398)
		(width 0.1651)
		(layer "B.Cu")
		(net "PCIE_IOM_A_TO_COMP_A_18_DN")
	)
	(segment
		(start 236.710728 -61.861446)
		(end 236.050074 -62.200028)
		(width 0.1651)
		(layer "B.Cu")
		(net "PCIE_IOM_A_TO_COMP_A_18_DN")
	)
	(segment
		(start 199.881998 -53.683154)
		(end 200.366884 -53.581554)
		(width 0.1651)
		(layer "B.Cu")
		(net "PCIE_IOM_A_TO_COMP_A_18_DN")
	)
	(segment
		(start 219.295218 -56.605424)
		(end 219.78112 -56.701944)
		(width 0.1651)
		(layer "B.Cu")
		(net "PCIE_IOM_A_TO_COMP_A_18_DN")
	)
	(segment
		(start 199.3011 -53.93182)
		(end 199.785732 -53.830474)
		(width 0.1651)
		(layer "B.Cu")
		(net "PCIE_IOM_A_TO_COMP_A_18_DN")
	)
	(segment
		(start 224.852992 -57.827926)
		(end 224.987358 -57.738264)
		(width 0.1651)
		(layer "B.Cu")
		(net "PCIE_IOM_A_TO_COMP_A_18_DN")
	)
	(segment
		(start 216.193624 -55.98795)
		(end 216.28354 -56.12257)
		(width 0.1651)
		(layer "B.Cu")
		(net "PCIE_IOM_A_TO_COMP_A_18_DN")
	)
	(segment
		(start 121.894346 -39.989506)
		(end 139.732004 -51.900328)
		(width 0.1651)
		(layer "B.Cu")
		(net "PCIE_IOM_A_TO_COMP_A_18_DN")
	)
	(segment
		(start 228.574854 -58.452258)
		(end 229.060502 -58.548778)
		(width 0.1651)
		(layer "B.Cu")
		(net "PCIE_IOM_A_TO_COMP_A_18_DN")
	)
	(segment
		(start 206.815436 -54.111398)
		(end 206.913226 -54.257702)
		(width 0.1651)
		(layer "B.Cu")
		(net "PCIE_IOM_A_TO_COMP_A_18_DN")
	)
	(segment
		(start 208.03108 -54.353206)
		(end 208.12887 -54.499764)
		(width 0.1651)
		(layer "B.Cu")
		(net "PCIE_IOM_A_TO_COMP_A_18_DN")
	)
	(segment
		(start 206.913226 -54.257702)
		(end 207.398874 -54.354476)
		(width 0.1651)
		(layer "B.Cu")
		(net "PCIE_IOM_A_TO_COMP_A_18_DN")
	)
	(segment
		(start 227.244656 -58.303922)
		(end 227.379022 -58.21426)
		(width 0.1651)
		(layer "B.Cu")
		(net "PCIE_IOM_A_TO_COMP_A_18_DN")
	)
	(arc
		(start 117.633242 -22.796246)
		(mid 117.465491 -22.865731)
		(end 117.396006 -23.033482)
		(width 0.1651)
		(layer "B.Cu")
		(net "PCIE_IOM_A_TO_COMP_A_18_DN")
	)
	(arc
		(start 236.866176 -61.836554)
		(mid 236.786466 -61.836627)
		(end 236.710728 -61.861446)
		(width 0.1651)
		(layer "B.Cu")
		(net "PCIE_IOM_A_TO_COMP_A_18_DN")
	)
	(arc
		(start 237.18393 -62.423294)
		(mid 237.219671 -62.369804)
		(end 237.23219 -62.306708)
		(width 0.1651)
		(layer "B.Cu")
		(net "PCIE_IOM_A_TO_COMP_A_18_DN")
	)
	(arc
		(start 237.021878 -61.910214)
		(mid 236.957412 -61.863542)
		(end 236.88167 -61.839094)
		(width 0.1651)
		(layer "B.Cu")
		(net "PCIE_IOM_A_TO_COMP_A_18_DN")
	)
	(arc
		(start 237.23219 -62.188852)
		(mid 237.219642 -62.125768)
		(end 237.18393 -62.072266)
		(width 0.1651)
		(layer "B.Cu")
		(net "PCIE_IOM_A_TO_COMP_A_18_DN")
	)
	(arc
		(start 118.149878 -22.962616)
		(mid 118.101149 -22.844975)
		(end 117.983508 -22.796246)
		(width 0.1651)
		(layer "B.Cu")
		(net "PCIE_IOM_A_TO_COMP_A_18_DN")
	)
	(arc
		(start 236.424724 -63.014352)
		(mid 236.580207 -62.983349)
		(end 236.711998 -62.895226)
		(width 0.1651)
		(layer "B.Cu")
		(net "PCIE_IOM_A_TO_COMP_A_18_DN")
	)
	(segment
		(start 237.332266 -57.807352)
		(end 237.33252 -57.807352)
		(width 0.1651)
		(layer "B.Cu")
		(net "PCIE_IOM_A_TO_COMP_A_17_DP")
	)
	(segment
		(start 150.61565 -50.287682)
		(end 176.43094 -55.514494)
		(width 0.1651)
		(layer "B.Cu")
		(net "PCIE_IOM_A_TO_COMP_A_17_DP")
	)
	(segment
		(start 232.713022 -57.836308)
		(end 234.621578 -59.30646)
		(width 0.1651)
		(layer "B.Cu")
		(net "PCIE_IOM_A_TO_COMP_A_17_DP")
	)
	(segment
		(start 135.098028 -45.238162)
		(end 145.922238 -47.440596)
		(width 0.1651)
		(layer "B.Cu")
		(net "PCIE_IOM_A_TO_COMP_A_17_DP")
	)
	(segment
		(start 237.376462 -57.53735)
		(end 238.05007 -57.200038)
		(width 0.1651)
		(layer "B.Cu")
		(net "PCIE_IOM_A_TO_COMP_A_17_DP")
	)
	(segment
		(start 237.449868 -57.924954)
		(end 237.332266 -57.807352)
		(width 0.1651)
		(layer "B.Cu")
		(net "PCIE_IOM_A_TO_COMP_A_17_DP")
	)
	(segment
		(start 198.165466 -50.972974)
		(end 232.713022 -57.836308)
		(width 0.1651)
		(layer "B.Cu")
		(net "PCIE_IOM_A_TO_COMP_A_17_DP")
	)
	(segment
		(start 118.904004 -32.045402)
		(end 121.592848 -36.128706)
		(width 0.1651)
		(layer "B.Cu")
		(net "PCIE_IOM_A_TO_COMP_A_17_DP")
	)
	(segment
		(start 119.783606 -21.504148)
		(end 119.43334 -21.504148)
		(width 0.1651)
		(layer "B.Cu")
		(net "PCIE_IOM_A_TO_COMP_A_17_DP")
	)
	(segment
		(start 146.489166 -47.555912)
		(end 150.61565 -50.287682)
		(width 0.1651)
		(layer "B.Cu")
		(net "PCIE_IOM_A_TO_COMP_A_17_DP")
	)
	(segment
		(start 176.43094 -55.514494)
		(end 198.165466 -50.972974)
		(width 0.1651)
		(layer "B.Cu")
		(net "PCIE_IOM_A_TO_COMP_A_17_DP")
	)
	(segment
		(start 118.904004 -22.033484)
		(end 118.904004 -32.045402)
		(width 0.1651)
		(layer "B.Cu")
		(net "PCIE_IOM_A_TO_COMP_A_17_DP")
	)
	(segment
		(start 119.949976 -20.950174)
		(end 119.949976 -21.337778)
		(width 0.1651)
		(layer "B.Cu")
		(net "PCIE_IOM_A_TO_COMP_A_17_DP")
	)
	(segment
		(start 145.922238 -47.440596)
		(end 146.489166 -47.555912)
		(width 0.1651)
		(layer "B.Cu")
		(net "PCIE_IOM_A_TO_COMP_A_17_DP")
	)
	(segment
		(start 234.621578 -59.30646)
		(end 236.424724 -59.30646)
		(width 0.1651)
		(layer "B.Cu")
		(net "PCIE_IOM_A_TO_COMP_A_17_DP")
	)
	(segment
		(start 121.592848 -36.128706)
		(end 135.098028 -45.238162)
		(width 0.1651)
		(layer "B.Cu")
		(net "PCIE_IOM_A_TO_COMP_A_17_DP")
	)
	(segment
		(start 236.918754 -59.10199)
		(end 237.449868 -58.570622)
		(width 0.1651)
		(layer "B.Cu")
		(net "PCIE_IOM_A_TO_COMP_A_17_DP")
	)
	(segment
		(start 237.52429 -58.391044)
		(end 237.52429 -58.104532)
		(width 0.1651)
		(layer "B.Cu")
		(net "PCIE_IOM_A_TO_COMP_A_17_DP")
	)
	(arc
		(start 237.285276 -57.661302)
		(mid 237.315979 -57.588371)
		(end 237.376462 -57.53735)
		(width 0.1651)
		(layer "B.Cu")
		(net "PCIE_IOM_A_TO_COMP_A_17_DP")
	)
	(arc
		(start 237.33252 -57.807352)
		(mid 237.315525 -57.78759)
		(end 237.301786 -57.765442)
		(width 0.1651)
		(layer "B.Cu")
		(net "PCIE_IOM_A_TO_COMP_A_17_DP")
	)
	(arc
		(start 119.949976 -21.337778)
		(mid 119.901247 -21.455419)
		(end 119.783606 -21.504148)
		(width 0.1651)
		(layer "B.Cu")
		(net "PCIE_IOM_A_TO_COMP_A_17_DP")
	)
	(arc
		(start 237.449868 -58.570622)
		(mid 237.504974 -58.488245)
		(end 237.52429 -58.391044)
		(width 0.1651)
		(layer "B.Cu")
		(net "PCIE_IOM_A_TO_COMP_A_17_DP")
	)
	(arc
		(start 237.301786 -57.765442)
		(mid 237.285179 -57.714694)
		(end 237.285276 -57.661302)
		(width 0.1651)
		(layer "B.Cu")
		(net "PCIE_IOM_A_TO_COMP_A_17_DP")
	)
	(arc
		(start 236.424724 -59.30646)
		(mid 236.692057 -59.25332)
		(end 236.918754 -59.10199)
		(width 0.1651)
		(layer "B.Cu")
		(net "PCIE_IOM_A_TO_COMP_A_17_DP")
	)
	(arc
		(start 237.52429 -58.104532)
		(mid 237.50494 -58.007345)
		(end 237.449868 -57.924954)
		(width 0.1651)
		(layer "B.Cu")
		(net "PCIE_IOM_A_TO_COMP_A_17_DP")
	)
	(arc
		(start 119.43334 -21.504148)
		(mid 119.059043 -21.659187)
		(end 118.904004 -22.033484)
		(width 0.1651)
		(layer "B.Cu")
		(net "PCIE_IOM_A_TO_COMP_A_17_DP")
	)
	(segment
		(start 234.721146 -59.01436)
		(end 236.42447 -59.01436)
		(width 0.1651)
		(layer "B.Cu")
		(net "PCIE_IOM_A_TO_COMP_A_17_DN")
	)
	(segment
		(start 231.775762 -57.235598)
		(end 232.261664 -57.332118)
		(width 0.1651)
		(layer "B.Cu")
		(net "PCIE_IOM_A_TO_COMP_A_17_DN")
	)
	(segment
		(start 160.596326 -51.88331)
		(end 160.693608 -52.030122)
		(width 0.1651)
		(layer "B.Cu")
		(net "PCIE_IOM_A_TO_COMP_A_17_DN")
	)
	(segment
		(start 232.837228 -57.563004)
		(end 234.721146 -59.01436)
		(width 0.1651)
		(layer "B.Cu")
		(net "PCIE_IOM_A_TO_COMP_A_17_DN")
	)
	(segment
		(start 159.478726 -51.783996)
		(end 159.96412 -51.882294)
		(width 0.1651)
		(layer "B.Cu")
		(net "PCIE_IOM_A_TO_COMP_A_17_DN")
	)
	(segment
		(start 119.196104 -31.957772)
		(end 120.500394 -33.93821)
		(width 0.1651)
		(layer "B.Cu")
		(net "PCIE_IOM_A_TO_COMP_A_17_DN")
	)
	(segment
		(start 218.642692 -54.62651)
		(end 219.128594 -54.72303)
		(width 0.1651)
		(layer "B.Cu")
		(net "PCIE_IOM_A_TO_COMP_A_17_DN")
	)
	(segment
		(start 215.541098 -54.010306)
		(end 215.631014 -54.144672)
		(width 0.1651)
		(layer "B.Cu")
		(net "PCIE_IOM_A_TO_COMP_A_17_DN")
	)
	(segment
		(start 208.384902 -52.705254)
		(end 208.870804 -52.801774)
		(width 0.1651)
		(layer "B.Cu")
		(net "PCIE_IOM_A_TO_COMP_A_17_DN")
	)
	(segment
		(start 208.870804 -52.801774)
		(end 209.017108 -52.703984)
		(width 0.1651)
		(layer "B.Cu")
		(net "PCIE_IOM_A_TO_COMP_A_17_DN")
	)
	(segment
		(start 198.163942 -50.674778)
		(end 205.223364 -52.077112)
		(width 0.1651)
		(layer "B.Cu")
		(net "PCIE_IOM_A_TO_COMP_A_17_DN")
	)
	(segment
		(start 219.128594 -54.72303)
		(end 219.21851 -54.857396)
		(width 0.1651)
		(layer "B.Cu")
		(net "PCIE_IOM_A_TO_COMP_A_17_DN")
	)
	(segment
		(start 232.351326 -57.466484)
		(end 232.837228 -57.563004)
		(width 0.1651)
		(layer "B.Cu")
		(net "PCIE_IOM_A_TO_COMP_A_17_DN")
	)
	(segment
		(start 176.429924 -55.216044)
		(end 198.163942 -50.674778)
		(width 0.1651)
		(layer "B.Cu")
		(net "PCIE_IOM_A_TO_COMP_A_17_DN")
	)
	(segment
		(start 120.500394 -33.938464)
		(end 121.804684 -35.919156)
		(width 0.1651)
		(layer "B.Cu")
		(net "PCIE_IOM_A_TO_COMP_A_17_DN")
	)
	(segment
		(start 119.196104 -22.033484)
		(end 119.196104 -31.957772)
		(width 0.1651)
		(layer "B.Cu")
		(net "PCIE_IOM_A_TO_COMP_A_17_DN")
	)
	(segment
		(start 205.223364 -52.077112)
		(end 205.369668 -51.979322)
		(width 0.1651)
		(layer "B.Cu")
		(net "PCIE_IOM_A_TO_COMP_A_17_DN")
	)
	(segment
		(start 236.88167 -57.839102)
		(end 236.866176 -57.836562)
		(width 0.1651)
		(layer "B.Cu")
		(net "PCIE_IOM_A_TO_COMP_A_17_DN")
	)
	(segment
		(start 229.959662 -56.99125)
		(end 230.445564 -57.08777)
		(width 0.1651)
		(layer "B.Cu")
		(net "PCIE_IOM_A_TO_COMP_A_17_DN")
	)
	(segment
		(start 232.261664 -57.332118)
		(end 232.351326 -57.466484)
		(width 0.1651)
		(layer "B.Cu")
		(net "PCIE_IOM_A_TO_COMP_A_17_DN")
	)
	(segment
		(start 216.116662 -54.241192)
		(end 216.251028 -54.151276)
		(width 0.1651)
		(layer "B.Cu")
		(net "PCIE_IOM_A_TO_COMP_A_17_DN")
	)
	(segment
		(start 231.641396 -57.325514)
		(end 231.775762 -57.235598)
		(width 0.1651)
		(layer "B.Cu")
		(net "PCIE_IOM_A_TO_COMP_A_17_DN")
	)
	(segment
		(start 236.710728 -57.861454)
		(end 236.050074 -58.200036)
		(width 0.1651)
		(layer "B.Cu")
		(net "PCIE_IOM_A_TO_COMP_A_17_DN")
	)
	(segment
		(start 157.681168 -51.293014)
		(end 158.166562 -51.391312)
		(width 0.1651)
		(layer "B.Cu")
		(net "PCIE_IOM_A_TO_COMP_A_17_DN")
	)
	(segment
		(start 158.749238 -51.636422)
		(end 158.89605 -51.53914)
		(width 0.1651)
		(layer "B.Cu")
		(net "PCIE_IOM_A_TO_COMP_A_17_DN")
	)
	(segment
		(start 231.065832 -57.094628)
		(end 231.155494 -57.228994)
		(width 0.1651)
		(layer "B.Cu")
		(net "PCIE_IOM_A_TO_COMP_A_17_DN")
	)
	(segment
		(start 205.95336 -52.222146)
		(end 206.439262 -52.318666)
		(width 0.1651)
		(layer "B.Cu")
		(net "PCIE_IOM_A_TO_COMP_A_17_DN")
	)
	(segment
		(start 216.826846 -54.382162)
		(end 217.312494 -54.478682)
		(width 0.1651)
		(layer "B.Cu")
		(net "PCIE_IOM_A_TO_COMP_A_17_DN")
	)
	(segment
		(start 128.509014 -40.441372)
		(end 135.213344 -44.963334)
		(width 0.1651)
		(layer "B.Cu")
		(net "PCIE_IOM_A_TO_COMP_A_17_DN")
	)
	(segment
		(start 230.57993 -56.998108)
		(end 231.065832 -57.094628)
		(width 0.1651)
		(layer "B.Cu")
		(net "PCIE_IOM_A_TO_COMP_A_17_DN")
	)
	(segment
		(start 206.439262 -52.318666)
		(end 206.585566 -52.220876)
		(width 0.1651)
		(layer "B.Cu")
		(net "PCIE_IOM_A_TO_COMP_A_17_DN")
	)
	(segment
		(start 228.188266 -56.522874)
		(end 228.674168 -56.619394)
		(width 0.1651)
		(layer "B.Cu")
		(net "PCIE_IOM_A_TO_COMP_A_17_DN")
	)
	(segment
		(start 208.287112 -52.55895)
		(end 208.384902 -52.705254)
		(width 0.1651)
		(layer "B.Cu")
		(net "PCIE_IOM_A_TO_COMP_A_17_DN")
	)
	(segment
		(start 128.509268 -40.441372)
		(end 128.509014 -40.441372)
		(width 0.1651)
		(layer "B.Cu")
		(net "PCIE_IOM_A_TO_COMP_A_17_DN")
	)
	(segment
		(start 207.654906 -52.56022)
		(end 207.80121 -52.46243)
		(width 0.1651)
		(layer "B.Cu")
		(net "PCIE_IOM_A_TO_COMP_A_17_DN")
	)
	(segment
		(start 205.85557 -52.075842)
		(end 205.95336 -52.222146)
		(width 0.1651)
		(layer "B.Cu")
		(net "PCIE_IOM_A_TO_COMP_A_17_DN")
	)
	(segment
		(start 214.92083 -54.003702)
		(end 215.055196 -53.913786)
		(width 0.1651)
		(layer "B.Cu")
		(net "PCIE_IOM_A_TO_COMP_A_17_DN")
	)
	(segment
		(start 236.711998 -58.895234)
		(end 237.18393 -58.423302)
		(width 0.1651)
		(layer "B.Cu")
		(net "PCIE_IOM_A_TO_COMP_A_17_DN")
	)
	(segment
		(start 219.21851 -54.857396)
		(end 228.0539 -56.61279)
		(width 0.1651)
		(layer "B.Cu")
		(net "PCIE_IOM_A_TO_COMP_A_17_DN")
	)
	(segment
		(start 205.369668 -51.979322)
		(end 205.85557 -52.075842)
		(width 0.1651)
		(layer "B.Cu")
		(net "PCIE_IOM_A_TO_COMP_A_17_DN")
	)
	(segment
		(start 120.500394 -33.93821)
		(end 120.500394 -33.938464)
		(width 0.1651)
		(layer "B.Cu")
		(net "PCIE_IOM_A_TO_COMP_A_17_DN")
	)
	(segment
		(start 207.169004 -52.4637)
		(end 207.654906 -52.56022)
		(width 0.1651)
		(layer "B.Cu")
		(net "PCIE_IOM_A_TO_COMP_A_17_DN")
	)
	(segment
		(start 160.693608 -52.030122)
		(end 176.429924 -55.216044)
		(width 0.1651)
		(layer "B.Cu")
		(net "PCIE_IOM_A_TO_COMP_A_17_DN")
	)
	(segment
		(start 146.603212 -47.28083)
		(end 150.729442 -50.0126)
		(width 0.1651)
		(layer "B.Cu")
		(net "PCIE_IOM_A_TO_COMP_A_17_DN")
	)
	(segment
		(start 217.44686 -54.38902)
		(end 217.932762 -54.48554)
		(width 0.1651)
		(layer "B.Cu")
		(net "PCIE_IOM_A_TO_COMP_A_17_DN")
	)
	(segment
		(start 229.384098 -56.760364)
		(end 229.87 -56.856884)
		(width 0.1651)
		(layer "B.Cu")
		(net "PCIE_IOM_A_TO_COMP_A_17_DN")
	)
	(segment
		(start 159.381444 -51.637438)
		(end 159.478726 -51.783996)
		(width 0.1651)
		(layer "B.Cu")
		(net "PCIE_IOM_A_TO_COMP_A_17_DN")
	)
	(segment
		(start 158.166562 -51.391312)
		(end 158.263844 -51.538124)
		(width 0.1651)
		(layer "B.Cu")
		(net "PCIE_IOM_A_TO_COMP_A_17_DN")
	)
	(segment
		(start 216.73693 -54.247796)
		(end 216.826846 -54.382162)
		(width 0.1651)
		(layer "B.Cu")
		(net "PCIE_IOM_A_TO_COMP_A_17_DN")
	)
	(segment
		(start 218.508326 -54.716426)
		(end 218.642692 -54.62651)
		(width 0.1651)
		(layer "B.Cu")
		(net "PCIE_IOM_A_TO_COMP_A_17_DN")
	)
	(segment
		(start 217.932762 -54.48554)
		(end 218.022678 -54.619906)
		(width 0.1651)
		(layer "B.Cu")
		(net "PCIE_IOM_A_TO_COMP_A_17_DN")
	)
	(segment
		(start 215.055196 -53.913786)
		(end 215.541098 -54.010306)
		(width 0.1651)
		(layer "B.Cu")
		(net "PCIE_IOM_A_TO_COMP_A_17_DN")
	)
	(segment
		(start 209.017108 -52.703984)
		(end 209.502756 -52.800504)
		(width 0.1651)
		(layer "B.Cu")
		(net "PCIE_IOM_A_TO_COMP_A_17_DN")
	)
	(segment
		(start 209.600546 -52.946808)
		(end 214.92083 -54.003702)
		(width 0.1651)
		(layer "B.Cu")
		(net "PCIE_IOM_A_TO_COMP_A_17_DN")
	)
	(segment
		(start 157.534356 -51.390296)
		(end 157.681168 -51.293014)
		(width 0.1651)
		(layer "B.Cu")
		(net "PCIE_IOM_A_TO_COMP_A_17_DN")
	)
	(segment
		(start 215.631014 -54.144672)
		(end 216.116662 -54.241192)
		(width 0.1651)
		(layer "B.Cu")
		(net "PCIE_IOM_A_TO_COMP_A_17_DN")
	)
	(segment
		(start 228.76383 -56.75376)
		(end 229.249732 -56.85028)
		(width 0.1651)
		(layer "B.Cu")
		(net "PCIE_IOM_A_TO_COMP_A_17_DN")
	)
	(segment
		(start 121.804684 -35.919156)
		(end 128.509268 -40.441372)
		(width 0.1651)
		(layer "B.Cu")
		(net "PCIE_IOM_A_TO_COMP_A_17_DN")
	)
	(segment
		(start 150.729442 -50.0126)
		(end 157.534356 -51.390296)
		(width 0.1651)
		(layer "B.Cu")
		(net "PCIE_IOM_A_TO_COMP_A_17_DN")
	)
	(segment
		(start 229.87 -56.856884)
		(end 229.959662 -56.99125)
		(width 0.1651)
		(layer "B.Cu")
		(net "PCIE_IOM_A_TO_COMP_A_17_DN")
	)
	(segment
		(start 207.80121 -52.46243)
		(end 208.287112 -52.55895)
		(width 0.1651)
		(layer "B.Cu")
		(net "PCIE_IOM_A_TO_COMP_A_17_DN")
	)
	(segment
		(start 228.674168 -56.619394)
		(end 228.76383 -56.75376)
		(width 0.1651)
		(layer "B.Cu")
		(net "PCIE_IOM_A_TO_COMP_A_17_DN")
	)
	(segment
		(start 216.251028 -54.151276)
		(end 216.73693 -54.247796)
		(width 0.1651)
		(layer "B.Cu")
		(net "PCIE_IOM_A_TO_COMP_A_17_DN")
	)
	(segment
		(start 218.022678 -54.619906)
		(end 218.508326 -54.716426)
		(width 0.1651)
		(layer "B.Cu")
		(net "PCIE_IOM_A_TO_COMP_A_17_DN")
	)
	(segment
		(start 230.445564 -57.08777)
		(end 230.57993 -56.998108)
		(width 0.1651)
		(layer "B.Cu")
		(net "PCIE_IOM_A_TO_COMP_A_17_DN")
	)
	(segment
		(start 158.263844 -51.538124)
		(end 158.749238 -51.636422)
		(width 0.1651)
		(layer "B.Cu")
		(net "PCIE_IOM_A_TO_COMP_A_17_DN")
	)
	(segment
		(start 231.155494 -57.228994)
		(end 231.641396 -57.325514)
		(width 0.1651)
		(layer "B.Cu")
		(net "PCIE_IOM_A_TO_COMP_A_17_DN")
	)
	(segment
		(start 207.071214 -52.317396)
		(end 207.169004 -52.4637)
		(width 0.1651)
		(layer "B.Cu")
		(net "PCIE_IOM_A_TO_COMP_A_17_DN")
	)
	(segment
		(start 237.23219 -58.306716)
		(end 237.23219 -58.18886)
		(width 0.1651)
		(layer "B.Cu")
		(net "PCIE_IOM_A_TO_COMP_A_17_DN")
	)
	(segment
		(start 119.949976 -22.350222)
		(end 119.949976 -21.962618)
		(width 0.1651)
		(layer "B.Cu")
		(net "PCIE_IOM_A_TO_COMP_A_17_DN")
	)
	(segment
		(start 228.0539 -56.61279)
		(end 228.188266 -56.522874)
		(width 0.1651)
		(layer "B.Cu")
		(net "PCIE_IOM_A_TO_COMP_A_17_DN")
	)
	(segment
		(start 217.312494 -54.478682)
		(end 217.44686 -54.38902)
		(width 0.1651)
		(layer "B.Cu")
		(net "PCIE_IOM_A_TO_COMP_A_17_DN")
	)
	(segment
		(start 159.96412 -51.882294)
		(end 160.110932 -51.785012)
		(width 0.1651)
		(layer "B.Cu")
		(net "PCIE_IOM_A_TO_COMP_A_17_DN")
	)
	(segment
		(start 158.89605 -51.53914)
		(end 159.381444 -51.637438)
		(width 0.1651)
		(layer "B.Cu")
		(net "PCIE_IOM_A_TO_COMP_A_17_DN")
	)
	(segment
		(start 119.783606 -21.796248)
		(end 119.43334 -21.796248)
		(width 0.1651)
		(layer "B.Cu")
		(net "PCIE_IOM_A_TO_COMP_A_17_DN")
	)
	(segment
		(start 206.585566 -52.220876)
		(end 207.071214 -52.317396)
		(width 0.1651)
		(layer "B.Cu")
		(net "PCIE_IOM_A_TO_COMP_A_17_DN")
	)
	(segment
		(start 135.213344 -44.963334)
		(end 146.603212 -47.28083)
		(width 0.1651)
		(layer "B.Cu")
		(net "PCIE_IOM_A_TO_COMP_A_17_DN")
	)
	(segment
		(start 237.18393 -58.072274)
		(end 237.021878 -57.910222)
		(width 0.1651)
		(layer "B.Cu")
		(net "PCIE_IOM_A_TO_COMP_A_17_DN")
	)
	(segment
		(start 160.110932 -51.785012)
		(end 160.596326 -51.88331)
		(width 0.1651)
		(layer "B.Cu")
		(net "PCIE_IOM_A_TO_COMP_A_17_DN")
	)
	(segment
		(start 229.249732 -56.85028)
		(end 229.384098 -56.760364)
		(width 0.1651)
		(layer "B.Cu")
		(net "PCIE_IOM_A_TO_COMP_A_17_DN")
	)
	(segment
		(start 209.502756 -52.800504)
		(end 209.600546 -52.946808)
		(width 0.1651)
		(layer "B.Cu")
		(net "PCIE_IOM_A_TO_COMP_A_17_DN")
	)
	(arc
		(start 237.23219 -58.18886)
		(mid 237.219642 -58.125776)
		(end 237.18393 -58.072274)
		(width 0.1651)
		(layer "B.Cu")
		(net "PCIE_IOM_A_TO_COMP_A_17_DN")
	)
	(arc
		(start 237.18393 -58.423302)
		(mid 237.219671 -58.369812)
		(end 237.23219 -58.306716)
		(width 0.1651)
		(layer "B.Cu")
		(net "PCIE_IOM_A_TO_COMP_A_17_DN")
	)
	(arc
		(start 237.021878 -57.910222)
		(mid 236.957412 -57.86355)
		(end 236.88167 -57.839102)
		(width 0.1651)
		(layer "B.Cu")
		(net "PCIE_IOM_A_TO_COMP_A_17_DN")
	)
	(arc
		(start 119.949976 -21.962618)
		(mid 119.901247 -21.844977)
		(end 119.783606 -21.796248)
		(width 0.1651)
		(layer "B.Cu")
		(net "PCIE_IOM_A_TO_COMP_A_17_DN")
	)
	(arc
		(start 236.866176 -57.836562)
		(mid 236.786466 -57.836635)
		(end 236.710728 -57.861454)
		(width 0.1651)
		(layer "B.Cu")
		(net "PCIE_IOM_A_TO_COMP_A_17_DN")
	)
	(arc
		(start 236.42447 -59.01436)
		(mid 236.58009 -58.983405)
		(end 236.711998 -58.895234)
		(width 0.1651)
		(layer "B.Cu")
		(net "PCIE_IOM_A_TO_COMP_A_17_DN")
	)
	(arc
		(start 119.43334 -21.796248)
		(mid 119.265589 -21.865733)
		(end 119.196104 -22.033484)
		(width 0.1651)
		(layer "B.Cu")
		(net "PCIE_IOM_A_TO_COMP_A_17_DN")
	)
	(segment
		(start 176.554384 -53.75021)
		(end 202.02271 -48.569372)
		(width 0.1651)
		(layer "B.Cu")
		(net "PCIE_IOM_A_TO_COMP_A_16_DP")
	)
	(segment
		(start 237.332266 -53.80736)
		(end 237.33252 -53.80736)
		(width 0.1651)
		(layer "B.Cu")
		(net "PCIE_IOM_A_TO_COMP_A_16_DP")
	)
	(segment
		(start 234.80649 -55.306468)
		(end 236.424724 -55.306468)
		(width 0.1651)
		(layer "B.Cu")
		(net "PCIE_IOM_A_TO_COMP_A_16_DP")
	)
	(segment
		(start 120.704102 -31.924244)
		(end 120.752108 -31.97225)
		(width 0.1651)
		(layer "B.Cu")
		(net "PCIE_IOM_A_TO_COMP_A_16_DP")
	)
	(segment
		(start 237.52429 -54.391052)
		(end 237.52429 -54.10454)
		(width 0.1651)
		(layer "B.Cu")
		(net "PCIE_IOM_A_TO_COMP_A_16_DP")
	)
	(segment
		(start 151.754078 -48.705262)
		(end 176.554384 -53.75021)
		(width 0.1651)
		(layer "B.Cu")
		(net "PCIE_IOM_A_TO_COMP_A_16_DP")
	)
	(segment
		(start 135.903208 -43.669966)
		(end 147.684236 -45.959776)
		(width 0.1651)
		(layer "B.Cu")
		(net "PCIE_IOM_A_TO_COMP_A_16_DP")
	)
	(segment
		(start 121.583704 -22.504146)
		(end 121.233438 -22.504146)
		(width 0.1651)
		(layer "B.Cu")
		(net "PCIE_IOM_A_TO_COMP_A_16_DP")
	)
	(segment
		(start 202.02271 -48.569372)
		(end 234.27309 -55.04561)
		(width 0.1651)
		(layer "B.Cu")
		(net "PCIE_IOM_A_TO_COMP_A_16_DP")
	)
	(segment
		(start 121.750074 -21.950172)
		(end 121.750074 -22.337776)
		(width 0.1651)
		(layer "B.Cu")
		(net "PCIE_IOM_A_TO_COMP_A_16_DP")
	)
	(segment
		(start 147.684236 -45.959776)
		(end 151.754078 -48.705262)
		(width 0.1651)
		(layer "B.Cu")
		(net "PCIE_IOM_A_TO_COMP_A_16_DP")
	)
	(segment
		(start 122.509026 -34.63798)
		(end 135.903208 -43.669966)
		(width 0.1651)
		(layer "B.Cu")
		(net "PCIE_IOM_A_TO_COMP_A_16_DP")
	)
	(segment
		(start 236.918754 -55.101998)
		(end 237.449868 -54.57063)
		(width 0.1651)
		(layer "B.Cu")
		(net "PCIE_IOM_A_TO_COMP_A_16_DP")
	)
	(segment
		(start 120.704102 -23.033482)
		(end 120.704102 -31.924244)
		(width 0.1651)
		(layer "B.Cu")
		(net "PCIE_IOM_A_TO_COMP_A_16_DP")
	)
	(segment
		(start 120.752108 -31.97225)
		(end 122.509026 -34.63798)
		(width 0.1651)
		(layer "B.Cu")
		(net "PCIE_IOM_A_TO_COMP_A_16_DP")
	)
	(segment
		(start 237.449868 -53.924962)
		(end 237.332266 -53.80736)
		(width 0.1651)
		(layer "B.Cu")
		(net "PCIE_IOM_A_TO_COMP_A_16_DP")
	)
	(segment
		(start 237.376462 -53.537358)
		(end 238.05007 -53.200046)
		(width 0.1651)
		(layer "B.Cu")
		(net "PCIE_IOM_A_TO_COMP_A_16_DP")
	)
	(segment
		(start 234.27309 -55.04561)
		(end 234.80649 -55.306468)
		(width 0.1651)
		(layer "B.Cu")
		(net "PCIE_IOM_A_TO_COMP_A_16_DP")
	)
	(arc
		(start 121.750074 -22.337776)
		(mid 121.701345 -22.455417)
		(end 121.583704 -22.504146)
		(width 0.1651)
		(layer "B.Cu")
		(net "PCIE_IOM_A_TO_COMP_A_16_DP")
	)
	(arc
		(start 237.33252 -53.80736)
		(mid 237.315525 -53.787598)
		(end 237.301786 -53.76545)
		(width 0.1651)
		(layer "B.Cu")
		(net "PCIE_IOM_A_TO_COMP_A_16_DP")
	)
	(arc
		(start 237.285276 -53.66131)
		(mid 237.315979 -53.588379)
		(end 237.376462 -53.537358)
		(width 0.1651)
		(layer "B.Cu")
		(net "PCIE_IOM_A_TO_COMP_A_16_DP")
	)
	(arc
		(start 237.52429 -54.10454)
		(mid 237.50494 -54.007353)
		(end 237.449868 -53.924962)
		(width 0.1651)
		(layer "B.Cu")
		(net "PCIE_IOM_A_TO_COMP_A_16_DP")
	)
	(arc
		(start 236.424724 -55.306468)
		(mid 236.692057 -55.253328)
		(end 236.918754 -55.101998)
		(width 0.1651)
		(layer "B.Cu")
		(net "PCIE_IOM_A_TO_COMP_A_16_DP")
	)
	(arc
		(start 237.449868 -54.57063)
		(mid 237.504974 -54.488253)
		(end 237.52429 -54.391052)
		(width 0.1651)
		(layer "B.Cu")
		(net "PCIE_IOM_A_TO_COMP_A_16_DP")
	)
	(arc
		(start 237.301786 -53.76545)
		(mid 237.285179 -53.714702)
		(end 237.285276 -53.66131)
		(width 0.1651)
		(layer "B.Cu")
		(net "PCIE_IOM_A_TO_COMP_A_16_DP")
	)
	(arc
		(start 121.233438 -22.504146)
		(mid 120.859141 -22.659185)
		(end 120.704102 -23.033482)
		(width 0.1651)
		(layer "B.Cu")
		(net "PCIE_IOM_A_TO_COMP_A_16_DP")
	)
	(segment
		(start 231.638348 -54.101746)
		(end 231.72801 -54.236112)
		(width 0.1651)
		(layer "B.Cu")
		(net "PCIE_IOM_A_TO_COMP_A_16_DN")
	)
	(segment
		(start 216.186258 -50.998628)
		(end 216.671906 -51.096164)
		(width 0.1651)
		(layer "B.Cu")
		(net "PCIE_IOM_A_TO_COMP_A_16_DN")
	)
	(segment
		(start 231.018588 -54.093618)
		(end 231.152954 -54.00421)
		(width 0.1651)
		(layer "B.Cu")
		(net "PCIE_IOM_A_TO_COMP_A_16_DN")
	)
	(segment
		(start 234.874308 -55.014368)
		(end 236.424978 -55.014368)
		(width 0.1651)
		(layer "B.Cu")
		(net "PCIE_IOM_A_TO_COMP_A_16_DN")
	)
	(segment
		(start 205.83652 -48.909986)
		(end 205.934056 -49.056544)
		(width 0.1651)
		(layer "B.Cu")
		(net "PCIE_IOM_A_TO_COMP_A_16_DN")
	)
	(segment
		(start 232.923334 -54.476142)
		(end 234.367578 -54.766464)
		(width 0.1651)
		(layer "B.Cu")
		(net "PCIE_IOM_A_TO_COMP_A_16_DN")
	)
	(segment
		(start 216.671906 -51.096164)
		(end 216.761314 -51.230784)
		(width 0.1651)
		(layer "B.Cu")
		(net "PCIE_IOM_A_TO_COMP_A_16_DN")
	)
	(segment
		(start 237.18393 -54.072282)
		(end 237.021878 -53.91023)
		(width 0.1651)
		(layer "B.Cu")
		(net "PCIE_IOM_A_TO_COMP_A_16_DN")
	)
	(segment
		(start 121.583704 -22.796246)
		(end 121.233438 -22.796246)
		(width 0.1651)
		(layer "B.Cu")
		(net "PCIE_IOM_A_TO_COMP_A_16_DN")
	)
	(segment
		(start 212.465666 -50.3682)
		(end 212.600286 -50.278538)
		(width 0.1651)
		(layer "B.Cu")
		(net "PCIE_IOM_A_TO_COMP_A_16_DN")
	)
	(segment
		(start 202.022456 -48.271176)
		(end 202.773788 -48.422052)
		(width 0.1651)
		(layer "B.Cu")
		(net "PCIE_IOM_A_TO_COMP_A_16_DN")
	)
	(segment
		(start 198.91756 -48.902874)
		(end 199.014588 -48.756062)
		(width 0.1651)
		(layer "B.Cu")
		(net "PCIE_IOM_A_TO_COMP_A_16_DN")
	)
	(segment
		(start 224.842324 -52.853336)
		(end 225.328226 -52.951126)
		(width 0.1651)
		(layer "B.Cu")
		(net "PCIE_IOM_A_TO_COMP_A_16_DN")
	)
	(segment
		(start 199.499982 -48.657256)
		(end 199.646794 -48.754538)
		(width 0.1651)
		(layer "B.Cu")
		(net "PCIE_IOM_A_TO_COMP_A_16_DN")
	)
	(segment
		(start 176.554384 -53.452014)
		(end 197.702932 -49.149762)
		(width 0.1651)
		(layer "B.Cu")
		(net "PCIE_IOM_A_TO_COMP_A_16_DN")
	)
	(segment
		(start 202.920346 -48.324516)
		(end 203.405994 -48.422052)
		(width 0.1651)
		(layer "B.Cu")
		(net "PCIE_IOM_A_TO_COMP_A_16_DN")
	)
	(segment
		(start 203.50353 -48.56861)
		(end 203.989178 -48.666146)
		(width 0.1651)
		(layer "B.Cu")
		(net "PCIE_IOM_A_TO_COMP_A_16_DN")
	)
	(segment
		(start 234.367578 -54.766464)
		(end 234.874308 -55.014368)
		(width 0.1651)
		(layer "B.Cu")
		(net "PCIE_IOM_A_TO_COMP_A_16_DN")
	)
	(segment
		(start 222.937578 -52.471066)
		(end 223.071944 -52.381404)
		(width 0.1651)
		(layer "B.Cu")
		(net "PCIE_IOM_A_TO_COMP_A_16_DN")
	)
	(segment
		(start 236.88167 -53.83911)
		(end 236.866176 -53.83657)
		(width 0.1651)
		(layer "B.Cu")
		(net "PCIE_IOM_A_TO_COMP_A_16_DN")
	)
	(segment
		(start 223.071944 -52.381404)
		(end 223.557592 -52.47894)
		(width 0.1651)
		(layer "B.Cu")
		(net "PCIE_IOM_A_TO_COMP_A_16_DN")
	)
	(segment
		(start 224.132902 -52.711096)
		(end 224.267268 -52.621434)
		(width 0.1651)
		(layer "B.Cu")
		(net "PCIE_IOM_A_TO_COMP_A_16_DN")
	)
	(segment
		(start 197.79996 -49.00295)
		(end 198.285354 -48.904398)
		(width 0.1651)
		(layer "B.Cu")
		(net "PCIE_IOM_A_TO_COMP_A_16_DN")
	)
	(segment
		(start 213.66099 -50.60823)
		(end 213.79561 -50.518568)
		(width 0.1651)
		(layer "B.Cu")
		(net "PCIE_IOM_A_TO_COMP_A_16_DN")
	)
	(segment
		(start 205.934056 -49.056544)
		(end 212.465666 -50.3682)
		(width 0.1651)
		(layer "B.Cu")
		(net "PCIE_IOM_A_TO_COMP_A_16_DN")
	)
	(segment
		(start 205.204314 -48.909986)
		(end 205.350872 -48.812704)
		(width 0.1651)
		(layer "B.Cu")
		(net "PCIE_IOM_A_TO_COMP_A_16_DN")
	)
	(segment
		(start 212.600286 -50.278538)
		(end 213.085934 -50.376074)
		(width 0.1651)
		(layer "B.Cu")
		(net "PCIE_IOM_A_TO_COMP_A_16_DN")
	)
	(segment
		(start 120.996202 -31.811722)
		(end 122.720862 -34.42843)
		(width 0.1651)
		(layer "B.Cu")
		(net "PCIE_IOM_A_TO_COMP_A_16_DN")
	)
	(segment
		(start 237.23219 -54.306724)
		(end 237.23219 -54.188868)
		(width 0.1651)
		(layer "B.Cu")
		(net "PCIE_IOM_A_TO_COMP_A_16_DN")
	)
	(segment
		(start 213.79561 -50.518568)
		(end 214.281258 -50.616104)
		(width 0.1651)
		(layer "B.Cu")
		(net "PCIE_IOM_A_TO_COMP_A_16_DN")
	)
	(segment
		(start 122.720862 -34.42843)
		(end 136.017254 -43.394376)
		(width 0.1651)
		(layer "B.Cu")
		(net "PCIE_IOM_A_TO_COMP_A_16_DN")
	)
	(segment
		(start 236.711998 -54.895242)
		(end 237.18393 -54.42331)
		(width 0.1651)
		(layer "B.Cu")
		(net "PCIE_IOM_A_TO_COMP_A_16_DN")
	)
	(segment
		(start 232.213912 -54.333648)
		(end 232.348278 -54.24424)
		(width 0.1651)
		(layer "B.Cu")
		(net "PCIE_IOM_A_TO_COMP_A_16_DN")
	)
	(segment
		(start 224.267268 -52.621434)
		(end 224.752916 -52.71897)
		(width 0.1651)
		(layer "B.Cu")
		(net "PCIE_IOM_A_TO_COMP_A_16_DN")
	)
	(segment
		(start 203.405994 -48.422052)
		(end 203.50353 -48.56861)
		(width 0.1651)
		(layer "B.Cu")
		(net "PCIE_IOM_A_TO_COMP_A_16_DN")
	)
	(segment
		(start 136.017254 -43.394376)
		(end 147.798536 -45.684186)
		(width 0.1651)
		(layer "B.Cu")
		(net "PCIE_IOM_A_TO_COMP_A_16_DN")
	)
	(segment
		(start 225.328226 -52.951126)
		(end 225.462592 -52.861464)
		(width 0.1651)
		(layer "B.Cu")
		(net "PCIE_IOM_A_TO_COMP_A_16_DN")
	)
	(segment
		(start 198.432166 -49.001426)
		(end 198.91756 -48.902874)
		(width 0.1651)
		(layer "B.Cu")
		(net "PCIE_IOM_A_TO_COMP_A_16_DN")
	)
	(segment
		(start 222.451676 -52.373276)
		(end 222.937578 -52.471066)
		(width 0.1651)
		(layer "B.Cu")
		(net "PCIE_IOM_A_TO_COMP_A_16_DN")
	)
	(segment
		(start 215.56599 -50.990754)
		(end 216.051638 -51.08829)
		(width 0.1651)
		(layer "B.Cu")
		(net "PCIE_IOM_A_TO_COMP_A_16_DN")
	)
	(segment
		(start 204.135736 -48.56861)
		(end 204.62113 -48.666146)
		(width 0.1651)
		(layer "B.Cu")
		(net "PCIE_IOM_A_TO_COMP_A_16_DN")
	)
	(segment
		(start 220.787976 -52.039266)
		(end 221.742254 -52.231036)
		(width 0.1651)
		(layer "B.Cu")
		(net "PCIE_IOM_A_TO_COMP_A_16_DN")
	)
	(segment
		(start 224.752916 -52.71897)
		(end 224.842324 -52.853336)
		(width 0.1651)
		(layer "B.Cu")
		(net "PCIE_IOM_A_TO_COMP_A_16_DN")
	)
	(segment
		(start 199.646794 -48.754538)
		(end 202.022456 -48.271176)
		(width 0.1651)
		(layer "B.Cu")
		(net "PCIE_IOM_A_TO_COMP_A_16_DN")
	)
	(segment
		(start 232.348278 -54.24424)
		(end 232.833672 -54.341776)
		(width 0.1651)
		(layer "B.Cu")
		(net "PCIE_IOM_A_TO_COMP_A_16_DN")
	)
	(segment
		(start 214.281258 -50.616104)
		(end 214.370666 -50.750724)
		(width 0.1651)
		(layer "B.Cu")
		(net "PCIE_IOM_A_TO_COMP_A_16_DN")
	)
	(segment
		(start 203.989178 -48.666146)
		(end 204.135736 -48.56861)
		(width 0.1651)
		(layer "B.Cu")
		(net "PCIE_IOM_A_TO_COMP_A_16_DN")
	)
	(segment
		(start 197.702932 -49.149762)
		(end 197.79996 -49.00295)
		(width 0.1651)
		(layer "B.Cu")
		(net "PCIE_IOM_A_TO_COMP_A_16_DN")
	)
	(segment
		(start 232.833672 -54.341776)
		(end 232.923334 -54.476142)
		(width 0.1651)
		(layer "B.Cu")
		(net "PCIE_IOM_A_TO_COMP_A_16_DN")
	)
	(segment
		(start 236.710728 -53.861462)
		(end 236.050074 -54.200044)
		(width 0.1651)
		(layer "B.Cu")
		(net "PCIE_IOM_A_TO_COMP_A_16_DN")
	)
	(segment
		(start 223.557592 -52.47894)
		(end 223.647 -52.613306)
		(width 0.1651)
		(layer "B.Cu")
		(net "PCIE_IOM_A_TO_COMP_A_16_DN")
	)
	(segment
		(start 120.996202 -23.033482)
		(end 120.996202 -31.811722)
		(width 0.1651)
		(layer "B.Cu")
		(net "PCIE_IOM_A_TO_COMP_A_16_DN")
	)
	(segment
		(start 215.476582 -50.856134)
		(end 215.56599 -50.990754)
		(width 0.1651)
		(layer "B.Cu")
		(net "PCIE_IOM_A_TO_COMP_A_16_DN")
	)
	(segment
		(start 213.085934 -50.376074)
		(end 213.175342 -50.510694)
		(width 0.1651)
		(layer "B.Cu")
		(net "PCIE_IOM_A_TO_COMP_A_16_DN")
	)
	(segment
		(start 216.051638 -51.08829)
		(end 216.186258 -50.998628)
		(width 0.1651)
		(layer "B.Cu")
		(net "PCIE_IOM_A_TO_COMP_A_16_DN")
	)
	(segment
		(start 225.462592 -52.861464)
		(end 225.94824 -52.959)
		(width 0.1651)
		(layer "B.Cu")
		(net "PCIE_IOM_A_TO_COMP_A_16_DN")
	)
	(segment
		(start 147.798536 -45.684186)
		(end 151.869394 -48.430434)
		(width 0.1651)
		(layer "B.Cu")
		(net "PCIE_IOM_A_TO_COMP_A_16_DN")
	)
	(segment
		(start 121.750074 -23.35022)
		(end 121.750074 -22.962616)
		(width 0.1651)
		(layer "B.Cu")
		(net "PCIE_IOM_A_TO_COMP_A_16_DN")
	)
	(segment
		(start 204.62113 -48.666146)
		(end 204.718666 -48.812704)
		(width 0.1651)
		(layer "B.Cu")
		(net "PCIE_IOM_A_TO_COMP_A_16_DN")
	)
	(segment
		(start 226.037648 -53.093366)
		(end 231.018588 -54.093618)
		(width 0.1651)
		(layer "B.Cu")
		(net "PCIE_IOM_A_TO_COMP_A_16_DN")
	)
	(segment
		(start 221.87662 -52.141374)
		(end 222.362268 -52.23891)
		(width 0.1651)
		(layer "B.Cu")
		(net "PCIE_IOM_A_TO_COMP_A_16_DN")
	)
	(segment
		(start 214.990934 -50.758598)
		(end 215.476582 -50.856134)
		(width 0.1651)
		(layer "B.Cu")
		(net "PCIE_IOM_A_TO_COMP_A_16_DN")
	)
	(segment
		(start 198.285354 -48.904398)
		(end 198.432166 -49.001426)
		(width 0.1651)
		(layer "B.Cu")
		(net "PCIE_IOM_A_TO_COMP_A_16_DN")
	)
	(segment
		(start 222.362268 -52.23891)
		(end 222.451676 -52.373276)
		(width 0.1651)
		(layer "B.Cu")
		(net "PCIE_IOM_A_TO_COMP_A_16_DN")
	)
	(segment
		(start 231.152954 -54.00421)
		(end 231.638348 -54.101746)
		(width 0.1651)
		(layer "B.Cu")
		(net "PCIE_IOM_A_TO_COMP_A_16_DN")
	)
	(segment
		(start 202.773788 -48.422052)
		(end 202.920346 -48.324516)
		(width 0.1651)
		(layer "B.Cu")
		(net "PCIE_IOM_A_TO_COMP_A_16_DN")
	)
	(segment
		(start 214.856314 -50.84826)
		(end 214.990934 -50.758598)
		(width 0.1651)
		(layer "B.Cu")
		(net "PCIE_IOM_A_TO_COMP_A_16_DN")
	)
	(segment
		(start 225.94824 -52.959)
		(end 226.037648 -53.093366)
		(width 0.1651)
		(layer "B.Cu")
		(net "PCIE_IOM_A_TO_COMP_A_16_DN")
	)
	(segment
		(start 204.718666 -48.812704)
		(end 205.204314 -48.909986)
		(width 0.1651)
		(layer "B.Cu")
		(net "PCIE_IOM_A_TO_COMP_A_16_DN")
	)
	(segment
		(start 216.761314 -51.230784)
		(end 220.787976 -52.039266)
		(width 0.1651)
		(layer "B.Cu")
		(net "PCIE_IOM_A_TO_COMP_A_16_DN")
	)
	(segment
		(start 205.350872 -48.812704)
		(end 205.83652 -48.909986)
		(width 0.1651)
		(layer "B.Cu")
		(net "PCIE_IOM_A_TO_COMP_A_16_DN")
	)
	(segment
		(start 221.742254 -52.231036)
		(end 221.87662 -52.141374)
		(width 0.1651)
		(layer "B.Cu")
		(net "PCIE_IOM_A_TO_COMP_A_16_DN")
	)
	(segment
		(start 214.370666 -50.750724)
		(end 214.856314 -50.84826)
		(width 0.1651)
		(layer "B.Cu")
		(net "PCIE_IOM_A_TO_COMP_A_16_DN")
	)
	(segment
		(start 223.647 -52.613306)
		(end 224.132902 -52.711096)
		(width 0.1651)
		(layer "B.Cu")
		(net "PCIE_IOM_A_TO_COMP_A_16_DN")
	)
	(segment
		(start 231.72801 -54.236112)
		(end 232.213912 -54.333648)
		(width 0.1651)
		(layer "B.Cu")
		(net "PCIE_IOM_A_TO_COMP_A_16_DN")
	)
	(segment
		(start 199.014588 -48.756062)
		(end 199.499982 -48.657256)
		(width 0.1651)
		(layer "B.Cu")
		(net "PCIE_IOM_A_TO_COMP_A_16_DN")
	)
	(segment
		(start 213.175342 -50.510694)
		(end 213.66099 -50.60823)
		(width 0.1651)
		(layer "B.Cu")
		(net "PCIE_IOM_A_TO_COMP_A_16_DN")
	)
	(segment
		(start 151.869394 -48.430434)
		(end 176.554384 -53.452014)
		(width 0.1651)
		(layer "B.Cu")
		(net "PCIE_IOM_A_TO_COMP_A_16_DN")
	)
	(arc
		(start 121.233438 -22.796246)
		(mid 121.065687 -22.865731)
		(end 120.996202 -23.033482)
		(width 0.1651)
		(layer "B.Cu")
		(net "PCIE_IOM_A_TO_COMP_A_16_DN")
	)
	(arc
		(start 237.23219 -54.188868)
		(mid 237.219642 -54.125784)
		(end 237.18393 -54.072282)
		(width 0.1651)
		(layer "B.Cu")
		(net "PCIE_IOM_A_TO_COMP_A_16_DN")
	)
	(arc
		(start 121.750074 -22.962616)
		(mid 121.701345 -22.844975)
		(end 121.583704 -22.796246)
		(width 0.1651)
		(layer "B.Cu")
		(net "PCIE_IOM_A_TO_COMP_A_16_DN")
	)
	(arc
		(start 237.021878 -53.91023)
		(mid 236.957412 -53.863558)
		(end 236.88167 -53.83911)
		(width 0.1651)
		(layer "B.Cu")
		(net "PCIE_IOM_A_TO_COMP_A_16_DN")
	)
	(arc
		(start 236.424978 -55.014368)
		(mid 236.580325 -54.983316)
		(end 236.711998 -54.895242)
		(width 0.1651)
		(layer "B.Cu")
		(net "PCIE_IOM_A_TO_COMP_A_16_DN")
	)
	(arc
		(start 237.18393 -54.42331)
		(mid 237.219671 -54.36982)
		(end 237.23219 -54.306724)
		(width 0.1651)
		(layer "B.Cu")
		(net "PCIE_IOM_A_TO_COMP_A_16_DN")
	)
	(arc
		(start 236.866176 -53.83657)
		(mid 236.786466 -53.836643)
		(end 236.710728 -53.861462)
		(width 0.1651)
		(layer "B.Cu")
		(net "PCIE_IOM_A_TO_COMP_A_16_DN")
	)
	(segment
		(start 135.856218 -39.158672)
		(end 141.233906 -42.787062)
		(width 0.1651)
		(layer "B.Cu")
		(net "PCIE_IOM_A_TO_COMP_A_15_DP")
	)
	(segment
		(start 131.796028 -22.033484)
		(end 131.796028 -32.991552)
		(width 0.1651)
		(layer "B.Cu")
		(net "PCIE_IOM_A_TO_COMP_A_15_DP")
	)
	(segment
		(start 141.233906 -42.787062)
		(end 155.852114 -45.62856)
		(width 0.1651)
		(layer "B.Cu")
		(net "PCIE_IOM_A_TO_COMP_A_15_DP")
	)
	(segment
		(start 237.218474 -49.560988)
		(end 237.233968 -49.563528)
		(width 0.1651)
		(layer "B.Cu")
		(net "PCIE_IOM_A_TO_COMP_A_15_DP")
	)
	(segment
		(start 155.852114 -45.62856)
		(end 182.878222 -39.96817)
		(width 0.1651)
		(layer "B.Cu")
		(net "PCIE_IOM_A_TO_COMP_A_15_DP")
	)
	(segment
		(start 130.750056 -20.950174)
		(end 130.750056 -21.337778)
		(width 0.1651)
		(layer "B.Cu")
		(net "PCIE_IOM_A_TO_COMP_A_15_DP")
	)
	(segment
		(start 228.738684 -49.083976)
		(end 236.388148 -49.083976)
		(width 0.1651)
		(layer "B.Cu")
		(net "PCIE_IOM_A_TO_COMP_A_15_DP")
	)
	(segment
		(start 220.657674 -47.477426)
		(end 220.65742 -47.47768)
		(width 0.1651)
		(layer "B.Cu")
		(net "PCIE_IOM_A_TO_COMP_A_15_DP")
	)
	(segment
		(start 220.65742 -47.47768)
		(end 228.738684 -49.083976)
		(width 0.1651)
		(layer "B.Cu")
		(net "PCIE_IOM_A_TO_COMP_A_15_DP")
	)
	(segment
		(start 182.878222 -39.96817)
		(end 220.657674 -47.477426)
		(width 0.1651)
		(layer "B.Cu")
		(net "PCIE_IOM_A_TO_COMP_A_15_DP")
	)
	(segment
		(start 130.916426 -21.504148)
		(end 131.266692 -21.504148)
		(width 0.1651)
		(layer "B.Cu")
		(net "PCIE_IOM_A_TO_COMP_A_15_DP")
	)
	(segment
		(start 236.873288 -49.28489)
		(end 237.078266 -49.489868)
		(width 0.1651)
		(layer "B.Cu")
		(net "PCIE_IOM_A_TO_COMP_A_15_DP")
	)
	(segment
		(start 131.796028 -32.991552)
		(end 135.856218 -39.158672)
		(width 0.1651)
		(layer "B.Cu")
		(net "PCIE_IOM_A_TO_COMP_A_15_DP")
	)
	(segment
		(start 237.389416 -49.538636)
		(end 238.05007 -49.200054)
		(width 0.1651)
		(layer "B.Cu")
		(net "PCIE_IOM_A_TO_COMP_A_15_DP")
	)
	(arc
		(start 236.388148 -49.083976)
		(mid 236.55859 -49.10542)
		(end 236.718348 -49.168558)
		(width 0.1651)
		(layer "B.Cu")
		(net "PCIE_IOM_A_TO_COMP_A_15_DP")
	)
	(arc
		(start 130.750056 -21.337778)
		(mid 130.798785 -21.455419)
		(end 130.916426 -21.504148)
		(width 0.1651)
		(layer "B.Cu")
		(net "PCIE_IOM_A_TO_COMP_A_15_DP")
	)
	(arc
		(start 236.718348 -49.168558)
		(mid 236.799931 -49.221243)
		(end 236.873288 -49.28489)
		(width 0.1651)
		(layer "B.Cu")
		(net "PCIE_IOM_A_TO_COMP_A_15_DP")
	)
	(arc
		(start 237.078266 -49.489868)
		(mid 237.142732 -49.53654)
		(end 237.218474 -49.560988)
		(width 0.1651)
		(layer "B.Cu")
		(net "PCIE_IOM_A_TO_COMP_A_15_DP")
	)
	(arc
		(start 237.233968 -49.563528)
		(mid 237.313678 -49.563455)
		(end 237.389416 -49.538636)
		(width 0.1651)
		(layer "B.Cu")
		(net "PCIE_IOM_A_TO_COMP_A_15_DP")
	)
	(arc
		(start 131.266692 -21.504148)
		(mid 131.640989 -21.659187)
		(end 131.796028 -22.033484)
		(width 0.1651)
		(layer "B.Cu")
		(net "PCIE_IOM_A_TO_COMP_A_15_DP")
	)
	(segment
		(start 221.796356 -48.001936)
		(end 221.886272 -48.136302)
		(width 0.1651)
		(layer "B.Cu")
		(net "PCIE_IOM_A_TO_COMP_A_15_DN")
	)
	(segment
		(start 220.600524 -47.764192)
		(end 220.69044 -47.898558)
		(width 0.1651)
		(layer "B.Cu")
		(net "PCIE_IOM_A_TO_COMP_A_15_DN")
	)
	(segment
		(start 220.69044 -47.898558)
		(end 221.176088 -47.995078)
		(width 0.1651)
		(layer "B.Cu")
		(net "PCIE_IOM_A_TO_COMP_A_15_DN")
	)
	(segment
		(start 130.750056 -22.350222)
		(end 130.750056 -21.962618)
		(width 0.1651)
		(layer "B.Cu")
		(net "PCIE_IOM_A_TO_COMP_A_15_DN")
	)
	(segment
		(start 221.310454 -47.905416)
		(end 221.796356 -48.001936)
		(width 0.1651)
		(layer "B.Cu")
		(net "PCIE_IOM_A_TO_COMP_A_15_DN")
	)
	(segment
		(start 131.503928 -33.079182)
		(end 135.644382 -39.368222)
		(width 0.1651)
		(layer "B.Cu")
		(net "PCIE_IOM_A_TO_COMP_A_15_DN")
	)
	(segment
		(start 223.08185 -48.374046)
		(end 223.567752 -48.470566)
		(width 0.1651)
		(layer "B.Cu")
		(net "PCIE_IOM_A_TO_COMP_A_15_DN")
	)
	(segment
		(start 224.89795 -48.618394)
		(end 228.709728 -49.376076)
		(width 0.1651)
		(layer "B.Cu")
		(net "PCIE_IOM_A_TO_COMP_A_15_DN")
	)
	(segment
		(start 236.723682 -49.86274)
		(end 236.050074 -50.200052)
		(width 0.1651)
		(layer "B.Cu")
		(net "PCIE_IOM_A_TO_COMP_A_15_DN")
	)
	(segment
		(start 131.503928 -22.033484)
		(end 131.503928 -33.079182)
		(width 0.1651)
		(layer "B.Cu")
		(net "PCIE_IOM_A_TO_COMP_A_15_DN")
	)
	(segment
		(start 236.666532 -49.491646)
		(end 236.767624 -49.592738)
		(width 0.1651)
		(layer "B.Cu")
		(net "PCIE_IOM_A_TO_COMP_A_15_DN")
	)
	(segment
		(start 222.506286 -48.14316)
		(end 222.992188 -48.23968)
		(width 0.1651)
		(layer "B.Cu")
		(net "PCIE_IOM_A_TO_COMP_A_15_DN")
	)
	(segment
		(start 224.18802 -48.477424)
		(end 224.277682 -48.61179)
		(width 0.1651)
		(layer "B.Cu")
		(net "PCIE_IOM_A_TO_COMP_A_15_DN")
	)
	(segment
		(start 228.709728 -49.376076)
		(end 236.388402 -49.376076)
		(width 0.1651)
		(layer "B.Cu")
		(net "PCIE_IOM_A_TO_COMP_A_15_DN")
	)
	(segment
		(start 222.992188 -48.23968)
		(end 223.08185 -48.374046)
		(width 0.1651)
		(layer "B.Cu")
		(net "PCIE_IOM_A_TO_COMP_A_15_DN")
	)
	(segment
		(start 141.119606 -43.062652)
		(end 155.8544 -45.926756)
		(width 0.1651)
		(layer "B.Cu")
		(net "PCIE_IOM_A_TO_COMP_A_15_DN")
	)
	(segment
		(start 155.8544 -45.926756)
		(end 182.879746 -40.266366)
		(width 0.1651)
		(layer "B.Cu")
		(net "PCIE_IOM_A_TO_COMP_A_15_DN")
	)
	(segment
		(start 223.702118 -48.38065)
		(end 224.18802 -48.477424)
		(width 0.1651)
		(layer "B.Cu")
		(net "PCIE_IOM_A_TO_COMP_A_15_DN")
	)
	(segment
		(start 221.176088 -47.995078)
		(end 221.310454 -47.905416)
		(width 0.1651)
		(layer "B.Cu")
		(net "PCIE_IOM_A_TO_COMP_A_15_DN")
	)
	(segment
		(start 221.886272 -48.136302)
		(end 222.37192 -48.232822)
		(width 0.1651)
		(layer "B.Cu")
		(net "PCIE_IOM_A_TO_COMP_A_15_DN")
	)
	(segment
		(start 135.644382 -39.368222)
		(end 141.119606 -43.062652)
		(width 0.1651)
		(layer "B.Cu")
		(net "PCIE_IOM_A_TO_COMP_A_15_DN")
	)
	(segment
		(start 224.763584 -48.70831)
		(end 224.89795 -48.618394)
		(width 0.1651)
		(layer "B.Cu")
		(net "PCIE_IOM_A_TO_COMP_A_15_DN")
	)
	(segment
		(start 224.277682 -48.61179)
		(end 224.763584 -48.70831)
		(width 0.1651)
		(layer "B.Cu")
		(net "PCIE_IOM_A_TO_COMP_A_15_DN")
	)
	(segment
		(start 182.879746 -40.266366)
		(end 220.600524 -47.764192)
		(width 0.1651)
		(layer "B.Cu")
		(net "PCIE_IOM_A_TO_COMP_A_15_DN")
	)
	(segment
		(start 223.567752 -48.470566)
		(end 223.702118 -48.38065)
		(width 0.1651)
		(layer "B.Cu")
		(net "PCIE_IOM_A_TO_COMP_A_15_DN")
	)
	(segment
		(start 130.916426 -21.796248)
		(end 131.266692 -21.796248)
		(width 0.1651)
		(layer "B.Cu")
		(net "PCIE_IOM_A_TO_COMP_A_15_DN")
	)
	(segment
		(start 222.37192 -48.232822)
		(end 222.506286 -48.14316)
		(width 0.1651)
		(layer "B.Cu")
		(net "PCIE_IOM_A_TO_COMP_A_15_DN")
	)
	(arc
		(start 236.814868 -49.738788)
		(mid 236.784165 -49.811719)
		(end 236.723682 -49.86274)
		(width 0.1651)
		(layer "B.Cu")
		(net "PCIE_IOM_A_TO_COMP_A_15_DN")
	)
	(arc
		(start 236.388402 -49.376076)
		(mid 236.4861 -49.388512)
		(end 236.577632 -49.424844)
		(width 0.1651)
		(layer "B.Cu")
		(net "PCIE_IOM_A_TO_COMP_A_15_DN")
	)
	(arc
		(start 131.266692 -21.796248)
		(mid 131.434443 -21.865733)
		(end 131.503928 -22.033484)
		(width 0.1651)
		(layer "B.Cu")
		(net "PCIE_IOM_A_TO_COMP_A_15_DN")
	)
	(arc
		(start 130.750056 -21.962618)
		(mid 130.798785 -21.844977)
		(end 130.916426 -21.796248)
		(width 0.1651)
		(layer "B.Cu")
		(net "PCIE_IOM_A_TO_COMP_A_15_DN")
	)
	(arc
		(start 236.767624 -49.592738)
		(mid 236.808852 -49.660078)
		(end 236.814868 -49.738788)
		(width 0.1651)
		(layer "B.Cu")
		(net "PCIE_IOM_A_TO_COMP_A_15_DN")
	)
	(arc
		(start 236.577632 -49.424844)
		(mid 236.624445 -49.455098)
		(end 236.666532 -49.491646)
		(width 0.1651)
		(layer "B.Cu")
		(net "PCIE_IOM_A_TO_COMP_A_15_DN")
	)
	(segment
		(start 137.085324 -38.067996)
		(end 141.74089 -41.20896)
		(width 0.1651)
		(layer "B.Cu")
		(net "PCIE_IOM_A_TO_COMP_A_14_DP")
	)
	(segment
		(start 235.268008 -45.083984)
		(end 236.388148 -45.083984)
		(width 0.1651)
		(layer "B.Cu")
		(net "PCIE_IOM_A_TO_COMP_A_14_DP")
	)
	(segment
		(start 236.873288 -45.284898)
		(end 237.078266 -45.489876)
		(width 0.1651)
		(layer "B.Cu")
		(net "PCIE_IOM_A_TO_COMP_A_14_DP")
	)
	(segment
		(start 155.161234 -43.817794)
		(end 191.066928 -36.297616)
		(width 0.1651)
		(layer "B.Cu")
		(net "PCIE_IOM_A_TO_COMP_A_14_DP")
	)
	(segment
		(start 133.595872 -23.033482)
		(end 133.595872 -32.769302)
		(width 0.1651)
		(layer "B.Cu")
		(net "PCIE_IOM_A_TO_COMP_A_14_DP")
	)
	(segment
		(start 132.5499 -21.950172)
		(end 132.5499 -22.337776)
		(width 0.1651)
		(layer "B.Cu")
		(net "PCIE_IOM_A_TO_COMP_A_14_DP")
	)
	(segment
		(start 133.595872 -32.769302)
		(end 137.085324 -38.067996)
		(width 0.1651)
		(layer "B.Cu")
		(net "PCIE_IOM_A_TO_COMP_A_14_DP")
	)
	(segment
		(start 237.218474 -45.560996)
		(end 237.233968 -45.563536)
		(width 0.1651)
		(layer "B.Cu")
		(net "PCIE_IOM_A_TO_COMP_A_14_DP")
	)
	(segment
		(start 191.066928 -36.297616)
		(end 235.268008 -45.083984)
		(width 0.1651)
		(layer "B.Cu")
		(net "PCIE_IOM_A_TO_COMP_A_14_DP")
	)
	(segment
		(start 237.389416 -45.538644)
		(end 238.05007 -45.200062)
		(width 0.1651)
		(layer "B.Cu")
		(net "PCIE_IOM_A_TO_COMP_A_14_DP")
	)
	(segment
		(start 132.71627 -22.504146)
		(end 133.066536 -22.504146)
		(width 0.1651)
		(layer "B.Cu")
		(net "PCIE_IOM_A_TO_COMP_A_14_DP")
	)
	(segment
		(start 141.74089 -41.20896)
		(end 155.161234 -43.817794)
		(width 0.1651)
		(layer "B.Cu")
		(net "PCIE_IOM_A_TO_COMP_A_14_DP")
	)
	(arc
		(start 237.233968 -45.563536)
		(mid 237.313678 -45.563463)
		(end 237.389416 -45.538644)
		(width 0.1651)
		(layer "B.Cu")
		(net "PCIE_IOM_A_TO_COMP_A_14_DP")
	)
	(arc
		(start 132.5499 -22.337776)
		(mid 132.598629 -22.455417)
		(end 132.71627 -22.504146)
		(width 0.1651)
		(layer "B.Cu")
		(net "PCIE_IOM_A_TO_COMP_A_14_DP")
	)
	(arc
		(start 236.718348 -45.168566)
		(mid 236.799931 -45.221251)
		(end 236.873288 -45.284898)
		(width 0.1651)
		(layer "B.Cu")
		(net "PCIE_IOM_A_TO_COMP_A_14_DP")
	)
	(arc
		(start 133.066536 -22.504146)
		(mid 133.440833 -22.659185)
		(end 133.595872 -23.033482)
		(width 0.1651)
		(layer "B.Cu")
		(net "PCIE_IOM_A_TO_COMP_A_14_DP")
	)
	(arc
		(start 237.078266 -45.489876)
		(mid 237.142732 -45.536548)
		(end 237.218474 -45.560996)
		(width 0.1651)
		(layer "B.Cu")
		(net "PCIE_IOM_A_TO_COMP_A_14_DP")
	)
	(arc
		(start 236.388148 -45.083984)
		(mid 236.55859 -45.105428)
		(end 236.718348 -45.168566)
		(width 0.1651)
		(layer "B.Cu")
		(net "PCIE_IOM_A_TO_COMP_A_14_DP")
	)
	(segment
		(start 207.532478 -39.985188)
		(end 207.666844 -39.895272)
		(width 0.1651)
		(layer "B.Cu")
		(net "PCIE_IOM_A_TO_COMP_A_14_DN")
	)
	(segment
		(start 207.666844 -39.895272)
		(end 235.239052 -45.376084)
		(width 0.1651)
		(layer "B.Cu")
		(net "PCIE_IOM_A_TO_COMP_A_14_DN")
	)
	(segment
		(start 236.666532 -45.491654)
		(end 236.767624 -45.592746)
		(width 0.1651)
		(layer "B.Cu")
		(net "PCIE_IOM_A_TO_COMP_A_14_DN")
	)
	(segment
		(start 132.71627 -22.796246)
		(end 133.066536 -22.796246)
		(width 0.1651)
		(layer "B.Cu")
		(net "PCIE_IOM_A_TO_COMP_A_14_DN")
	)
	(segment
		(start 204.079348 -39.182294)
		(end 204.56525 -39.278814)
		(width 0.1651)
		(layer "B.Cu")
		(net "PCIE_IOM_A_TO_COMP_A_14_DN")
	)
	(segment
		(start 141.62659 -41.48455)
		(end 155.163266 -44.11599)
		(width 0.1651)
		(layer "B.Cu")
		(net "PCIE_IOM_A_TO_COMP_A_14_DN")
	)
	(segment
		(start 203.369418 -39.04107)
		(end 203.45908 -39.175436)
		(width 0.1651)
		(layer "B.Cu")
		(net "PCIE_IOM_A_TO_COMP_A_14_DN")
	)
	(segment
		(start 205.140814 -39.5097)
		(end 205.27518 -39.419784)
		(width 0.1651)
		(layer "B.Cu")
		(net "PCIE_IOM_A_TO_COMP_A_14_DN")
	)
	(segment
		(start 206.95666 -39.754302)
		(end 207.046576 -39.888668)
		(width 0.1651)
		(layer "B.Cu")
		(net "PCIE_IOM_A_TO_COMP_A_14_DN")
	)
	(segment
		(start 191.068452 -36.595812)
		(end 203.369418 -39.04107)
		(width 0.1651)
		(layer "B.Cu")
		(net "PCIE_IOM_A_TO_COMP_A_14_DN")
	)
	(segment
		(start 203.45908 -39.175436)
		(end 203.944982 -39.271956)
		(width 0.1651)
		(layer "B.Cu")
		(net "PCIE_IOM_A_TO_COMP_A_14_DN")
	)
	(segment
		(start 207.046576 -39.888668)
		(end 207.532478 -39.985188)
		(width 0.1651)
		(layer "B.Cu")
		(net "PCIE_IOM_A_TO_COMP_A_14_DN")
	)
	(segment
		(start 133.303772 -32.856932)
		(end 136.873488 -38.2778)
		(width 0.1651)
		(layer "B.Cu")
		(net "PCIE_IOM_A_TO_COMP_A_14_DN")
	)
	(segment
		(start 132.5499 -23.35022)
		(end 132.5499 -22.962616)
		(width 0.1651)
		(layer "B.Cu")
		(net "PCIE_IOM_A_TO_COMP_A_14_DN")
	)
	(segment
		(start 204.654912 -39.41318)
		(end 205.140814 -39.5097)
		(width 0.1651)
		(layer "B.Cu")
		(net "PCIE_IOM_A_TO_COMP_A_14_DN")
	)
	(segment
		(start 205.27518 -39.419784)
		(end 205.761082 -39.516558)
		(width 0.1651)
		(layer "B.Cu")
		(net "PCIE_IOM_A_TO_COMP_A_14_DN")
	)
	(segment
		(start 236.723682 -45.862748)
		(end 236.050074 -46.20006)
		(width 0.1651)
		(layer "B.Cu")
		(net "PCIE_IOM_A_TO_COMP_A_14_DN")
	)
	(segment
		(start 203.944982 -39.271956)
		(end 204.079348 -39.182294)
		(width 0.1651)
		(layer "B.Cu")
		(net "PCIE_IOM_A_TO_COMP_A_14_DN")
	)
	(segment
		(start 206.471012 -39.657528)
		(end 206.95666 -39.754302)
		(width 0.1651)
		(layer "B.Cu")
		(net "PCIE_IOM_A_TO_COMP_A_14_DN")
	)
	(segment
		(start 133.303772 -23.033482)
		(end 133.303772 -32.856932)
		(width 0.1651)
		(layer "B.Cu")
		(net "PCIE_IOM_A_TO_COMP_A_14_DN")
	)
	(segment
		(start 204.56525 -39.278814)
		(end 204.654912 -39.41318)
		(width 0.1651)
		(layer "B.Cu")
		(net "PCIE_IOM_A_TO_COMP_A_14_DN")
	)
	(segment
		(start 136.873488 -38.2778)
		(end 141.62659 -41.48455)
		(width 0.1651)
		(layer "B.Cu")
		(net "PCIE_IOM_A_TO_COMP_A_14_DN")
	)
	(segment
		(start 155.163266 -44.11599)
		(end 191.068452 -36.595812)
		(width 0.1651)
		(layer "B.Cu")
		(net "PCIE_IOM_A_TO_COMP_A_14_DN")
	)
	(segment
		(start 206.336646 -39.747444)
		(end 206.471012 -39.657528)
		(width 0.1651)
		(layer "B.Cu")
		(net "PCIE_IOM_A_TO_COMP_A_14_DN")
	)
	(segment
		(start 235.239052 -45.376084)
		(end 236.388402 -45.376084)
		(width 0.1651)
		(layer "B.Cu")
		(net "PCIE_IOM_A_TO_COMP_A_14_DN")
	)
	(segment
		(start 205.761082 -39.516558)
		(end 205.850744 -39.650924)
		(width 0.1651)
		(layer "B.Cu")
		(net "PCIE_IOM_A_TO_COMP_A_14_DN")
	)
	(segment
		(start 205.850744 -39.650924)
		(end 206.336646 -39.747444)
		(width 0.1651)
		(layer "B.Cu")
		(net "PCIE_IOM_A_TO_COMP_A_14_DN")
	)
	(arc
		(start 132.5499 -22.962616)
		(mid 132.598629 -22.844975)
		(end 132.71627 -22.796246)
		(width 0.1651)
		(layer "B.Cu")
		(net "PCIE_IOM_A_TO_COMP_A_14_DN")
	)
	(arc
		(start 236.388402 -45.376084)
		(mid 236.4861 -45.38852)
		(end 236.577632 -45.424852)
		(width 0.1651)
		(layer "B.Cu")
		(net "PCIE_IOM_A_TO_COMP_A_14_DN")
	)
	(arc
		(start 236.814868 -45.738796)
		(mid 236.784165 -45.811727)
		(end 236.723682 -45.862748)
		(width 0.1651)
		(layer "B.Cu")
		(net "PCIE_IOM_A_TO_COMP_A_14_DN")
	)
	(arc
		(start 236.767624 -45.592746)
		(mid 236.808852 -45.660086)
		(end 236.814868 -45.738796)
		(width 0.1651)
		(layer "B.Cu")
		(net "PCIE_IOM_A_TO_COMP_A_14_DN")
	)
	(arc
		(start 236.577632 -45.424852)
		(mid 236.624445 -45.455106)
		(end 236.666532 -45.491654)
		(width 0.1651)
		(layer "B.Cu")
		(net "PCIE_IOM_A_TO_COMP_A_14_DN")
	)
	(arc
		(start 133.066536 -22.796246)
		(mid 133.234287 -22.865731)
		(end 133.303772 -23.033482)
		(width 0.1651)
		(layer "B.Cu")
		(net "PCIE_IOM_A_TO_COMP_A_14_DN")
	)
	(segment
		(start 137.967974 -36.375594)
		(end 142.355062 -39.709598)
		(width 0.1651)
		(layer "B.Cu")
		(net "PCIE_IOM_A_TO_COMP_A_13_DP")
	)
	(segment
		(start 154.28341 -42.02811)
		(end 196.49567 -33.53562)
		(width 0.1651)
		(layer "B.Cu")
		(net "PCIE_IOM_A_TO_COMP_A_13_DP")
	)
	(segment
		(start 134.516368 -21.504148)
		(end 134.866634 -21.504148)
		(width 0.1651)
		(layer "B.Cu")
		(net "PCIE_IOM_A_TO_COMP_A_13_DP")
	)
	(segment
		(start 237.389416 -41.538652)
		(end 238.05007 -41.20007)
		(width 0.1651)
		(layer "B.Cu")
		(net "PCIE_IOM_A_TO_COMP_A_13_DP")
	)
	(segment
		(start 136.681972 -34.422842)
		(end 137.967974 -36.375594)
		(width 0.1651)
		(layer "B.Cu")
		(net "PCIE_IOM_A_TO_COMP_A_13_DP")
	)
	(segment
		(start 136.681972 -34.422588)
		(end 136.681972 -34.422842)
		(width 0.1651)
		(layer "B.Cu")
		(net "PCIE_IOM_A_TO_COMP_A_13_DP")
	)
	(segment
		(start 142.355062 -39.709598)
		(end 154.28341 -42.02811)
		(width 0.1651)
		(layer "B.Cu")
		(net "PCIE_IOM_A_TO_COMP_A_13_DP")
	)
	(segment
		(start 134.349998 -20.950174)
		(end 134.349998 -21.337778)
		(width 0.1651)
		(layer "B.Cu")
		(net "PCIE_IOM_A_TO_COMP_A_13_DP")
	)
	(segment
		(start 135.39597 -22.033484)
		(end 135.39597 -32.47009)
		(width 0.1651)
		(layer "B.Cu")
		(net "PCIE_IOM_A_TO_COMP_A_13_DP")
	)
	(segment
		(start 236.873288 -41.284906)
		(end 237.078266 -41.489884)
		(width 0.1651)
		(layer "B.Cu")
		(net "PCIE_IOM_A_TO_COMP_A_13_DP")
	)
	(segment
		(start 237.218474 -41.561004)
		(end 237.233968 -41.563544)
		(width 0.1651)
		(layer "B.Cu")
		(net "PCIE_IOM_A_TO_COMP_A_13_DP")
	)
	(segment
		(start 235.331762 -41.083992)
		(end 236.388148 -41.083992)
		(width 0.1651)
		(layer "B.Cu")
		(net "PCIE_IOM_A_TO_COMP_A_13_DP")
	)
	(segment
		(start 135.39597 -32.47009)
		(end 136.681972 -34.422588)
		(width 0.1651)
		(layer "B.Cu")
		(net "PCIE_IOM_A_TO_COMP_A_13_DP")
	)
	(segment
		(start 196.49567 -33.53562)
		(end 235.331762 -41.083992)
		(width 0.1651)
		(layer "B.Cu")
		(net "PCIE_IOM_A_TO_COMP_A_13_DP")
	)
	(arc
		(start 134.349998 -21.337778)
		(mid 134.398727 -21.455419)
		(end 134.516368 -21.504148)
		(width 0.1651)
		(layer "B.Cu")
		(net "PCIE_IOM_A_TO_COMP_A_13_DP")
	)
	(arc
		(start 236.718348 -41.168574)
		(mid 236.799931 -41.221259)
		(end 236.873288 -41.284906)
		(width 0.1651)
		(layer "B.Cu")
		(net "PCIE_IOM_A_TO_COMP_A_13_DP")
	)
	(arc
		(start 237.233968 -41.563544)
		(mid 237.313678 -41.563471)
		(end 237.389416 -41.538652)
		(width 0.1651)
		(layer "B.Cu")
		(net "PCIE_IOM_A_TO_COMP_A_13_DP")
	)
	(arc
		(start 134.866634 -21.504148)
		(mid 135.240931 -21.659187)
		(end 135.39597 -22.033484)
		(width 0.1651)
		(layer "B.Cu")
		(net "PCIE_IOM_A_TO_COMP_A_13_DP")
	)
	(arc
		(start 237.078266 -41.489884)
		(mid 237.142732 -41.536556)
		(end 237.218474 -41.561004)
		(width 0.1651)
		(layer "B.Cu")
		(net "PCIE_IOM_A_TO_COMP_A_13_DP")
	)
	(arc
		(start 236.388148 -41.083992)
		(mid 236.55859 -41.105436)
		(end 236.718348 -41.168574)
		(width 0.1651)
		(layer "B.Cu")
		(net "PCIE_IOM_A_TO_COMP_A_13_DP")
	)
	(segment
		(start 235.30306 -41.376092)
		(end 236.388402 -41.376092)
		(width 0.1651)
		(layer "B.Cu")
		(net "PCIE_IOM_A_TO_COMP_A_13_DN")
	)
	(segment
		(start 207.191102 -35.912044)
		(end 207.677258 -36.006786)
		(width 0.1651)
		(layer "B.Cu")
		(net "PCIE_IOM_A_TO_COMP_A_13_DN")
	)
	(segment
		(start 236.723682 -41.862756)
		(end 236.050074 -42.200068)
		(width 0.1651)
		(layer "B.Cu")
		(net "PCIE_IOM_A_TO_COMP_A_13_DN")
	)
	(segment
		(start 134.349998 -22.350222)
		(end 134.349998 -21.962618)
		(width 0.1651)
		(layer "B.Cu")
		(net "PCIE_IOM_A_TO_COMP_A_13_DN")
	)
	(segment
		(start 205.283816 -35.541458)
		(end 205.37424 -35.67557)
		(width 0.1651)
		(layer "B.Cu")
		(net "PCIE_IOM_A_TO_COMP_A_13_DN")
	)
	(segment
		(start 209.450686 -36.467796)
		(end 209.584798 -36.377372)
		(width 0.1651)
		(layer "B.Cu")
		(net "PCIE_IOM_A_TO_COMP_A_13_DN")
	)
	(segment
		(start 208.38795 -36.144708)
		(end 208.874106 -36.239196)
		(width 0.1651)
		(layer "B.Cu")
		(net "PCIE_IOM_A_TO_COMP_A_13_DN")
	)
	(segment
		(start 209.584798 -36.377372)
		(end 235.30306 -41.376092)
		(width 0.1651)
		(layer "B.Cu")
		(net "PCIE_IOM_A_TO_COMP_A_13_DN")
	)
	(segment
		(start 208.96453 -36.373308)
		(end 209.450686 -36.467796)
		(width 0.1651)
		(layer "B.Cu")
		(net "PCIE_IOM_A_TO_COMP_A_13_DN")
	)
	(segment
		(start 205.37424 -35.67557)
		(end 205.860396 -35.770058)
		(width 0.1651)
		(layer "B.Cu")
		(net "PCIE_IOM_A_TO_COMP_A_13_DN")
	)
	(segment
		(start 154.284426 -42.326052)
		(end 196.496686 -33.833562)
		(width 0.1651)
		(layer "B.Cu")
		(net "PCIE_IOM_A_TO_COMP_A_13_DN")
	)
	(segment
		(start 236.666532 -41.491662)
		(end 236.767624 -41.592754)
		(width 0.1651)
		(layer "B.Cu")
		(net "PCIE_IOM_A_TO_COMP_A_13_DN")
	)
	(segment
		(start 206.571088 -35.90798)
		(end 207.057244 -36.002468)
		(width 0.1651)
		(layer "B.Cu")
		(net "PCIE_IOM_A_TO_COMP_A_13_DN")
	)
	(segment
		(start 142.23238 -39.98341)
		(end 154.284426 -42.326052)
		(width 0.1651)
		(layer "B.Cu")
		(net "PCIE_IOM_A_TO_COMP_A_13_DN")
	)
	(segment
		(start 135.10387 -22.033484)
		(end 135.10387 -32.55772)
		(width 0.1651)
		(layer "B.Cu")
		(net "PCIE_IOM_A_TO_COMP_A_13_DN")
	)
	(segment
		(start 134.516368 -21.796248)
		(end 134.866634 -21.796248)
		(width 0.1651)
		(layer "B.Cu")
		(net "PCIE_IOM_A_TO_COMP_A_13_DN")
	)
	(segment
		(start 207.057244 -36.002468)
		(end 207.191102 -35.912044)
		(width 0.1651)
		(layer "B.Cu")
		(net "PCIE_IOM_A_TO_COMP_A_13_DN")
	)
	(segment
		(start 206.480664 -35.774122)
		(end 206.571088 -35.90798)
		(width 0.1651)
		(layer "B.Cu")
		(net "PCIE_IOM_A_TO_COMP_A_13_DN")
	)
	(segment
		(start 135.10387 -32.55772)
		(end 137.751312 -36.578032)
		(width 0.1651)
		(layer "B.Cu")
		(net "PCIE_IOM_A_TO_COMP_A_13_DN")
	)
	(segment
		(start 205.994254 -35.679634)
		(end 206.480664 -35.774122)
		(width 0.1651)
		(layer "B.Cu")
		(net "PCIE_IOM_A_TO_COMP_A_13_DN")
	)
	(segment
		(start 196.496686 -33.833562)
		(end 205.283816 -35.541458)
		(width 0.1651)
		(layer "B.Cu")
		(net "PCIE_IOM_A_TO_COMP_A_13_DN")
	)
	(segment
		(start 137.751312 -36.578032)
		(end 142.23238 -39.98341)
		(width 0.1651)
		(layer "B.Cu")
		(net "PCIE_IOM_A_TO_COMP_A_13_DN")
	)
	(segment
		(start 208.874106 -36.239196)
		(end 208.96453 -36.373308)
		(width 0.1651)
		(layer "B.Cu")
		(net "PCIE_IOM_A_TO_COMP_A_13_DN")
	)
	(segment
		(start 207.767682 -36.140644)
		(end 208.254092 -36.235132)
		(width 0.1651)
		(layer "B.Cu")
		(net "PCIE_IOM_A_TO_COMP_A_13_DN")
	)
	(segment
		(start 205.860396 -35.770058)
		(end 205.994254 -35.679634)
		(width 0.1651)
		(layer "B.Cu")
		(net "PCIE_IOM_A_TO_COMP_A_13_DN")
	)
	(segment
		(start 208.254092 -36.235132)
		(end 208.38795 -36.144708)
		(width 0.1651)
		(layer "B.Cu")
		(net "PCIE_IOM_A_TO_COMP_A_13_DN")
	)
	(segment
		(start 207.677258 -36.006786)
		(end 207.767682 -36.140644)
		(width 0.1651)
		(layer "B.Cu")
		(net "PCIE_IOM_A_TO_COMP_A_13_DN")
	)
	(arc
		(start 236.388402 -41.376092)
		(mid 236.4861 -41.388528)
		(end 236.577632 -41.42486)
		(width 0.1651)
		(layer "B.Cu")
		(net "PCIE_IOM_A_TO_COMP_A_13_DN")
	)
	(arc
		(start 236.767624 -41.592754)
		(mid 236.808852 -41.660094)
		(end 236.814868 -41.738804)
		(width 0.1651)
		(layer "B.Cu")
		(net "PCIE_IOM_A_TO_COMP_A_13_DN")
	)
	(arc
		(start 236.814868 -41.738804)
		(mid 236.784165 -41.811735)
		(end 236.723682 -41.862756)
		(width 0.1651)
		(layer "B.Cu")
		(net "PCIE_IOM_A_TO_COMP_A_13_DN")
	)
	(arc
		(start 134.866634 -21.796248)
		(mid 135.034385 -21.865733)
		(end 135.10387 -22.033484)
		(width 0.1651)
		(layer "B.Cu")
		(net "PCIE_IOM_A_TO_COMP_A_13_DN")
	)
	(arc
		(start 236.577632 -41.42486)
		(mid 236.624445 -41.455114)
		(end 236.666532 -41.491662)
		(width 0.1651)
		(layer "B.Cu")
		(net "PCIE_IOM_A_TO_COMP_A_13_DN")
	)
	(arc
		(start 134.349998 -21.962618)
		(mid 134.398727 -21.844977)
		(end 134.516368 -21.796248)
		(width 0.1651)
		(layer "B.Cu")
		(net "PCIE_IOM_A_TO_COMP_A_13_DN")
	)
	(segment
		(start 139.925298 -35.865054)
		(end 143.500856 -38.276784)
		(width 0.1651)
		(layer "B.Cu")
		(net "PCIE_IOM_A_TO_COMP_A_12_DP")
	)
	(segment
		(start 136.150096 -21.950172)
		(end 136.150096 -22.337776)
		(width 0.1651)
		(layer "B.Cu")
		(net "PCIE_IOM_A_TO_COMP_A_12_DP")
	)
	(segment
		(start 136.316466 -22.504146)
		(end 136.666732 -22.504146)
		(width 0.1651)
		(layer "B.Cu")
		(net "PCIE_IOM_A_TO_COMP_A_12_DP")
	)
	(segment
		(start 137.196068 -23.033482)
		(end 137.196068 -31.719266)
		(width 0.1651)
		(layer "B.Cu")
		(net "PCIE_IOM_A_TO_COMP_A_12_DP")
	)
	(segment
		(start 237.389416 -37.53866)
		(end 238.05007 -37.200078)
		(width 0.1651)
		(layer "B.Cu")
		(net "PCIE_IOM_A_TO_COMP_A_12_DP")
	)
	(segment
		(start 236.873288 -37.284914)
		(end 237.078266 -37.489892)
		(width 0.1651)
		(layer "B.Cu")
		(net "PCIE_IOM_A_TO_COMP_A_12_DP")
	)
	(segment
		(start 201.741024 -30.55366)
		(end 235.334556 -37.083492)
		(width 0.1651)
		(layer "B.Cu")
		(net "PCIE_IOM_A_TO_COMP_A_12_DP")
	)
	(segment
		(start 235.336588 -37.084)
		(end 236.388148 -37.084)
		(width 0.1651)
		(layer "B.Cu")
		(net "PCIE_IOM_A_TO_COMP_A_12_DP")
	)
	(segment
		(start 237.218474 -37.561012)
		(end 237.233968 -37.563552)
		(width 0.1651)
		(layer "B.Cu")
		(net "PCIE_IOM_A_TO_COMP_A_12_DP")
	)
	(segment
		(start 235.334556 -37.083492)
		(end 235.335318 -37.083746)
		(width 0.1651)
		(layer "B.Cu")
		(net "PCIE_IOM_A_TO_COMP_A_12_DP")
	)
	(segment
		(start 235.335318 -37.083746)
		(end 235.336588 -37.084)
		(width 0.1651)
		(layer "B.Cu")
		(net "PCIE_IOM_A_TO_COMP_A_12_DP")
	)
	(segment
		(start 143.500856 -38.276784)
		(end 154.38247 -40.39235)
		(width 0.1651)
		(layer "B.Cu")
		(net "PCIE_IOM_A_TO_COMP_A_12_DP")
	)
	(segment
		(start 137.196068 -31.719266)
		(end 139.925298 -35.865054)
		(width 0.1651)
		(layer "B.Cu")
		(net "PCIE_IOM_A_TO_COMP_A_12_DP")
	)
	(segment
		(start 154.38247 -40.39235)
		(end 201.741024 -30.55366)
		(width 0.1651)
		(layer "B.Cu")
		(net "PCIE_IOM_A_TO_COMP_A_12_DP")
	)
	(arc
		(start 136.666732 -22.504146)
		(mid 137.041029 -22.659185)
		(end 137.196068 -23.033482)
		(width 0.1651)
		(layer "B.Cu")
		(net "PCIE_IOM_A_TO_COMP_A_12_DP")
	)
	(arc
		(start 236.388148 -37.084)
		(mid 236.55859 -37.105444)
		(end 236.718348 -37.168582)
		(width 0.1651)
		(layer "B.Cu")
		(net "PCIE_IOM_A_TO_COMP_A_12_DP")
	)
	(arc
		(start 236.718348 -37.168582)
		(mid 236.799931 -37.221267)
		(end 236.873288 -37.284914)
		(width 0.1651)
		(layer "B.Cu")
		(net "PCIE_IOM_A_TO_COMP_A_12_DP")
	)
	(arc
		(start 237.078266 -37.489892)
		(mid 237.142732 -37.536564)
		(end 237.218474 -37.561012)
		(width 0.1651)
		(layer "B.Cu")
		(net "PCIE_IOM_A_TO_COMP_A_12_DP")
	)
	(arc
		(start 136.150096 -22.337776)
		(mid 136.198825 -22.455417)
		(end 136.316466 -22.504146)
		(width 0.1651)
		(layer "B.Cu")
		(net "PCIE_IOM_A_TO_COMP_A_12_DP")
	)
	(arc
		(start 237.233968 -37.563552)
		(mid 237.313678 -37.563479)
		(end 237.389416 -37.53866)
		(width 0.1651)
		(layer "B.Cu")
		(net "PCIE_IOM_A_TO_COMP_A_12_DP")
	)
	(segment
		(start 230.121968 -36.368228)
		(end 230.608124 -36.462716)
		(width 0.1651)
		(layer "B.Cu")
		(net "PCIE_IOM_A_TO_COMP_A_12_DN")
	)
	(segment
		(start 136.150096 -23.35022)
		(end 136.150096 -22.962616)
		(width 0.1651)
		(layer "B.Cu")
		(net "PCIE_IOM_A_TO_COMP_A_12_DN")
	)
	(segment
		(start 228.92512 -36.135564)
		(end 229.41153 -36.230052)
		(width 0.1651)
		(layer "B.Cu")
		(net "PCIE_IOM_A_TO_COMP_A_12_DN")
	)
	(segment
		(start 143.38681 -38.552374)
		(end 154.384502 -40.690546)
		(width 0.1651)
		(layer "B.Cu")
		(net "PCIE_IOM_A_TO_COMP_A_12_DN")
	)
	(segment
		(start 143.386556 -38.552374)
		(end 143.38681 -38.552628)
		(width 0.1651)
		(layer "B.Cu")
		(net "PCIE_IOM_A_TO_COMP_A_12_DN")
	)
	(segment
		(start 231.895396 -36.829492)
		(end 232.381552 -36.92398)
		(width 0.1651)
		(layer "B.Cu")
		(net "PCIE_IOM_A_TO_COMP_A_12_DN")
	)
	(segment
		(start 228.305106 -36.1315)
		(end 228.791262 -36.225988)
		(width 0.1651)
		(layer "B.Cu")
		(net "PCIE_IOM_A_TO_COMP_A_12_DN")
	)
	(segment
		(start 231.318816 -36.600892)
		(end 231.804972 -36.69538)
		(width 0.1651)
		(layer "B.Cu")
		(net "PCIE_IOM_A_TO_COMP_A_12_DN")
	)
	(segment
		(start 228.214682 -35.997642)
		(end 228.305106 -36.1315)
		(width 0.1651)
		(layer "B.Cu")
		(net "PCIE_IOM_A_TO_COMP_A_12_DN")
	)
	(segment
		(start 201.743056 -30.851856)
		(end 228.214428 -35.997388)
		(width 0.1651)
		(layer "B.Cu")
		(net "PCIE_IOM_A_TO_COMP_A_12_DN")
	)
	(segment
		(start 236.723682 -37.862764)
		(end 236.050074 -38.200076)
		(width 0.1651)
		(layer "B.Cu")
		(net "PCIE_IOM_A_TO_COMP_A_12_DN")
	)
	(segment
		(start 229.5017 -36.364164)
		(end 229.98811 -36.458652)
		(width 0.1651)
		(layer "B.Cu")
		(net "PCIE_IOM_A_TO_COMP_A_12_DN")
	)
	(segment
		(start 136.903968 -31.806896)
		(end 136.95172 -31.879794)
		(width 0.1651)
		(layer "B.Cu")
		(net "PCIE_IOM_A_TO_COMP_A_12_DN")
	)
	(segment
		(start 231.184704 -36.691316)
		(end 231.318816 -36.600892)
		(width 0.1651)
		(layer "B.Cu")
		(net "PCIE_IOM_A_TO_COMP_A_12_DN")
	)
	(segment
		(start 236.666532 -37.49167)
		(end 236.767624 -37.592762)
		(width 0.1651)
		(layer "B.Cu")
		(net "PCIE_IOM_A_TO_COMP_A_12_DN")
	)
	(segment
		(start 232.381552 -36.92398)
		(end 232.515664 -36.833556)
		(width 0.1651)
		(layer "B.Cu")
		(net "PCIE_IOM_A_TO_COMP_A_12_DN")
	)
	(segment
		(start 139.713462 -36.074604)
		(end 143.386556 -38.552374)
		(width 0.1651)
		(layer "B.Cu")
		(net "PCIE_IOM_A_TO_COMP_A_12_DN")
	)
	(segment
		(start 154.384502 -40.690546)
		(end 201.743056 -30.851856)
		(width 0.1651)
		(layer "B.Cu")
		(net "PCIE_IOM_A_TO_COMP_A_12_DN")
	)
	(segment
		(start 228.791262 -36.225988)
		(end 228.92512 -36.135564)
		(width 0.1651)
		(layer "B.Cu")
		(net "PCIE_IOM_A_TO_COMP_A_12_DN")
	)
	(segment
		(start 235.307378 -37.3761)
		(end 236.388402 -37.3761)
		(width 0.1651)
		(layer "B.Cu")
		(net "PCIE_IOM_A_TO_COMP_A_12_DN")
	)
	(segment
		(start 230.698548 -36.596828)
		(end 231.184704 -36.691316)
		(width 0.1651)
		(layer "B.Cu")
		(net "PCIE_IOM_A_TO_COMP_A_12_DN")
	)
	(segment
		(start 136.903968 -23.033482)
		(end 136.903968 -31.806896)
		(width 0.1651)
		(layer "B.Cu")
		(net "PCIE_IOM_A_TO_COMP_A_12_DN")
	)
	(segment
		(start 232.515664 -36.833556)
		(end 235.278676 -37.370512)
		(width 0.1651)
		(layer "B.Cu")
		(net "PCIE_IOM_A_TO_COMP_A_12_DN")
	)
	(segment
		(start 136.95172 -31.879794)
		(end 139.713462 -36.074604)
		(width 0.1651)
		(layer "B.Cu")
		(net "PCIE_IOM_A_TO_COMP_A_12_DN")
	)
	(segment
		(start 229.98811 -36.458652)
		(end 230.121968 -36.368228)
		(width 0.1651)
		(layer "B.Cu")
		(net "PCIE_IOM_A_TO_COMP_A_12_DN")
	)
	(segment
		(start 231.804972 -36.69538)
		(end 231.895396 -36.829492)
		(width 0.1651)
		(layer "B.Cu")
		(net "PCIE_IOM_A_TO_COMP_A_12_DN")
	)
	(segment
		(start 136.316466 -22.796246)
		(end 136.666732 -22.796246)
		(width 0.1651)
		(layer "B.Cu")
		(net "PCIE_IOM_A_TO_COMP_A_12_DN")
	)
	(segment
		(start 235.278676 -37.370512)
		(end 235.279692 -37.370766)
		(width 0.1651)
		(layer "B.Cu")
		(net "PCIE_IOM_A_TO_COMP_A_12_DN")
	)
	(segment
		(start 228.214428 -35.997388)
		(end 228.214682 -35.997642)
		(width 0.1651)
		(layer "B.Cu")
		(net "PCIE_IOM_A_TO_COMP_A_12_DN")
	)
	(segment
		(start 230.608124 -36.462716)
		(end 230.698548 -36.596828)
		(width 0.1651)
		(layer "B.Cu")
		(net "PCIE_IOM_A_TO_COMP_A_12_DN")
	)
	(segment
		(start 235.279692 -37.370766)
		(end 235.307378 -37.3761)
		(width 0.1651)
		(layer "B.Cu")
		(net "PCIE_IOM_A_TO_COMP_A_12_DN")
	)
	(segment
		(start 229.41153 -36.230052)
		(end 229.5017 -36.364164)
		(width 0.1651)
		(layer "B.Cu")
		(net "PCIE_IOM_A_TO_COMP_A_12_DN")
	)
	(segment
		(start 143.38681 -38.552628)
		(end 143.38681 -38.552374)
		(width 0.1651)
		(layer "B.Cu")
		(net "PCIE_IOM_A_TO_COMP_A_12_DN")
	)
	(arc
		(start 236.388402 -37.3761)
		(mid 236.4861 -37.388536)
		(end 236.577632 -37.424868)
		(width 0.1651)
		(layer "B.Cu")
		(net "PCIE_IOM_A_TO_COMP_A_12_DN")
	)
	(arc
		(start 136.666732 -22.796246)
		(mid 136.834483 -22.865731)
		(end 136.903968 -23.033482)
		(width 0.1651)
		(layer "B.Cu")
		(net "PCIE_IOM_A_TO_COMP_A_12_DN")
	)
	(arc
		(start 236.814868 -37.738812)
		(mid 236.784165 -37.811743)
		(end 236.723682 -37.862764)
		(width 0.1651)
		(layer "B.Cu")
		(net "PCIE_IOM_A_TO_COMP_A_12_DN")
	)
	(arc
		(start 136.150096 -22.962616)
		(mid 136.198825 -22.844975)
		(end 136.316466 -22.796246)
		(width 0.1651)
		(layer "B.Cu")
		(net "PCIE_IOM_A_TO_COMP_A_12_DN")
	)
	(arc
		(start 236.767624 -37.592762)
		(mid 236.808852 -37.660102)
		(end 236.814868 -37.738812)
		(width 0.1651)
		(layer "B.Cu")
		(net "PCIE_IOM_A_TO_COMP_A_12_DN")
	)
	(arc
		(start 236.577632 -37.424868)
		(mid 236.624445 -37.455122)
		(end 236.666532 -37.49167)
		(width 0.1651)
		(layer "B.Cu")
		(net "PCIE_IOM_A_TO_COMP_A_12_DN")
	)
	(segment
		(start 244.462554 -34.86785)
		(end 249.135646 -58.909458)
		(width 0.1651)
		(layer "B.Cu")
		(net "PCIE_IOM_A_TO_COMP_A_11_DP")
	)
	(segment
		(start 235.621322 -177.3809)
		(end 236.388148 -177.383694)
		(width 0.1651)
		(layer "B.Cu")
		(net "PCIE_IOM_A_TO_COMP_A_11_DP")
	)
	(segment
		(start 243.239036 -33.054036)
		(end 244.462554 -34.86785)
		(width 0.1651)
		(layer "B.Cu")
		(net "PCIE_IOM_A_TO_COMP_A_11_DP")
	)
	(segment
		(start 220.381576 -141.965172)
		(end 224.02165 -160.695132)
		(width 0.1651)
		(layer "B.Cu")
		(net "PCIE_IOM_A_TO_COMP_A_11_DP")
	)
	(segment
		(start 236.873288 -177.584608)
		(end 237.078266 -177.789586)
		(width 0.1651)
		(layer "B.Cu")
		(net "PCIE_IOM_A_TO_COMP_A_11_DP")
	)
	(segment
		(start 143.129254 -35.985958)
		(end 151.351234 -37.58438)
		(width 0.1651)
		(layer "B.Cu")
		(net "PCIE_IOM_A_TO_COMP_A_11_DP")
	)
	(segment
		(start 139.023344 -31.60268)
		(end 140.915898 -34.476944)
		(width 0.1651)
		(layer "B.Cu")
		(net "PCIE_IOM_A_TO_COMP_A_11_DP")
	)
	(segment
		(start 142.031974 -35.245294)
		(end 142.580614 -35.61588)
		(width 0.1651)
		(layer "B.Cu")
		(net "PCIE_IOM_A_TO_COMP_A_11_DP")
	)
	(segment
		(start 242.866926 -87.80653)
		(end 231.462072 -96.977962)
		(width 0.1651)
		(layer "B.Cu")
		(net "PCIE_IOM_A_TO_COMP_A_11_DP")
	)
	(segment
		(start 242.02517 -33.054036)
		(end 243.239036 -33.054036)
		(width 0.1651)
		(layer "B.Cu")
		(net "PCIE_IOM_A_TO_COMP_A_11_DP")
	)
	(segment
		(start 233.858054 -31.05404)
		(end 236.525054 -31.05404)
		(width 0.1651)
		(layer "B.Cu")
		(net "PCIE_IOM_A_TO_COMP_A_11_DP")
	)
	(segment
		(start 236.525054 -31.05404)
		(end 237.525052 -32.054038)
		(width 0.1651)
		(layer "B.Cu")
		(net "PCIE_IOM_A_TO_COMP_A_11_DP")
	)
	(segment
		(start 209.401664 -26.30043)
		(end 233.858054 -31.05404)
		(width 0.1651)
		(layer "B.Cu")
		(net "PCIE_IOM_A_TO_COMP_A_11_DP")
	)
	(segment
		(start 138.995912 -22.033484)
		(end 138.995912 -23.006558)
		(width 0.1651)
		(layer "B.Cu")
		(net "PCIE_IOM_A_TO_COMP_A_11_DP")
	)
	(segment
		(start 249.135646 -58.909458)
		(end 243.787676 -86.441534)
		(width 0.1651)
		(layer "B.Cu")
		(net "PCIE_IOM_A_TO_COMP_A_11_DP")
	)
	(segment
		(start 237.389416 -177.838354)
		(end 238.05007 -177.499772)
		(width 0.1651)
		(layer "B.Cu")
		(net "PCIE_IOM_A_TO_COMP_A_11_DP")
	)
	(segment
		(start 137.94994 -20.950174)
		(end 137.94994 -21.337778)
		(width 0.1651)
		(layer "B.Cu")
		(net "PCIE_IOM_A_TO_COMP_A_11_DP")
	)
	(segment
		(start 243.787676 -86.441534)
		(end 242.866926 -87.80653)
		(width 0.1651)
		(layer "B.Cu")
		(net "PCIE_IOM_A_TO_COMP_A_11_DP")
	)
	(segment
		(start 224.02165 -160.695132)
		(end 234.901232 -176.826164)
		(width 0.1651)
		(layer "B.Cu")
		(net "PCIE_IOM_A_TO_COMP_A_11_DP")
	)
	(segment
		(start 140.961618 -34.523172)
		(end 142.031974 -35.245294)
		(width 0.1651)
		(layer "B.Cu")
		(net "PCIE_IOM_A_TO_COMP_A_11_DP")
	)
	(segment
		(start 231.462072 -96.977962)
		(end 228.1809 -101.84384)
		(width 0.1651)
		(layer "B.Cu")
		(net "PCIE_IOM_A_TO_COMP_A_11_DP")
	)
	(segment
		(start 138.995912 -23.006558)
		(end 138.996166 -23.006558)
		(width 0.1651)
		(layer "B.Cu")
		(net "PCIE_IOM_A_TO_COMP_A_11_DP")
	)
	(segment
		(start 138.996166 -23.006558)
		(end 138.996166 -31.511748)
		(width 0.1651)
		(layer "B.Cu")
		(net "PCIE_IOM_A_TO_COMP_A_11_DP")
	)
	(segment
		(start 228.1809 -101.84384)
		(end 220.381576 -141.965172)
		(width 0.1651)
		(layer "B.Cu")
		(net "PCIE_IOM_A_TO_COMP_A_11_DP")
	)
	(segment
		(start 237.525052 -32.054038)
		(end 241.025172 -32.054038)
		(width 0.1651)
		(layer "B.Cu")
		(net "PCIE_IOM_A_TO_COMP_A_11_DP")
	)
	(segment
		(start 234.901232 -176.826164)
		(end 235.621322 -177.3809)
		(width 0.1651)
		(layer "B.Cu")
		(net "PCIE_IOM_A_TO_COMP_A_11_DP")
	)
	(segment
		(start 151.351234 -37.58438)
		(end 209.401664 -26.30043)
		(width 0.1651)
		(layer "B.Cu")
		(net "PCIE_IOM_A_TO_COMP_A_11_DP")
	)
	(segment
		(start 138.11631 -21.504148)
		(end 138.466576 -21.504148)
		(width 0.1651)
		(layer "B.Cu")
		(net "PCIE_IOM_A_TO_COMP_A_11_DP")
	)
	(segment
		(start 241.025172 -32.054038)
		(end 242.02517 -33.054036)
		(width 0.1651)
		(layer "B.Cu")
		(net "PCIE_IOM_A_TO_COMP_A_11_DP")
	)
	(segment
		(start 237.218474 -177.860706)
		(end 237.233968 -177.863246)
		(width 0.1651)
		(layer "B.Cu")
		(net "PCIE_IOM_A_TO_COMP_A_11_DP")
	)
	(segment
		(start 142.580614 -35.61588)
		(end 143.129254 -35.985958)
		(width 0.1651)
		(layer "B.Cu")
		(net "PCIE_IOM_A_TO_COMP_A_11_DP")
	)
	(arc
		(start 237.233968 -177.863246)
		(mid 237.313678 -177.863173)
		(end 237.389416 -177.838354)
		(width 0.1651)
		(layer "B.Cu")
		(net "PCIE_IOM_A_TO_COMP_A_11_DP")
	)
	(arc
		(start 138.996166 -31.511748)
		(mid 139.003061 -31.559218)
		(end 139.023344 -31.60268)
		(width 0.1651)
		(layer "B.Cu")
		(net "PCIE_IOM_A_TO_COMP_A_11_DP")
	)
	(arc
		(start 236.388148 -177.383694)
		(mid 236.55859 -177.405138)
		(end 236.718348 -177.468276)
		(width 0.1651)
		(layer "B.Cu")
		(net "PCIE_IOM_A_TO_COMP_A_11_DP")
	)
	(arc
		(start 237.078266 -177.789586)
		(mid 237.142732 -177.836258)
		(end 237.218474 -177.860706)
		(width 0.1651)
		(layer "B.Cu")
		(net "PCIE_IOM_A_TO_COMP_A_11_DP")
	)
	(arc
		(start 138.466576 -21.504148)
		(mid 138.840873 -21.659187)
		(end 138.995912 -22.033484)
		(width 0.1651)
		(layer "B.Cu")
		(net "PCIE_IOM_A_TO_COMP_A_11_DP")
	)
	(arc
		(start 137.94994 -21.337778)
		(mid 137.998669 -21.455419)
		(end 138.11631 -21.504148)
		(width 0.1651)
		(layer "B.Cu")
		(net "PCIE_IOM_A_TO_COMP_A_11_DP")
	)
	(arc
		(start 236.718348 -177.468276)
		(mid 236.799931 -177.520961)
		(end 236.873288 -177.584608)
		(width 0.1651)
		(layer "B.Cu")
		(net "PCIE_IOM_A_TO_COMP_A_11_DP")
	)
	(arc
		(start 140.915898 -34.476944)
		(mid 140.936459 -34.502332)
		(end 140.961618 -34.523172)
		(width 0.1651)
		(layer "B.Cu")
		(net "PCIE_IOM_A_TO_COMP_A_11_DP")
	)
	(segment
		(start 233.87304 -176.028858)
		(end 234.03179 -176.059592)
		(width 0.1651)
		(layer "B.Cu")
		(net "PCIE_IOM_A_TO_COMP_A_11_DN")
	)
	(segment
		(start 233.626914 -175.45939)
		(end 233.595926 -175.61814)
		(width 0.1651)
		(layer "B.Cu")
		(net "PCIE_IOM_A_TO_COMP_A_11_DN")
	)
	(segment
		(start 232.668318 -174.038006)
		(end 232.945178 -174.448724)
		(width 0.1651)
		(layer "B.Cu")
		(net "PCIE_IOM_A_TO_COMP_A_11_DN")
	)
	(segment
		(start 231.827832 -172.996352)
		(end 231.986582 -173.02734)
		(width 0.1651)
		(layer "B.Cu")
		(net "PCIE_IOM_A_TO_COMP_A_11_DN")
	)
	(segment
		(start 138.704066 -23.298658)
		(end 138.704066 -31.572962)
		(width 0.1651)
		(layer "B.Cu")
		(net "PCIE_IOM_A_TO_COMP_A_11_DN")
	)
	(segment
		(start 232.263442 -173.437804)
		(end 232.232708 -173.596554)
		(width 0.1651)
		(layer "B.Cu")
		(net "PCIE_IOM_A_TO_COMP_A_11_DN")
	)
	(segment
		(start 232.509568 -174.007272)
		(end 232.668318 -174.038006)
		(width 0.1651)
		(layer "B.Cu")
		(net "PCIE_IOM_A_TO_COMP_A_11_DN")
	)
	(segment
		(start 236.403896 -31.34614)
		(end 237.403894 -32.346138)
		(width 0.1651)
		(layer "B.Cu")
		(net "PCIE_IOM_A_TO_COMP_A_11_DN")
	)
	(segment
		(start 240.904014 -32.346138)
		(end 241.904012 -33.346136)
		(width 0.1651)
		(layer "B.Cu")
		(net "PCIE_IOM_A_TO_COMP_A_11_DN")
	)
	(segment
		(start 220.083888 -141.965172)
		(end 223.74606 -160.809178)
		(width 0.1651)
		(layer "B.Cu")
		(net "PCIE_IOM_A_TO_COMP_A_11_DN")
	)
	(segment
		(start 236.387132 -177.675794)
		(end 236.388402 -177.675794)
		(width 0.1651)
		(layer "B.Cu")
		(net "PCIE_IOM_A_TO_COMP_A_11_DN")
	)
	(segment
		(start 151.351234 -37.882068)
		(end 209.401664 -26.598118)
		(width 0.1651)
		(layer "B.Cu")
		(net "PCIE_IOM_A_TO_COMP_A_11_DN")
	)
	(segment
		(start 232.945178 -174.448724)
		(end 232.914444 -174.607474)
		(width 0.1651)
		(layer "B.Cu")
		(net "PCIE_IOM_A_TO_COMP_A_11_DN")
	)
	(segment
		(start 231.244394 -96.77781)
		(end 227.90531 -101.729794)
		(width 0.1651)
		(layer "B.Cu")
		(net "PCIE_IOM_A_TO_COMP_A_11_DN")
	)
	(segment
		(start 232.232708 -173.596554)
		(end 232.509568 -174.007272)
		(width 0.1651)
		(layer "B.Cu")
		(net "PCIE_IOM_A_TO_COMP_A_11_DN")
	)
	(segment
		(start 140.72235 -34.71418)
		(end 141.868398 -35.48761)
		(width 0.1651)
		(layer "B.Cu")
		(net "PCIE_IOM_A_TO_COMP_A_11_DN")
	)
	(segment
		(start 242.649248 -87.606378)
		(end 231.244394 -96.77781)
		(width 0.1651)
		(layer "B.Cu")
		(net "PCIE_IOM_A_TO_COMP_A_11_DN")
	)
	(segment
		(start 236.666532 -177.791364)
		(end 236.767624 -177.892456)
		(width 0.1651)
		(layer "B.Cu")
		(net "PCIE_IOM_A_TO_COMP_A_11_DN")
	)
	(segment
		(start 138.11631 -21.796248)
		(end 138.466576 -21.796248)
		(width 0.1651)
		(layer "B.Cu")
		(net "PCIE_IOM_A_TO_COMP_A_11_DN")
	)
	(segment
		(start 231.986582 -173.02734)
		(end 232.263442 -173.437804)
		(width 0.1651)
		(layer "B.Cu")
		(net "PCIE_IOM_A_TO_COMP_A_11_DN")
	)
	(segment
		(start 233.350054 -175.048926)
		(end 233.626914 -175.45939)
		(width 0.1651)
		(layer "B.Cu")
		(net "PCIE_IOM_A_TO_COMP_A_11_DN")
	)
	(segment
		(start 234.03179 -176.059592)
		(end 234.685332 -177.028856)
		(width 0.1651)
		(layer "B.Cu")
		(net "PCIE_IOM_A_TO_COMP_A_11_DN")
	)
	(segment
		(start 231.581706 -172.427138)
		(end 231.550972 -172.585888)
		(width 0.1651)
		(layer "B.Cu")
		(net "PCIE_IOM_A_TO_COMP_A_11_DN")
	)
	(segment
		(start 227.90531 -101.729794)
		(end 220.083888 -141.965172)
		(width 0.1651)
		(layer "B.Cu")
		(net "PCIE_IOM_A_TO_COMP_A_11_DN")
	)
	(segment
		(start 235.521754 -177.673)
		(end 236.387132 -177.675794)
		(width 0.1651)
		(layer "B.Cu")
		(net "PCIE_IOM_A_TO_COMP_A_11_DN")
	)
	(segment
		(start 209.401664 -26.598118)
		(end 233.82986 -31.34614)
		(width 0.1651)
		(layer "B.Cu")
		(net "PCIE_IOM_A_TO_COMP_A_11_DN")
	)
	(segment
		(start 243.512086 -86.327488)
		(end 242.649248 -87.606378)
		(width 0.1651)
		(layer "B.Cu")
		(net "PCIE_IOM_A_TO_COMP_A_11_DN")
	)
	(segment
		(start 243.083588 -33.346136)
		(end 244.186964 -34.981896)
		(width 0.1651)
		(layer "B.Cu")
		(net "PCIE_IOM_A_TO_COMP_A_11_DN")
	)
	(segment
		(start 233.191304 -175.017938)
		(end 233.350054 -175.048926)
		(width 0.1651)
		(layer "B.Cu")
		(net "PCIE_IOM_A_TO_COMP_A_11_DN")
	)
	(segment
		(start 141.868398 -35.48761)
		(end 143.014954 -36.261548)
		(width 0.1651)
		(layer "B.Cu")
		(net "PCIE_IOM_A_TO_COMP_A_11_DN")
	)
	(segment
		(start 138.703812 -22.033484)
		(end 138.703812 -23.298658)
		(width 0.1651)
		(layer "B.Cu")
		(net "PCIE_IOM_A_TO_COMP_A_11_DN")
	)
	(segment
		(start 234.685332 -177.028856)
		(end 235.521754 -177.673)
		(width 0.1651)
		(layer "B.Cu")
		(net "PCIE_IOM_A_TO_COMP_A_11_DN")
	)
	(segment
		(start 237.403894 -32.346138)
		(end 240.904014 -32.346138)
		(width 0.1651)
		(layer "B.Cu")
		(net "PCIE_IOM_A_TO_COMP_A_11_DN")
	)
	(segment
		(start 223.74606 -160.809178)
		(end 231.581706 -172.427138)
		(width 0.1651)
		(layer "B.Cu")
		(net "PCIE_IOM_A_TO_COMP_A_11_DN")
	)
	(segment
		(start 236.723682 -178.162458)
		(end 236.050074 -178.49977)
		(width 0.1651)
		(layer "B.Cu")
		(net "PCIE_IOM_A_TO_COMP_A_11_DN")
	)
	(segment
		(start 244.186964 -34.98215)
		(end 248.837958 -58.909458)
		(width 0.1651)
		(layer "B.Cu")
		(net "PCIE_IOM_A_TO_COMP_A_11_DN")
	)
	(segment
		(start 138.703812 -23.298658)
		(end 138.704066 -23.298658)
		(width 0.1651)
		(layer "B.Cu")
		(net "PCIE_IOM_A_TO_COMP_A_11_DN")
	)
	(segment
		(start 231.550972 -172.585888)
		(end 231.827832 -172.996352)
		(width 0.1651)
		(layer "B.Cu")
		(net "PCIE_IOM_A_TO_COMP_A_11_DN")
	)
	(segment
		(start 138.745976 -31.712662)
		(end 140.72235 -34.71418)
		(width 0.1651)
		(layer "B.Cu")
		(net "PCIE_IOM_A_TO_COMP_A_11_DN")
	)
	(segment
		(start 137.94994 -22.350222)
		(end 137.94994 -21.962618)
		(width 0.1651)
		(layer "B.Cu")
		(net "PCIE_IOM_A_TO_COMP_A_11_DN")
	)
	(segment
		(start 143.014954 -36.261548)
		(end 151.351234 -37.882068)
		(width 0.1651)
		(layer "B.Cu")
		(net "PCIE_IOM_A_TO_COMP_A_11_DN")
	)
	(segment
		(start 248.837958 -58.909458)
		(end 243.512086 -86.327488)
		(width 0.1651)
		(layer "B.Cu")
		(net "PCIE_IOM_A_TO_COMP_A_11_DN")
	)
	(segment
		(start 241.904012 -33.346136)
		(end 243.083588 -33.346136)
		(width 0.1651)
		(layer "B.Cu")
		(net "PCIE_IOM_A_TO_COMP_A_11_DN")
	)
	(segment
		(start 232.914444 -174.607474)
		(end 233.191304 -175.017938)
		(width 0.1651)
		(layer "B.Cu")
		(net "PCIE_IOM_A_TO_COMP_A_11_DN")
	)
	(segment
		(start 233.82986 -31.34614)
		(end 236.403896 -31.34614)
		(width 0.1651)
		(layer "B.Cu")
		(net "PCIE_IOM_A_TO_COMP_A_11_DN")
	)
	(segment
		(start 233.595926 -175.61814)
		(end 233.87304 -176.028858)
		(width 0.1651)
		(layer "B.Cu")
		(net "PCIE_IOM_A_TO_COMP_A_11_DN")
	)
	(segment
		(start 244.186964 -34.981896)
		(end 244.186964 -34.98215)
		(width 0.1651)
		(layer "B.Cu")
		(net "PCIE_IOM_A_TO_COMP_A_11_DN")
	)
	(arc
		(start 138.704066 -31.572962)
		(mid 138.714771 -31.645887)
		(end 138.745976 -31.712662)
		(width 0.1651)
		(layer "B.Cu")
		(net "PCIE_IOM_A_TO_COMP_A_11_DN")
	)
	(arc
		(start 137.94994 -21.962618)
		(mid 137.998669 -21.844977)
		(end 138.11631 -21.796248)
		(width 0.1651)
		(layer "B.Cu")
		(net "PCIE_IOM_A_TO_COMP_A_11_DN")
	)
	(arc
		(start 236.577632 -177.724562)
		(mid 236.624445 -177.754816)
		(end 236.666532 -177.791364)
		(width 0.1651)
		(layer "B.Cu")
		(net "PCIE_IOM_A_TO_COMP_A_11_DN")
	)
	(arc
		(start 236.388402 -177.675794)
		(mid 236.4861 -177.68823)
		(end 236.577632 -177.724562)
		(width 0.1651)
		(layer "B.Cu")
		(net "PCIE_IOM_A_TO_COMP_A_11_DN")
	)
	(arc
		(start 236.814868 -178.038506)
		(mid 236.784165 -178.111437)
		(end 236.723682 -178.162458)
		(width 0.1651)
		(layer "B.Cu")
		(net "PCIE_IOM_A_TO_COMP_A_11_DN")
	)
	(arc
		(start 138.466576 -21.796248)
		(mid 138.634327 -21.865733)
		(end 138.703812 -22.033484)
		(width 0.1651)
		(layer "B.Cu")
		(net "PCIE_IOM_A_TO_COMP_A_11_DN")
	)
	(arc
		(start 236.767624 -177.892456)
		(mid 236.808852 -177.959796)
		(end 236.814868 -178.038506)
		(width 0.1651)
		(layer "B.Cu")
		(net "PCIE_IOM_A_TO_COMP_A_11_DN")
	)
	(segment
		(start 245.946422 -34.141918)
		(end 251.024136 -60.263532)
		(width 0.1651)
		(layer "B.Cu")
		(net "PCIE_IOM_A_TO_COMP_A_10_DP")
	)
	(segment
		(start 142.242032 -33.471612)
		(end 143.020288 -33.996122)
		(width 0.1651)
		(layer "B.Cu")
		(net "PCIE_IOM_A_TO_COMP_A_10_DP")
	)
	(segment
		(start 139.750038 -21.950172)
		(end 139.750038 -22.337776)
		(width 0.1651)
		(layer "B.Cu")
		(net "PCIE_IOM_A_TO_COMP_A_10_DP")
	)
	(segment
		(start 143.020288 -33.996122)
		(end 152.051512 -35.75177)
		(width 0.1651)
		(layer "B.Cu")
		(net "PCIE_IOM_A_TO_COMP_A_10_DP")
	)
	(segment
		(start 251.024136 -60.263532)
		(end 246.017796 -86.018116)
		(width 0.1651)
		(layer "B.Cu")
		(net "PCIE_IOM_A_TO_COMP_A_10_DP")
	)
	(segment
		(start 233.180128 -29.054044)
		(end 236.525054 -29.054044)
		(width 0.1651)
		(layer "B.Cu")
		(net "PCIE_IOM_A_TO_COMP_A_10_DP")
	)
	(segment
		(start 209.843878 -24.518366)
		(end 233.180128 -29.054044)
		(width 0.1651)
		(layer "B.Cu")
		(net "PCIE_IOM_A_TO_COMP_A_10_DP")
	)
	(segment
		(start 140.79601 -23.033482)
		(end 140.79601 -31.276036)
		(width 0.1651)
		(layer "B.Cu")
		(net "PCIE_IOM_A_TO_COMP_A_10_DP")
	)
	(segment
		(start 246.017796 -86.018116)
		(end 244.136926 -88.80729)
		(width 0.1651)
		(layer "B.Cu")
		(net "PCIE_IOM_A_TO_COMP_A_10_DP")
	)
	(segment
		(start 241.024918 -30.054042)
		(end 242.024916 -31.05404)
		(width 0.1651)
		(layer "B.Cu")
		(net "PCIE_IOM_A_TO_COMP_A_10_DP")
	)
	(segment
		(start 140.79601 -31.276036)
		(end 142.242032 -33.471612)
		(width 0.1651)
		(layer "B.Cu")
		(net "PCIE_IOM_A_TO_COMP_A_10_DP")
	)
	(segment
		(start 244.136926 -88.80729)
		(end 232.657396 -98.039174)
		(width 0.1651)
		(layer "B.Cu")
		(net "PCIE_IOM_A_TO_COMP_A_10_DP")
	)
	(segment
		(start 230.026464 -101.941884)
		(end 222.1357 -142.532862)
		(width 0.1651)
		(layer "B.Cu")
		(net "PCIE_IOM_A_TO_COMP_A_10_DP")
	)
	(segment
		(start 243.024914 -31.05404)
		(end 244.476524 -31.962852)
		(width 0.1651)
		(layer "B.Cu")
		(net "PCIE_IOM_A_TO_COMP_A_10_DP")
	)
	(segment
		(start 139.916408 -22.504146)
		(end 140.266674 -22.504146)
		(width 0.1651)
		(layer "B.Cu")
		(net "PCIE_IOM_A_TO_COMP_A_10_DP")
	)
	(segment
		(start 152.051512 -35.75177)
		(end 209.843878 -24.518366)
		(width 0.1651)
		(layer "B.Cu")
		(net "PCIE_IOM_A_TO_COMP_A_10_DP")
	)
	(segment
		(start 232.657396 -98.039174)
		(end 230.026464 -101.941884)
		(width 0.1651)
		(layer "B.Cu")
		(net "PCIE_IOM_A_TO_COMP_A_10_DP")
	)
	(segment
		(start 237.389416 -173.838362)
		(end 238.05007 -173.49978)
		(width 0.1651)
		(layer "B.Cu")
		(net "PCIE_IOM_A_TO_COMP_A_10_DP")
	)
	(segment
		(start 235.053886 -172.943774)
		(end 235.621322 -173.380908)
		(width 0.1651)
		(layer "B.Cu")
		(net "PCIE_IOM_A_TO_COMP_A_10_DP")
	)
	(segment
		(start 236.525054 -29.054044)
		(end 237.525052 -30.054042)
		(width 0.1651)
		(layer "B.Cu")
		(net "PCIE_IOM_A_TO_COMP_A_10_DP")
	)
	(segment
		(start 237.525052 -30.054042)
		(end 241.024918 -30.054042)
		(width 0.1651)
		(layer "B.Cu")
		(net "PCIE_IOM_A_TO_COMP_A_10_DP")
	)
	(segment
		(start 235.621322 -173.380908)
		(end 236.388148 -173.383702)
		(width 0.1651)
		(layer "B.Cu")
		(net "PCIE_IOM_A_TO_COMP_A_10_DP")
	)
	(segment
		(start 237.218474 -173.860714)
		(end 237.233968 -173.863254)
		(width 0.1651)
		(layer "B.Cu")
		(net "PCIE_IOM_A_TO_COMP_A_10_DP")
	)
	(segment
		(start 242.024916 -31.05404)
		(end 243.024914 -31.05404)
		(width 0.1651)
		(layer "B.Cu")
		(net "PCIE_IOM_A_TO_COMP_A_10_DP")
	)
	(segment
		(start 225.209608 -158.348172)
		(end 235.053886 -172.943774)
		(width 0.1651)
		(layer "B.Cu")
		(net "PCIE_IOM_A_TO_COMP_A_10_DP")
	)
	(segment
		(start 244.476524 -31.962852)
		(end 245.946422 -34.141918)
		(width 0.1651)
		(layer "B.Cu")
		(net "PCIE_IOM_A_TO_COMP_A_10_DP")
	)
	(segment
		(start 236.873288 -173.584616)
		(end 237.078266 -173.789594)
		(width 0.1651)
		(layer "B.Cu")
		(net "PCIE_IOM_A_TO_COMP_A_10_DP")
	)
	(segment
		(start 222.1357 -142.532862)
		(end 225.209608 -158.348172)
		(width 0.1651)
		(layer "B.Cu")
		(net "PCIE_IOM_A_TO_COMP_A_10_DP")
	)
	(arc
		(start 237.233968 -173.863254)
		(mid 237.313678 -173.863181)
		(end 237.389416 -173.838362)
		(width 0.1651)
		(layer "B.Cu")
		(net "PCIE_IOM_A_TO_COMP_A_10_DP")
	)
	(arc
		(start 139.750038 -22.337776)
		(mid 139.798767 -22.455417)
		(end 139.916408 -22.504146)
		(width 0.1651)
		(layer "B.Cu")
		(net "PCIE_IOM_A_TO_COMP_A_10_DP")
	)
	(arc
		(start 140.266674 -22.504146)
		(mid 140.640971 -22.659185)
		(end 140.79601 -23.033482)
		(width 0.1651)
		(layer "B.Cu")
		(net "PCIE_IOM_A_TO_COMP_A_10_DP")
	)
	(arc
		(start 236.718348 -173.468284)
		(mid 236.799931 -173.520969)
		(end 236.873288 -173.584616)
		(width 0.1651)
		(layer "B.Cu")
		(net "PCIE_IOM_A_TO_COMP_A_10_DP")
	)
	(arc
		(start 237.078266 -173.789594)
		(mid 237.142732 -173.836266)
		(end 237.218474 -173.860714)
		(width 0.1651)
		(layer "B.Cu")
		(net "PCIE_IOM_A_TO_COMP_A_10_DP")
	)
	(arc
		(start 236.388148 -173.383702)
		(mid 236.55859 -173.405146)
		(end 236.718348 -173.468284)
		(width 0.1651)
		(layer "B.Cu")
		(net "PCIE_IOM_A_TO_COMP_A_10_DP")
	)
	(segment
		(start 245.742206 -85.90407)
		(end 243.919248 -88.607138)
		(width 0.1651)
		(layer "B.Cu")
		(net "PCIE_IOM_A_TO_COMP_A_10_DN")
	)
	(segment
		(start 142.030196 -33.681162)
		(end 142.906242 -34.271712)
		(width 0.1651)
		(layer "B.Cu")
		(net "PCIE_IOM_A_TO_COMP_A_10_DN")
	)
	(segment
		(start 232.439718 -97.839022)
		(end 229.750874 -101.827838)
		(width 0.1651)
		(layer "B.Cu")
		(net "PCIE_IOM_A_TO_COMP_A_10_DN")
	)
	(segment
		(start 250.726448 -60.263532)
		(end 245.742206 -85.90407)
		(width 0.1651)
		(layer "B.Cu")
		(net "PCIE_IOM_A_TO_COMP_A_10_DN")
	)
	(segment
		(start 140.50391 -31.363666)
		(end 142.030196 -33.681162)
		(width 0.1651)
		(layer "B.Cu")
		(net "PCIE_IOM_A_TO_COMP_A_10_DN")
	)
	(segment
		(start 229.750874 -101.827838)
		(end 221.838012 -142.532862)
		(width 0.1651)
		(layer "B.Cu")
		(net "PCIE_IOM_A_TO_COMP_A_10_DN")
	)
	(segment
		(start 234.178094 -172.168312)
		(end 234.837986 -173.146466)
		(width 0.1651)
		(layer "B.Cu")
		(net "PCIE_IOM_A_TO_COMP_A_10_DN")
	)
	(segment
		(start 232.41 -169.546524)
		(end 232.379012 -169.705274)
		(width 0.1651)
		(layer "B.Cu")
		(net "PCIE_IOM_A_TO_COMP_A_10_DN")
	)
	(segment
		(start 233.742484 -171.726606)
		(end 234.019598 -172.137324)
		(width 0.1651)
		(layer "B.Cu")
		(net "PCIE_IOM_A_TO_COMP_A_10_DN")
	)
	(segment
		(start 233.091736 -170.55719)
		(end 233.060748 -170.71594)
		(width 0.1651)
		(layer "B.Cu")
		(net "PCIE_IOM_A_TO_COMP_A_10_DN")
	)
	(segment
		(start 232.814622 -170.146726)
		(end 233.091736 -170.55719)
		(width 0.1651)
		(layer "B.Cu")
		(net "PCIE_IOM_A_TO_COMP_A_10_DN")
	)
	(segment
		(start 231.97439 -169.105072)
		(end 232.132886 -169.135806)
		(width 0.1651)
		(layer "B.Cu")
		(net "PCIE_IOM_A_TO_COMP_A_10_DN")
	)
	(segment
		(start 140.50391 -23.033482)
		(end 140.50391 -31.363666)
		(width 0.1651)
		(layer "B.Cu")
		(net "PCIE_IOM_A_TO_COMP_A_10_DN")
	)
	(segment
		(start 139.916408 -22.796246)
		(end 140.266674 -22.796246)
		(width 0.1651)
		(layer "B.Cu")
		(net "PCIE_IOM_A_TO_COMP_A_10_DN")
	)
	(segment
		(start 245.670832 -34.256218)
		(end 250.726448 -60.263532)
		(width 0.1651)
		(layer "B.Cu")
		(net "PCIE_IOM_A_TO_COMP_A_10_DN")
	)
	(segment
		(start 233.496358 -171.157392)
		(end 233.773472 -171.56811)
		(width 0.1651)
		(layer "B.Cu")
		(net "PCIE_IOM_A_TO_COMP_A_10_DN")
	)
	(segment
		(start 233.773472 -171.56811)
		(end 233.742484 -171.726606)
		(width 0.1651)
		(layer "B.Cu")
		(net "PCIE_IOM_A_TO_COMP_A_10_DN")
	)
	(segment
		(start 240.90376 -30.346142)
		(end 241.903758 -31.34614)
		(width 0.1651)
		(layer "B.Cu")
		(net "PCIE_IOM_A_TO_COMP_A_10_DN")
	)
	(segment
		(start 209.843878 -24.816054)
		(end 233.151934 -29.346144)
		(width 0.1651)
		(layer "B.Cu")
		(net "PCIE_IOM_A_TO_COMP_A_10_DN")
	)
	(segment
		(start 236.403896 -29.346144)
		(end 237.403894 -30.346142)
		(width 0.1651)
		(layer "B.Cu")
		(net "PCIE_IOM_A_TO_COMP_A_10_DN")
	)
	(segment
		(start 235.521754 -173.673008)
		(end 236.388402 -173.675802)
		(width 0.1651)
		(layer "B.Cu")
		(net "PCIE_IOM_A_TO_COMP_A_10_DN")
	)
	(segment
		(start 234.837986 -173.146466)
		(end 235.521754 -173.673008)
		(width 0.1651)
		(layer "B.Cu")
		(net "PCIE_IOM_A_TO_COMP_A_10_DN")
	)
	(segment
		(start 236.723682 -174.162466)
		(end 236.050074 -174.499778)
		(width 0.1651)
		(layer "B.Cu")
		(net "PCIE_IOM_A_TO_COMP_A_10_DN")
	)
	(segment
		(start 233.337862 -171.126658)
		(end 233.496358 -171.157392)
		(width 0.1651)
		(layer "B.Cu")
		(net "PCIE_IOM_A_TO_COMP_A_10_DN")
	)
	(segment
		(start 232.656126 -170.115738)
		(end 232.814622 -170.146726)
		(width 0.1651)
		(layer "B.Cu")
		(net "PCIE_IOM_A_TO_COMP_A_10_DN")
	)
	(segment
		(start 221.838012 -142.532862)
		(end 224.934018 -158.462218)
		(width 0.1651)
		(layer "B.Cu")
		(net "PCIE_IOM_A_TO_COMP_A_10_DN")
	)
	(segment
		(start 243.919248 -88.607138)
		(end 232.439718 -97.839022)
		(width 0.1651)
		(layer "B.Cu")
		(net "PCIE_IOM_A_TO_COMP_A_10_DN")
	)
	(segment
		(start 236.666532 -173.791372)
		(end 236.767624 -173.892464)
		(width 0.1651)
		(layer "B.Cu")
		(net "PCIE_IOM_A_TO_COMP_A_10_DN")
	)
	(segment
		(start 244.268752 -32.177736)
		(end 245.670832 -34.256218)
		(width 0.1651)
		(layer "B.Cu")
		(net "PCIE_IOM_A_TO_COMP_A_10_DN")
	)
	(segment
		(start 231.697276 -168.694354)
		(end 231.97439 -169.105072)
		(width 0.1651)
		(layer "B.Cu")
		(net "PCIE_IOM_A_TO_COMP_A_10_DN")
	)
	(segment
		(start 234.019598 -172.137324)
		(end 234.178094 -172.168312)
		(width 0.1651)
		(layer "B.Cu")
		(net "PCIE_IOM_A_TO_COMP_A_10_DN")
	)
	(segment
		(start 233.151934 -29.346144)
		(end 236.403896 -29.346144)
		(width 0.1651)
		(layer "B.Cu")
		(net "PCIE_IOM_A_TO_COMP_A_10_DN")
	)
	(segment
		(start 232.379012 -169.705274)
		(end 232.656126 -170.115738)
		(width 0.1651)
		(layer "B.Cu")
		(net "PCIE_IOM_A_TO_COMP_A_10_DN")
	)
	(segment
		(start 243.60505 -31.761938)
		(end 244.268752 -32.177736)
		(width 0.1651)
		(layer "B.Cu")
		(net "PCIE_IOM_A_TO_COMP_A_10_DN")
	)
	(segment
		(start 224.934018 -158.462218)
		(end 231.728264 -168.535604)
		(width 0.1651)
		(layer "B.Cu")
		(net "PCIE_IOM_A_TO_COMP_A_10_DN")
	)
	(segment
		(start 237.403894 -30.346142)
		(end 240.90376 -30.346142)
		(width 0.1651)
		(layer "B.Cu")
		(net "PCIE_IOM_A_TO_COMP_A_10_DN")
	)
	(segment
		(start 232.132886 -169.135806)
		(end 232.41 -169.546524)
		(width 0.1651)
		(layer "B.Cu")
		(net "PCIE_IOM_A_TO_COMP_A_10_DN")
	)
	(segment
		(start 241.903758 -31.34614)
		(end 242.94084 -31.34614)
		(width 0.1651)
		(layer "B.Cu")
		(net "PCIE_IOM_A_TO_COMP_A_10_DN")
	)
	(segment
		(start 242.94084 -31.34614)
		(end 243.60505 -31.761938)
		(width 0.1651)
		(layer "B.Cu")
		(net "PCIE_IOM_A_TO_COMP_A_10_DN")
	)
	(segment
		(start 142.906242 -34.271712)
		(end 152.051512 -36.049458)
		(width 0.1651)
		(layer "B.Cu")
		(net "PCIE_IOM_A_TO_COMP_A_10_DN")
	)
	(segment
		(start 233.060748 -170.71594)
		(end 233.337862 -171.126658)
		(width 0.1651)
		(layer "B.Cu")
		(net "PCIE_IOM_A_TO_COMP_A_10_DN")
	)
	(segment
		(start 231.728264 -168.535604)
		(end 231.697276 -168.694354)
		(width 0.1651)
		(layer "B.Cu")
		(net "PCIE_IOM_A_TO_COMP_A_10_DN")
	)
	(segment
		(start 139.750038 -23.35022)
		(end 139.750038 -22.962616)
		(width 0.1651)
		(layer "B.Cu")
		(net "PCIE_IOM_A_TO_COMP_A_10_DN")
	)
	(segment
		(start 152.051512 -36.049458)
		(end 209.843878 -24.816054)
		(width 0.1651)
		(layer "B.Cu")
		(net "PCIE_IOM_A_TO_COMP_A_10_DN")
	)
	(arc
		(start 236.388402 -173.675802)
		(mid 236.4861 -173.688238)
		(end 236.577632 -173.72457)
		(width 0.1651)
		(layer "B.Cu")
		(net "PCIE_IOM_A_TO_COMP_A_10_DN")
	)
	(arc
		(start 139.750038 -22.962616)
		(mid 139.798767 -22.844975)
		(end 139.916408 -22.796246)
		(width 0.1651)
		(layer "B.Cu")
		(net "PCIE_IOM_A_TO_COMP_A_10_DN")
	)
	(arc
		(start 236.577632 -173.72457)
		(mid 236.624445 -173.754824)
		(end 236.666532 -173.791372)
		(width 0.1651)
		(layer "B.Cu")
		(net "PCIE_IOM_A_TO_COMP_A_10_DN")
	)
	(arc
		(start 236.767624 -173.892464)
		(mid 236.808852 -173.959804)
		(end 236.814868 -174.038514)
		(width 0.1651)
		(layer "B.Cu")
		(net "PCIE_IOM_A_TO_COMP_A_10_DN")
	)
	(arc
		(start 236.814868 -174.038514)
		(mid 236.784165 -174.111445)
		(end 236.723682 -174.162466)
		(width 0.1651)
		(layer "B.Cu")
		(net "PCIE_IOM_A_TO_COMP_A_10_DN")
	)
	(arc
		(start 140.266674 -22.796246)
		(mid 140.434425 -22.865731)
		(end 140.50391 -23.033482)
		(width 0.1651)
		(layer "B.Cu")
		(net "PCIE_IOM_A_TO_COMP_A_10_DN")
	)
	(segment
		(start 293.346378 -346.502228)
		(end 302.913542 -336.935064)
		(width 0.17145)
		(layer "F.Cu")
		(net "PCIE_COMP_B_TO_SCC_B_RST_0")
	)
	(segment
		(start 291.27704 -211.90077)
		(end 264.353548 -184.977278)
		(width 0.17145)
		(layer "F.Cu")
		(net "PCIE_COMP_B_TO_SCC_B_RST_0")
	)
	(segment
		(start 291.6174 -366.0902)
		(end 293.346378 -364.361222)
		(width 0.17145)
		(layer "F.Cu")
		(net "PCIE_COMP_B_TO_SCC_B_RST_0")
	)
	(segment
		(start 285.058866 -366.0902)
		(end 291.6174 -366.0902)
		(width 0.17145)
		(layer "F.Cu")
		(net "PCIE_COMP_B_TO_SCC_B_RST_0")
	)
	(segment
		(start 302.913542 -336.935064)
		(end 302.913542 -266.711938)
		(width 0.17145)
		(layer "F.Cu")
		(net "PCIE_COMP_B_TO_SCC_B_RST_0")
	)
	(segment
		(start 304.30216 -235.331)
		(end 296.3926 -235.331)
		(width 0.17145)
		(layer "F.Cu")
		(net "PCIE_COMP_B_TO_SCC_B_RST_0")
	)
	(segment
		(start 266.636754 -110.79226)
		(end 266.636754 -110.339886)
		(width 0.17145)
		(layer "F.Cu")
		(net "PCIE_COMP_B_TO_SCC_B_RST_0")
	)
	(segment
		(start 291.27704 -230.21544)
		(end 291.27704 -211.90077)
		(width 0.17145)
		(layer "F.Cu")
		(net "PCIE_COMP_B_TO_SCC_B_RST_0")
	)
	(segment
		(start 266.184634 -111.24438)
		(end 266.636754 -110.79226)
		(width 0.17145)
		(layer "F.Cu")
		(net "PCIE_COMP_B_TO_SCC_B_RST_0")
	)
	(segment
		(start 222.968312 -381.096266)
		(end 227.244148 -381.096266)
		(width 0.17145)
		(layer "F.Cu")
		(net "PCIE_COMP_B_TO_SCC_B_RST_0")
	)
	(segment
		(start 283.401516 -364.43285)
		(end 285.058866 -366.0902)
		(width 0.17145)
		(layer "F.Cu")
		(net "PCIE_COMP_B_TO_SCC_B_RST_0")
	)
	(segment
		(start 293.346378 -364.361222)
		(end 293.346378 -346.502228)
		(width 0.17145)
		(layer "F.Cu")
		(net "PCIE_COMP_B_TO_SCC_B_RST_0")
	)
	(segment
		(start 227.244148 -381.096266)
		(end 233.648758 -374.691656)
		(width 0.17145)
		(layer "F.Cu")
		(net "PCIE_COMP_B_TO_SCC_B_RST_0")
	)
	(segment
		(start 280.75001 -109.499908)
		(end 279.444196 -110.805722)
		(width 0.17145)
		(layer "F.Cu")
		(net "PCIE_COMP_B_TO_SCC_B_RST_0")
	)
	(segment
		(start 302.913542 -266.711938)
		(end 308.08422 -261.54126)
		(width 0.17145)
		(layer "F.Cu")
		(net "PCIE_COMP_B_TO_SCC_B_RST_0")
	)
	(segment
		(start 268.645132 -110.805722)
		(end 268.179296 -110.339886)
		(width 0.17145)
		(layer "F.Cu")
		(net "PCIE_COMP_B_TO_SCC_B_RST_0")
	)
	(segment
		(start 233.648758 -374.691656)
		(end 246.67464 -374.691656)
		(width 0.17145)
		(layer "F.Cu")
		(net "PCIE_COMP_B_TO_SCC_B_RST_0")
	)
	(segment
		(start 308.08422 -239.11306)
		(end 304.30216 -235.331)
		(width 0.17145)
		(layer "F.Cu")
		(net "PCIE_COMP_B_TO_SCC_B_RST_0")
	)
	(segment
		(start 264.353548 -112.053624)
		(end 265.162792 -111.24438)
		(width 0.17145)
		(layer "F.Cu")
		(net "PCIE_COMP_B_TO_SCC_B_RST_0")
	)
	(segment
		(start 265.162792 -111.24438)
		(end 266.184634 -111.24438)
		(width 0.17145)
		(layer "F.Cu")
		(net "PCIE_COMP_B_TO_SCC_B_RST_0")
	)
	(segment
		(start 279.444196 -110.805722)
		(end 268.645132 -110.805722)
		(width 0.17145)
		(layer "F.Cu")
		(net "PCIE_COMP_B_TO_SCC_B_RST_0")
	)
	(segment
		(start 268.179296 -110.339886)
		(end 267.645134 -110.339886)
		(width 0.17145)
		(layer "F.Cu")
		(net "PCIE_COMP_B_TO_SCC_B_RST_0")
	)
	(segment
		(start 267.645134 -110.339886)
		(end 266.636754 -110.339886)
		(width 0.17145)
		(layer "F.Cu")
		(net "PCIE_COMP_B_TO_SCC_B_RST_0")
	)
	(segment
		(start 246.67464 -374.691656)
		(end 256.933446 -364.43285)
		(width 0.17145)
		(layer "F.Cu")
		(net "PCIE_COMP_B_TO_SCC_B_RST_0")
	)
	(segment
		(start 256.933446 -364.43285)
		(end 283.401516 -364.43285)
		(width 0.17145)
		(layer "F.Cu")
		(net "PCIE_COMP_B_TO_SCC_B_RST_0")
	)
	(segment
		(start 264.353548 -184.977278)
		(end 264.353548 -112.053624)
		(width 0.17145)
		(layer "F.Cu")
		(net "PCIE_COMP_B_TO_SCC_B_RST_0")
	)
	(segment
		(start 296.3926 -235.331)
		(end 291.27704 -230.21544)
		(width 0.17145)
		(layer "F.Cu")
		(net "PCIE_COMP_B_TO_SCC_B_RST_0")
	)
	(segment
		(start 308.08422 -261.54126)
		(end 308.08422 -239.11306)
		(width 0.17145)
		(layer "F.Cu")
		(net "PCIE_COMP_B_TO_SCC_B_RST_0")
	)
	(via
		(at 267.645134 -110.339886)
		(size 0.6604)
		(drill 0.3302)
		(layers "F.Cu" "B.Cu")
		(net "PCIE_COMP_B_TO_SCC_B_RST_0")
	)
	(via
		(at 222.968312 -381.096266)
		(size 0.5588)
		(drill 0.3048)
		(layers "F.Cu" "B.Cu")
		(net "PCIE_COMP_B_TO_SCC_B_RST_0")
	)
	(segment
		(start 216.578688 -389.154162)
		(end 216.578688 -408.419046)
		(width 0.13335)
		(layer "In2.Cu")
		(net "PCIE_COMP_B_TO_SCC_B_RST_0")
	)
	(segment
		(start 217.482674 -385.557268)
		(end 217.482674 -388.250176)
		(width 0.13335)
		(layer "In2.Cu")
		(net "PCIE_COMP_B_TO_SCC_B_RST_0")
	)
	(segment
		(start 222.968312 -381.096266)
		(end 221.943676 -381.096266)
		(width 0.13335)
		(layer "In2.Cu")
		(net "PCIE_COMP_B_TO_SCC_B_RST_0")
	)
	(segment
		(start 217.482674 -388.250176)
		(end 216.578688 -389.154162)
		(width 0.13335)
		(layer "In2.Cu")
		(net "PCIE_COMP_B_TO_SCC_B_RST_0")
	)
	(segment
		(start 215.400128 -409.597606)
		(end 215.400128 -409.600146)
		(width 0.13335)
		(layer "In2.Cu")
		(net "PCIE_COMP_B_TO_SCC_B_RST_0")
	)
	(segment
		(start 221.943676 -381.096266)
		(end 217.482674 -385.557268)
		(width 0.13335)
		(layer "In2.Cu")
		(net "PCIE_COMP_B_TO_SCC_B_RST_0")
	)
	(segment
		(start 216.578688 -408.419046)
		(end 215.400128 -409.597606)
		(width 0.13335)
		(layer "In2.Cu")
		(net "PCIE_COMP_B_TO_SCC_B_RST_0")
	)
	(segment
		(start 202.755754 -339.697314)
		(end 265.377422 -133.31698)
		(width 0.1397)
		(layer "In9.Cu")
		(net "PCIE_COMP_B_TO_SCC_B_CLK_0_DP")
	)
	(segment
		(start 204.182218 -392.956796)
		(end 209.439256 -369.233196)
		(width 0.1397)
		(layer "In9.Cu")
		(net "PCIE_COMP_B_TO_SCC_B_CLK_0_DP")
	)
	(segment
		(start 277.327868 -113.755424)
		(end 277.801578 -113.448084)
		(width 0.1397)
		(layer "In9.Cu")
		(net "PCIE_COMP_B_TO_SCC_B_CLK_0_DP")
	)
	(segment
		(start 265.377676 -133.316218)
		(end 265.90498 -131.57835)
		(width 0.1397)
		(layer "In9.Cu")
		(net "PCIE_COMP_B_TO_SCC_B_CLK_0_DP")
	)
	(segment
		(start 265.905234 -131.577588)
		(end 266.038584 -131.138168)
		(width 0.1397)
		(layer "In9.Cu")
		(net "PCIE_COMP_B_TO_SCC_B_CLK_0_DP")
	)
	(segment
		(start 209.439256 -369.233196)
		(end 202.755754 -339.697314)
		(width 0.1397)
		(layer "In9.Cu")
		(net "PCIE_COMP_B_TO_SCC_B_CLK_0_DP")
	)
	(segment
		(start 209.963004 -411.536134)
		(end 209.910172 -411.483302)
		(width 0.1397)
		(layer "In9.Cu")
		(net "PCIE_COMP_B_TO_SCC_B_CLK_0_DP")
	)
	(segment
		(start 209.232754 -411.414468)
		(end 209.164682 -411.386274)
		(width 0.1397)
		(layer "In9.Cu")
		(net "PCIE_COMP_B_TO_SCC_B_CLK_0_DP")
	)
	(segment
		(start 209.82051 -411.446218)
		(end 209.393028 -411.446218)
		(width 0.1397)
		(layer "In9.Cu")
		(net "PCIE_COMP_B_TO_SCC_B_CLK_0_DP")
	)
	(segment
		(start 277.801578 -113.448084)
		(end 278.215852 -113.3602)
		(width 0.1397)
		(layer "In9.Cu")
		(net "PCIE_COMP_B_TO_SCC_B_CLK_0_DP")
	)
	(segment
		(start 278.215852 -113.3602)
		(end 278.97328 -113.3602)
		(width 0.1397)
		(layer "In9.Cu")
		(net "PCIE_COMP_B_TO_SCC_B_CLK_0_DP")
	)
	(segment
		(start 279.755854 -113.684304)
		(end 279.818338 -113.809526)
		(width 0.1397)
		(layer "In9.Cu")
		(net "PCIE_COMP_B_TO_SCC_B_CLK_0_DP")
	)
	(segment
		(start 265.377422 -133.31698)
		(end 265.377676 -133.316218)
		(width 0.1397)
		(layer "In9.Cu")
		(net "PCIE_COMP_B_TO_SCC_B_CLK_0_DP")
	)
	(segment
		(start 208.129124 -410.396182)
		(end 204.182218 -392.956796)
		(width 0.1397)
		(layer "In9.Cu")
		(net "PCIE_COMP_B_TO_SCC_B_CLK_0_DP")
	)
	(segment
		(start 266.038584 -131.138168)
		(end 271.677638 -122.455686)
		(width 0.1397)
		(layer "In9.Cu")
		(net "PCIE_COMP_B_TO_SCC_B_CLK_0_DP")
	)
	(segment
		(start 209.028792 -411.295596)
		(end 208.129124 -410.396182)
		(width 0.1397)
		(layer "In9.Cu")
		(net "PCIE_COMP_B_TO_SCC_B_CLK_0_DP")
	)
	(segment
		(start 280.00579 -113.87201)
		(end 280.75001 -113.4999)
		(width 0.1397)
		(layer "In9.Cu")
		(net "PCIE_COMP_B_TO_SCC_B_CLK_0_DP")
	)
	(segment
		(start 265.90498 -131.57835)
		(end 265.905234 -131.577588)
		(width 0.1397)
		(layer "In9.Cu")
		(net "PCIE_COMP_B_TO_SCC_B_CLK_0_DP")
	)
	(segment
		(start 271.677638 -122.455686)
		(end 277.327868 -113.755424)
		(width 0.1397)
		(layer "In9.Cu")
		(net "PCIE_COMP_B_TO_SCC_B_CLK_0_DP")
	)
	(segment
		(start 210.000088 -412.000192)
		(end 210.000088 -411.625796)
		(width 0.1397)
		(layer "In9.Cu")
		(net "PCIE_COMP_B_TO_SCC_B_CLK_0_DP")
	)
	(arc
		(start 278.97328 -113.3602)
		(mid 279.396787 -113.444441)
		(end 279.755854 -113.684304)
		(width 0.1397)
		(layer "In9.Cu")
		(net "PCIE_COMP_B_TO_SCC_B_CLK_0_DP")
	)
	(arc
		(start 279.818338 -113.809526)
		(mid 279.899123 -113.879591)
		(end 280.00579 -113.87201)
		(width 0.1397)
		(layer "In9.Cu")
		(net "PCIE_COMP_B_TO_SCC_B_CLK_0_DP")
	)
	(arc
		(start 209.393028 -411.446218)
		(mid 209.311331 -411.438224)
		(end 209.232754 -411.414468)
		(width 0.1397)
		(layer "In9.Cu")
		(net "PCIE_COMP_B_TO_SCC_B_CLK_0_DP")
	)
	(arc
		(start 210.000088 -411.625796)
		(mid 209.990455 -411.577278)
		(end 209.963004 -411.536134)
		(width 0.1397)
		(layer "In9.Cu")
		(net "PCIE_COMP_B_TO_SCC_B_CLK_0_DP")
	)
	(arc
		(start 209.910172 -411.483302)
		(mid 209.869021 -411.455869)
		(end 209.82051 -411.446218)
		(width 0.1397)
		(layer "In9.Cu")
		(net "PCIE_COMP_B_TO_SCC_B_CLK_0_DP")
	)
	(arc
		(start 209.164682 -411.386274)
		(mid 209.092277 -411.347619)
		(end 209.028792 -411.295596)
		(width 0.1397)
		(layer "In9.Cu")
		(net "PCIE_COMP_B_TO_SCC_B_CLK_0_DP")
	)
	(segment
		(start 209.344514 -411.144466)
		(end 209.276442 -411.116272)
		(width 0.1397)
		(layer "In9.Cu")
		(net "PCIE_COMP_B_TO_SCC_B_CLK_0_DN")
	)
	(segment
		(start 276.060154 -116.500656)
		(end 276.019006 -116.307362)
		(width 0.1397)
		(layer "In9.Cu")
		(net "PCIE_COMP_B_TO_SCC_B_CLK_0_DN")
	)
	(segment
		(start 265.535664 -133.802628)
		(end 265.65733 -133.401562)
		(width 0.1397)
		(layer "In9.Cu")
		(net "PCIE_COMP_B_TO_SCC_B_CLK_0_DN")
	)
	(segment
		(start 271.273778 -123.613926)
		(end 271.467072 -123.572778)
		(width 0.1397)
		(layer "In9.Cu")
		(net "PCIE_COMP_B_TO_SCC_B_CLK_0_DN")
	)
	(segment
		(start 270.436848 -124.902468)
		(end 270.665194 -124.551186)
		(width 0.1397)
		(layer "In9.Cu")
		(net "PCIE_COMP_B_TO_SCC_B_CLK_0_DN")
	)
	(segment
		(start 271.045686 -123.965208)
		(end 271.273778 -123.613926)
		(width 0.1397)
		(layer "In9.Cu")
		(net "PCIE_COMP_B_TO_SCC_B_CLK_0_DN")
	)
	(segment
		(start 275.45157 -117.437916)
		(end 275.410422 -117.244622)
		(width 0.1397)
		(layer "In9.Cu")
		(net "PCIE_COMP_B_TO_SCC_B_CLK_0_DN")
	)
	(segment
		(start 270.858488 -124.510038)
		(end 271.08658 -124.158502)
		(width 0.1397)
		(layer "In9.Cu")
		(net "PCIE_COMP_B_TO_SCC_B_CLK_0_DN")
	)
	(segment
		(start 277.915116 -113.722658)
		(end 278.246586 -113.6523)
		(width 0.1397)
		(layer "In9.Cu")
		(net "PCIE_COMP_B_TO_SCC_B_CLK_0_DN")
	)
	(segment
		(start 209.738722 -369.232434)
		(end 203.05776 -339.708236)
		(width 0.1397)
		(layer "In9.Cu")
		(net "PCIE_COMP_B_TO_SCC_B_CLK_0_DN")
	)
	(segment
		(start 276.85619 -115.018566)
		(end 277.04923 -114.977418)
		(width 0.1397)
		(layer "In9.Cu")
		(net "PCIE_COMP_B_TO_SCC_B_CLK_0_DN")
	)
	(segment
		(start 275.02993 -117.830346)
		(end 275.223224 -117.789198)
		(width 0.1397)
		(layer "In9.Cu")
		(net "PCIE_COMP_B_TO_SCC_B_CLK_0_DN")
	)
	(segment
		(start 209.235294 -411.08884)
		(end 208.39557 -410.249116)
		(width 0.1397)
		(layer "In9.Cu")
		(net "PCIE_COMP_B_TO_SCC_B_CLK_0_DN")
	)
	(segment
		(start 270.665194 -124.551186)
		(end 270.858488 -124.510038)
		(width 0.1397)
		(layer "In9.Cu")
		(net "PCIE_COMP_B_TO_SCC_B_CLK_0_DN")
	)
	(segment
		(start 271.882616 -122.676412)
		(end 272.07591 -122.635518)
		(width 0.1397)
		(layer "In9.Cu")
		(net "PCIE_COMP_B_TO_SCC_B_CLK_0_DN")
	)
	(segment
		(start 276.627844 -115.370102)
		(end 276.85619 -115.018566)
		(width 0.1397)
		(layer "In9.Cu")
		(net "PCIE_COMP_B_TO_SCC_B_CLK_0_DN")
	)
	(segment
		(start 278.246586 -113.6523)
		(end 278.973534 -113.6523)
		(width 0.1397)
		(layer "In9.Cu")
		(net "PCIE_COMP_B_TO_SCC_B_CLK_0_DN")
	)
	(segment
		(start 276.440646 -115.914678)
		(end 276.668992 -115.563396)
		(width 0.1397)
		(layer "In9.Cu")
		(net "PCIE_COMP_B_TO_SCC_B_CLK_0_DN")
	)
	(segment
		(start 277.539196 -113.966752)
		(end 277.915116 -113.722658)
		(width 0.1397)
		(layer "In9.Cu")
		(net "PCIE_COMP_B_TO_SCC_B_CLK_0_DN")
	)
	(segment
		(start 277.236428 -114.432842)
		(end 277.539196 -113.966752)
		(width 0.1397)
		(layer "In9.Cu")
		(net "PCIE_COMP_B_TO_SCC_B_CLK_0_DN")
	)
	(segment
		(start 276.668992 -115.563396)
		(end 276.627844 -115.370102)
		(width 0.1397)
		(layer "In9.Cu")
		(net "PCIE_COMP_B_TO_SCC_B_CLK_0_DN")
	)
	(segment
		(start 265.95324 -132.907278)
		(end 265.860022 -132.733034)
		(width 0.1397)
		(layer "In9.Cu")
		(net "PCIE_COMP_B_TO_SCC_B_CLK_0_DN")
	)
	(segment
		(start 265.860022 -132.733034)
		(end 265.981688 -132.331968)
		(width 0.1397)
		(layer "In9.Cu")
		(net "PCIE_COMP_B_TO_SCC_B_CLK_0_DN")
	)
	(segment
		(start 275.638768 -116.893086)
		(end 275.831808 -116.851938)
		(width 0.1397)
		(layer "In9.Cu")
		(net "PCIE_COMP_B_TO_SCC_B_CLK_0_DN")
	)
	(segment
		(start 271.65427 -123.027948)
		(end 271.882616 -122.676412)
		(width 0.1397)
		(layer "In9.Cu")
		(net "PCIE_COMP_B_TO_SCC_B_CLK_0_DN")
	)
	(segment
		(start 265.332718 -134.470902)
		(end 265.506962 -134.377938)
		(width 0.1397)
		(layer "In9.Cu")
		(net "PCIE_COMP_B_TO_SCC_B_CLK_0_DN")
	)
	(segment
		(start 272.304002 -122.283982)
		(end 272.263108 -122.090688)
		(width 0.1397)
		(layer "In9.Cu")
		(net "PCIE_COMP_B_TO_SCC_B_CLK_0_DN")
	)
	(segment
		(start 277.277576 -114.625882)
		(end 277.236428 -114.432842)
		(width 0.1397)
		(layer "In9.Cu")
		(net "PCIE_COMP_B_TO_SCC_B_CLK_0_DN")
	)
	(segment
		(start 271.695418 -123.221242)
		(end 271.65427 -123.027948)
		(width 0.1397)
		(layer "In9.Cu")
		(net "PCIE_COMP_B_TO_SCC_B_CLK_0_DN")
	)
	(segment
		(start 266.3063 -131.262628)
		(end 270.056356 -125.488446)
		(width 0.1397)
		(layer "In9.Cu")
		(net "PCIE_COMP_B_TO_SCC_B_CLK_0_DN")
	)
	(segment
		(start 272.07591 -122.635518)
		(end 272.304002 -122.283982)
		(width 0.1397)
		(layer "In9.Cu")
		(net "PCIE_COMP_B_TO_SCC_B_CLK_0_DN")
	)
	(segment
		(start 277.04923 -114.977418)
		(end 277.277576 -114.625882)
		(width 0.1397)
		(layer "In9.Cu")
		(net "PCIE_COMP_B_TO_SCC_B_CLK_0_DN")
	)
	(segment
		(start 265.831574 -133.308344)
		(end 265.95324 -132.907278)
		(width 0.1397)
		(layer "In9.Cu")
		(net "PCIE_COMP_B_TO_SCC_B_CLK_0_DN")
	)
	(segment
		(start 270.056356 -125.488446)
		(end 270.24965 -125.447298)
		(width 0.1397)
		(layer "In9.Cu")
		(net "PCIE_COMP_B_TO_SCC_B_CLK_0_DN")
	)
	(segment
		(start 279.494488 -114.127534)
		(end 278.750014 -114.499898)
		(width 0.1397)
		(layer "In9.Cu")
		(net "PCIE_COMP_B_TO_SCC_B_CLK_0_DN")
	)
	(segment
		(start 275.410422 -117.244622)
		(end 275.638768 -116.893086)
		(width 0.1397)
		(layer "In9.Cu")
		(net "PCIE_COMP_B_TO_SCC_B_CLK_0_DN")
	)
	(segment
		(start 266.184634 -131.663694)
		(end 266.185142 -131.66217)
		(width 0.1397)
		(layer "In9.Cu")
		(net "PCIE_COMP_B_TO_SCC_B_CLK_0_DN")
	)
	(segment
		(start 276.247352 -115.955826)
		(end 276.440646 -115.914678)
		(width 0.1397)
		(layer "In9.Cu")
		(net "PCIE_COMP_B_TO_SCC_B_CLK_0_DN")
	)
	(segment
		(start 265.628628 -133.976872)
		(end 265.535664 -133.802628)
		(width 0.1397)
		(layer "In9.Cu")
		(net "PCIE_COMP_B_TO_SCC_B_CLK_0_DN")
	)
	(segment
		(start 210.000088 -410.600144)
		(end 210.000088 -410.975048)
		(width 0.1397)
		(layer "In9.Cu")
		(net "PCIE_COMP_B_TO_SCC_B_CLK_0_DN")
	)
	(segment
		(start 208.39557 -410.249116)
		(end 204.481684 -392.956034)
		(width 0.1397)
		(layer "In9.Cu")
		(net "PCIE_COMP_B_TO_SCC_B_CLK_0_DN")
	)
	(segment
		(start 265.506962 -134.377938)
		(end 265.628628 -133.976872)
		(width 0.1397)
		(layer "In9.Cu")
		(net "PCIE_COMP_B_TO_SCC_B_CLK_0_DN")
	)
	(segment
		(start 266.277852 -131.837938)
		(end 266.184634 -131.663694)
		(width 0.1397)
		(layer "In9.Cu")
		(net "PCIE_COMP_B_TO_SCC_B_CLK_0_DN")
	)
	(segment
		(start 265.981688 -132.331968)
		(end 266.155932 -132.239004)
		(width 0.1397)
		(layer "In9.Cu")
		(net "PCIE_COMP_B_TO_SCC_B_CLK_0_DN")
	)
	(segment
		(start 204.481684 -392.956034)
		(end 209.738722 -369.232434)
		(width 0.1397)
		(layer "In9.Cu")
		(net "PCIE_COMP_B_TO_SCC_B_CLK_0_DN")
	)
	(segment
		(start 209.821018 -411.154118)
		(end 209.393028 -411.154118)
		(width 0.1397)
		(layer "In9.Cu")
		(net "PCIE_COMP_B_TO_SCC_B_CLK_0_DN")
	)
	(segment
		(start 266.155932 -132.239004)
		(end 266.277852 -131.837938)
		(width 0.1397)
		(layer "In9.Cu")
		(net "PCIE_COMP_B_TO_SCC_B_CLK_0_DN")
	)
	(segment
		(start 279.517094 -113.860834)
		(end 279.556972 -113.940082)
		(width 0.1397)
		(layer "In9.Cu")
		(net "PCIE_COMP_B_TO_SCC_B_CLK_0_DN")
	)
	(segment
		(start 272.263108 -122.090688)
		(end 275.02993 -117.830346)
		(width 0.1397)
		(layer "In9.Cu")
		(net "PCIE_COMP_B_TO_SCC_B_CLK_0_DN")
	)
	(segment
		(start 265.65733 -133.401562)
		(end 265.831574 -133.308344)
		(width 0.1397)
		(layer "In9.Cu")
		(net "PCIE_COMP_B_TO_SCC_B_CLK_0_DN")
	)
	(segment
		(start 275.831808 -116.851938)
		(end 276.060154 -116.500656)
		(width 0.1397)
		(layer "In9.Cu")
		(net "PCIE_COMP_B_TO_SCC_B_CLK_0_DN")
	)
	(segment
		(start 266.185142 -131.66217)
		(end 266.3063 -131.262628)
		(width 0.1397)
		(layer "In9.Cu")
		(net "PCIE_COMP_B_TO_SCC_B_CLK_0_DN")
	)
	(segment
		(start 271.08658 -124.158502)
		(end 271.045686 -123.965208)
		(width 0.1397)
		(layer "In9.Cu")
		(net "PCIE_COMP_B_TO_SCC_B_CLK_0_DN")
	)
	(segment
		(start 271.467072 -123.572778)
		(end 271.695418 -123.221242)
		(width 0.1397)
		(layer "In9.Cu")
		(net "PCIE_COMP_B_TO_SCC_B_CLK_0_DN")
	)
	(segment
		(start 203.05776 -339.708236)
		(end 265.332718 -134.470902)
		(width 0.1397)
		(layer "In9.Cu")
		(net "PCIE_COMP_B_TO_SCC_B_CLK_0_DN")
	)
	(segment
		(start 270.477996 -125.095762)
		(end 270.436848 -124.902468)
		(width 0.1397)
		(layer "In9.Cu")
		(net "PCIE_COMP_B_TO_SCC_B_CLK_0_DN")
	)
	(segment
		(start 275.223224 -117.789198)
		(end 275.45157 -117.437916)
		(width 0.1397)
		(layer "In9.Cu")
		(net "PCIE_COMP_B_TO_SCC_B_CLK_0_DN")
	)
	(segment
		(start 276.019006 -116.307362)
		(end 276.247352 -115.955826)
		(width 0.1397)
		(layer "In9.Cu")
		(net "PCIE_COMP_B_TO_SCC_B_CLK_0_DN")
	)
	(segment
		(start 270.24965 -125.447298)
		(end 270.477996 -125.095762)
		(width 0.1397)
		(layer "In9.Cu")
		(net "PCIE_COMP_B_TO_SCC_B_CLK_0_DN")
	)
	(segment
		(start 209.963004 -411.06471)
		(end 209.91068 -411.117034)
		(width 0.1397)
		(layer "In9.Cu")
		(net "PCIE_COMP_B_TO_SCC_B_CLK_0_DN")
	)
	(arc
		(start 209.276442 -411.116272)
		(mid 209.25452 -411.104579)
		(end 209.235294 -411.08884)
		(width 0.1397)
		(layer "In9.Cu")
		(net "PCIE_COMP_B_TO_SCC_B_CLK_0_DN")
	)
	(arc
		(start 210.000088 -410.975048)
		(mid 209.990455 -411.023566)
		(end 209.963004 -411.06471)
		(width 0.1397)
		(layer "In9.Cu")
		(net "PCIE_COMP_B_TO_SCC_B_CLK_0_DN")
	)
	(arc
		(start 278.973534 -113.6523)
		(mid 279.264562 -113.706372)
		(end 279.517094 -113.860834)
		(width 0.1397)
		(layer "In9.Cu")
		(net "PCIE_COMP_B_TO_SCC_B_CLK_0_DN")
	)
	(arc
		(start 209.91068 -411.117034)
		(mid 209.869529 -411.144467)
		(end 209.821018 -411.154118)
		(width 0.1397)
		(layer "In9.Cu")
		(net "PCIE_COMP_B_TO_SCC_B_CLK_0_DN")
	)
	(arc
		(start 209.393028 -411.154118)
		(mid 209.368296 -411.151682)
		(end 209.344514 -411.144466)
		(width 0.1397)
		(layer "In9.Cu")
		(net "PCIE_COMP_B_TO_SCC_B_CLK_0_DN")
	)
	(arc
		(start 279.556972 -113.940082)
		(mid 279.564553 -114.046749)
		(end 279.494488 -114.127534)
		(width 0.1397)
		(layer "In9.Cu")
		(net "PCIE_COMP_B_TO_SCC_B_CLK_0_DN")
	)
	(segment
		(start 279.39619 -163.35375)
		(end 280.396188 -164.353748)
		(width 0.1397)
		(layer "In9.Cu")
		(net "PCIE_COMP_B_TO_SCC_B_7_DP")
	)
	(segment
		(start 222.600012 -418.200078)
		(end 222.600012 -417.825682)
		(width 0.1397)
		(layer "In9.Cu")
		(net "PCIE_COMP_B_TO_SCC_B_7_DP")
	)
	(segment
		(start 273.071336 -167.282368)
		(end 273.071844 -167.282876)
		(width 0.1397)
		(layer "In9.Cu")
		(net "PCIE_COMP_B_TO_SCC_B_7_DP")
	)
	(segment
		(start 217.368374 -386.932932)
		(end 220.70568 -370.464334)
		(width 0.1397)
		(layer "In9.Cu")
		(net "PCIE_COMP_B_TO_SCC_B_7_DP")
	)
	(segment
		(start 280.396188 -164.353748)
		(end 283.58592 -164.353748)
		(width 0.1397)
		(layer "In9.Cu")
		(net "PCIE_COMP_B_TO_SCC_B_7_DP")
	)
	(segment
		(start 214.46744 -342.89873)
		(end 263.083802 -182.66029)
		(width 0.1397)
		(layer "In9.Cu")
		(net "PCIE_COMP_B_TO_SCC_B_7_DP")
	)
	(segment
		(start 283.994352 -164.184584)
		(end 284.056836 -164.059616)
		(width 0.1397)
		(layer "In9.Cu")
		(net "PCIE_COMP_B_TO_SCC_B_7_DP")
	)
	(segment
		(start 273.071844 -167.282876)
		(end 277.958804 -163.35375)
		(width 0.1397)
		(layer "In9.Cu")
		(net "PCIE_COMP_B_TO_SCC_B_7_DP")
	)
	(segment
		(start 222.420434 -417.646104)
		(end 222.213932 -417.646104)
		(width 0.1397)
		(layer "In9.Cu")
		(net "PCIE_COMP_B_TO_SCC_B_7_DP")
	)
	(segment
		(start 277.958804 -163.35375)
		(end 279.39619 -163.35375)
		(width 0.1397)
		(layer "In9.Cu")
		(net "PCIE_COMP_B_TO_SCC_B_7_DP")
	)
	(segment
		(start 222.562928 -417.73602)
		(end 222.510096 -417.683188)
		(width 0.1397)
		(layer "In9.Cu")
		(net "PCIE_COMP_B_TO_SCC_B_7_DP")
	)
	(segment
		(start 263.083802 -182.66029)
		(end 273.071336 -167.282368)
		(width 0.1397)
		(layer "In9.Cu")
		(net "PCIE_COMP_B_TO_SCC_B_7_DP")
	)
	(segment
		(start 220.70568 -370.464334)
		(end 214.46744 -342.89873)
		(width 0.1397)
		(layer "In9.Cu")
		(net "PCIE_COMP_B_TO_SCC_B_7_DP")
	)
	(segment
		(start 283.994352 -163.872164)
		(end 283.249878 -163.4998)
		(width 0.1397)
		(layer "In9.Cu")
		(net "PCIE_COMP_B_TO_SCC_B_7_DP")
	)
	(segment
		(start 221.550484 -405.474424)
		(end 217.369136 -386.991606)
		(width 0.1397)
		(layer "In9.Cu")
		(net "PCIE_COMP_B_TO_SCC_B_7_DP")
	)
	(segment
		(start 221.55404 -416.986212)
		(end 221.55404 -405.505158)
		(width 0.1397)
		(layer "In9.Cu")
		(net "PCIE_COMP_B_TO_SCC_B_7_DP")
	)
	(arc
		(start 283.58592 -164.353748)
		(mid 283.806956 -164.309781)
		(end 283.994352 -164.184584)
		(width 0.1397)
		(layer "In9.Cu")
		(net "PCIE_COMP_B_TO_SCC_B_7_DP")
	)
	(arc
		(start 221.55404 -405.505158)
		(mid 221.553125 -405.489691)
		(end 221.550484 -405.474424)
		(width 0.1397)
		(layer "In9.Cu")
		(net "PCIE_COMP_B_TO_SCC_B_7_DP")
	)
	(arc
		(start 222.213932 -417.646104)
		(mid 221.747318 -417.452826)
		(end 221.55404 -416.986212)
		(width 0.1397)
		(layer "In9.Cu")
		(net "PCIE_COMP_B_TO_SCC_B_7_DP")
	)
	(arc
		(start 284.056836 -164.059616)
		(mid 284.064417 -163.952949)
		(end 283.994352 -163.872164)
		(width 0.1397)
		(layer "In9.Cu")
		(net "PCIE_COMP_B_TO_SCC_B_7_DP")
	)
	(arc
		(start 217.369136 -386.991606)
		(mid 217.365664 -386.962312)
		(end 217.368374 -386.932932)
		(width 0.1397)
		(layer "In9.Cu")
		(net "PCIE_COMP_B_TO_SCC_B_7_DP")
	)
	(arc
		(start 222.600012 -417.825682)
		(mid 222.590379 -417.777164)
		(end 222.562928 -417.73602)
		(width 0.1397)
		(layer "In9.Cu")
		(net "PCIE_COMP_B_TO_SCC_B_7_DP")
	)
	(arc
		(start 222.510096 -417.683188)
		(mid 222.468945 -417.655755)
		(end 222.420434 -417.646104)
		(width 0.1397)
		(layer "In9.Cu")
		(net "PCIE_COMP_B_TO_SCC_B_7_DP")
	)
	(segment
		(start 277.385526 -164.381688)
		(end 277.71217 -164.119052)
		(width 0.1397)
		(layer "In9.Cu")
		(net "PCIE_COMP_B_TO_SCC_B_7_DN")
	)
	(segment
		(start 221.84614 -416.986212)
		(end 221.84614 -405.456898)
		(width 0.1397)
		(layer "In9.Cu")
		(net "PCIE_COMP_B_TO_SCC_B_7_DN")
	)
	(segment
		(start 274.164806 -166.971218)
		(end 274.18792 -166.760652)
		(width 0.1397)
		(layer "In9.Cu")
		(net "PCIE_COMP_B_TO_SCC_B_7_DN")
	)
	(segment
		(start 277.71217 -164.119052)
		(end 277.73503 -163.908486)
		(width 0.1397)
		(layer "In9.Cu")
		(net "PCIE_COMP_B_TO_SCC_B_7_DN")
	)
	(segment
		(start 284.505654 -164.127688)
		(end 285.249874 -164.499798)
		(width 0.1397)
		(layer "In9.Cu")
		(net "PCIE_COMP_B_TO_SCC_B_7_DN")
	)
	(segment
		(start 275.051774 -166.25824)
		(end 275.074634 -166.047674)
		(width 0.1397)
		(layer "In9.Cu")
		(net "PCIE_COMP_B_TO_SCC_B_7_DN")
	)
	(segment
		(start 277.17496 -164.358828)
		(end 277.385526 -164.381688)
		(width 0.1397)
		(layer "In9.Cu")
		(net "PCIE_COMP_B_TO_SCC_B_7_DN")
	)
	(segment
		(start 278.061674 -163.64585)
		(end 279.275032 -163.64585)
		(width 0.1397)
		(layer "In9.Cu")
		(net "PCIE_COMP_B_TO_SCC_B_7_DN")
	)
	(segment
		(start 222.420942 -417.354004)
		(end 222.213932 -417.354004)
		(width 0.1397)
		(layer "In9.Cu")
		(net "PCIE_COMP_B_TO_SCC_B_7_DN")
	)
	(segment
		(start 217.66149 -386.959094)
		(end 217.661236 -386.958586)
		(width 0.1397)
		(layer "In9.Cu")
		(net "PCIE_COMP_B_TO_SCC_B_7_DN")
	)
	(segment
		(start 275.401278 -165.785038)
		(end 275.611844 -165.807898)
		(width 0.1397)
		(layer "In9.Cu")
		(net "PCIE_COMP_B_TO_SCC_B_7_DN")
	)
	(segment
		(start 273.2913 -167.481504)
		(end 273.627596 -167.210994)
		(width 0.1397)
		(layer "In9.Cu")
		(net "PCIE_COMP_B_TO_SCC_B_7_DN")
	)
	(segment
		(start 222.562928 -417.264596)
		(end 222.510604 -417.31692)
		(width 0.1397)
		(layer "In9.Cu")
		(net "PCIE_COMP_B_TO_SCC_B_7_DN")
	)
	(segment
		(start 276.848316 -164.621464)
		(end 277.17496 -164.358828)
		(width 0.1397)
		(layer "In9.Cu")
		(net "PCIE_COMP_B_TO_SCC_B_7_DN")
	)
	(segment
		(start 275.938488 -165.545262)
		(end 275.961348 -165.334442)
		(width 0.1397)
		(layer "In9.Cu")
		(net "PCIE_COMP_B_TO_SCC_B_7_DN")
	)
	(segment
		(start 275.961348 -165.334442)
		(end 276.287992 -165.071806)
		(width 0.1397)
		(layer "In9.Cu")
		(net "PCIE_COMP_B_TO_SCC_B_7_DN")
	)
	(segment
		(start 276.825456 -164.832284)
		(end 276.848316 -164.621464)
		(width 0.1397)
		(layer "In9.Cu")
		(net "PCIE_COMP_B_TO_SCC_B_7_DN")
	)
	(segment
		(start 275.611844 -165.807898)
		(end 275.938488 -165.545262)
		(width 0.1397)
		(layer "In9.Cu")
		(net "PCIE_COMP_B_TO_SCC_B_7_DN")
	)
	(segment
		(start 221.84614 -405.456898)
		(end 217.66149 -386.959094)
		(width 0.1397)
		(layer "In9.Cu")
		(net "PCIE_COMP_B_TO_SCC_B_7_DN")
	)
	(segment
		(start 217.661236 -386.958586)
		(end 221.004638 -370.461032)
		(width 0.1397)
		(layer "In9.Cu")
		(net "PCIE_COMP_B_TO_SCC_B_7_DN")
	)
	(segment
		(start 274.72513 -166.520876)
		(end 275.051774 -166.25824)
		(width 0.1397)
		(layer "In9.Cu")
		(net "PCIE_COMP_B_TO_SCC_B_7_DN")
	)
	(segment
		(start 275.074634 -166.047674)
		(end 275.401278 -165.785038)
		(width 0.1397)
		(layer "In9.Cu")
		(net "PCIE_COMP_B_TO_SCC_B_7_DN")
	)
	(segment
		(start 284.236668 -164.35324)
		(end 284.318202 -164.190172)
		(width 0.1397)
		(layer "In9.Cu")
		(net "PCIE_COMP_B_TO_SCC_B_7_DN")
	)
	(segment
		(start 273.627596 -167.210994)
		(end 273.838416 -167.233854)
		(width 0.1397)
		(layer "In9.Cu")
		(net "PCIE_COMP_B_TO_SCC_B_7_DN")
	)
	(segment
		(start 274.51431 -166.498016)
		(end 274.72513 -166.520876)
		(width 0.1397)
		(layer "In9.Cu")
		(net "PCIE_COMP_B_TO_SCC_B_7_DN")
	)
	(segment
		(start 214.769446 -342.909652)
		(end 263.351518 -182.78475)
		(width 0.1397)
		(layer "In9.Cu")
		(net "PCIE_COMP_B_TO_SCC_B_7_DN")
	)
	(segment
		(start 273.290792 -167.48125)
		(end 273.2913 -167.481504)
		(width 0.1397)
		(layer "In9.Cu")
		(net "PCIE_COMP_B_TO_SCC_B_7_DN")
	)
	(segment
		(start 221.004638 -370.461032)
		(end 214.769446 -342.909652)
		(width 0.1397)
		(layer "In9.Cu")
		(net "PCIE_COMP_B_TO_SCC_B_7_DN")
	)
	(segment
		(start 276.498812 -165.09492)
		(end 276.825456 -164.832284)
		(width 0.1397)
		(layer "In9.Cu")
		(net "PCIE_COMP_B_TO_SCC_B_7_DN")
	)
	(segment
		(start 273.838416 -167.233854)
		(end 274.164806 -166.971218)
		(width 0.1397)
		(layer "In9.Cu")
		(net "PCIE_COMP_B_TO_SCC_B_7_DN")
	)
	(segment
		(start 276.287992 -165.071806)
		(end 276.498812 -165.09492)
		(width 0.1397)
		(layer "In9.Cu")
		(net "PCIE_COMP_B_TO_SCC_B_7_DN")
	)
	(segment
		(start 222.600012 -416.80003)
		(end 222.600012 -417.174934)
		(width 0.1397)
		(layer "In9.Cu")
		(net "PCIE_COMP_B_TO_SCC_B_7_DN")
	)
	(segment
		(start 280.27503 -164.645848)
		(end 283.585666 -164.645848)
		(width 0.1397)
		(layer "In9.Cu")
		(net "PCIE_COMP_B_TO_SCC_B_7_DN")
	)
	(segment
		(start 263.351518 -182.78475)
		(end 273.290792 -167.48125)
		(width 0.1397)
		(layer "In9.Cu")
		(net "PCIE_COMP_B_TO_SCC_B_7_DN")
	)
	(segment
		(start 277.73503 -163.908486)
		(end 278.061674 -163.64585)
		(width 0.1397)
		(layer "In9.Cu")
		(net "PCIE_COMP_B_TO_SCC_B_7_DN")
	)
	(segment
		(start 279.275032 -163.64585)
		(end 280.27503 -164.645848)
		(width 0.1397)
		(layer "In9.Cu")
		(net "PCIE_COMP_B_TO_SCC_B_7_DN")
	)
	(segment
		(start 274.18792 -166.760652)
		(end 274.51431 -166.498016)
		(width 0.1397)
		(layer "In9.Cu")
		(net "PCIE_COMP_B_TO_SCC_B_7_DN")
	)
	(arc
		(start 284.318202 -164.190172)
		(mid 284.398987 -164.120107)
		(end 284.505654 -164.127688)
		(width 0.1397)
		(layer "In9.Cu")
		(net "PCIE_COMP_B_TO_SCC_B_7_DN")
	)
	(arc
		(start 283.585666 -164.645848)
		(mid 283.942542 -164.569368)
		(end 284.236668 -164.35324)
		(width 0.1397)
		(layer "In9.Cu")
		(net "PCIE_COMP_B_TO_SCC_B_7_DN")
	)
	(arc
		(start 222.213932 -417.354004)
		(mid 221.953864 -417.24628)
		(end 221.84614 -416.986212)
		(width 0.1397)
		(layer "In9.Cu")
		(net "PCIE_COMP_B_TO_SCC_B_7_DN")
	)
	(arc
		(start 222.600012 -417.174934)
		(mid 222.590379 -417.223452)
		(end 222.562928 -417.264596)
		(width 0.1397)
		(layer "In9.Cu")
		(net "PCIE_COMP_B_TO_SCC_B_7_DN")
	)
	(arc
		(start 222.510604 -417.31692)
		(mid 222.469453 -417.344353)
		(end 222.420942 -417.354004)
		(width 0.1397)
		(layer "In9.Cu")
		(net "PCIE_COMP_B_TO_SCC_B_7_DN")
	)
	(segment
		(start 279.248616 -159.353758)
		(end 280.248614 -160.353756)
		(width 0.1397)
		(layer "In9.Cu")
		(net "PCIE_COMP_B_TO_SCC_B_6_DP")
	)
	(segment
		(start 219.754196 -414.478978)
		(end 219.754196 -405.36622)
		(width 0.1397)
		(layer "In9.Cu")
		(net "PCIE_COMP_B_TO_SCC_B_6_DP")
	)
	(segment
		(start 283.994352 -159.872172)
		(end 283.249878 -159.499808)
		(width 0.1397)
		(layer "In9.Cu")
		(net "PCIE_COMP_B_TO_SCC_B_6_DP")
	)
	(segment
		(start 219.17914 -370.43106)
		(end 212.846158 -342.42375)
		(width 0.1397)
		(layer "In9.Cu")
		(net "PCIE_COMP_B_TO_SCC_B_6_DP")
	)
	(segment
		(start 280.248614 -160.353756)
		(end 283.58592 -160.353756)
		(width 0.1397)
		(layer "In9.Cu")
		(net "PCIE_COMP_B_TO_SCC_B_6_DP")
	)
	(segment
		(start 272.937732 -163.511738)
		(end 272.936208 -163.50996)
		(width 0.1397)
		(layer "In9.Cu")
		(net "PCIE_COMP_B_TO_SCC_B_6_DP")
	)
	(segment
		(start 219.75064 -405.335486)
		(end 215.563704 -386.830316)
		(width 0.1397)
		(layer "In9.Cu")
		(net "PCIE_COMP_B_TO_SCC_B_6_DP")
	)
	(segment
		(start 220.800168 -415.600134)
		(end 220.800168 -415.257996)
		(width 0.1397)
		(layer "In9.Cu")
		(net "PCIE_COMP_B_TO_SCC_B_6_DP")
	)
	(segment
		(start 212.846158 -342.42375)
		(end 262.033766 -180.302662)
		(width 0.1397)
		(layer "In9.Cu")
		(net "PCIE_COMP_B_TO_SCC_B_6_DP")
	)
	(segment
		(start 215.563704 -386.769356)
		(end 219.17914 -370.43106)
		(width 0.1397)
		(layer "In9.Cu")
		(net "PCIE_COMP_B_TO_SCC_B_6_DP")
	)
	(segment
		(start 283.994352 -160.184592)
		(end 284.056836 -160.059624)
		(width 0.1397)
		(layer "In9.Cu")
		(net "PCIE_COMP_B_TO_SCC_B_6_DP")
	)
	(segment
		(start 278.10587 -159.353758)
		(end 279.248616 -159.353758)
		(width 0.1397)
		(layer "In9.Cu")
		(net "PCIE_COMP_B_TO_SCC_B_6_DP")
	)
	(segment
		(start 262.033766 -180.302662)
		(end 272.937732 -163.511738)
		(width 0.1397)
		(layer "In9.Cu")
		(net "PCIE_COMP_B_TO_SCC_B_6_DP")
	)
	(segment
		(start 220.588332 -415.04616)
		(end 220.321378 -415.04616)
		(width 0.1397)
		(layer "In9.Cu")
		(net "PCIE_COMP_B_TO_SCC_B_6_DP")
	)
	(segment
		(start 272.936208 -163.50996)
		(end 278.10587 -159.353758)
		(width 0.1397)
		(layer "In9.Cu")
		(net "PCIE_COMP_B_TO_SCC_B_6_DP")
	)
	(arc
		(start 215.563704 -386.830316)
		(mid 215.56034 -386.799836)
		(end 215.563704 -386.769356)
		(width 0.1397)
		(layer "In9.Cu")
		(net "PCIE_COMP_B_TO_SCC_B_6_DP")
	)
	(arc
		(start 283.58592 -160.353756)
		(mid 283.806956 -160.309789)
		(end 283.994352 -160.184592)
		(width 0.1397)
		(layer "In9.Cu")
		(net "PCIE_COMP_B_TO_SCC_B_6_DP")
	)
	(arc
		(start 220.321378 -415.04616)
		(mid 219.92032 -414.880036)
		(end 219.754196 -414.478978)
		(width 0.1397)
		(layer "In9.Cu")
		(net "PCIE_COMP_B_TO_SCC_B_6_DP")
	)
	(arc
		(start 284.056836 -160.059624)
		(mid 284.064417 -159.952957)
		(end 283.994352 -159.872172)
		(width 0.1397)
		(layer "In9.Cu")
		(net "PCIE_COMP_B_TO_SCC_B_6_DP")
	)
	(arc
		(start 220.800168 -415.257996)
		(mid 220.738123 -415.108205)
		(end 220.588332 -415.04616)
		(width 0.1397)
		(layer "In9.Cu")
		(net "PCIE_COMP_B_TO_SCC_B_6_DP")
	)
	(arc
		(start 219.754196 -405.36622)
		(mid 219.753281 -405.350753)
		(end 219.75064 -405.335486)
		(width 0.1397)
		(layer "In9.Cu")
		(net "PCIE_COMP_B_TO_SCC_B_6_DP")
	)
	(segment
		(start 219.478606 -370.430298)
		(end 213.148164 -342.434672)
		(width 0.1397)
		(layer "In9.Cu")
		(net "PCIE_COMP_B_TO_SCC_B_6_DN")
	)
	(segment
		(start 273.156172 -163.708334)
		(end 273.774662 -163.211002)
		(width 0.1397)
		(layer "In9.Cu")
		(net "PCIE_COMP_B_TO_SCC_B_6_DN")
	)
	(segment
		(start 274.334986 -162.76066)
		(end 274.661376 -162.498024)
		(width 0.1397)
		(layer "In9.Cu")
		(net "PCIE_COMP_B_TO_SCC_B_6_DN")
	)
	(segment
		(start 276.108414 -161.33445)
		(end 276.435058 -161.071814)
		(width 0.1397)
		(layer "In9.Cu")
		(net "PCIE_COMP_B_TO_SCC_B_6_DN")
	)
	(segment
		(start 278.20874 -159.645858)
		(end 279.127458 -159.645858)
		(width 0.1397)
		(layer "In9.Cu")
		(net "PCIE_COMP_B_TO_SCC_B_6_DN")
	)
	(segment
		(start 215.856312 -386.799074)
		(end 219.478606 -370.430298)
		(width 0.1397)
		(layer "In9.Cu")
		(net "PCIE_COMP_B_TO_SCC_B_6_DN")
	)
	(segment
		(start 284.505654 -160.127696)
		(end 285.249874 -160.499806)
		(width 0.1397)
		(layer "In9.Cu")
		(net "PCIE_COMP_B_TO_SCC_B_6_DN")
	)
	(segment
		(start 277.532592 -160.381696)
		(end 277.859236 -160.11906)
		(width 0.1397)
		(layer "In9.Cu")
		(net "PCIE_COMP_B_TO_SCC_B_6_DN")
	)
	(segment
		(start 275.75891 -161.807906)
		(end 276.085554 -161.54527)
		(width 0.1397)
		(layer "In9.Cu")
		(net "PCIE_COMP_B_TO_SCC_B_6_DN")
	)
	(segment
		(start 213.148164 -342.434672)
		(end 262.301482 -180.427122)
		(width 0.1397)
		(layer "In9.Cu")
		(net "PCIE_COMP_B_TO_SCC_B_6_DN")
	)
	(segment
		(start 262.301482 -180.427122)
		(end 273.157442 -163.710112)
		(width 0.1397)
		(layer "In9.Cu")
		(net "PCIE_COMP_B_TO_SCC_B_6_DN")
	)
	(segment
		(start 276.995382 -160.621472)
		(end 277.322026 -160.358836)
		(width 0.1397)
		(layer "In9.Cu")
		(net "PCIE_COMP_B_TO_SCC_B_6_DN")
	)
	(segment
		(start 275.19884 -162.258248)
		(end 275.2217 -162.047682)
		(width 0.1397)
		(layer "In9.Cu")
		(net "PCIE_COMP_B_TO_SCC_B_6_DN")
	)
	(segment
		(start 275.2217 -162.047682)
		(end 275.548344 -161.785046)
		(width 0.1397)
		(layer "In9.Cu")
		(net "PCIE_COMP_B_TO_SCC_B_6_DN")
	)
	(segment
		(start 220.588332 -414.75406)
		(end 220.321378 -414.75406)
		(width 0.1397)
		(layer "In9.Cu")
		(net "PCIE_COMP_B_TO_SCC_B_6_DN")
	)
	(segment
		(start 274.872196 -162.520884)
		(end 275.19884 -162.258248)
		(width 0.1397)
		(layer "In9.Cu")
		(net "PCIE_COMP_B_TO_SCC_B_6_DN")
	)
	(segment
		(start 276.435058 -161.071814)
		(end 276.645878 -161.094928)
		(width 0.1397)
		(layer "In9.Cu")
		(net "PCIE_COMP_B_TO_SCC_B_6_DN")
	)
	(segment
		(start 220.046296 -405.31796)
		(end 215.856312 -386.799074)
		(width 0.1397)
		(layer "In9.Cu")
		(net "PCIE_COMP_B_TO_SCC_B_6_DN")
	)
	(segment
		(start 274.311872 -162.971226)
		(end 274.334986 -162.76066)
		(width 0.1397)
		(layer "In9.Cu")
		(net "PCIE_COMP_B_TO_SCC_B_6_DN")
	)
	(segment
		(start 276.085554 -161.54527)
		(end 276.108414 -161.33445)
		(width 0.1397)
		(layer "In9.Cu")
		(net "PCIE_COMP_B_TO_SCC_B_6_DN")
	)
	(segment
		(start 277.882096 -159.908494)
		(end 278.20874 -159.645858)
		(width 0.1397)
		(layer "In9.Cu")
		(net "PCIE_COMP_B_TO_SCC_B_6_DN")
	)
	(segment
		(start 220.800168 -414.200086)
		(end 220.800168 -414.542224)
		(width 0.1397)
		(layer "In9.Cu")
		(net "PCIE_COMP_B_TO_SCC_B_6_DN")
	)
	(segment
		(start 220.046296 -414.478978)
		(end 220.046296 -405.31796)
		(width 0.1397)
		(layer "In9.Cu")
		(net "PCIE_COMP_B_TO_SCC_B_6_DN")
	)
	(segment
		(start 273.985482 -163.233862)
		(end 274.311872 -162.971226)
		(width 0.1397)
		(layer "In9.Cu")
		(net "PCIE_COMP_B_TO_SCC_B_6_DN")
	)
	(segment
		(start 273.774662 -163.211002)
		(end 273.985482 -163.233862)
		(width 0.1397)
		(layer "In9.Cu")
		(net "PCIE_COMP_B_TO_SCC_B_6_DN")
	)
	(segment
		(start 274.661376 -162.498024)
		(end 274.872196 -162.520884)
		(width 0.1397)
		(layer "In9.Cu")
		(net "PCIE_COMP_B_TO_SCC_B_6_DN")
	)
	(segment
		(start 284.236668 -160.353248)
		(end 284.318202 -160.19018)
		(width 0.1397)
		(layer "In9.Cu")
		(net "PCIE_COMP_B_TO_SCC_B_6_DN")
	)
	(segment
		(start 273.157442 -163.710112)
		(end 273.156172 -163.708334)
		(width 0.1397)
		(layer "In9.Cu")
		(net "PCIE_COMP_B_TO_SCC_B_6_DN")
	)
	(segment
		(start 277.859236 -160.11906)
		(end 277.882096 -159.908494)
		(width 0.1397)
		(layer "In9.Cu")
		(net "PCIE_COMP_B_TO_SCC_B_6_DN")
	)
	(segment
		(start 280.127456 -160.645856)
		(end 283.585666 -160.645856)
		(width 0.1397)
		(layer "In9.Cu")
		(net "PCIE_COMP_B_TO_SCC_B_6_DN")
	)
	(segment
		(start 279.127458 -159.645858)
		(end 280.127456 -160.645856)
		(width 0.1397)
		(layer "In9.Cu")
		(net "PCIE_COMP_B_TO_SCC_B_6_DN")
	)
	(segment
		(start 276.645878 -161.094928)
		(end 276.972522 -160.832292)
		(width 0.1397)
		(layer "In9.Cu")
		(net "PCIE_COMP_B_TO_SCC_B_6_DN")
	)
	(segment
		(start 275.548344 -161.785046)
		(end 275.75891 -161.807906)
		(width 0.1397)
		(layer "In9.Cu")
		(net "PCIE_COMP_B_TO_SCC_B_6_DN")
	)
	(segment
		(start 277.322026 -160.358836)
		(end 277.532592 -160.381696)
		(width 0.1397)
		(layer "In9.Cu")
		(net "PCIE_COMP_B_TO_SCC_B_6_DN")
	)
	(segment
		(start 276.972522 -160.832292)
		(end 276.995382 -160.621472)
		(width 0.1397)
		(layer "In9.Cu")
		(net "PCIE_COMP_B_TO_SCC_B_6_DN")
	)
	(arc
		(start 283.585666 -160.645856)
		(mid 283.942542 -160.569376)
		(end 284.236668 -160.353248)
		(width 0.1397)
		(layer "In9.Cu")
		(net "PCIE_COMP_B_TO_SCC_B_6_DN")
	)
	(arc
		(start 284.318202 -160.19018)
		(mid 284.398987 -160.120115)
		(end 284.505654 -160.127696)
		(width 0.1397)
		(layer "In9.Cu")
		(net "PCIE_COMP_B_TO_SCC_B_6_DN")
	)
	(arc
		(start 220.800168 -414.542224)
		(mid 220.738123 -414.692015)
		(end 220.588332 -414.75406)
		(width 0.1397)
		(layer "In9.Cu")
		(net "PCIE_COMP_B_TO_SCC_B_6_DN")
	)
	(arc
		(start 220.321378 -414.75406)
		(mid 220.126866 -414.67349)
		(end 220.046296 -414.478978)
		(width 0.1397)
		(layer "In9.Cu")
		(net "PCIE_COMP_B_TO_SCC_B_6_DN")
	)
	(segment
		(start 219.00007 -418.200078)
		(end 219.00007 -417.825682)
		(width 0.1397)
		(layer "In9.Cu")
		(net "PCIE_COMP_B_TO_SCC_B_5_DP")
	)
	(segment
		(start 280.38679 -156.353764)
		(end 283.58592 -156.353764)
		(width 0.1397)
		(layer "In9.Cu")
		(net "PCIE_COMP_B_TO_SCC_B_5_DP")
	)
	(segment
		(start 283.994352 -155.87218)
		(end 283.249878 -155.499816)
		(width 0.1397)
		(layer "In9.Cu")
		(net "PCIE_COMP_B_TO_SCC_B_5_DP")
	)
	(segment
		(start 213.73338 -387.642862)
		(end 217.49385 -369.168426)
		(width 0.1397)
		(layer "In9.Cu")
		(net "PCIE_COMP_B_TO_SCC_B_5_DP")
	)
	(segment
		(start 279.386792 -155.353766)
		(end 280.38679 -156.353764)
		(width 0.1397)
		(layer "In9.Cu")
		(net "PCIE_COMP_B_TO_SCC_B_5_DP")
	)
	(segment
		(start 211.290154 -341.734902)
		(end 260.719062 -178.818794)
		(width 0.1397)
		(layer "In9.Cu")
		(net "PCIE_COMP_B_TO_SCC_B_5_DP")
	)
	(segment
		(start 218.962986 -417.73602)
		(end 218.910154 -417.683188)
		(width 0.1397)
		(layer "In9.Cu")
		(net "PCIE_COMP_B_TO_SCC_B_5_DP")
	)
	(segment
		(start 217.950542 -406.335992)
		(end 213.733888 -387.701536)
		(width 0.1397)
		(layer "In9.Cu")
		(net "PCIE_COMP_B_TO_SCC_B_5_DP")
	)
	(segment
		(start 218.820492 -417.646104)
		(end 218.639136 -417.646104)
		(width 0.1397)
		(layer "In9.Cu")
		(net "PCIE_COMP_B_TO_SCC_B_5_DP")
	)
	(segment
		(start 273.82216 -158.641542)
		(end 277.908512 -155.353766)
		(width 0.1397)
		(layer "In9.Cu")
		(net "PCIE_COMP_B_TO_SCC_B_5_DP")
	)
	(segment
		(start 283.994352 -156.1846)
		(end 284.056836 -156.059632)
		(width 0.1397)
		(layer "In9.Cu")
		(net "PCIE_COMP_B_TO_SCC_B_5_DP")
	)
	(segment
		(start 217.954098 -416.961066)
		(end 217.954098 -406.366726)
		(width 0.1397)
		(layer "In9.Cu")
		(net "PCIE_COMP_B_TO_SCC_B_5_DP")
	)
	(segment
		(start 277.908512 -155.353766)
		(end 279.386792 -155.353766)
		(width 0.1397)
		(layer "In9.Cu")
		(net "PCIE_COMP_B_TO_SCC_B_5_DP")
	)
	(segment
		(start 260.719062 -178.818794)
		(end 273.82216 -158.641542)
		(width 0.1397)
		(layer "In9.Cu")
		(net "PCIE_COMP_B_TO_SCC_B_5_DP")
	)
	(segment
		(start 217.49385 -369.168426)
		(end 211.290154 -341.734902)
		(width 0.1397)
		(layer "In9.Cu")
		(net "PCIE_COMP_B_TO_SCC_B_5_DP")
	)
	(arc
		(start 218.639136 -417.646104)
		(mid 218.154741 -417.445461)
		(end 217.954098 -416.961066)
		(width 0.1397)
		(layer "In9.Cu")
		(net "PCIE_COMP_B_TO_SCC_B_5_DP")
	)
	(arc
		(start 219.00007 -417.825682)
		(mid 218.990437 -417.777164)
		(end 218.962986 -417.73602)
		(width 0.1397)
		(layer "In9.Cu")
		(net "PCIE_COMP_B_TO_SCC_B_5_DP")
	)
	(arc
		(start 217.954098 -406.366726)
		(mid 217.953183 -406.351259)
		(end 217.950542 -406.335992)
		(width 0.1397)
		(layer "In9.Cu")
		(net "PCIE_COMP_B_TO_SCC_B_5_DP")
	)
	(arc
		(start 218.910154 -417.683188)
		(mid 218.869003 -417.655755)
		(end 218.820492 -417.646104)
		(width 0.1397)
		(layer "In9.Cu")
		(net "PCIE_COMP_B_TO_SCC_B_5_DP")
	)
	(arc
		(start 284.056836 -156.059632)
		(mid 284.064417 -155.952965)
		(end 283.994352 -155.87218)
		(width 0.1397)
		(layer "In9.Cu")
		(net "PCIE_COMP_B_TO_SCC_B_5_DP")
	)
	(arc
		(start 213.733888 -387.701536)
		(mid 213.730529 -387.672227)
		(end 213.73338 -387.642862)
		(width 0.1397)
		(layer "In9.Cu")
		(net "PCIE_COMP_B_TO_SCC_B_5_DP")
	)
	(arc
		(start 283.58592 -156.353764)
		(mid 283.806956 -156.309797)
		(end 283.994352 -156.1846)
		(width 0.1397)
		(layer "In9.Cu")
		(net "PCIE_COMP_B_TO_SCC_B_5_DP")
	)
	(segment
		(start 218.246198 -416.961066)
		(end 218.246198 -406.318466)
		(width 0.1397)
		(layer "In9.Cu")
		(net "PCIE_COMP_B_TO_SCC_B_5_DN")
	)
	(segment
		(start 218.246198 -406.318466)
		(end 214.026242 -387.669024)
		(width 0.1397)
		(layer "In9.Cu")
		(net "PCIE_COMP_B_TO_SCC_B_5_DN")
	)
	(segment
		(start 270.94307 -163.61156)
		(end 271.150334 -163.567618)
		(width 0.1397)
		(layer "In9.Cu")
		(net "PCIE_COMP_B_TO_SCC_B_5_DN")
	)
	(segment
		(start 273.813524 -159.191452)
		(end 274.04187 -158.839916)
		(width 0.1397)
		(layer "In9.Cu")
		(net "PCIE_COMP_B_TO_SCC_B_5_DN")
	)
	(segment
		(start 284.505654 -156.127704)
		(end 285.249874 -156.499814)
		(width 0.1397)
		(layer "In9.Cu")
		(net "PCIE_COMP_B_TO_SCC_B_5_DN")
	)
	(segment
		(start 284.236668 -156.353256)
		(end 284.318202 -156.190188)
		(width 0.1397)
		(layer "In9.Cu")
		(net "PCIE_COMP_B_TO_SCC_B_5_DN")
	)
	(segment
		(start 273.42211 -159.794194)
		(end 273.629374 -159.750252)
		(width 0.1397)
		(layer "In9.Cu")
		(net "PCIE_COMP_B_TO_SCC_B_5_DN")
	)
	(segment
		(start 271.150334 -163.567618)
		(end 271.37868 -163.216082)
		(width 0.1397)
		(layer "In9.Cu")
		(net "PCIE_COMP_B_TO_SCC_B_5_DN")
	)
	(segment
		(start 218.821 -417.354004)
		(end 218.639136 -417.354004)
		(width 0.1397)
		(layer "In9.Cu")
		(net "PCIE_COMP_B_TO_SCC_B_5_DN")
	)
	(segment
		(start 271.37868 -163.216082)
		(end 271.334484 -163.008818)
		(width 0.1397)
		(layer "In9.Cu")
		(net "PCIE_COMP_B_TO_SCC_B_5_DN")
	)
	(segment
		(start 272.80235 -160.748472)
		(end 273.009614 -160.70453)
		(width 0.1397)
		(layer "In9.Cu")
		(net "PCIE_COMP_B_TO_SCC_B_5_DN")
	)
	(segment
		(start 271.56283 -162.657282)
		(end 271.770094 -162.613086)
		(width 0.1397)
		(layer "In9.Cu")
		(net "PCIE_COMP_B_TO_SCC_B_5_DN")
	)
	(segment
		(start 271.954244 -162.05454)
		(end 272.18259 -161.703004)
		(width 0.1397)
		(layer "In9.Cu")
		(net "PCIE_COMP_B_TO_SCC_B_5_DN")
	)
	(segment
		(start 273.629374 -159.750252)
		(end 273.85772 -159.398716)
		(width 0.1397)
		(layer "In9.Cu")
		(net "PCIE_COMP_B_TO_SCC_B_5_DN")
	)
	(segment
		(start 219.00007 -416.80003)
		(end 219.00007 -417.174934)
		(width 0.1397)
		(layer "In9.Cu")
		(net "PCIE_COMP_B_TO_SCC_B_5_DN")
	)
	(segment
		(start 260.986778 -178.943254)
		(end 270.94307 -163.61156)
		(width 0.1397)
		(layer "In9.Cu")
		(net "PCIE_COMP_B_TO_SCC_B_5_DN")
	)
	(segment
		(start 211.59216 -341.745824)
		(end 260.986778 -178.943254)
		(width 0.1397)
		(layer "In9.Cu")
		(net "PCIE_COMP_B_TO_SCC_B_5_DN")
	)
	(segment
		(start 218.962986 -417.264596)
		(end 218.910662 -417.31692)
		(width 0.1397)
		(layer "In9.Cu")
		(net "PCIE_COMP_B_TO_SCC_B_5_DN")
	)
	(segment
		(start 273.009614 -160.70453)
		(end 273.23796 -160.352994)
		(width 0.1397)
		(layer "In9.Cu")
		(net "PCIE_COMP_B_TO_SCC_B_5_DN")
	)
	(segment
		(start 214.026242 -387.669024)
		(end 217.792808 -369.165124)
		(width 0.1397)
		(layer "In9.Cu")
		(net "PCIE_COMP_B_TO_SCC_B_5_DN")
	)
	(segment
		(start 272.389854 -161.658808)
		(end 272.6182 -161.307272)
		(width 0.1397)
		(layer "In9.Cu")
		(net "PCIE_COMP_B_TO_SCC_B_5_DN")
	)
	(segment
		(start 272.6182 -161.307272)
		(end 272.574004 -161.100008)
		(width 0.1397)
		(layer "In9.Cu")
		(net "PCIE_COMP_B_TO_SCC_B_5_DN")
	)
	(segment
		(start 273.23796 -160.352994)
		(end 273.193764 -160.14573)
		(width 0.1397)
		(layer "In9.Cu")
		(net "PCIE_COMP_B_TO_SCC_B_5_DN")
	)
	(segment
		(start 271.334484 -163.008818)
		(end 271.56283 -162.657282)
		(width 0.1397)
		(layer "In9.Cu")
		(net "PCIE_COMP_B_TO_SCC_B_5_DN")
	)
	(segment
		(start 273.85772 -159.398716)
		(end 273.813524 -159.191452)
		(width 0.1397)
		(layer "In9.Cu")
		(net "PCIE_COMP_B_TO_SCC_B_5_DN")
	)
	(segment
		(start 278.011636 -155.645866)
		(end 279.265634 -155.645866)
		(width 0.1397)
		(layer "In9.Cu")
		(net "PCIE_COMP_B_TO_SCC_B_5_DN")
	)
	(segment
		(start 272.574004 -161.100008)
		(end 272.80235 -160.748472)
		(width 0.1397)
		(layer "In9.Cu")
		(net "PCIE_COMP_B_TO_SCC_B_5_DN")
	)
	(segment
		(start 280.265632 -156.645864)
		(end 283.585666 -156.645864)
		(width 0.1397)
		(layer "In9.Cu")
		(net "PCIE_COMP_B_TO_SCC_B_5_DN")
	)
	(segment
		(start 272.18259 -161.703004)
		(end 272.389854 -161.658808)
		(width 0.1397)
		(layer "In9.Cu")
		(net "PCIE_COMP_B_TO_SCC_B_5_DN")
	)
	(segment
		(start 279.265634 -155.645866)
		(end 280.265632 -156.645864)
		(width 0.1397)
		(layer "In9.Cu")
		(net "PCIE_COMP_B_TO_SCC_B_5_DN")
	)
	(segment
		(start 274.04187 -158.839916)
		(end 278.011636 -155.645866)
		(width 0.1397)
		(layer "In9.Cu")
		(net "PCIE_COMP_B_TO_SCC_B_5_DN")
	)
	(segment
		(start 273.193764 -160.14573)
		(end 273.42211 -159.794194)
		(width 0.1397)
		(layer "In9.Cu")
		(net "PCIE_COMP_B_TO_SCC_B_5_DN")
	)
	(segment
		(start 217.792808 -369.165124)
		(end 211.59216 -341.745824)
		(width 0.1397)
		(layer "In9.Cu")
		(net "PCIE_COMP_B_TO_SCC_B_5_DN")
	)
	(segment
		(start 271.99844 -162.261804)
		(end 271.954244 -162.05454)
		(width 0.1397)
		(layer "In9.Cu")
		(net "PCIE_COMP_B_TO_SCC_B_5_DN")
	)
	(segment
		(start 271.770094 -162.613086)
		(end 271.99844 -162.261804)
		(width 0.1397)
		(layer "In9.Cu")
		(net "PCIE_COMP_B_TO_SCC_B_5_DN")
	)
	(arc
		(start 218.910662 -417.31692)
		(mid 218.869511 -417.344353)
		(end 218.821 -417.354004)
		(width 0.1397)
		(layer "In9.Cu")
		(net "PCIE_COMP_B_TO_SCC_B_5_DN")
	)
	(arc
		(start 219.00007 -417.174934)
		(mid 218.990437 -417.223452)
		(end 218.962986 -417.264596)
		(width 0.1397)
		(layer "In9.Cu")
		(net "PCIE_COMP_B_TO_SCC_B_5_DN")
	)
	(arc
		(start 218.639136 -417.354004)
		(mid 218.361287 -417.238915)
		(end 218.246198 -416.961066)
		(width 0.1397)
		(layer "In9.Cu")
		(net "PCIE_COMP_B_TO_SCC_B_5_DN")
	)
	(arc
		(start 284.318202 -156.190188)
		(mid 284.398987 -156.120123)
		(end 284.505654 -156.127704)
		(width 0.1397)
		(layer "In9.Cu")
		(net "PCIE_COMP_B_TO_SCC_B_5_DN")
	)
	(arc
		(start 283.585666 -156.645864)
		(mid 283.942542 -156.569384)
		(end 284.236668 -156.353256)
		(width 0.1397)
		(layer "In9.Cu")
		(net "PCIE_COMP_B_TO_SCC_B_5_DN")
	)
	(segment
		(start 274.689316 -153.912824)
		(end 277.868888 -151.353774)
		(width 0.1397)
		(layer "In9.Cu")
		(net "PCIE_COMP_B_TO_SCC_B_4_DP")
	)
	(segment
		(start 259.30098 -177.607976)
		(end 274.689316 -153.912824)
		(width 0.1397)
		(layer "In9.Cu")
		(net "PCIE_COMP_B_TO_SCC_B_4_DP")
	)
	(segment
		(start 217.199972 -415.600134)
		(end 217.199972 -415.257996)
		(width 0.1397)
		(layer "In9.Cu")
		(net "PCIE_COMP_B_TO_SCC_B_4_DP")
	)
	(segment
		(start 216.150444 -404.074884)
		(end 212.137498 -386.336286)
		(width 0.1397)
		(layer "In9.Cu")
		(net "PCIE_COMP_B_TO_SCC_B_4_DP")
	)
	(segment
		(start 216.154 -414.478978)
		(end 216.154 -404.105618)
		(width 0.1397)
		(layer "In9.Cu")
		(net "PCIE_COMP_B_TO_SCC_B_4_DP")
	)
	(segment
		(start 216.988136 -415.04616)
		(end 216.721182 -415.04616)
		(width 0.1397)
		(layer "In9.Cu")
		(net "PCIE_COMP_B_TO_SCC_B_4_DP")
	)
	(segment
		(start 283.994352 -152.184608)
		(end 284.056836 -152.05964)
		(width 0.1397)
		(layer "In9.Cu")
		(net "PCIE_COMP_B_TO_SCC_B_4_DP")
	)
	(segment
		(start 283.994352 -151.872188)
		(end 283.249878 -151.499824)
		(width 0.1397)
		(layer "In9.Cu")
		(net "PCIE_COMP_B_TO_SCC_B_4_DP")
	)
	(segment
		(start 277.868888 -151.353774)
		(end 279.339548 -151.353774)
		(width 0.1397)
		(layer "In9.Cu")
		(net "PCIE_COMP_B_TO_SCC_B_4_DP")
	)
	(segment
		(start 279.339548 -151.353774)
		(end 280.339546 -152.353772)
		(width 0.1397)
		(layer "In9.Cu")
		(net "PCIE_COMP_B_TO_SCC_B_4_DP")
	)
	(segment
		(start 214.027258 -377.73483)
		(end 215.895428 -369.291362)
		(width 0.1397)
		(layer "In9.Cu")
		(net "PCIE_COMP_B_TO_SCC_B_4_DP")
	)
	(segment
		(start 212.137498 -386.275326)
		(end 214.027258 -377.73483)
		(width 0.1397)
		(layer "In9.Cu")
		(net "PCIE_COMP_B_TO_SCC_B_4_DP")
	)
	(segment
		(start 280.339546 -152.353772)
		(end 283.58592 -152.353772)
		(width 0.1397)
		(layer "In9.Cu")
		(net "PCIE_COMP_B_TO_SCC_B_4_DP")
	)
	(segment
		(start 215.895428 -369.291362)
		(end 209.593688 -341.44077)
		(width 0.1397)
		(layer "In9.Cu")
		(net "PCIE_COMP_B_TO_SCC_B_4_DP")
	)
	(segment
		(start 209.593688 -341.44077)
		(end 259.30098 -177.607976)
		(width 0.1397)
		(layer "In9.Cu")
		(net "PCIE_COMP_B_TO_SCC_B_4_DP")
	)
	(arc
		(start 284.056836 -152.05964)
		(mid 284.064417 -151.952973)
		(end 283.994352 -151.872188)
		(width 0.1397)
		(layer "In9.Cu")
		(net "PCIE_COMP_B_TO_SCC_B_4_DP")
	)
	(arc
		(start 217.199972 -415.257996)
		(mid 217.137927 -415.108205)
		(end 216.988136 -415.04616)
		(width 0.1397)
		(layer "In9.Cu")
		(net "PCIE_COMP_B_TO_SCC_B_4_DP")
	)
	(arc
		(start 212.137498 -386.336286)
		(mid 212.134134 -386.305806)
		(end 212.137498 -386.275326)
		(width 0.1397)
		(layer "In9.Cu")
		(net "PCIE_COMP_B_TO_SCC_B_4_DP")
	)
	(arc
		(start 216.721182 -415.04616)
		(mid 216.320124 -414.880036)
		(end 216.154 -414.478978)
		(width 0.1397)
		(layer "In9.Cu")
		(net "PCIE_COMP_B_TO_SCC_B_4_DP")
	)
	(arc
		(start 216.154 -404.105618)
		(mid 216.153085 -404.090151)
		(end 216.150444 -404.074884)
		(width 0.1397)
		(layer "In9.Cu")
		(net "PCIE_COMP_B_TO_SCC_B_4_DP")
	)
	(arc
		(start 283.58592 -152.353772)
		(mid 283.806956 -152.309805)
		(end 283.994352 -152.184608)
		(width 0.1397)
		(layer "In9.Cu")
		(net "PCIE_COMP_B_TO_SCC_B_4_DP")
	)
	(segment
		(start 273.049746 -156.974286)
		(end 273.25701 -156.93009)
		(width 0.1397)
		(layer "In9.Cu")
		(net "PCIE_COMP_B_TO_SCC_B_4_DN")
	)
	(segment
		(start 280.218388 -152.645872)
		(end 283.585666 -152.645872)
		(width 0.1397)
		(layer "In9.Cu")
		(net "PCIE_COMP_B_TO_SCC_B_4_DN")
	)
	(segment
		(start 274.105116 -155.624276)
		(end 274.06092 -155.417012)
		(width 0.1397)
		(layer "In9.Cu")
		(net "PCIE_COMP_B_TO_SCC_B_4_DN")
	)
	(segment
		(start 273.485356 -156.578554)
		(end 273.44116 -156.37129)
		(width 0.1397)
		(layer "In9.Cu")
		(net "PCIE_COMP_B_TO_SCC_B_4_DN")
	)
	(segment
		(start 209.895694 -341.451692)
		(end 259.568696 -177.732436)
		(width 0.1397)
		(layer "In9.Cu")
		(net "PCIE_COMP_B_TO_SCC_B_4_DN")
	)
	(segment
		(start 212.430106 -386.305044)
		(end 216.194894 -369.2906)
		(width 0.1397)
		(layer "In9.Cu")
		(net "PCIE_COMP_B_TO_SCC_B_4_DN")
	)
	(segment
		(start 277.972012 -151.645874)
		(end 279.21839 -151.645874)
		(width 0.1397)
		(layer "In9.Cu")
		(net "PCIE_COMP_B_TO_SCC_B_4_DN")
	)
	(segment
		(start 272.20164 -158.2801)
		(end 272.429986 -157.928564)
		(width 0.1397)
		(layer "In9.Cu")
		(net "PCIE_COMP_B_TO_SCC_B_4_DN")
	)
	(segment
		(start 284.236668 -152.353264)
		(end 284.318202 -152.190196)
		(width 0.1397)
		(layer "In9.Cu")
		(net "PCIE_COMP_B_TO_SCC_B_4_DN")
	)
	(segment
		(start 272.63725 -157.884368)
		(end 272.865596 -157.533086)
		(width 0.1397)
		(layer "In9.Cu")
		(net "PCIE_COMP_B_TO_SCC_B_4_DN")
	)
	(segment
		(start 272.429986 -157.928564)
		(end 272.63725 -157.884368)
		(width 0.1397)
		(layer "In9.Cu")
		(net "PCIE_COMP_B_TO_SCC_B_4_DN")
	)
	(segment
		(start 273.25701 -156.93009)
		(end 273.485356 -156.578554)
		(width 0.1397)
		(layer "In9.Cu")
		(net "PCIE_COMP_B_TO_SCC_B_4_DN")
	)
	(segment
		(start 272.865596 -157.533086)
		(end 272.8214 -157.325568)
		(width 0.1397)
		(layer "In9.Cu")
		(net "PCIE_COMP_B_TO_SCC_B_4_DN")
	)
	(segment
		(start 284.505654 -152.127712)
		(end 285.249874 -152.499822)
		(width 0.1397)
		(layer "In9.Cu")
		(net "PCIE_COMP_B_TO_SCC_B_4_DN")
	)
	(segment
		(start 216.4461 -404.057358)
		(end 212.430106 -386.305044)
		(width 0.1397)
		(layer "In9.Cu")
		(net "PCIE_COMP_B_TO_SCC_B_4_DN")
	)
	(segment
		(start 274.724876 -154.669998)
		(end 274.68068 -154.462734)
		(width 0.1397)
		(layer "In9.Cu")
		(net "PCIE_COMP_B_TO_SCC_B_4_DN")
	)
	(segment
		(start 274.49653 -155.021534)
		(end 274.724876 -154.669998)
		(width 0.1397)
		(layer "In9.Cu")
		(net "PCIE_COMP_B_TO_SCC_B_4_DN")
	)
	(segment
		(start 273.44116 -156.37129)
		(end 273.669506 -156.019754)
		(width 0.1397)
		(layer "In9.Cu")
		(net "PCIE_COMP_B_TO_SCC_B_4_DN")
	)
	(segment
		(start 274.06092 -155.417012)
		(end 274.289266 -155.065476)
		(width 0.1397)
		(layer "In9.Cu")
		(net "PCIE_COMP_B_TO_SCC_B_4_DN")
	)
	(segment
		(start 274.68068 -154.462734)
		(end 274.909026 -154.111198)
		(width 0.1397)
		(layer "In9.Cu")
		(net "PCIE_COMP_B_TO_SCC_B_4_DN")
	)
	(segment
		(start 259.568696 -177.732436)
		(end 271.810226 -158.882842)
		(width 0.1397)
		(layer "In9.Cu")
		(net "PCIE_COMP_B_TO_SCC_B_4_DN")
	)
	(segment
		(start 216.194894 -369.2906)
		(end 209.895694 -341.451692)
		(width 0.1397)
		(layer "In9.Cu")
		(net "PCIE_COMP_B_TO_SCC_B_4_DN")
	)
	(segment
		(start 217.199972 -414.200086)
		(end 217.199972 -414.542224)
		(width 0.1397)
		(layer "In9.Cu")
		(net "PCIE_COMP_B_TO_SCC_B_4_DN")
	)
	(segment
		(start 273.669506 -156.019754)
		(end 273.87677 -155.975812)
		(width 0.1397)
		(layer "In9.Cu")
		(net "PCIE_COMP_B_TO_SCC_B_4_DN")
	)
	(segment
		(start 272.245836 -158.487364)
		(end 272.20164 -158.2801)
		(width 0.1397)
		(layer "In9.Cu")
		(net "PCIE_COMP_B_TO_SCC_B_4_DN")
	)
	(segment
		(start 216.988136 -414.75406)
		(end 216.721182 -414.75406)
		(width 0.1397)
		(layer "In9.Cu")
		(net "PCIE_COMP_B_TO_SCC_B_4_DN")
	)
	(segment
		(start 272.01749 -158.8389)
		(end 272.245836 -158.487364)
		(width 0.1397)
		(layer "In9.Cu")
		(net "PCIE_COMP_B_TO_SCC_B_4_DN")
	)
	(segment
		(start 279.21839 -151.645874)
		(end 280.218388 -152.645872)
		(width 0.1397)
		(layer "In9.Cu")
		(net "PCIE_COMP_B_TO_SCC_B_4_DN")
	)
	(segment
		(start 271.810226 -158.882842)
		(end 272.01749 -158.8389)
		(width 0.1397)
		(layer "In9.Cu")
		(net "PCIE_COMP_B_TO_SCC_B_4_DN")
	)
	(segment
		(start 272.8214 -157.325568)
		(end 273.049746 -156.974286)
		(width 0.1397)
		(layer "In9.Cu")
		(net "PCIE_COMP_B_TO_SCC_B_4_DN")
	)
	(segment
		(start 216.4461 -414.478978)
		(end 216.4461 -404.057358)
		(width 0.1397)
		(layer "In9.Cu")
		(net "PCIE_COMP_B_TO_SCC_B_4_DN")
	)
	(segment
		(start 273.87677 -155.975812)
		(end 274.105116 -155.624276)
		(width 0.1397)
		(layer "In9.Cu")
		(net "PCIE_COMP_B_TO_SCC_B_4_DN")
	)
	(segment
		(start 274.909026 -154.111198)
		(end 277.972012 -151.645874)
		(width 0.1397)
		(layer "In9.Cu")
		(net "PCIE_COMP_B_TO_SCC_B_4_DN")
	)
	(segment
		(start 274.289266 -155.065476)
		(end 274.49653 -155.021534)
		(width 0.1397)
		(layer "In9.Cu")
		(net "PCIE_COMP_B_TO_SCC_B_4_DN")
	)
	(arc
		(start 284.318202 -152.190196)
		(mid 284.398987 -152.120131)
		(end 284.505654 -152.127712)
		(width 0.1397)
		(layer "In9.Cu")
		(net "PCIE_COMP_B_TO_SCC_B_4_DN")
	)
	(arc
		(start 217.199972 -414.542224)
		(mid 217.137927 -414.692015)
		(end 216.988136 -414.75406)
		(width 0.1397)
		(layer "In9.Cu")
		(net "PCIE_COMP_B_TO_SCC_B_4_DN")
	)
	(arc
		(start 283.585666 -152.645872)
		(mid 283.942542 -152.569392)
		(end 284.236668 -152.353264)
		(width 0.1397)
		(layer "In9.Cu")
		(net "PCIE_COMP_B_TO_SCC_B_4_DN")
	)
	(arc
		(start 216.721182 -414.75406)
		(mid 216.52667 -414.67349)
		(end 216.4461 -414.478978)
		(width 0.1397)
		(layer "In9.Cu")
		(net "PCIE_COMP_B_TO_SCC_B_4_DN")
	)
	(segment
		(start 207.927448 -341.18169)
		(end 207.927702 -341.18169)
		(width 0.1397)
		(layer "In9.Cu")
		(net "PCIE_COMP_B_TO_SCC_B_3_DP")
	)
	(segment
		(start 214.354156 -417.213288)
		(end 214.354156 -405.96947)
		(width 0.1397)
		(layer "In9.Cu")
		(net "PCIE_COMP_B_TO_SCC_B_3_DP")
	)
	(segment
		(start 207.927702 -341.18169)
		(end 268.47292 -141.626844)
		(width 0.1397)
		(layer "In9.Cu")
		(net "PCIE_COMP_B_TO_SCC_B_3_DP")
	)
	(segment
		(start 207.90535 -341.25535)
		(end 207.927448 -341.18169)
		(width 0.1397)
		(layer "In9.Cu")
		(net "PCIE_COMP_B_TO_SCC_B_3_DP")
	)
	(segment
		(start 214.490808 -417.523676)
		(end 214.476584 -417.509706)
		(width 0.1397)
		(layer "In9.Cu")
		(net "PCIE_COMP_B_TO_SCC_B_3_DP")
	)
	(segment
		(start 215.363044 -417.73602)
		(end 215.310212 -417.683188)
		(width 0.1397)
		(layer "In9.Cu")
		(net "PCIE_COMP_B_TO_SCC_B_3_DP")
	)
	(segment
		(start 215.22055 -417.646104)
		(end 214.786972 -417.646104)
		(width 0.1397)
		(layer "In9.Cu")
		(net "PCIE_COMP_B_TO_SCC_B_3_DP")
	)
	(segment
		(start 278.292052 -127.353822)
		(end 279.39619 -127.353822)
		(width 0.1397)
		(layer "In9.Cu")
		(net "PCIE_COMP_B_TO_SCC_B_3_DP")
	)
	(segment
		(start 215.400128 -418.200078)
		(end 215.400128 -417.825682)
		(width 0.1397)
		(layer "In9.Cu")
		(net "PCIE_COMP_B_TO_SCC_B_3_DP")
	)
	(segment
		(start 210.278726 -387.88975)
		(end 212.205316 -378.248164)
		(width 0.1397)
		(layer "In9.Cu")
		(net "PCIE_COMP_B_TO_SCC_B_3_DP")
	)
	(segment
		(start 277.342346 -127.970534)
		(end 278.292052 -127.353822)
		(width 0.1397)
		(layer "In9.Cu")
		(net "PCIE_COMP_B_TO_SCC_B_3_DP")
	)
	(segment
		(start 279.39619 -127.353822)
		(end 280.396188 -128.35382)
		(width 0.1397)
		(layer "In9.Cu")
		(net "PCIE_COMP_B_TO_SCC_B_3_DP")
	)
	(segment
		(start 283.994352 -127.872236)
		(end 283.249878 -127.499872)
		(width 0.1397)
		(layer "In9.Cu")
		(net "PCIE_COMP_B_TO_SCC_B_3_DP")
	)
	(segment
		(start 214.113364 -368.699542)
		(end 207.90535 -341.25535)
		(width 0.1397)
		(layer "In9.Cu")
		(net "PCIE_COMP_B_TO_SCC_B_3_DP")
	)
	(segment
		(start 212.205316 -378.248164)
		(end 214.113364 -368.699542)
		(width 0.1397)
		(layer "In9.Cu")
		(net "PCIE_COMP_B_TO_SCC_B_3_DP")
	)
	(segment
		(start 268.47292 -141.626844)
		(end 277.342346 -127.970534)
		(width 0.1397)
		(layer "In9.Cu")
		(net "PCIE_COMP_B_TO_SCC_B_3_DP")
	)
	(segment
		(start 280.396188 -128.35382)
		(end 283.58592 -128.35382)
		(width 0.1397)
		(layer "In9.Cu")
		(net "PCIE_COMP_B_TO_SCC_B_3_DP")
	)
	(segment
		(start 283.994352 -128.184656)
		(end 284.056836 -128.059688)
		(width 0.1397)
		(layer "In9.Cu")
		(net "PCIE_COMP_B_TO_SCC_B_3_DP")
	)
	(segment
		(start 214.3506 -405.938736)
		(end 210.279488 -387.947916)
		(width 0.1397)
		(layer "In9.Cu")
		(net "PCIE_COMP_B_TO_SCC_B_3_DP")
	)
	(arc
		(start 214.476584 -417.509706)
		(mid 214.38585 -417.373679)
		(end 214.354156 -417.213288)
		(width 0.1397)
		(layer "In9.Cu")
		(net "PCIE_COMP_B_TO_SCC_B_3_DP")
	)
	(arc
		(start 284.056836 -128.059688)
		(mid 284.064417 -127.953021)
		(end 283.994352 -127.872236)
		(width 0.1397)
		(layer "In9.Cu")
		(net "PCIE_COMP_B_TO_SCC_B_3_DP")
	)
	(arc
		(start 210.279488 -387.947916)
		(mid 210.276019 -387.918871)
		(end 210.278726 -387.88975)
		(width 0.1397)
		(layer "In9.Cu")
		(net "PCIE_COMP_B_TO_SCC_B_3_DP")
	)
	(arc
		(start 214.354156 -405.96947)
		(mid 214.353241 -405.954003)
		(end 214.3506 -405.938736)
		(width 0.1397)
		(layer "In9.Cu")
		(net "PCIE_COMP_B_TO_SCC_B_3_DP")
	)
	(arc
		(start 215.310212 -417.683188)
		(mid 215.269061 -417.655755)
		(end 215.22055 -417.646104)
		(width 0.1397)
		(layer "In9.Cu")
		(net "PCIE_COMP_B_TO_SCC_B_3_DP")
	)
	(arc
		(start 214.786972 -417.646104)
		(mid 214.626702 -417.614354)
		(end 214.490808 -417.523676)
		(width 0.1397)
		(layer "In9.Cu")
		(net "PCIE_COMP_B_TO_SCC_B_3_DP")
	)
	(arc
		(start 215.400128 -417.825682)
		(mid 215.390495 -417.777164)
		(end 215.363044 -417.73602)
		(width 0.1397)
		(layer "In9.Cu")
		(net "PCIE_COMP_B_TO_SCC_B_3_DP")
	)
	(arc
		(start 283.58592 -128.35382)
		(mid 283.806956 -128.309853)
		(end 283.994352 -128.184656)
		(width 0.1397)
		(layer "In9.Cu")
		(net "PCIE_COMP_B_TO_SCC_B_3_DP")
	)
	(segment
		(start 214.646256 -405.92121)
		(end 210.571588 -387.91515)
		(width 0.1397)
		(layer "In9.Cu")
		(net "PCIE_COMP_B_TO_SCC_B_3_DN")
	)
	(segment
		(start 277.553674 -128.181862)
		(end 278.378666 -127.645922)
		(width 0.1397)
		(layer "In9.Cu")
		(net "PCIE_COMP_B_TO_SCC_B_3_DN")
	)
	(segment
		(start 279.275032 -127.645922)
		(end 280.27503 -128.64592)
		(width 0.1397)
		(layer "In9.Cu")
		(net "PCIE_COMP_B_TO_SCC_B_3_DN")
	)
	(segment
		(start 276.805898 -129.589784)
		(end 277.03399 -129.238248)
		(width 0.1397)
		(layer "In9.Cu")
		(net "PCIE_COMP_B_TO_SCC_B_3_DN")
	)
	(segment
		(start 208.207356 -341.266272)
		(end 268.740636 -141.751304)
		(width 0.1397)
		(layer "In9.Cu")
		(net "PCIE_COMP_B_TO_SCC_B_3_DN")
	)
	(segment
		(start 275.816568 -131.112768)
		(end 275.77542 -130.919728)
		(width 0.1397)
		(layer "In9.Cu")
		(net "PCIE_COMP_B_TO_SCC_B_3_DN")
	)
	(segment
		(start 275.77542 -130.919728)
		(end 276.003766 -130.568192)
		(width 0.1397)
		(layer "In9.Cu")
		(net "PCIE_COMP_B_TO_SCC_B_3_DN")
	)
	(segment
		(start 276.425406 -130.175508)
		(end 276.384258 -129.982468)
		(width 0.1397)
		(layer "In9.Cu")
		(net "PCIE_COMP_B_TO_SCC_B_3_DN")
	)
	(segment
		(start 274.786344 -132.442712)
		(end 274.979638 -132.401564)
		(width 0.1397)
		(layer "In9.Cu")
		(net "PCIE_COMP_B_TO_SCC_B_3_DN")
	)
	(segment
		(start 215.363044 -417.264596)
		(end 215.31072 -417.31692)
		(width 0.1397)
		(layer "In9.Cu")
		(net "PCIE_COMP_B_TO_SCC_B_3_DN")
	)
	(segment
		(start 276.384258 -129.982468)
		(end 276.612604 -129.630932)
		(width 0.1397)
		(layer "In9.Cu")
		(net "PCIE_COMP_B_TO_SCC_B_3_DN")
	)
	(segment
		(start 276.993096 -129.045208)
		(end 277.553674 -128.181862)
		(width 0.1397)
		(layer "In9.Cu")
		(net "PCIE_COMP_B_TO_SCC_B_3_DN")
	)
	(segment
		(start 274.177506 -133.379972)
		(end 274.3708 -133.338824)
		(width 0.1397)
		(layer "In9.Cu")
		(net "PCIE_COMP_B_TO_SCC_B_3_DN")
	)
	(segment
		(start 280.27503 -128.64592)
		(end 283.585666 -128.64592)
		(width 0.1397)
		(layer "In9.Cu")
		(net "PCIE_COMP_B_TO_SCC_B_3_DN")
	)
	(segment
		(start 274.979638 -132.401564)
		(end 275.207984 -132.050028)
		(width 0.1397)
		(layer "In9.Cu")
		(net "PCIE_COMP_B_TO_SCC_B_3_DN")
	)
	(segment
		(start 274.3708 -133.338824)
		(end 274.599146 -132.987288)
		(width 0.1397)
		(layer "In9.Cu")
		(net "PCIE_COMP_B_TO_SCC_B_3_DN")
	)
	(segment
		(start 274.599146 -132.987288)
		(end 274.557998 -132.794248)
		(width 0.1397)
		(layer "In9.Cu")
		(net "PCIE_COMP_B_TO_SCC_B_3_DN")
	)
	(segment
		(start 215.400128 -416.80003)
		(end 215.400128 -417.174934)
		(width 0.1397)
		(layer "In9.Cu")
		(net "PCIE_COMP_B_TO_SCC_B_3_DN")
	)
	(segment
		(start 284.236668 -128.353312)
		(end 284.318202 -128.190244)
		(width 0.1397)
		(layer "In9.Cu")
		(net "PCIE_COMP_B_TO_SCC_B_3_DN")
	)
	(segment
		(start 275.588222 -131.464304)
		(end 275.816568 -131.112768)
		(width 0.1397)
		(layer "In9.Cu")
		(net "PCIE_COMP_B_TO_SCC_B_3_DN")
	)
	(segment
		(start 214.646256 -417.213288)
		(end 214.646256 -405.92121)
		(width 0.1397)
		(layer "In9.Cu")
		(net "PCIE_COMP_B_TO_SCC_B_3_DN")
	)
	(segment
		(start 278.378666 -127.645922)
		(end 279.275032 -127.645922)
		(width 0.1397)
		(layer "In9.Cu")
		(net "PCIE_COMP_B_TO_SCC_B_3_DN")
	)
	(segment
		(start 275.395182 -131.505452)
		(end 275.588222 -131.464304)
		(width 0.1397)
		(layer "In9.Cu")
		(net "PCIE_COMP_B_TO_SCC_B_3_DN")
	)
	(segment
		(start 274.557998 -132.794248)
		(end 274.786344 -132.442712)
		(width 0.1397)
		(layer "In9.Cu")
		(net "PCIE_COMP_B_TO_SCC_B_3_DN")
	)
	(segment
		(start 210.571588 -387.91515)
		(end 214.412068 -368.695732)
		(width 0.1397)
		(layer "In9.Cu")
		(net "PCIE_COMP_B_TO_SCC_B_3_DN")
	)
	(segment
		(start 276.612604 -129.630932)
		(end 276.805898 -129.589784)
		(width 0.1397)
		(layer "In9.Cu")
		(net "PCIE_COMP_B_TO_SCC_B_3_DN")
	)
	(segment
		(start 277.03399 -129.238248)
		(end 276.993096 -129.045208)
		(width 0.1397)
		(layer "In9.Cu")
		(net "PCIE_COMP_B_TO_SCC_B_3_DN")
	)
	(segment
		(start 275.166836 -131.856988)
		(end 275.395182 -131.505452)
		(width 0.1397)
		(layer "In9.Cu")
		(net "PCIE_COMP_B_TO_SCC_B_3_DN")
	)
	(segment
		(start 215.221058 -417.354004)
		(end 214.786972 -417.354004)
		(width 0.1397)
		(layer "In9.Cu")
		(net "PCIE_COMP_B_TO_SCC_B_3_DN")
	)
	(segment
		(start 214.69731 -417.31692)
		(end 214.68334 -417.30295)
		(width 0.1397)
		(layer "In9.Cu")
		(net "PCIE_COMP_B_TO_SCC_B_3_DN")
	)
	(segment
		(start 276.19706 -130.527044)
		(end 276.425406 -130.175508)
		(width 0.1397)
		(layer "In9.Cu")
		(net "PCIE_COMP_B_TO_SCC_B_3_DN")
	)
	(segment
		(start 214.412068 -368.695732)
		(end 208.207356 -341.266272)
		(width 0.1397)
		(layer "In9.Cu")
		(net "PCIE_COMP_B_TO_SCC_B_3_DN")
	)
	(segment
		(start 284.505654 -128.12776)
		(end 285.249874 -128.49987)
		(width 0.1397)
		(layer "In9.Cu")
		(net "PCIE_COMP_B_TO_SCC_B_3_DN")
	)
	(segment
		(start 276.003766 -130.568192)
		(end 276.19706 -130.527044)
		(width 0.1397)
		(layer "In9.Cu")
		(net "PCIE_COMP_B_TO_SCC_B_3_DN")
	)
	(segment
		(start 275.207984 -132.050028)
		(end 275.166836 -131.856988)
		(width 0.1397)
		(layer "In9.Cu")
		(net "PCIE_COMP_B_TO_SCC_B_3_DN")
	)
	(segment
		(start 268.740636 -141.751304)
		(end 274.177506 -133.379972)
		(width 0.1397)
		(layer "In9.Cu")
		(net "PCIE_COMP_B_TO_SCC_B_3_DN")
	)
	(arc
		(start 284.318202 -128.190244)
		(mid 284.398987 -128.120179)
		(end 284.505654 -128.12776)
		(width 0.1397)
		(layer "In9.Cu")
		(net "PCIE_COMP_B_TO_SCC_B_3_DN")
	)
	(arc
		(start 214.68334 -417.30295)
		(mid 214.655907 -417.261799)
		(end 214.646256 -417.213288)
		(width 0.1397)
		(layer "In9.Cu")
		(net "PCIE_COMP_B_TO_SCC_B_3_DN")
	)
	(arc
		(start 215.31072 -417.31692)
		(mid 215.269569 -417.344353)
		(end 215.221058 -417.354004)
		(width 0.1397)
		(layer "In9.Cu")
		(net "PCIE_COMP_B_TO_SCC_B_3_DN")
	)
	(arc
		(start 214.786972 -417.354004)
		(mid 214.738454 -417.344371)
		(end 214.69731 -417.31692)
		(width 0.1397)
		(layer "In9.Cu")
		(net "PCIE_COMP_B_TO_SCC_B_3_DN")
	)
	(arc
		(start 215.400128 -417.174934)
		(mid 215.390495 -417.223452)
		(end 215.363044 -417.264596)
		(width 0.1397)
		(layer "In9.Cu")
		(net "PCIE_COMP_B_TO_SCC_B_3_DN")
	)
	(arc
		(start 283.585666 -128.64592)
		(mid 283.942542 -128.56944)
		(end 284.236668 -128.353312)
		(width 0.1397)
		(layer "In9.Cu")
		(net "PCIE_COMP_B_TO_SCC_B_3_DN")
	)
	(segment
		(start 283.994352 -124.184664)
		(end 284.056836 -124.059696)
		(width 0.1397)
		(layer "In9.Cu")
		(net "PCIE_COMP_B_TO_SCC_B_2_DP")
	)
	(segment
		(start 212.554058 -414.478978)
		(end 212.554058 -404.388066)
		(width 0.1397)
		(layer "In9.Cu")
		(net "PCIE_COMP_B_TO_SCC_B_2_DP")
	)
	(segment
		(start 269.947136 -135.217408)
		(end 269.946882 -135.217408)
		(width 0.1397)
		(layer "In9.Cu")
		(net "PCIE_COMP_B_TO_SCC_B_2_DP")
	)
	(segment
		(start 269.946882 -135.217408)
		(end 277.203154 -124.044456)
		(width 0.1397)
		(layer "In9.Cu")
		(net "PCIE_COMP_B_TO_SCC_B_2_DP")
	)
	(segment
		(start 208.601056 -386.838698)
		(end 210.609434 -377.7742)
		(width 0.1397)
		(layer "In9.Cu")
		(net "PCIE_COMP_B_TO_SCC_B_2_DP")
	)
	(segment
		(start 206.268828 -340.832694)
		(end 267.517118 -138.959082)
		(width 0.1397)
		(layer "In9.Cu")
		(net "PCIE_COMP_B_TO_SCC_B_2_DP")
	)
	(segment
		(start 267.517118 -138.959082)
		(end 269.947136 -135.217408)
		(width 0.1397)
		(layer "In9.Cu")
		(net "PCIE_COMP_B_TO_SCC_B_2_DP")
	)
	(segment
		(start 278.26716 -123.35383)
		(end 279.383744 -123.35383)
		(width 0.1397)
		(layer "In9.Cu")
		(net "PCIE_COMP_B_TO_SCC_B_2_DP")
	)
	(segment
		(start 283.994352 -123.872244)
		(end 283.249878 -123.49988)
		(width 0.1397)
		(layer "In9.Cu")
		(net "PCIE_COMP_B_TO_SCC_B_2_DP")
	)
	(segment
		(start 210.609434 -377.7742)
		(end 212.596476 -368.806984)
		(width 0.1397)
		(layer "In9.Cu")
		(net "PCIE_COMP_B_TO_SCC_B_2_DP")
	)
	(segment
		(start 212.550502 -404.357332)
		(end 208.601056 -386.899658)
		(width 0.1397)
		(layer "In9.Cu")
		(net "PCIE_COMP_B_TO_SCC_B_2_DP")
	)
	(segment
		(start 213.60003 -415.600134)
		(end 213.60003 -415.257996)
		(width 0.1397)
		(layer "In9.Cu")
		(net "PCIE_COMP_B_TO_SCC_B_2_DP")
	)
	(segment
		(start 280.383742 -124.353828)
		(end 283.58592 -124.353828)
		(width 0.1397)
		(layer "In9.Cu")
		(net "PCIE_COMP_B_TO_SCC_B_2_DP")
	)
	(segment
		(start 212.596476 -368.806984)
		(end 206.268828 -340.832694)
		(width 0.1397)
		(layer "In9.Cu")
		(net "PCIE_COMP_B_TO_SCC_B_2_DP")
	)
	(segment
		(start 277.203154 -124.044456)
		(end 278.26716 -123.35383)
		(width 0.1397)
		(layer "In9.Cu")
		(net "PCIE_COMP_B_TO_SCC_B_2_DP")
	)
	(segment
		(start 213.388194 -415.04616)
		(end 213.12124 -415.04616)
		(width 0.1397)
		(layer "In9.Cu")
		(net "PCIE_COMP_B_TO_SCC_B_2_DP")
	)
	(segment
		(start 279.383744 -123.35383)
		(end 280.383742 -124.353828)
		(width 0.1397)
		(layer "In9.Cu")
		(net "PCIE_COMP_B_TO_SCC_B_2_DP")
	)
	(arc
		(start 283.58592 -124.353828)
		(mid 283.806956 -124.309861)
		(end 283.994352 -124.184664)
		(width 0.1397)
		(layer "In9.Cu")
		(net "PCIE_COMP_B_TO_SCC_B_2_DP")
	)
	(arc
		(start 213.12124 -415.04616)
		(mid 212.720182 -414.880036)
		(end 212.554058 -414.478978)
		(width 0.1397)
		(layer "In9.Cu")
		(net "PCIE_COMP_B_TO_SCC_B_2_DP")
	)
	(arc
		(start 213.60003 -415.257996)
		(mid 213.537985 -415.108205)
		(end 213.388194 -415.04616)
		(width 0.1397)
		(layer "In9.Cu")
		(net "PCIE_COMP_B_TO_SCC_B_2_DP")
	)
	(arc
		(start 212.554058 -404.388066)
		(mid 212.553143 -404.372599)
		(end 212.550502 -404.357332)
		(width 0.1397)
		(layer "In9.Cu")
		(net "PCIE_COMP_B_TO_SCC_B_2_DP")
	)
	(arc
		(start 208.601056 -386.899658)
		(mid 208.597692 -386.869178)
		(end 208.601056 -386.838698)
		(width 0.1397)
		(layer "In9.Cu")
		(net "PCIE_COMP_B_TO_SCC_B_2_DP")
	)
	(arc
		(start 284.056836 -124.059696)
		(mid 284.064417 -123.953029)
		(end 283.994352 -123.872244)
		(width 0.1397)
		(layer "In9.Cu")
		(net "PCIE_COMP_B_TO_SCC_B_2_DP")
	)
	(segment
		(start 276.814026 -125.436884)
		(end 277.042372 -125.085348)
		(width 0.1397)
		(layer "In9.Cu")
		(net "PCIE_COMP_B_TO_SCC_B_2_DN")
	)
	(segment
		(start 212.846158 -404.339806)
		(end 208.893664 -386.868416)
		(width 0.1397)
		(layer "In9.Cu")
		(net "PCIE_COMP_B_TO_SCC_B_2_DN")
	)
	(segment
		(start 278.353774 -123.64593)
		(end 279.262586 -123.64593)
		(width 0.1397)
		(layer "In9.Cu")
		(net "PCIE_COMP_B_TO_SCC_B_2_DN")
	)
	(segment
		(start 208.893664 -386.868416)
		(end 212.895942 -368.806222)
		(width 0.1397)
		(layer "In9.Cu")
		(net "PCIE_COMP_B_TO_SCC_B_2_DN")
	)
	(segment
		(start 212.895942 -368.806222)
		(end 206.570834 -340.843616)
		(width 0.1397)
		(layer "In9.Cu")
		(net "PCIE_COMP_B_TO_SCC_B_2_DN")
	)
	(segment
		(start 274.56638 -128.641094)
		(end 274.794726 -128.289812)
		(width 0.1397)
		(layer "In9.Cu")
		(net "PCIE_COMP_B_TO_SCC_B_2_DN")
	)
	(segment
		(start 275.40331 -127.352552)
		(end 275.596604 -127.311404)
		(width 0.1397)
		(layer "In9.Cu")
		(net "PCIE_COMP_B_TO_SCC_B_2_DN")
	)
	(segment
		(start 274.185888 -129.227072)
		(end 274.379182 -129.185924)
		(width 0.1397)
		(layer "In9.Cu")
		(net "PCIE_COMP_B_TO_SCC_B_2_DN")
	)
	(segment
		(start 213.60003 -414.200086)
		(end 213.60003 -414.542224)
		(width 0.1397)
		(layer "In9.Cu")
		(net "PCIE_COMP_B_TO_SCC_B_2_DN")
	)
	(segment
		(start 284.236668 -124.35332)
		(end 284.318202 -124.190252)
		(width 0.1397)
		(layer "In9.Cu")
		(net "PCIE_COMP_B_TO_SCC_B_2_DN")
	)
	(segment
		(start 277.042372 -125.085348)
		(end 277.001224 -124.892054)
		(width 0.1397)
		(layer "In9.Cu")
		(net "PCIE_COMP_B_TO_SCC_B_2_DN")
	)
	(segment
		(start 212.846158 -414.478978)
		(end 212.846158 -404.339806)
		(width 0.1397)
		(layer "In9.Cu")
		(net "PCIE_COMP_B_TO_SCC_B_2_DN")
	)
	(segment
		(start 274.794726 -128.289812)
		(end 274.98802 -128.248664)
		(width 0.1397)
		(layer "In9.Cu")
		(net "PCIE_COMP_B_TO_SCC_B_2_DN")
	)
	(segment
		(start 274.607528 -128.834388)
		(end 274.56638 -128.641094)
		(width 0.1397)
		(layer "In9.Cu")
		(net "PCIE_COMP_B_TO_SCC_B_2_DN")
	)
	(segment
		(start 275.82495 -126.959868)
		(end 275.783802 -126.766574)
		(width 0.1397)
		(layer "In9.Cu")
		(net "PCIE_COMP_B_TO_SCC_B_2_DN")
	)
	(segment
		(start 276.205442 -126.374144)
		(end 276.433534 -126.022608)
		(width 0.1397)
		(layer "In9.Cu")
		(net "PCIE_COMP_B_TO_SCC_B_2_DN")
	)
	(segment
		(start 276.433534 -126.022608)
		(end 276.39264 -125.829314)
		(width 0.1397)
		(layer "In9.Cu")
		(net "PCIE_COMP_B_TO_SCC_B_2_DN")
	)
	(segment
		(start 275.783802 -126.766574)
		(end 276.012148 -126.415038)
		(width 0.1397)
		(layer "In9.Cu")
		(net "PCIE_COMP_B_TO_SCC_B_2_DN")
	)
	(segment
		(start 277.414482 -124.255784)
		(end 278.353774 -123.64593)
		(width 0.1397)
		(layer "In9.Cu")
		(net "PCIE_COMP_B_TO_SCC_B_2_DN")
	)
	(segment
		(start 284.505654 -124.127768)
		(end 285.249874 -124.499878)
		(width 0.1397)
		(layer "In9.Cu")
		(net "PCIE_COMP_B_TO_SCC_B_2_DN")
	)
	(segment
		(start 276.39264 -125.829314)
		(end 276.620732 -125.477778)
		(width 0.1397)
		(layer "In9.Cu")
		(net "PCIE_COMP_B_TO_SCC_B_2_DN")
	)
	(segment
		(start 206.570834 -340.843616)
		(end 267.784834 -139.083542)
		(width 0.1397)
		(layer "In9.Cu")
		(net "PCIE_COMP_B_TO_SCC_B_2_DN")
	)
	(segment
		(start 275.216112 -127.897128)
		(end 275.175218 -127.703834)
		(width 0.1397)
		(layer "In9.Cu")
		(net "PCIE_COMP_B_TO_SCC_B_2_DN")
	)
	(segment
		(start 274.379182 -129.185924)
		(end 274.607528 -128.834388)
		(width 0.1397)
		(layer "In9.Cu")
		(net "PCIE_COMP_B_TO_SCC_B_2_DN")
	)
	(segment
		(start 213.388194 -414.75406)
		(end 213.12124 -414.75406)
		(width 0.1397)
		(layer "In9.Cu")
		(net "PCIE_COMP_B_TO_SCC_B_2_DN")
	)
	(segment
		(start 279.262586 -123.64593)
		(end 280.262584 -124.645928)
		(width 0.1397)
		(layer "In9.Cu")
		(net "PCIE_COMP_B_TO_SCC_B_2_DN")
	)
	(segment
		(start 276.012148 -126.415038)
		(end 276.205442 -126.374144)
		(width 0.1397)
		(layer "In9.Cu")
		(net "PCIE_COMP_B_TO_SCC_B_2_DN")
	)
	(segment
		(start 277.001224 -124.892054)
		(end 277.414482 -124.255784)
		(width 0.1397)
		(layer "In9.Cu")
		(net "PCIE_COMP_B_TO_SCC_B_2_DN")
	)
	(segment
		(start 275.175218 -127.703834)
		(end 275.40331 -127.352552)
		(width 0.1397)
		(layer "In9.Cu")
		(net "PCIE_COMP_B_TO_SCC_B_2_DN")
	)
	(segment
		(start 274.98802 -128.248664)
		(end 275.216112 -127.897128)
		(width 0.1397)
		(layer "In9.Cu")
		(net "PCIE_COMP_B_TO_SCC_B_2_DN")
	)
	(segment
		(start 276.620732 -125.477778)
		(end 276.814026 -125.436884)
		(width 0.1397)
		(layer "In9.Cu")
		(net "PCIE_COMP_B_TO_SCC_B_2_DN")
	)
	(segment
		(start 280.262584 -124.645928)
		(end 283.585666 -124.645928)
		(width 0.1397)
		(layer "In9.Cu")
		(net "PCIE_COMP_B_TO_SCC_B_2_DN")
	)
	(segment
		(start 267.784834 -139.083542)
		(end 274.185888 -129.227072)
		(width 0.1397)
		(layer "In9.Cu")
		(net "PCIE_COMP_B_TO_SCC_B_2_DN")
	)
	(segment
		(start 275.596604 -127.311404)
		(end 275.82495 -126.959868)
		(width 0.1397)
		(layer "In9.Cu")
		(net "PCIE_COMP_B_TO_SCC_B_2_DN")
	)
	(arc
		(start 213.60003 -414.542224)
		(mid 213.537985 -414.692015)
		(end 213.388194 -414.75406)
		(width 0.1397)
		(layer "In9.Cu")
		(net "PCIE_COMP_B_TO_SCC_B_2_DN")
	)
	(arc
		(start 213.12124 -414.75406)
		(mid 212.926728 -414.67349)
		(end 212.846158 -414.478978)
		(width 0.1397)
		(layer "In9.Cu")
		(net "PCIE_COMP_B_TO_SCC_B_2_DN")
	)
	(arc
		(start 284.318202 -124.190252)
		(mid 284.398987 -124.120187)
		(end 284.505654 -124.127768)
		(width 0.1397)
		(layer "In9.Cu")
		(net "PCIE_COMP_B_TO_SCC_B_2_DN")
	)
	(arc
		(start 283.585666 -124.645928)
		(mid 283.942542 -124.569448)
		(end 284.236668 -124.35332)
		(width 0.1397)
		(layer "In9.Cu")
		(net "PCIE_COMP_B_TO_SCC_B_2_DN")
	)
	(segment
		(start 206.87538 -387.286754)
		(end 210.946238 -368.908838)
		(width 0.1397)
		(layer "In9.Cu")
		(net "PCIE_COMP_B_TO_SCC_B_1_DP")
	)
	(segment
		(start 204.391006 -339.942424)
		(end 219.70238 -289.477196)
		(width 0.1397)
		(layer "In9.Cu")
		(net "PCIE_COMP_B_TO_SCC_B_1_DP")
	)
	(segment
		(start 219.70238 -289.477196)
		(end 265.580876 -138.264392)
		(width 0.1397)
		(layer "In9.Cu")
		(net "PCIE_COMP_B_TO_SCC_B_1_DP")
	)
	(segment
		(start 280.396188 -120.353836)
		(end 283.58592 -120.353836)
		(width 0.1397)
		(layer "In9.Cu")
		(net "PCIE_COMP_B_TO_SCC_B_1_DP")
	)
	(segment
		(start 277.534878 -119.857012)
		(end 278.309578 -119.353838)
		(width 0.1397)
		(layer "In9.Cu")
		(net "PCIE_COMP_B_TO_SCC_B_1_DP")
	)
	(segment
		(start 211.620608 -417.646104)
		(end 211.22132 -417.646104)
		(width 0.1397)
		(layer "In9.Cu")
		(net "PCIE_COMP_B_TO_SCC_B_1_DP")
	)
	(segment
		(start 211.763102 -417.73602)
		(end 211.71027 -417.683188)
		(width 0.1397)
		(layer "In9.Cu")
		(net "PCIE_COMP_B_TO_SCC_B_1_DP")
	)
	(segment
		(start 210.946238 -368.908838)
		(end 204.391006 -339.942424)
		(width 0.1397)
		(layer "In9.Cu")
		(net "PCIE_COMP_B_TO_SCC_B_1_DP")
	)
	(segment
		(start 211.800186 -418.200078)
		(end 211.800186 -417.825682)
		(width 0.1397)
		(layer "In9.Cu")
		(net "PCIE_COMP_B_TO_SCC_B_1_DP")
	)
	(segment
		(start 283.994352 -120.184672)
		(end 284.056836 -120.059704)
		(width 0.1397)
		(layer "In9.Cu")
		(net "PCIE_COMP_B_TO_SCC_B_1_DP")
	)
	(segment
		(start 210.925156 -417.523676)
		(end 210.876642 -417.475416)
		(width 0.1397)
		(layer "In9.Cu")
		(net "PCIE_COMP_B_TO_SCC_B_1_DP")
	)
	(segment
		(start 210.754214 -417.178998)
		(end 210.754214 -404.506176)
		(width 0.1397)
		(layer "In9.Cu")
		(net "PCIE_COMP_B_TO_SCC_B_1_DP")
	)
	(segment
		(start 283.994352 -119.872252)
		(end 283.249878 -119.499888)
		(width 0.1397)
		(layer "In9.Cu")
		(net "PCIE_COMP_B_TO_SCC_B_1_DP")
	)
	(segment
		(start 279.39619 -119.353838)
		(end 280.396188 -120.353836)
		(width 0.1397)
		(layer "In9.Cu")
		(net "PCIE_COMP_B_TO_SCC_B_1_DP")
	)
	(segment
		(start 278.309578 -119.353838)
		(end 279.39619 -119.353838)
		(width 0.1397)
		(layer "In9.Cu")
		(net "PCIE_COMP_B_TO_SCC_B_1_DP")
	)
	(segment
		(start 265.580876 -138.264392)
		(end 277.534878 -119.857012)
		(width 0.1397)
		(layer "In9.Cu")
		(net "PCIE_COMP_B_TO_SCC_B_1_DP")
	)
	(segment
		(start 210.750658 -404.475442)
		(end 206.87538 -387.347714)
		(width 0.1397)
		(layer "In9.Cu")
		(net "PCIE_COMP_B_TO_SCC_B_1_DP")
	)
	(arc
		(start 210.754214 -404.506176)
		(mid 210.753299 -404.490709)
		(end 210.750658 -404.475442)
		(width 0.1397)
		(layer "In9.Cu")
		(net "PCIE_COMP_B_TO_SCC_B_1_DP")
	)
	(arc
		(start 283.58592 -120.353836)
		(mid 283.806956 -120.309869)
		(end 283.994352 -120.184672)
		(width 0.1397)
		(layer "In9.Cu")
		(net "PCIE_COMP_B_TO_SCC_B_1_DP")
	)
	(arc
		(start 211.22132 -417.646104)
		(mid 211.06105 -417.614354)
		(end 210.925156 -417.523676)
		(width 0.1397)
		(layer "In9.Cu")
		(net "PCIE_COMP_B_TO_SCC_B_1_DP")
	)
	(arc
		(start 206.87538 -387.347714)
		(mid 206.872016 -387.317234)
		(end 206.87538 -387.286754)
		(width 0.1397)
		(layer "In9.Cu")
		(net "PCIE_COMP_B_TO_SCC_B_1_DP")
	)
	(arc
		(start 211.800186 -417.825682)
		(mid 211.790553 -417.777164)
		(end 211.763102 -417.73602)
		(width 0.1397)
		(layer "In9.Cu")
		(net "PCIE_COMP_B_TO_SCC_B_1_DP")
	)
	(arc
		(start 211.71027 -417.683188)
		(mid 211.669119 -417.655755)
		(end 211.620608 -417.646104)
		(width 0.1397)
		(layer "In9.Cu")
		(net "PCIE_COMP_B_TO_SCC_B_1_DP")
	)
	(arc
		(start 210.876642 -417.475416)
		(mid 210.785908 -417.339389)
		(end 210.754214 -417.178998)
		(width 0.1397)
		(layer "In9.Cu")
		(net "PCIE_COMP_B_TO_SCC_B_1_DP")
	)
	(arc
		(start 284.056836 -120.059704)
		(mid 284.064417 -119.953037)
		(end 283.994352 -119.872252)
		(width 0.1397)
		(layer "In9.Cu")
		(net "PCIE_COMP_B_TO_SCC_B_1_DP")
	)
	(segment
		(start 276.232366 -122.399552)
		(end 277.746206 -120.06834)
		(width 0.1397)
		(layer "In9.Cu")
		(net "PCIE_COMP_B_TO_SCC_B_1_DN")
	)
	(segment
		(start 273.610324 -126.693422)
		(end 273.83867 -126.341886)
		(width 0.1397)
		(layer "In9.Cu")
		(net "PCIE_COMP_B_TO_SCC_B_1_DN")
	)
	(segment
		(start 273.83867 -126.341886)
		(end 273.797522 -126.148592)
		(width 0.1397)
		(layer "In9.Cu")
		(net "PCIE_COMP_B_TO_SCC_B_1_DN")
	)
	(segment
		(start 274.827746 -124.818902)
		(end 275.056092 -124.467366)
		(width 0.1397)
		(layer "In9.Cu")
		(net "PCIE_COMP_B_TO_SCC_B_1_DN")
	)
	(segment
		(start 265.848592 -138.388852)
		(end 273.417284 -126.73457)
		(width 0.1397)
		(layer "In9.Cu")
		(net "PCIE_COMP_B_TO_SCC_B_1_DN")
	)
	(segment
		(start 278.396192 -119.645938)
		(end 279.275032 -119.645938)
		(width 0.1397)
		(layer "In9.Cu")
		(net "PCIE_COMP_B_TO_SCC_B_1_DN")
	)
	(segment
		(start 280.27503 -120.645936)
		(end 283.585666 -120.645936)
		(width 0.1397)
		(layer "In9.Cu")
		(net "PCIE_COMP_B_TO_SCC_B_1_DN")
	)
	(segment
		(start 275.664676 -123.530106)
		(end 275.623782 -123.336812)
		(width 0.1397)
		(layer "In9.Cu")
		(net "PCIE_COMP_B_TO_SCC_B_1_DN")
	)
	(segment
		(start 284.505654 -120.127776)
		(end 285.249874 -120.499886)
		(width 0.1397)
		(layer "In9.Cu")
		(net "PCIE_COMP_B_TO_SCC_B_1_DN")
	)
	(segment
		(start 275.851874 -122.985276)
		(end 276.045168 -122.944128)
		(width 0.1397)
		(layer "In9.Cu")
		(net "PCIE_COMP_B_TO_SCC_B_1_DN")
	)
	(segment
		(start 274.219162 -125.756162)
		(end 274.447254 -125.404626)
		(width 0.1397)
		(layer "In9.Cu")
		(net "PCIE_COMP_B_TO_SCC_B_1_DN")
	)
	(segment
		(start 275.623782 -123.336812)
		(end 275.851874 -122.985276)
		(width 0.1397)
		(layer "In9.Cu")
		(net "PCIE_COMP_B_TO_SCC_B_1_DN")
	)
	(segment
		(start 274.025868 -125.797056)
		(end 274.219162 -125.756162)
		(width 0.1397)
		(layer "In9.Cu")
		(net "PCIE_COMP_B_TO_SCC_B_1_DN")
	)
	(segment
		(start 275.436584 -123.881388)
		(end 275.664676 -123.530106)
		(width 0.1397)
		(layer "In9.Cu")
		(net "PCIE_COMP_B_TO_SCC_B_1_DN")
	)
	(segment
		(start 277.746206 -120.06834)
		(end 278.396192 -119.645938)
		(width 0.1397)
		(layer "In9.Cu")
		(net "PCIE_COMP_B_TO_SCC_B_1_DN")
	)
	(segment
		(start 207.167988 -387.316472)
		(end 211.245704 -368.908076)
		(width 0.1397)
		(layer "In9.Cu")
		(net "PCIE_COMP_B_TO_SCC_B_1_DN")
	)
	(segment
		(start 276.273514 -122.592592)
		(end 276.232366 -122.399552)
		(width 0.1397)
		(layer "In9.Cu")
		(net "PCIE_COMP_B_TO_SCC_B_1_DN")
	)
	(segment
		(start 279.275032 -119.645938)
		(end 280.27503 -120.645936)
		(width 0.1397)
		(layer "In9.Cu")
		(net "PCIE_COMP_B_TO_SCC_B_1_DN")
	)
	(segment
		(start 211.763102 -417.264596)
		(end 211.710778 -417.31692)
		(width 0.1397)
		(layer "In9.Cu")
		(net "PCIE_COMP_B_TO_SCC_B_1_DN")
	)
	(segment
		(start 273.417284 -126.73457)
		(end 273.610324 -126.693422)
		(width 0.1397)
		(layer "In9.Cu")
		(net "PCIE_COMP_B_TO_SCC_B_1_DN")
	)
	(segment
		(start 275.056092 -124.467366)
		(end 275.014944 -124.274072)
		(width 0.1397)
		(layer "In9.Cu")
		(net "PCIE_COMP_B_TO_SCC_B_1_DN")
	)
	(segment
		(start 276.045168 -122.944128)
		(end 276.273514 -122.592592)
		(width 0.1397)
		(layer "In9.Cu")
		(net "PCIE_COMP_B_TO_SCC_B_1_DN")
	)
	(segment
		(start 211.245704 -368.908076)
		(end 204.693012 -339.953346)
		(width 0.1397)
		(layer "In9.Cu")
		(net "PCIE_COMP_B_TO_SCC_B_1_DN")
	)
	(segment
		(start 211.131658 -417.31692)
		(end 211.083398 -417.26866)
		(width 0.1397)
		(layer "In9.Cu")
		(net "PCIE_COMP_B_TO_SCC_B_1_DN")
	)
	(segment
		(start 211.046314 -417.178998)
		(end 211.046314 -404.457916)
		(width 0.1397)
		(layer "In9.Cu")
		(net "PCIE_COMP_B_TO_SCC_B_1_DN")
	)
	(segment
		(start 273.797522 -126.148592)
		(end 274.025868 -125.797056)
		(width 0.1397)
		(layer "In9.Cu")
		(net "PCIE_COMP_B_TO_SCC_B_1_DN")
	)
	(segment
		(start 275.014944 -124.274072)
		(end 275.24329 -123.922536)
		(width 0.1397)
		(layer "In9.Cu")
		(net "PCIE_COMP_B_TO_SCC_B_1_DN")
	)
	(segment
		(start 204.693012 -339.953346)
		(end 265.848592 -138.388852)
		(width 0.1397)
		(layer "In9.Cu")
		(net "PCIE_COMP_B_TO_SCC_B_1_DN")
	)
	(segment
		(start 274.634452 -124.859796)
		(end 274.827746 -124.818902)
		(width 0.1397)
		(layer "In9.Cu")
		(net "PCIE_COMP_B_TO_SCC_B_1_DN")
	)
	(segment
		(start 211.046314 -404.457916)
		(end 207.167988 -387.316472)
		(width 0.1397)
		(layer "In9.Cu")
		(net "PCIE_COMP_B_TO_SCC_B_1_DN")
	)
	(segment
		(start 274.40636 -125.211332)
		(end 274.634452 -124.859796)
		(width 0.1397)
		(layer "In9.Cu")
		(net "PCIE_COMP_B_TO_SCC_B_1_DN")
	)
	(segment
		(start 275.24329 -123.922536)
		(end 275.436584 -123.881388)
		(width 0.1397)
		(layer "In9.Cu")
		(net "PCIE_COMP_B_TO_SCC_B_1_DN")
	)
	(segment
		(start 274.447254 -125.404626)
		(end 274.40636 -125.211332)
		(width 0.1397)
		(layer "In9.Cu")
		(net "PCIE_COMP_B_TO_SCC_B_1_DN")
	)
	(segment
		(start 284.236668 -120.353328)
		(end 284.318202 -120.19026)
		(width 0.1397)
		(layer "In9.Cu")
		(net "PCIE_COMP_B_TO_SCC_B_1_DN")
	)
	(segment
		(start 211.800186 -416.80003)
		(end 211.800186 -417.174934)
		(width 0.1397)
		(layer "In9.Cu")
		(net "PCIE_COMP_B_TO_SCC_B_1_DN")
	)
	(segment
		(start 211.621116 -417.354004)
		(end 211.22132 -417.354004)
		(width 0.1397)
		(layer "In9.Cu")
		(net "PCIE_COMP_B_TO_SCC_B_1_DN")
	)
	(arc
		(start 211.22132 -417.354004)
		(mid 211.172802 -417.344371)
		(end 211.131658 -417.31692)
		(width 0.1397)
		(layer "In9.Cu")
		(net "PCIE_COMP_B_TO_SCC_B_1_DN")
	)
	(arc
		(start 283.585666 -120.645936)
		(mid 283.942542 -120.569456)
		(end 284.236668 -120.353328)
		(width 0.1397)
		(layer "In9.Cu")
		(net "PCIE_COMP_B_TO_SCC_B_1_DN")
	)
	(arc
		(start 211.710778 -417.31692)
		(mid 211.669627 -417.344353)
		(end 211.621116 -417.354004)
		(width 0.1397)
		(layer "In9.Cu")
		(net "PCIE_COMP_B_TO_SCC_B_1_DN")
	)
	(arc
		(start 211.800186 -417.174934)
		(mid 211.790553 -417.223452)
		(end 211.763102 -417.264596)
		(width 0.1397)
		(layer "In9.Cu")
		(net "PCIE_COMP_B_TO_SCC_B_1_DN")
	)
	(arc
		(start 284.318202 -120.19026)
		(mid 284.398987 -120.120195)
		(end 284.505654 -120.127776)
		(width 0.1397)
		(layer "In9.Cu")
		(net "PCIE_COMP_B_TO_SCC_B_1_DN")
	)
	(arc
		(start 211.083398 -417.26866)
		(mid 211.055965 -417.227509)
		(end 211.046314 -417.178998)
		(width 0.1397)
		(layer "In9.Cu")
		(net "PCIE_COMP_B_TO_SCC_B_1_DN")
	)
	(segment
		(start 284.234128 -117.26164)
		(end 284.048454 -117.075966)
		(width 0.1397)
		(layer "In9.Cu")
		(net "PCIE_COMP_B_TO_SCC_B_0_DP")
	)
	(segment
		(start 261.295642 -140.951712)
		(end 261.295896 -140.95095)
		(width 0.1397)
		(layer "In9.Cu")
		(net "PCIE_COMP_B_TO_SCC_B_0_DP")
	)
	(segment
		(start 255.992884 -158.42742)
		(end 255.993138 -158.426658)
		(width 0.1397)
		(layer "In9.Cu")
		(net "PCIE_COMP_B_TO_SCC_B_0_DP")
	)
	(segment
		(start 277.51278 -111.053372)
		(end 279.603962 -108.962444)
		(width 0.1397)
		(layer "In9.Cu")
		(net "PCIE_COMP_B_TO_SCC_B_0_DP")
	)
	(segment
		(start 284.618684 -117.645942)
		(end 284.234382 -117.26164)
		(width 0.1397)
		(layer "In9.Cu")
		(net "PCIE_COMP_B_TO_SCC_B_0_DP")
	)
	(segment
		(start 261.295896 -140.95095)
		(end 264.446512 -130.567684)
		(width 0.1397)
		(layer "In9.Cu")
		(net "PCIE_COMP_B_TO_SCC_B_0_DP")
	)
	(segment
		(start 284.234382 -117.26164)
		(end 284.234128 -117.26164)
		(width 0.1397)
		(layer "In9.Cu")
		(net "PCIE_COMP_B_TO_SCC_B_0_DP")
	)
	(segment
		(start 255.993138 -158.426658)
		(end 257.995166 -151.8285)
		(width 0.1397)
		(layer "In9.Cu")
		(net "PCIE_COMP_B_TO_SCC_B_0_DP")
	)
	(segment
		(start 210.000088 -415.600134)
		(end 210.000088 -415.257996)
		(width 0.1397)
		(layer "In9.Cu")
		(net "PCIE_COMP_B_TO_SCC_B_0_DP")
	)
	(segment
		(start 207.33131 -413.717232)
		(end 202.650344 -393.007342)
		(width 0.1397)
		(layer "In9.Cu")
		(net "PCIE_COMP_B_TO_SCC_B_0_DP")
	)
	(segment
		(start 258.319778 -150.758906)
		(end 258.320032 -150.758144)
		(width 0.1397)
		(layer "In9.Cu")
		(net "PCIE_COMP_B_TO_SCC_B_0_DP")
	)
	(segment
		(start 267.6906 -125.722634)
		(end 275.00834 -114.793776)
		(width 0.1397)
		(layer "In9.Cu")
		(net "PCIE_COMP_B_TO_SCC_B_0_DP")
	)
	(segment
		(start 260.645656 -143.09344)
		(end 260.646926 -143.08963)
		(width 0.1397)
		(layer "In9.Cu")
		(net "PCIE_COMP_B_TO_SCC_B_0_DP")
	)
	(segment
		(start 286.698944 -117.015514)
		(end 286.068516 -117.645942)
		(width 0.1397)
		(layer "In9.Cu")
		(net "PCIE_COMP_B_TO_SCC_B_0_DP")
	)
	(segment
		(start 207.911446 -369.265454)
		(end 201.12228 -339.262974)
		(width 0.1397)
		(layer "In9.Cu")
		(net "PCIE_COMP_B_TO_SCC_B_0_DP")
	)
	(segment
		(start 284.012386 -116.14785)
		(end 284.056582 -116.059458)
		(width 0.1397)
		(layer "In9.Cu")
		(net "PCIE_COMP_B_TO_SCC_B_0_DP")
	)
	(segment
		(start 279.603962 -108.962444)
		(end 279.603962 -107.024932)
		(width 0.1397)
		(layer "In9.Cu")
		(net "PCIE_COMP_B_TO_SCC_B_0_DP")
	)
	(segment
		(start 257.99542 -151.827738)
		(end 258.319778 -150.758906)
		(width 0.1397)
		(layer "In9.Cu")
		(net "PCIE_COMP_B_TO_SCC_B_0_DP")
	)
	(segment
		(start 280.27503 -106.353864)
		(end 283.71038 -106.353864)
		(width 0.1397)
		(layer "In9.Cu")
		(net "PCIE_COMP_B_TO_SCC_B_0_DP")
	)
	(segment
		(start 260.32206 -144.159986)
		(end 260.322314 -144.159224)
		(width 0.1397)
		(layer "In9.Cu")
		(net "PCIE_COMP_B_TO_SCC_B_0_DP")
	)
	(segment
		(start 208.660238 -415.04616)
		(end 207.33131 -413.717232)
		(width 0.1397)
		(layer "In9.Cu")
		(net "PCIE_COMP_B_TO_SCC_B_0_DP")
	)
	(segment
		(start 279.603962 -107.024932)
		(end 280.27503 -106.353864)
		(width 0.1397)
		(layer "In9.Cu")
		(net "PCIE_COMP_B_TO_SCC_B_0_DP")
	)
	(segment
		(start 286.068516 -117.645942)
		(end 284.618684 -117.645942)
		(width 0.1397)
		(layer "In9.Cu")
		(net "PCIE_COMP_B_TO_SCC_B_0_DP")
	)
	(segment
		(start 285.724854 -105.353866)
		(end 286.698944 -106.327956)
		(width 0.1397)
		(layer "In9.Cu")
		(net "PCIE_COMP_B_TO_SCC_B_0_DP")
	)
	(segment
		(start 209.788252 -415.04616)
		(end 208.660238 -415.04616)
		(width 0.1397)
		(layer "In9.Cu")
		(net "PCIE_COMP_B_TO_SCC_B_0_DP")
	)
	(segment
		(start 284.710378 -105.353866)
		(end 285.724854 -105.353866)
		(width 0.1397)
		(layer "In9.Cu")
		(net "PCIE_COMP_B_TO_SCC_B_0_DP")
	)
	(segment
		(start 202.650344 -393.007342)
		(end 207.911446 -369.265454)
		(width 0.1397)
		(layer "In9.Cu")
		(net "PCIE_COMP_B_TO_SCC_B_0_DP")
	)
	(segment
		(start 264.446512 -130.567684)
		(end 267.6906 -125.722634)
		(width 0.1397)
		(layer "In9.Cu")
		(net "PCIE_COMP_B_TO_SCC_B_0_DP")
	)
	(segment
		(start 283.994098 -115.872006)
		(end 283.249878 -115.499896)
		(width 0.1397)
		(layer "In9.Cu")
		(net "PCIE_COMP_B_TO_SCC_B_0_DP")
	)
	(segment
		(start 257.995166 -151.8285)
		(end 257.99542 -151.827738)
		(width 0.1397)
		(layer "In9.Cu")
		(net "PCIE_COMP_B_TO_SCC_B_0_DP")
	)
	(segment
		(start 201.12228 -339.262974)
		(end 255.992884 -158.42742)
		(width 0.1397)
		(layer "In9.Cu")
		(net "PCIE_COMP_B_TO_SCC_B_0_DP")
	)
	(segment
		(start 258.320032 -150.758144)
		(end 260.32206 -144.159986)
		(width 0.1397)
		(layer "In9.Cu")
		(net "PCIE_COMP_B_TO_SCC_B_0_DP")
	)
	(segment
		(start 283.71038 -106.353864)
		(end 284.710378 -105.353866)
		(width 0.1397)
		(layer "In9.Cu")
		(net "PCIE_COMP_B_TO_SCC_B_0_DP")
	)
	(segment
		(start 286.698944 -106.327956)
		(end 286.698944 -117.015514)
		(width 0.1397)
		(layer "In9.Cu")
		(net "PCIE_COMP_B_TO_SCC_B_0_DP")
	)
	(segment
		(start 260.646926 -143.08963)
		(end 261.295642 -140.951712)
		(width 0.1397)
		(layer "In9.Cu")
		(net "PCIE_COMP_B_TO_SCC_B_0_DP")
	)
	(segment
		(start 275.00834 -114.793776)
		(end 277.51278 -111.053372)
		(width 0.1397)
		(layer "In9.Cu")
		(net "PCIE_COMP_B_TO_SCC_B_0_DP")
	)
	(segment
		(start 260.322314 -144.159224)
		(end 260.645656 -143.09344)
		(width 0.1397)
		(layer "In9.Cu")
		(net "PCIE_COMP_B_TO_SCC_B_0_DP")
	)
	(arc
		(start 284.048454 -117.075966)
		(mid 283.848651 -116.618955)
		(end 284.012386 -116.14785)
		(width 0.1397)
		(layer "In9.Cu")
		(net "PCIE_COMP_B_TO_SCC_B_0_DP")
	)
	(arc
		(start 210.000088 -415.257996)
		(mid 209.938043 -415.108205)
		(end 209.788252 -415.04616)
		(width 0.1397)
		(layer "In9.Cu")
		(net "PCIE_COMP_B_TO_SCC_B_0_DP")
	)
	(arc
		(start 284.056582 -116.059458)
		(mid 284.064163 -115.952791)
		(end 283.994098 -115.872006)
		(width 0.1397)
		(layer "In9.Cu")
		(net "PCIE_COMP_B_TO_SCC_B_0_DP")
	)
	(segment
		(start 256.244344 -159.087312)
		(end 256.151126 -158.913068)
		(width 0.1397)
		(layer "In9.Cu")
		(net "PCIE_COMP_B_TO_SCC_B_0_DN")
	)
	(segment
		(start 208.781396 -414.75406)
		(end 207.597756 -413.57042)
		(width 0.1397)
		(layer "In9.Cu")
		(net "PCIE_COMP_B_TO_SCC_B_0_DN")
	)
	(segment
		(start 263.873742 -133.94309)
		(end 263.780524 -133.768846)
		(width 0.1397)
		(layer "In9.Cu")
		(net "PCIE_COMP_B_TO_SCC_B_0_DN")
	)
	(segment
		(start 255.798066 -160.557972)
		(end 255.919986 -160.156906)
		(width 0.1397)
		(layer "In9.Cu")
		(net "PCIE_COMP_B_TO_SCC_B_0_DN")
	)
	(segment
		(start 256.272792 -158.512002)
		(end 256.447036 -158.418784)
		(width 0.1397)
		(layer "In9.Cu")
		(net "PCIE_COMP_B_TO_SCC_B_0_DN")
	)
	(segment
		(start 261.250938 -142.105634)
		(end 261.425182 -142.012416)
		(width 0.1397)
		(layer "In9.Cu")
		(net "PCIE_COMP_B_TO_SCC_B_0_DN")
	)
	(segment
		(start 261.778242 -140.367766)
		(end 263.25322 -135.506714)
		(width 0.1397)
		(layer "In9.Cu")
		(net "PCIE_COMP_B_TO_SCC_B_0_DN")
	)
	(segment
		(start 266.617196 -128.102106)
		(end 266.578842 -127.908304)
		(width 0.1397)
		(layer "In9.Cu")
		(net "PCIE_COMP_B_TO_SCC_B_0_DN")
	)
	(segment
		(start 255.623822 -160.650936)
		(end 255.798066 -160.557972)
		(width 0.1397)
		(layer "In9.Cu")
		(net "PCIE_COMP_B_TO_SCC_B_0_DN")
	)
	(segment
		(start 264.076434 -133.274562)
		(end 264.1981 -132.873496)
		(width 0.1397)
		(layer "In9.Cu")
		(net "PCIE_COMP_B_TO_SCC_B_0_DN")
	)
	(segment
		(start 263.577832 -134.43712)
		(end 263.752076 -134.344156)
		(width 0.1397)
		(layer "In9.Cu")
		(net "PCIE_COMP_B_TO_SCC_B_0_DN")
	)
	(segment
		(start 270.45412 -122.371866)
		(end 270.415766 -122.178064)
		(width 0.1397)
		(layer "In9.Cu")
		(net "PCIE_COMP_B_TO_SCC_B_0_DN")
	)
	(segment
		(start 261.453884 -141.437106)
		(end 261.57555 -141.036294)
		(width 0.1397)
		(layer "In9.Cu")
		(net "PCIE_COMP_B_TO_SCC_B_0_DN")
	)
	(segment
		(start 261.546848 -141.61135)
		(end 261.453884 -141.437106)
		(width 0.1397)
		(layer "In9.Cu")
		(net "PCIE_COMP_B_TO_SCC_B_0_DN")
	)
	(segment
		(start 283.831538 -106.645964)
		(end 284.831536 -105.645966)
		(width 0.1397)
		(layer "In9.Cu")
		(net "PCIE_COMP_B_TO_SCC_B_0_DN")
	)
	(segment
		(start 265.373612 -129.959354)
		(end 265.335258 -129.765552)
		(width 0.1397)
		(layer "In9.Cu")
		(net "PCIE_COMP_B_TO_SCC_B_0_DN")
	)
	(segment
		(start 284.831536 -105.645966)
		(end 285.603696 -105.645966)
		(width 0.1397)
		(layer "In9.Cu")
		(net "PCIE_COMP_B_TO_SCC_B_0_DN")
	)
	(segment
		(start 260.925564 -143.178022)
		(end 260.92658 -143.174974)
		(width 0.1397)
		(layer "In9.Cu")
		(net "PCIE_COMP_B_TO_SCC_B_0_DN")
	)
	(segment
		(start 280.396188 -106.645964)
		(end 283.831538 -106.645964)
		(width 0.1397)
		(layer "In9.Cu")
		(net "PCIE_COMP_B_TO_SCC_B_0_DN")
	)
	(segment
		(start 263.25322 -135.506714)
		(end 263.427464 -135.413496)
		(width 0.1397)
		(layer "In9.Cu")
		(net "PCIE_COMP_B_TO_SCC_B_0_DN")
	)
	(segment
		(start 266.812014 -127.56007)
		(end 267.005816 -127.521716)
		(width 0.1397)
		(layer "In9.Cu")
		(net "PCIE_COMP_B_TO_SCC_B_0_DN")
	)
	(segment
		(start 271.075912 -121.443242)
		(end 271.037558 -121.24944)
		(width 0.1397)
		(layer "In9.Cu")
		(net "PCIE_COMP_B_TO_SCC_B_0_DN")
	)
	(segment
		(start 263.752076 -134.344156)
		(end 263.873742 -133.94309)
		(width 0.1397)
		(layer "In9.Cu")
		(net "PCIE_COMP_B_TO_SCC_B_0_DN")
	)
	(segment
		(start 263.427464 -135.413496)
		(end 263.54913 -135.01243)
		(width 0.1397)
		(layer "In9.Cu")
		(net "PCIE_COMP_B_TO_SCC_B_0_DN")
	)
	(segment
		(start 258.77393 -150.750524)
		(end 258.895596 -150.349458)
		(width 0.1397)
		(layer "In9.Cu")
		(net "PCIE_COMP_B_TO_SCC_B_0_DN")
	)
	(segment
		(start 209.788252 -414.75406)
		(end 208.781396 -414.75406)
		(width 0.1397)
		(layer "In9.Cu")
		(net "PCIE_COMP_B_TO_SCC_B_0_DN")
	)
	(segment
		(start 284.5054 -116.12753)
		(end 285.249874 -116.499894)
		(width 0.1397)
		(layer "In9.Cu")
		(net "PCIE_COMP_B_TO_SCC_B_0_DN")
	)
	(segment
		(start 264.946638 -130.345942)
		(end 265.14044 -130.307588)
		(width 0.1397)
		(layer "In9.Cu")
		(net "PCIE_COMP_B_TO_SCC_B_0_DN")
	)
	(segment
		(start 256.151126 -158.913068)
		(end 256.272792 -158.512002)
		(width 0.1397)
		(layer "In9.Cu")
		(net "PCIE_COMP_B_TO_SCC_B_0_DN")
	)
	(segment
		(start 279.896062 -107.14609)
		(end 280.396188 -106.645964)
		(width 0.1397)
		(layer "In9.Cu")
		(net "PCIE_COMP_B_TO_SCC_B_0_DN")
	)
	(segment
		(start 255.826768 -159.982662)
		(end 255.948434 -159.581596)
		(width 0.1397)
		(layer "In9.Cu")
		(net "PCIE_COMP_B_TO_SCC_B_0_DN")
	)
	(segment
		(start 263.54913 -135.01243)
		(end 263.456166 -134.838186)
		(width 0.1397)
		(layer "In9.Cu")
		(net "PCIE_COMP_B_TO_SCC_B_0_DN")
	)
	(segment
		(start 267.005816 -127.521716)
		(end 267.238988 -127.173482)
		(width 0.1397)
		(layer "In9.Cu")
		(net "PCIE_COMP_B_TO_SCC_B_0_DN")
	)
	(segment
		(start 259.220208 -149.279864)
		(end 259.12699 -149.10562)
		(width 0.1397)
		(layer "In9.Cu")
		(net "PCIE_COMP_B_TO_SCC_B_0_DN")
	)
	(segment
		(start 260.897878 -143.750284)
		(end 260.80466 -143.57604)
		(width 0.1397)
		(layer "In9.Cu")
		(net "PCIE_COMP_B_TO_SCC_B_0_DN")
	)
	(segment
		(start 264.429494 -131.629912)
		(end 264.713466 -130.694176)
		(width 0.1397)
		(layer "In9.Cu")
		(net "PCIE_COMP_B_TO_SCC_B_0_DN")
	)
	(segment
		(start 207.597756 -413.57042)
		(end 202.94981 -393.006834)
		(width 0.1397)
		(layer "In9.Cu")
		(net "PCIE_COMP_B_TO_SCC_B_0_DN")
	)
	(segment
		(start 257.950716 -152.982422)
		(end 258.12496 -152.889458)
		(width 0.1397)
		(layer "In9.Cu")
		(net "PCIE_COMP_B_TO_SCC_B_0_DN")
	)
	(segment
		(start 258.449318 -151.819864)
		(end 258.571238 -151.418798)
		(width 0.1397)
		(layer "In9.Cu")
		(net "PCIE_COMP_B_TO_SCC_B_0_DN")
	)
	(segment
		(start 258.802378 -150.175214)
		(end 258.924298 -149.774148)
		(width 0.1397)
		(layer "In9.Cu")
		(net "PCIE_COMP_B_TO_SCC_B_0_DN")
	)
	(segment
		(start 258.599686 -150.843488)
		(end 258.77393 -150.750524)
		(width 0.1397)
		(layer "In9.Cu")
		(net "PCIE_COMP_B_TO_SCC_B_0_DN")
	)
	(segment
		(start 261.100824 -143.08201)
		(end 261.22249 -142.680944)
		(width 0.1397)
		(layer "In9.Cu")
		(net "PCIE_COMP_B_TO_SCC_B_0_DN")
	)
	(segment
		(start 263.90219 -133.36778)
		(end 264.076434 -133.274562)
		(width 0.1397)
		(layer "In9.Cu")
		(net "PCIE_COMP_B_TO_SCC_B_0_DN")
	)
	(segment
		(start 261.87146 -140.54201)
		(end 261.778242 -140.367766)
		(width 0.1397)
		(layer "In9.Cu")
		(net "PCIE_COMP_B_TO_SCC_B_0_DN")
	)
	(segment
		(start 256.447036 -158.418784)
		(end 256.568702 -158.017972)
		(width 0.1397)
		(layer "In9.Cu")
		(net "PCIE_COMP_B_TO_SCC_B_0_DN")
	)
	(segment
		(start 270.415766 -122.178064)
		(end 270.648938 -121.82983)
		(width 0.1397)
		(layer "In9.Cu")
		(net "PCIE_COMP_B_TO_SCC_B_0_DN")
	)
	(segment
		(start 261.129272 -142.5067)
		(end 261.250938 -142.105634)
		(width 0.1397)
		(layer "In9.Cu")
		(net "PCIE_COMP_B_TO_SCC_B_0_DN")
	)
	(segment
		(start 258.895596 -150.349458)
		(end 258.802378 -150.175214)
		(width 0.1397)
		(layer "In9.Cu")
		(net "PCIE_COMP_B_TO_SCC_B_0_DN")
	)
	(segment
		(start 264.226802 -132.298186)
		(end 264.401046 -132.205222)
		(width 0.1397)
		(layer "In9.Cu")
		(net "PCIE_COMP_B_TO_SCC_B_0_DN")
	)
	(segment
		(start 259.098542 -149.68093)
		(end 259.220208 -149.279864)
		(width 0.1397)
		(layer "In9.Cu")
		(net "PCIE_COMP_B_TO_SCC_B_0_DN")
	)
	(segment
		(start 286.406844 -106.449114)
		(end 286.406844 -116.894356)
		(width 0.1397)
		(layer "In9.Cu")
		(net "PCIE_COMP_B_TO_SCC_B_0_DN")
	)
	(segment
		(start 285.947358 -117.353842)
		(end 284.739842 -117.353842)
		(width 0.1397)
		(layer "In9.Cu")
		(net "PCIE_COMP_B_TO_SCC_B_0_DN")
	)
	(segment
		(start 260.80466 -143.57604)
		(end 260.925564 -143.178022)
		(width 0.1397)
		(layer "In9.Cu")
		(net "PCIE_COMP_B_TO_SCC_B_0_DN")
	)
	(segment
		(start 260.776212 -144.15135)
		(end 260.897878 -143.750284)
		(width 0.1397)
		(layer "In9.Cu")
		(net "PCIE_COMP_B_TO_SCC_B_0_DN")
	)
	(segment
		(start 258.275074 -151.913082)
		(end 258.449318 -151.819864)
		(width 0.1397)
		(layer "In9.Cu")
		(net "PCIE_COMP_B_TO_SCC_B_0_DN")
	)
	(segment
		(start 270.84274 -121.791476)
		(end 271.075912 -121.443242)
		(width 0.1397)
		(layer "In9.Cu")
		(net "PCIE_COMP_B_TO_SCC_B_0_DN")
	)
	(segment
		(start 258.924298 -149.774148)
		(end 259.098542 -149.68093)
		(width 0.1397)
		(layer "In9.Cu")
		(net "PCIE_COMP_B_TO_SCC_B_0_DN")
	)
	(segment
		(start 259.12699 -149.10562)
		(end 260.601968 -144.244568)
		(width 0.1397)
		(layer "In9.Cu")
		(net "PCIE_COMP_B_TO_SCC_B_0_DN")
	)
	(segment
		(start 267.238988 -127.173482)
		(end 267.200634 -126.97968)
		(width 0.1397)
		(layer "In9.Cu")
		(net "PCIE_COMP_B_TO_SCC_B_0_DN")
	)
	(segment
		(start 264.105136 -132.699252)
		(end 264.226802 -132.298186)
		(width 0.1397)
		(layer "In9.Cu")
		(net "PCIE_COMP_B_TO_SCC_B_0_DN")
	)
	(segment
		(start 284.25521 -116.315236)
		(end 284.255464 -116.314982)
		(width 0.1397)
		(layer "In9.Cu")
		(net "PCIE_COMP_B_TO_SCC_B_0_DN")
	)
	(segment
		(start 265.14044 -130.307588)
		(end 265.373612 -129.959354)
		(width 0.1397)
		(layer "In9.Cu")
		(net "PCIE_COMP_B_TO_SCC_B_0_DN")
	)
	(segment
		(start 264.713466 -130.694176)
		(end 264.946638 -130.345942)
		(width 0.1397)
		(layer "In9.Cu")
		(net "PCIE_COMP_B_TO_SCC_B_0_DN")
	)
	(segment
		(start 265.56843 -129.417318)
		(end 265.762232 -129.378964)
		(width 0.1397)
		(layer "In9.Cu")
		(net "PCIE_COMP_B_TO_SCC_B_0_DN")
	)
	(segment
		(start 201.424286 -339.273896)
		(end 255.623822 -160.650936)
		(width 0.1397)
		(layer "In9.Cu")
		(net "PCIE_COMP_B_TO_SCC_B_0_DN")
	)
	(segment
		(start 279.896062 -109.083602)
		(end 279.896062 -107.14609)
		(width 0.1397)
		(layer "In9.Cu")
		(net "PCIE_COMP_B_TO_SCC_B_0_DN")
	)
	(segment
		(start 256.122678 -159.488378)
		(end 256.244344 -159.087312)
		(width 0.1397)
		(layer "In9.Cu")
		(net "PCIE_COMP_B_TO_SCC_B_0_DN")
	)
	(segment
		(start 265.995404 -129.03073)
		(end 265.95705 -128.836928)
		(width 0.1397)
		(layer "In9.Cu")
		(net "PCIE_COMP_B_TO_SCC_B_0_DN")
	)
	(segment
		(start 271.65935 -120.320816)
		(end 277.739856 -111.239808)
		(width 0.1397)
		(layer "In9.Cu")
		(net "PCIE_COMP_B_TO_SCC_B_0_DN")
	)
	(segment
		(start 266.384024 -128.45034)
		(end 266.617196 -128.102106)
		(width 0.1397)
		(layer "In9.Cu")
		(net "PCIE_COMP_B_TO_SCC_B_0_DN")
	)
	(segment
		(start 264.1981 -132.873496)
		(end 264.105136 -132.699252)
		(width 0.1397)
		(layer "In9.Cu")
		(net "PCIE_COMP_B_TO_SCC_B_0_DN")
	)
	(segment
		(start 263.780524 -133.768846)
		(end 263.90219 -133.36778)
		(width 0.1397)
		(layer "In9.Cu")
		(net "PCIE_COMP_B_TO_SCC_B_0_DN")
	)
	(segment
		(start 208.204054 -369.234212)
		(end 204.817726 -354.269802)
		(width 0.1397)
		(layer "In9.Cu")
		(net "PCIE_COMP_B_TO_SCC_B_0_DN")
	)
	(segment
		(start 271.464532 -120.862852)
		(end 271.697704 -120.514618)
		(width 0.1397)
		(layer "In9.Cu")
		(net "PCIE_COMP_B_TO_SCC_B_0_DN")
	)
	(segment
		(start 285.603696 -105.645966)
		(end 286.406844 -106.449114)
		(width 0.1397)
		(layer "In9.Cu")
		(net "PCIE_COMP_B_TO_SCC_B_0_DN")
	)
	(segment
		(start 277.739856 -111.239808)
		(end 279.896062 -109.083602)
		(width 0.1397)
		(layer "In9.Cu")
		(net "PCIE_COMP_B_TO_SCC_B_0_DN")
	)
	(segment
		(start 270.220948 -122.7201)
		(end 270.45412 -122.371866)
		(width 0.1397)
		(layer "In9.Cu")
		(net "PCIE_COMP_B_TO_SCC_B_0_DN")
	)
	(segment
		(start 260.92658 -143.174974)
		(end 261.100824 -143.08201)
		(width 0.1397)
		(layer "In9.Cu")
		(net "PCIE_COMP_B_TO_SCC_B_0_DN")
	)
	(segment
		(start 267.200634 -126.97968)
		(end 270.027146 -122.758454)
		(width 0.1397)
		(layer "In9.Cu")
		(net "PCIE_COMP_B_TO_SCC_B_0_DN")
	)
	(segment
		(start 266.578842 -127.908304)
		(end 266.812014 -127.56007)
		(width 0.1397)
		(layer "In9.Cu")
		(net "PCIE_COMP_B_TO_SCC_B_0_DN")
	)
	(segment
		(start 264.401046 -132.205222)
		(end 264.522712 -131.804156)
		(width 0.1397)
		(layer "In9.Cu")
		(net "PCIE_COMP_B_TO_SCC_B_0_DN")
	)
	(segment
		(start 271.27073 -120.901206)
		(end 271.464532 -120.862852)
		(width 0.1397)
		(layer "In9.Cu")
		(net "PCIE_COMP_B_TO_SCC_B_0_DN")
	)
	(segment
		(start 266.190222 -128.488694)
		(end 266.384024 -128.45034)
		(width 0.1397)
		(layer "In9.Cu")
		(net "PCIE_COMP_B_TO_SCC_B_0_DN")
	)
	(segment
		(start 258.246626 -152.488392)
		(end 258.153408 -152.314148)
		(width 0.1397)
		(layer "In9.Cu")
		(net "PCIE_COMP_B_TO_SCC_B_0_DN")
	)
	(segment
		(start 256.568702 -158.017972)
		(end 256.475738 -157.843728)
		(width 0.1397)
		(layer "In9.Cu")
		(net "PCIE_COMP_B_TO_SCC_B_0_DN")
	)
	(segment
		(start 204.817726 -354.269802)
		(end 201.424286 -339.273896)
		(width 0.1397)
		(layer "In9.Cu")
		(net "PCIE_COMP_B_TO_SCC_B_0_DN")
	)
	(segment
		(start 258.47802 -151.244554)
		(end 258.599686 -150.843488)
		(width 0.1397)
		(layer "In9.Cu")
		(net "PCIE_COMP_B_TO_SCC_B_0_DN")
	)
	(segment
		(start 286.406844 -116.894356)
		(end 285.947358 -117.353842)
		(width 0.1397)
		(layer "In9.Cu")
		(net "PCIE_COMP_B_TO_SCC_B_0_DN")
	)
	(segment
		(start 271.037558 -121.24944)
		(end 271.27073 -120.901206)
		(width 0.1397)
		(layer "In9.Cu")
		(net "PCIE_COMP_B_TO_SCC_B_0_DN")
	)
	(segment
		(start 258.571238 -151.418798)
		(end 258.47802 -151.244554)
		(width 0.1397)
		(layer "In9.Cu")
		(net "PCIE_COMP_B_TO_SCC_B_0_DN")
	)
	(segment
		(start 284.739842 -117.353842)
		(end 284.25521 -116.86921)
		(width 0.1397)
		(layer "In9.Cu")
		(net "PCIE_COMP_B_TO_SCC_B_0_DN")
	)
	(segment
		(start 255.948434 -159.581596)
		(end 256.122678 -159.488378)
		(width 0.1397)
		(layer "In9.Cu")
		(net "PCIE_COMP_B_TO_SCC_B_0_DN")
	)
	(segment
		(start 261.425182 -142.012416)
		(end 261.546848 -141.61135)
		(width 0.1397)
		(layer "In9.Cu")
		(net "PCIE_COMP_B_TO_SCC_B_0_DN")
	)
	(segment
		(start 265.95705 -128.836928)
		(end 266.190222 -128.488694)
		(width 0.1397)
		(layer "In9.Cu")
		(net "PCIE_COMP_B_TO_SCC_B_0_DN")
	)
	(segment
		(start 270.027146 -122.758454)
		(end 270.220948 -122.7201)
		(width 0.1397)
		(layer "In9.Cu")
		(net "PCIE_COMP_B_TO_SCC_B_0_DN")
	)
	(segment
		(start 261.22249 -142.680944)
		(end 261.129272 -142.5067)
		(width 0.1397)
		(layer "In9.Cu")
		(net "PCIE_COMP_B_TO_SCC_B_0_DN")
	)
	(segment
		(start 258.153408 -152.314148)
		(end 258.275074 -151.913082)
		(width 0.1397)
		(layer "In9.Cu")
		(net "PCIE_COMP_B_TO_SCC_B_0_DN")
	)
	(segment
		(start 261.57555 -141.036294)
		(end 261.749794 -140.943076)
		(width 0.1397)
		(layer "In9.Cu")
		(net "PCIE_COMP_B_TO_SCC_B_0_DN")
	)
	(segment
		(start 265.762232 -129.378964)
		(end 265.995404 -129.03073)
		(width 0.1397)
		(layer "In9.Cu")
		(net "PCIE_COMP_B_TO_SCC_B_0_DN")
	)
	(segment
		(start 210.000088 -414.200086)
		(end 210.000088 -414.542224)
		(width 0.1397)
		(layer "In9.Cu")
		(net "PCIE_COMP_B_TO_SCC_B_0_DN")
	)
	(segment
		(start 265.335258 -129.765552)
		(end 265.56843 -129.417318)
		(width 0.1397)
		(layer "In9.Cu")
		(net "PCIE_COMP_B_TO_SCC_B_0_DN")
	)
	(segment
		(start 270.648938 -121.82983)
		(end 270.84274 -121.791476)
		(width 0.1397)
		(layer "In9.Cu")
		(net "PCIE_COMP_B_TO_SCC_B_0_DN")
	)
	(segment
		(start 261.749794 -140.943076)
		(end 261.87146 -140.54201)
		(width 0.1397)
		(layer "In9.Cu")
		(net "PCIE_COMP_B_TO_SCC_B_0_DN")
	)
	(segment
		(start 260.601968 -144.244568)
		(end 260.776212 -144.15135)
		(width 0.1397)
		(layer "In9.Cu")
		(net "PCIE_COMP_B_TO_SCC_B_0_DN")
	)
	(segment
		(start 255.919986 -160.156906)
		(end 255.826768 -159.982662)
		(width 0.1397)
		(layer "In9.Cu")
		(net "PCIE_COMP_B_TO_SCC_B_0_DN")
	)
	(segment
		(start 284.255464 -116.314982)
		(end 284.317948 -116.190014)
		(width 0.1397)
		(layer "In9.Cu")
		(net "PCIE_COMP_B_TO_SCC_B_0_DN")
	)
	(segment
		(start 263.456166 -134.838186)
		(end 263.577832 -134.43712)
		(width 0.1397)
		(layer "In9.Cu")
		(net "PCIE_COMP_B_TO_SCC_B_0_DN")
	)
	(segment
		(start 271.697704 -120.514618)
		(end 271.65935 -120.320816)
		(width 0.1397)
		(layer "In9.Cu")
		(net "PCIE_COMP_B_TO_SCC_B_0_DN")
	)
	(segment
		(start 258.12496 -152.889458)
		(end 258.246626 -152.488392)
		(width 0.1397)
		(layer "In9.Cu")
		(net "PCIE_COMP_B_TO_SCC_B_0_DN")
	)
	(segment
		(start 202.94981 -393.006834)
		(end 208.204054 -369.295172)
		(width 0.1397)
		(layer "In9.Cu")
		(net "PCIE_COMP_B_TO_SCC_B_0_DN")
	)
	(segment
		(start 256.475738 -157.843728)
		(end 257.950716 -152.982422)
		(width 0.1397)
		(layer "In9.Cu")
		(net "PCIE_COMP_B_TO_SCC_B_0_DN")
	)
	(segment
		(start 264.522712 -131.804156)
		(end 264.429494 -131.629912)
		(width 0.1397)
		(layer "In9.Cu")
		(net "PCIE_COMP_B_TO_SCC_B_0_DN")
	)
	(arc
		(start 284.317948 -116.190014)
		(mid 284.398733 -116.119949)
		(end 284.5054 -116.12753)
		(width 0.1397)
		(layer "In9.Cu")
		(net "PCIE_COMP_B_TO_SCC_B_0_DN")
	)
	(arc
		(start 210.000088 -414.542224)
		(mid 209.938043 -414.692015)
		(end 209.788252 -414.75406)
		(width 0.1397)
		(layer "In9.Cu")
		(net "PCIE_COMP_B_TO_SCC_B_0_DN")
	)
	(arc
		(start 208.204054 -369.295172)
		(mid 208.207418 -369.264692)
		(end 208.204054 -369.234212)
		(width 0.1397)
		(layer "In9.Cu")
		(net "PCIE_COMP_B_TO_SCC_B_0_DN")
	)
	(arc
		(start 284.25521 -116.86921)
		(mid 284.140653 -116.607466)
		(end 284.234382 -116.337588)
		(width 0.1397)
		(layer "In9.Cu")
		(net "PCIE_COMP_B_TO_SCC_B_0_DN")
	)
	(arc
		(start 284.234382 -116.337588)
		(mid 284.244578 -116.326209)
		(end 284.25521 -116.315236)
		(width 0.1397)
		(layer "In9.Cu")
		(net "PCIE_COMP_B_TO_SCC_B_0_DN")
	)
	(segment
		(start 287.281112 -17.674336)
		(end 287.281112 -21.628608)
		(width 0.17145)
		(layer "F.Cu")
		(net "PCIE_COMP_B_TO_IOM_B_RST_4")
	)
	(segment
		(start 297.574208 -24.585676)
		(end 298.945808 -24.585676)
		(width 0.17145)
		(layer "F.Cu")
		(net "PCIE_COMP_B_TO_IOM_B_RST_4")
	)
	(segment
		(start 287.281112 -21.628608)
		(end 290.23818 -24.585676)
		(width 0.17145)
		(layer "F.Cu")
		(net "PCIE_COMP_B_TO_IOM_B_RST_4")
	)
	(segment
		(start 285.806896 -16.20012)
		(end 287.281112 -17.674336)
		(width 0.17145)
		(layer "F.Cu")
		(net "PCIE_COMP_B_TO_IOM_B_RST_4")
	)
	(segment
		(start 290.23818 -24.585676)
		(end 297.574208 -24.585676)
		(width 0.17145)
		(layer "F.Cu")
		(net "PCIE_COMP_B_TO_IOM_B_RST_4")
	)
	(segment
		(start 285.249874 -16.20012)
		(end 285.806896 -16.20012)
		(width 0.17145)
		(layer "F.Cu")
		(net "PCIE_COMP_B_TO_IOM_B_RST_4")
	)
	(segment
		(start 298.945808 -23.72106)
		(end 298.945808 -24.585676)
		(width 0.17145)
		(layer "F.Cu")
		(net "PCIE_COMP_B_TO_IOM_B_RST_4")
	)
	(via
		(at 297.574208 -24.585676)
		(size 0.6604)
		(drill 0.3302)
		(layers "F.Cu" "B.Cu")
		(net "PCIE_COMP_B_TO_IOM_B_RST_4")
	)
	(via
		(at 298.945808 -23.72106)
		(size 0.5588)
		(drill 0.3048)
		(layers "F.Cu" "B.Cu")
		(net "PCIE_COMP_B_TO_IOM_B_RST_4")
	)
	(segment
		(start 339.749384 -29.698188)
		(end 304.005996 -29.698188)
		(width 0.13335)
		(layer "In2.Cu")
		(net "PCIE_COMP_B_TO_IOM_B_RST_4")
	)
	(segment
		(start 340.378288 -30.327092)
		(end 339.749384 -29.698188)
		(width 0.13335)
		(layer "In2.Cu")
		(net "PCIE_COMP_B_TO_IOM_B_RST_4")
	)
	(segment
		(start 367.75009 -25.550114)
		(end 366.5728 -26.727404)
		(width 0.13335)
		(layer "In2.Cu")
		(net "PCIE_COMP_B_TO_IOM_B_RST_4")
	)
	(segment
		(start 298.945808 -24.638)
		(end 298.945808 -23.72106)
		(width 0.13335)
		(layer "In2.Cu")
		(net "PCIE_COMP_B_TO_IOM_B_RST_4")
	)
	(segment
		(start 366.5728 -26.727404)
		(end 366.5728 -30.840172)
		(width 0.13335)
		(layer "In2.Cu")
		(net "PCIE_COMP_B_TO_IOM_B_RST_4")
	)
	(segment
		(start 304.005996 -29.698188)
		(end 298.945808 -24.638)
		(width 0.13335)
		(layer "In2.Cu")
		(net "PCIE_COMP_B_TO_IOM_B_RST_4")
	)
	(segment
		(start 366.5728 -30.840172)
		(end 360.87939 -36.533582)
		(width 0.13335)
		(layer "In2.Cu")
		(net "PCIE_COMP_B_TO_IOM_B_RST_4")
	)
	(segment
		(start 352.628962 -36.533582)
		(end 346.422472 -30.327092)
		(width 0.13335)
		(layer "In2.Cu")
		(net "PCIE_COMP_B_TO_IOM_B_RST_4")
	)
	(segment
		(start 360.87939 -36.533582)
		(end 352.628962 -36.533582)
		(width 0.13335)
		(layer "In2.Cu")
		(net "PCIE_COMP_B_TO_IOM_B_RST_4")
	)
	(segment
		(start 346.422472 -30.327092)
		(end 340.378288 -30.327092)
		(width 0.13335)
		(layer "In2.Cu")
		(net "PCIE_COMP_B_TO_IOM_B_RST_4")
	)
	(segment
		(start 297.78325 -25.74544)
		(end 298.906946 -25.74544)
		(width 0.17145)
		(layer "F.Cu")
		(net "PCIE_COMP_B_TO_IOM_B_RST_3")
	)
	(segment
		(start 286.505904 -21.814536)
		(end 290.436808 -25.74544)
		(width 0.17145)
		(layer "F.Cu")
		(net "PCIE_COMP_B_TO_IOM_B_RST_3")
	)
	(segment
		(start 284.096206 -14.046454)
		(end 284.096206 -16.533876)
		(width 0.17145)
		(layer "F.Cu")
		(net "PCIE_COMP_B_TO_IOM_B_RST_3")
	)
	(segment
		(start 284.096206 -16.533876)
		(end 284.88005 -17.31772)
		(width 0.17145)
		(layer "F.Cu")
		(net "PCIE_COMP_B_TO_IOM_B_RST_3")
	)
	(segment
		(start 283.249878 -13.200126)
		(end 284.096206 -14.046454)
		(width 0.17145)
		(layer "F.Cu")
		(net "PCIE_COMP_B_TO_IOM_B_RST_3")
	)
	(segment
		(start 290.436808 -25.74544)
		(end 297.78325 -25.74544)
		(width 0.17145)
		(layer "F.Cu")
		(net "PCIE_COMP_B_TO_IOM_B_RST_3")
	)
	(segment
		(start 285.58363 -17.31772)
		(end 286.505904 -18.239994)
		(width 0.17145)
		(layer "F.Cu")
		(net "PCIE_COMP_B_TO_IOM_B_RST_3")
	)
	(segment
		(start 284.88005 -17.31772)
		(end 285.58363 -17.31772)
		(width 0.17145)
		(layer "F.Cu")
		(net "PCIE_COMP_B_TO_IOM_B_RST_3")
	)
	(segment
		(start 286.505904 -18.239994)
		(end 286.505904 -21.814536)
		(width 0.17145)
		(layer "F.Cu")
		(net "PCIE_COMP_B_TO_IOM_B_RST_3")
	)
	(segment
		(start 298.906946 -26.10612)
		(end 299.378624 -26.577798)
		(width 0.17145)
		(layer "F.Cu")
		(net "PCIE_COMP_B_TO_IOM_B_RST_3")
	)
	(segment
		(start 298.906946 -25.74544)
		(end 298.906946 -26.10612)
		(width 0.17145)
		(layer "F.Cu")
		(net "PCIE_COMP_B_TO_IOM_B_RST_3")
	)
	(via
		(at 297.78325 -25.74544)
		(size 0.6604)
		(drill 0.3302)
		(layers "F.Cu" "B.Cu")
		(net "PCIE_COMP_B_TO_IOM_B_RST_3")
	)
	(via
		(at 299.378624 -26.577798)
		(size 0.5588)
		(drill 0.3048)
		(layers "F.Cu" "B.Cu")
		(net "PCIE_COMP_B_TO_IOM_B_RST_3")
	)
	(segment
		(start 372.924578 -38.888416)
		(end 363.411262 -38.888416)
		(width 0.13335)
		(layer "In2.Cu")
		(net "PCIE_COMP_B_TO_IOM_B_RST_3")
	)
	(segment
		(start 304.199798 -31.398972)
		(end 299.378624 -26.577798)
		(width 0.13335)
		(layer "In2.Cu")
		(net "PCIE_COMP_B_TO_IOM_B_RST_3")
	)
	(segment
		(start 354.60178 -40.73398)
		(end 352.971354 -39.103554)
		(width 0.13335)
		(layer "In2.Cu")
		(net "PCIE_COMP_B_TO_IOM_B_RST_3")
	)
	(segment
		(start 382.150112 -25.550114)
		(end 380.978156 -26.72207)
		(width 0.13335)
		(layer "In2.Cu")
		(net "PCIE_COMP_B_TO_IOM_B_RST_3")
	)
	(segment
		(start 380.978156 -30.834838)
		(end 372.924578 -38.888416)
		(width 0.13335)
		(layer "In2.Cu")
		(net "PCIE_COMP_B_TO_IOM_B_RST_3")
	)
	(segment
		(start 342.856312 -31.398972)
		(end 304.199798 -31.398972)
		(width 0.13335)
		(layer "In2.Cu")
		(net "PCIE_COMP_B_TO_IOM_B_RST_3")
	)
	(segment
		(start 350.560894 -39.103554)
		(end 342.856312 -31.398972)
		(width 0.13335)
		(layer "In2.Cu")
		(net "PCIE_COMP_B_TO_IOM_B_RST_3")
	)
	(segment
		(start 363.411262 -38.888416)
		(end 361.565698 -40.73398)
		(width 0.13335)
		(layer "In2.Cu")
		(net "PCIE_COMP_B_TO_IOM_B_RST_3")
	)
	(segment
		(start 380.978156 -26.72207)
		(end 380.978156 -30.834838)
		(width 0.13335)
		(layer "In2.Cu")
		(net "PCIE_COMP_B_TO_IOM_B_RST_3")
	)
	(segment
		(start 361.565698 -40.73398)
		(end 354.60178 -40.73398)
		(width 0.13335)
		(layer "In2.Cu")
		(net "PCIE_COMP_B_TO_IOM_B_RST_3")
	)
	(segment
		(start 352.971354 -39.103554)
		(end 350.560894 -39.103554)
		(width 0.13335)
		(layer "In2.Cu")
		(net "PCIE_COMP_B_TO_IOM_B_RST_3")
	)
	(segment
		(start 309.950104 -117.344444)
		(end 309.950104 -92.331032)
		(width 0.17145)
		(layer "F.Cu")
		(net "PCIE_COMP_B_TO_IOM_B_RST_2")
	)
	(segment
		(start 298.91609 -155.240228)
		(end 298.15409 -155.240228)
		(width 0.17145)
		(layer "F.Cu")
		(net "PCIE_COMP_B_TO_IOM_B_RST_2")
	)
	(segment
		(start 403.6314 -29.209746)
		(end 403.6314 -37.145214)
		(width 0.17145)
		(layer "F.Cu")
		(net "PCIE_COMP_B_TO_IOM_B_RST_2")
	)
	(segment
		(start 319.649602 -82.631534)
		(end 393.834366 -82.631534)
		(width 0.17145)
		(layer "F.Cu")
		(net "PCIE_COMP_B_TO_IOM_B_RST_2")
	)
	(segment
		(start 291.86251 -147.658836)
		(end 285.249874 -141.0462)
		(width 0.17145)
		(layer "F.Cu")
		(net "PCIE_COMP_B_TO_IOM_B_RST_2")
	)
	(segment
		(start 285.249874 -140.499846)
		(end 286.794702 -140.499846)
		(width 0.17145)
		(layer "F.Cu")
		(net "PCIE_COMP_B_TO_IOM_B_RST_2")
	)
	(segment
		(start 403.6314 -72.8345)
		(end 403.6314 -37.145214)
		(width 0.17145)
		(layer "F.Cu")
		(net "PCIE_COMP_B_TO_IOM_B_RST_2")
	)
	(segment
		(start 399.971768 -25.550114)
		(end 403.6314 -29.209746)
		(width 0.17145)
		(layer "F.Cu")
		(net "PCIE_COMP_B_TO_IOM_B_RST_2")
	)
	(segment
		(start 285.249874 -141.0462)
		(end 285.249874 -140.499846)
		(width 0.17145)
		(layer "F.Cu")
		(net "PCIE_COMP_B_TO_IOM_B_RST_2")
	)
	(segment
		(start 298.15409 -155.240228)
		(end 291.86251 -148.948648)
		(width 0.17145)
		(layer "F.Cu")
		(net "PCIE_COMP_B_TO_IOM_B_RST_2")
	)
	(segment
		(start 393.834366 -82.631534)
		(end 403.6314 -72.8345)
		(width 0.17145)
		(layer "F.Cu")
		(net "PCIE_COMP_B_TO_IOM_B_RST_2")
	)
	(segment
		(start 389.349996 -25.550114)
		(end 399.971768 -25.550114)
		(width 0.17145)
		(layer "F.Cu")
		(net "PCIE_COMP_B_TO_IOM_B_RST_2")
	)
	(segment
		(start 309.950104 -92.331032)
		(end 319.649602 -82.631534)
		(width 0.17145)
		(layer "F.Cu")
		(net "PCIE_COMP_B_TO_IOM_B_RST_2")
	)
	(segment
		(start 286.794702 -140.499846)
		(end 309.950104 -117.344444)
		(width 0.17145)
		(layer "F.Cu")
		(net "PCIE_COMP_B_TO_IOM_B_RST_2")
	)
	(segment
		(start 291.86251 -148.948648)
		(end 291.86251 -147.658836)
		(width 0.17145)
		(layer "F.Cu")
		(net "PCIE_COMP_B_TO_IOM_B_RST_2")
	)
	(via
		(at 403.6314 -37.145214)
		(size 0.6604)
		(drill 0.3302)
		(layers "F.Cu" "B.Cu")
		(net "PCIE_COMP_B_TO_IOM_B_RST_2")
	)
	(segment
		(start 291.877496 -23.565866)
		(end 287.296098 -16.511524)
		(width 0.127)
		(layer "In7.Cu")
		(net "PCIE_COMP_B_TO_IOM_B_CLK_4_DP")
	)
	(segment
		(start 286.369252 -15.084298)
		(end 286.161734 -14.764766)
		(width 0.127)
		(layer "In7.Cu")
		(net "PCIE_COMP_B_TO_IOM_B_CLK_4_DP")
	)
	(segment
		(start 315.639958 -30.801818)
		(end 310.847232 -29.738574)
		(width 0.127)
		(layer "In7.Cu")
		(net "PCIE_COMP_B_TO_IOM_B_CLK_4_DP")
	)
	(segment
		(start 306.05476 -28.67533)
		(end 296.470324 -26.549096)
		(width 0.127)
		(layer "In7.Cu")
		(net "PCIE_COMP_B_TO_IOM_B_CLK_4_DP")
	)
	(segment
		(start 286.770064 -15.444978)
		(end 286.562546 -15.125446)
		(width 0.127)
		(layer "In7.Cu")
		(net "PCIE_COMP_B_TO_IOM_B_CLK_4_DP")
	)
	(segment
		(start 286.562546 -15.125446)
		(end 286.369252 -15.084298)
		(width 0.127)
		(layer "In7.Cu")
		(net "PCIE_COMP_B_TO_IOM_B_CLK_4_DP")
	)
	(segment
		(start 287.296098 -16.511524)
		(end 287.337246 -16.31823)
		(width 0.127)
		(layer "In7.Cu")
		(net "PCIE_COMP_B_TO_IOM_B_CLK_4_DP")
	)
	(segment
		(start 365.21898 -32.069024)
		(end 359.948734 -33.225994)
		(width 0.127)
		(layer "In7.Cu")
		(net "PCIE_COMP_B_TO_IOM_B_CLK_4_DP")
	)
	(segment
		(start 285.59379 -13.890244)
		(end 283.763974 -12.060428)
		(width 0.127)
		(layer "In7.Cu")
		(net "PCIE_COMP_B_TO_IOM_B_CLK_4_DP")
	)
	(segment
		(start 286.202882 -14.571472)
		(end 285.995364 -14.25194)
		(width 0.127)
		(layer "In7.Cu")
		(net "PCIE_COMP_B_TO_IOM_B_CLK_4_DP")
	)
	(segment
		(start 359.948734 -33.225994)
		(end 332.2955 -27.522424)
		(width 0.127)
		(layer "In7.Cu")
		(net "PCIE_COMP_B_TO_IOM_B_CLK_4_DP")
	)
	(segment
		(start 366.710214 -30.164278)
		(end 366.710214 -30.903672)
		(width 0.127)
		(layer "In7.Cu")
		(net "PCIE_COMP_B_TO_IOM_B_CLK_4_DP")
	)
	(segment
		(start 367.62309 -29.679138)
		(end 367.195354 -29.679138)
		(width 0.127)
		(layer "In7.Cu")
		(net "PCIE_COMP_B_TO_IOM_B_CLK_4_DP")
	)
	(segment
		(start 285.995364 -14.25194)
		(end 285.80207 -14.211046)
		(width 0.127)
		(layer "In7.Cu")
		(net "PCIE_COMP_B_TO_IOM_B_CLK_4_DP")
	)
	(segment
		(start 283.763974 -12.060428)
		(end 280.463752 -12.060428)
		(width 0.127)
		(layer "In7.Cu")
		(net "PCIE_COMP_B_TO_IOM_B_CLK_4_DP")
	)
	(segment
		(start 310.847232 -29.738574)
		(end 306.05476 -28.67533)
		(width 0.127)
		(layer "In7.Cu")
		(net "PCIE_COMP_B_TO_IOM_B_CLK_4_DP")
	)
	(segment
		(start 367.75009 -29.150056)
		(end 367.75009 -29.552138)
		(width 0.127)
		(layer "In7.Cu")
		(net "PCIE_COMP_B_TO_IOM_B_CLK_4_DP")
	)
	(segment
		(start 286.728916 -15.638272)
		(end 286.770064 -15.444978)
		(width 0.127)
		(layer "In7.Cu")
		(net "PCIE_COMP_B_TO_IOM_B_CLK_4_DP")
	)
	(segment
		(start 287.129728 -15.998698)
		(end 286.936434 -15.957804)
		(width 0.127)
		(layer "In7.Cu")
		(net "PCIE_COMP_B_TO_IOM_B_CLK_4_DP")
	)
	(segment
		(start 280.086054 -11.903964)
		(end 279.963118 -11.781028)
		(width 0.127)
		(layer "In7.Cu")
		(net "PCIE_COMP_B_TO_IOM_B_CLK_4_DP")
	)
	(segment
		(start 296.470324 -26.549096)
		(end 291.877496 -23.565866)
		(width 0.127)
		(layer "In7.Cu")
		(net "PCIE_COMP_B_TO_IOM_B_CLK_4_DP")
	)
	(segment
		(start 280.006044 -11.572748)
		(end 280.75001 -11.20013)
		(width 0.127)
		(layer "In7.Cu")
		(net "PCIE_COMP_B_TO_IOM_B_CLK_4_DP")
	)
	(segment
		(start 287.337246 -16.31823)
		(end 287.129728 -15.998698)
		(width 0.127)
		(layer "In7.Cu")
		(net "PCIE_COMP_B_TO_IOM_B_CLK_4_DP")
	)
	(segment
		(start 279.996138 -11.577828)
		(end 280.006044 -11.572748)
		(width 0.127)
		(layer "In7.Cu")
		(net "PCIE_COMP_B_TO_IOM_B_CLK_4_DP")
	)
	(segment
		(start 286.161734 -14.764766)
		(end 286.202882 -14.571472)
		(width 0.127)
		(layer "In7.Cu")
		(net "PCIE_COMP_B_TO_IOM_B_CLK_4_DP")
	)
	(segment
		(start 286.936434 -15.957804)
		(end 286.728916 -15.638272)
		(width 0.127)
		(layer "In7.Cu")
		(net "PCIE_COMP_B_TO_IOM_B_CLK_4_DP")
	)
	(segment
		(start 332.2955 -27.522424)
		(end 315.639958 -30.801818)
		(width 0.127)
		(layer "In7.Cu")
		(net "PCIE_COMP_B_TO_IOM_B_CLK_4_DP")
	)
	(segment
		(start 285.80207 -14.211046)
		(end 285.59379 -13.890244)
		(width 0.127)
		(layer "In7.Cu")
		(net "PCIE_COMP_B_TO_IOM_B_CLK_4_DP")
	)
	(segment
		(start 366.710214 -30.903672)
		(end 366.487456 -31.23057)
		(width 0.127)
		(layer "In7.Cu")
		(net "PCIE_COMP_B_TO_IOM_B_CLK_4_DP")
	)
	(segment
		(start 366.487456 -31.23057)
		(end 365.21898 -32.069024)
		(width 0.127)
		(layer "In7.Cu")
		(net "PCIE_COMP_B_TO_IOM_B_CLK_4_DP")
	)
	(arc
		(start 280.463752 -12.060428)
		(mid 280.259337 -12.019767)
		(end 280.086054 -11.903964)
		(width 0.127)
		(layer "In7.Cu")
		(net "PCIE_COMP_B_TO_IOM_B_CLK_4_DP")
	)
	(arc
		(start 279.963118 -11.781028)
		(mid 279.927698 -11.670993)
		(end 279.996138 -11.577828)
		(width 0.127)
		(layer "In7.Cu")
		(net "PCIE_COMP_B_TO_IOM_B_CLK_4_DP")
	)
	(arc
		(start 367.75009 -29.552138)
		(mid 367.712893 -29.641941)
		(end 367.62309 -29.679138)
		(width 0.127)
		(layer "In7.Cu")
		(net "PCIE_COMP_B_TO_IOM_B_CLK_4_DP")
	)
	(arc
		(start 367.195354 -29.679138)
		(mid 366.852308 -29.821232)
		(end 366.710214 -30.164278)
		(width 0.127)
		(layer "In7.Cu")
		(net "PCIE_COMP_B_TO_IOM_B_CLK_4_DP")
	)
	(segment
		(start 283.64815 -12.339828)
		(end 280.463498 -12.339828)
		(width 0.127)
		(layer "In7.Cu")
		(net "PCIE_COMP_B_TO_IOM_B_CLK_4_DN")
	)
	(segment
		(start 366.687608 -31.433516)
		(end 365.329724 -32.330898)
		(width 0.127)
		(layer "In7.Cu")
		(net "PCIE_COMP_B_TO_IOM_B_CLK_4_DN")
	)
	(segment
		(start 296.360342 -26.811224)
		(end 291.675312 -23.76805)
		(width 0.127)
		(layer "In7.Cu")
		(net "PCIE_COMP_B_TO_IOM_B_CLK_4_DN")
	)
	(segment
		(start 332.29423 -27.807666)
		(end 315.636656 -31.087314)
		(width 0.127)
		(layer "In7.Cu")
		(net "PCIE_COMP_B_TO_IOM_B_CLK_4_DN")
	)
	(segment
		(start 366.989614 -30.164278)
		(end 366.989614 -30.990032)
		(width 0.127)
		(layer "In7.Cu")
		(net "PCIE_COMP_B_TO_IOM_B_CLK_4_DN")
	)
	(segment
		(start 366.989614 -30.990032)
		(end 366.687608 -31.433516)
		(width 0.127)
		(layer "In7.Cu")
		(net "PCIE_COMP_B_TO_IOM_B_CLK_4_DN")
	)
	(segment
		(start 291.675312 -23.76805)
		(end 285.37535 -14.067028)
		(width 0.127)
		(layer "In7.Cu")
		(net "PCIE_COMP_B_TO_IOM_B_CLK_4_DN")
	)
	(segment
		(start 285.37535 -14.067028)
		(end 283.64815 -12.339828)
		(width 0.127)
		(layer "In7.Cu")
		(net "PCIE_COMP_B_TO_IOM_B_CLK_4_DN")
	)
	(segment
		(start 359.950512 -33.511744)
		(end 332.29423 -27.807666)
		(width 0.127)
		(layer "In7.Cu")
		(net "PCIE_COMP_B_TO_IOM_B_CLK_4_DN")
	)
	(segment
		(start 279.475946 -11.836654)
		(end 278.750014 -12.200128)
		(width 0.127)
		(layer "In7.Cu")
		(net "PCIE_COMP_B_TO_IOM_B_CLK_4_DN")
	)
	(segment
		(start 279.888442 -12.101576)
		(end 279.651968 -11.865102)
		(width 0.127)
		(layer "In7.Cu")
		(net "PCIE_COMP_B_TO_IOM_B_CLK_4_DN")
	)
	(segment
		(start 315.636656 -31.087314)
		(end 296.360342 -26.811224)
		(width 0.127)
		(layer "In7.Cu")
		(net "PCIE_COMP_B_TO_IOM_B_CLK_4_DN")
	)
	(segment
		(start 365.329724 -32.330898)
		(end 359.950512 -33.511744)
		(width 0.127)
		(layer "In7.Cu")
		(net "PCIE_COMP_B_TO_IOM_B_CLK_4_DN")
	)
	(segment
		(start 367.75009 -30.550104)
		(end 367.75009 -30.085538)
		(width 0.127)
		(layer "In7.Cu")
		(net "PCIE_COMP_B_TO_IOM_B_CLK_4_DN")
	)
	(segment
		(start 367.62309 -29.958538)
		(end 367.195354 -29.958538)
		(width 0.127)
		(layer "In7.Cu")
		(net "PCIE_COMP_B_TO_IOM_B_CLK_4_DN")
	)
	(arc
		(start 279.651968 -11.865102)
		(mid 279.568556 -11.822441)
		(end 279.475946 -11.836654)
		(width 0.127)
		(layer "In7.Cu")
		(net "PCIE_COMP_B_TO_IOM_B_CLK_4_DN")
	)
	(arc
		(start 367.75009 -30.085538)
		(mid 367.712893 -29.995735)
		(end 367.62309 -29.958538)
		(width 0.127)
		(layer "In7.Cu")
		(net "PCIE_COMP_B_TO_IOM_B_CLK_4_DN")
	)
	(arc
		(start 280.463498 -12.339828)
		(mid 280.152298 -12.277851)
		(end 279.888442 -12.101576)
		(width 0.127)
		(layer "In7.Cu")
		(net "PCIE_COMP_B_TO_IOM_B_CLK_4_DN")
	)
	(arc
		(start 367.195354 -29.958538)
		(mid 367.049874 -30.018798)
		(end 366.989614 -30.164278)
		(width 0.127)
		(layer "In7.Cu")
		(net "PCIE_COMP_B_TO_IOM_B_CLK_4_DN")
	)
	(segment
		(start 302.610266 -31.754064)
		(end 285.85287 -35.0774)
		(width 0.127)
		(layer "In7.Cu")
		(net "PCIE_COMP_B_TO_IOM_B_CLK_3_DP")
	)
	(segment
		(start 382.150112 -29.150056)
		(end 382.150112 -29.552138)
		(width 0.127)
		(layer "In7.Cu")
		(net "PCIE_COMP_B_TO_IOM_B_CLK_3_DP")
	)
	(segment
		(start 310.81853 -33.452562)
		(end 302.610266 -31.754064)
		(width 0.127)
		(layer "In7.Cu")
		(net "PCIE_COMP_B_TO_IOM_B_CLK_3_DP")
	)
	(segment
		(start 382.023112 -29.679138)
		(end 381.595376 -29.679138)
		(width 0.127)
		(layer "In7.Cu")
		(net "PCIE_COMP_B_TO_IOM_B_CLK_3_DP")
	)
	(segment
		(start 381.110236 -30.164278)
		(end 381.110236 -30.960822)
		(width 0.127)
		(layer "In7.Cu")
		(net "PCIE_COMP_B_TO_IOM_B_CLK_3_DP")
	)
	(segment
		(start 363.919262 -35.52444)
		(end 332.817724 -29.08935)
		(width 0.127)
		(layer "In7.Cu")
		(net "PCIE_COMP_B_TO_IOM_B_CLK_3_DP")
	)
	(segment
		(start 380.149862 -31.95066)
		(end 363.919262 -35.52444)
		(width 0.127)
		(layer "In7.Cu")
		(net "PCIE_COMP_B_TO_IOM_B_CLK_3_DP")
	)
	(segment
		(start 284.264354 -35.359086)
		(end 284.187392 -35.512248)
		(width 0.127)
		(layer "In7.Cu")
		(net "PCIE_COMP_B_TO_IOM_B_CLK_3_DP")
	)
	(segment
		(start 332.817724 -29.08935)
		(end 310.81853 -33.452562)
		(width 0.127)
		(layer "In7.Cu")
		(net "PCIE_COMP_B_TO_IOM_B_CLK_3_DP")
	)
	(segment
		(start 283.999178 -35.57524)
		(end 283.249878 -35.200082)
		(width 0.127)
		(layer "In7.Cu")
		(net "PCIE_COMP_B_TO_IOM_B_CLK_3_DP")
	)
	(segment
		(start 380.663704 -31.616904)
		(end 380.149862 -31.95066)
		(width 0.127)
		(layer "In7.Cu")
		(net "PCIE_COMP_B_TO_IOM_B_CLK_3_DP")
	)
	(segment
		(start 285.85287 -35.0774)
		(end 284.7213 -35.0774)
		(width 0.127)
		(layer "In7.Cu")
		(net "PCIE_COMP_B_TO_IOM_B_CLK_3_DP")
	)
	(segment
		(start 381.110236 -30.960822)
		(end 380.663704 -31.616904)
		(width 0.127)
		(layer "In7.Cu")
		(net "PCIE_COMP_B_TO_IOM_B_CLK_3_DP")
	)
	(arc
		(start 381.595376 -29.679138)
		(mid 381.25233 -29.821232)
		(end 381.110236 -30.164278)
		(width 0.127)
		(layer "In7.Cu")
		(net "PCIE_COMP_B_TO_IOM_B_CLK_3_DP")
	)
	(arc
		(start 284.7213 -35.0774)
		(mid 284.452928 -35.153494)
		(end 284.264354 -35.359086)
		(width 0.127)
		(layer "In7.Cu")
		(net "PCIE_COMP_B_TO_IOM_B_CLK_3_DP")
	)
	(arc
		(start 382.150112 -29.552138)
		(mid 382.112915 -29.641941)
		(end 382.023112 -29.679138)
		(width 0.127)
		(layer "In7.Cu")
		(net "PCIE_COMP_B_TO_IOM_B_CLK_3_DP")
	)
	(arc
		(start 284.187392 -35.512248)
		(mid 284.106368 -35.582837)
		(end 283.999178 -35.57524)
		(width 0.127)
		(layer "In7.Cu")
		(net "PCIE_COMP_B_TO_IOM_B_CLK_3_DP")
	)
	(segment
		(start 381.389636 -31.046928)
		(end 380.863094 -31.820612)
		(width 0.127)
		(layer "In7.Cu")
		(net "PCIE_COMP_B_TO_IOM_B_CLK_3_DN")
	)
	(segment
		(start 284.488636 -35.818826)
		(end 285.249874 -36.20008)
		(width 0.127)
		(layer "In7.Cu")
		(net "PCIE_COMP_B_TO_IOM_B_CLK_3_DN")
	)
	(segment
		(start 381.389636 -30.164278)
		(end 381.389636 -31.046928)
		(width 0.127)
		(layer "In7.Cu")
		(net "PCIE_COMP_B_TO_IOM_B_CLK_3_DN")
	)
	(segment
		(start 284.47365 -35.565334)
		(end 284.431994 -35.648392)
		(width 0.127)
		(layer "In7.Cu")
		(net "PCIE_COMP_B_TO_IOM_B_CLK_3_DN")
	)
	(segment
		(start 289.84575 -34.570416)
		(end 285.880556 -35.3568)
		(width 0.127)
		(layer "In7.Cu")
		(net "PCIE_COMP_B_TO_IOM_B_CLK_3_DN")
	)
	(segment
		(start 285.880556 -35.3568)
		(end 284.736286 -35.3568)
		(width 0.127)
		(layer "In7.Cu")
		(net "PCIE_COMP_B_TO_IOM_B_CLK_3_DN")
	)
	(segment
		(start 332.816454 -29.374592)
		(end 310.81726 -33.737804)
		(width 0.127)
		(layer "In7.Cu")
		(net "PCIE_COMP_B_TO_IOM_B_CLK_3_DN")
	)
	(segment
		(start 382.023112 -29.958538)
		(end 381.595376 -29.958538)
		(width 0.127)
		(layer "In7.Cu")
		(net "PCIE_COMP_B_TO_IOM_B_CLK_3_DN")
	)
	(segment
		(start 290.383722 -34.60623)
		(end 290.010088 -34.680398)
		(width 0.127)
		(layer "In7.Cu")
		(net "PCIE_COMP_B_TO_IOM_B_CLK_3_DN")
	)
	(segment
		(start 290.010088 -34.680398)
		(end 289.84575 -34.570416)
		(width 0.127)
		(layer "In7.Cu")
		(net "PCIE_COMP_B_TO_IOM_B_CLK_3_DN")
	)
	(segment
		(start 310.81726 -33.737804)
		(end 306.65801 -32.877506)
		(width 0.127)
		(layer "In7.Cu")
		(net "PCIE_COMP_B_TO_IOM_B_CLK_3_DN")
	)
	(segment
		(start 382.150112 -30.550104)
		(end 382.150112 -30.085538)
		(width 0.127)
		(layer "In7.Cu")
		(net "PCIE_COMP_B_TO_IOM_B_CLK_3_DN")
	)
	(segment
		(start 380.25959 -32.212788)
		(end 363.92104 -35.81019)
		(width 0.127)
		(layer "In7.Cu")
		(net "PCIE_COMP_B_TO_IOM_B_CLK_3_DN")
	)
	(segment
		(start 302.608996 -32.039306)
		(end 291.515038 -34.239454)
		(width 0.127)
		(layer "In7.Cu")
		(net "PCIE_COMP_B_TO_IOM_B_CLK_3_DN")
	)
	(segment
		(start 284.50794 -35.497516)
		(end 284.473904 -35.56508)
		(width 0.127)
		(layer "In7.Cu")
		(net "PCIE_COMP_B_TO_IOM_B_CLK_3_DN")
	)
	(segment
		(start 284.473904 -35.56508)
		(end 284.473904 -35.565334)
		(width 0.127)
		(layer "In7.Cu")
		(net "PCIE_COMP_B_TO_IOM_B_CLK_3_DN")
	)
	(segment
		(start 380.863094 -31.820612)
		(end 380.25959 -32.212788)
		(width 0.127)
		(layer "In7.Cu")
		(net "PCIE_COMP_B_TO_IOM_B_CLK_3_DN")
	)
	(segment
		(start 340.56447 -30.97784)
		(end 332.816454 -29.374592)
		(width 0.127)
		(layer "In7.Cu")
		(net "PCIE_COMP_B_TO_IOM_B_CLK_3_DN")
	)
	(segment
		(start 290.493704 -34.441892)
		(end 290.383722 -34.60623)
		(width 0.127)
		(layer "In7.Cu")
		(net "PCIE_COMP_B_TO_IOM_B_CLK_3_DN")
	)
	(segment
		(start 363.92104 -35.81019)
		(end 340.56447 -30.97784)
		(width 0.127)
		(layer "In7.Cu")
		(net "PCIE_COMP_B_TO_IOM_B_CLK_3_DN")
	)
	(segment
		(start 291.031422 -34.477706)
		(end 290.867338 -34.367978)
		(width 0.127)
		(layer "In7.Cu")
		(net "PCIE_COMP_B_TO_IOM_B_CLK_3_DN")
	)
	(segment
		(start 306.65801 -32.877506)
		(end 302.608996 -32.039306)
		(width 0.127)
		(layer "In7.Cu")
		(net "PCIE_COMP_B_TO_IOM_B_CLK_3_DN")
	)
	(segment
		(start 284.473904 -35.565334)
		(end 284.47365 -35.565334)
		(width 0.127)
		(layer "In7.Cu")
		(net "PCIE_COMP_B_TO_IOM_B_CLK_3_DN")
	)
	(segment
		(start 291.40531 -34.403538)
		(end 291.031422 -34.477706)
		(width 0.127)
		(layer "In7.Cu")
		(net "PCIE_COMP_B_TO_IOM_B_CLK_3_DN")
	)
	(segment
		(start 291.515038 -34.239454)
		(end 291.40531 -34.403538)
		(width 0.127)
		(layer "In7.Cu")
		(net "PCIE_COMP_B_TO_IOM_B_CLK_3_DN")
	)
	(segment
		(start 290.867338 -34.367978)
		(end 290.493704 -34.441892)
		(width 0.127)
		(layer "In7.Cu")
		(net "PCIE_COMP_B_TO_IOM_B_CLK_3_DN")
	)
	(arc
		(start 381.595376 -29.958538)
		(mid 381.449896 -30.018798)
		(end 381.389636 -30.164278)
		(width 0.127)
		(layer "In7.Cu")
		(net "PCIE_COMP_B_TO_IOM_B_CLK_3_DN")
	)
	(arc
		(start 284.431994 -35.648392)
		(mid 284.425017 -35.74534)
		(end 284.488636 -35.818826)
		(width 0.127)
		(layer "In7.Cu")
		(net "PCIE_COMP_B_TO_IOM_B_CLK_3_DN")
	)
	(arc
		(start 382.150112 -30.085538)
		(mid 382.112915 -29.995735)
		(end 382.023112 -29.958538)
		(width 0.127)
		(layer "In7.Cu")
		(net "PCIE_COMP_B_TO_IOM_B_CLK_3_DN")
	)
	(arc
		(start 284.736286 -35.3568)
		(mid 284.602154 -35.394791)
		(end 284.50794 -35.497516)
		(width 0.127)
		(layer "In7.Cu")
		(net "PCIE_COMP_B_TO_IOM_B_CLK_3_DN")
	)
	(segment
		(start 336.668364 -39.188136)
		(end 332.091792 -37.351716)
		(width 0.1651)
		(layer "F.Cu")
		(net "PCIE_COMP_B_TO_IOM_B_CLK_2_DP")
	)
	(segment
		(start 389.349996 -29.150056)
		(end 389.349996 -29.57703)
		(width 0.1651)
		(layer "F.Cu")
		(net "PCIE_COMP_B_TO_IOM_B_CLK_2_DP")
	)
	(segment
		(start 288.369248 -135.291576)
		(end 288.078672 -135.692642)
		(width 0.1651)
		(layer "F.Cu")
		(net "PCIE_COMP_B_TO_IOM_B_CLK_2_DP")
	)
	(segment
		(start 388.30377 -30.367478)
		(end 388.30377 -31.41218)
		(width 0.1651)
		(layer "F.Cu")
		(net "PCIE_COMP_B_TO_IOM_B_CLK_2_DP")
	)
	(segment
		(start 316.821312 -39.656258)
		(end 314.044076 -44.015914)
		(width 0.1651)
		(layer "F.Cu")
		(net "PCIE_COMP_B_TO_IOM_B_CLK_2_DP")
	)
	(segment
		(start 289.920934 -133.326124)
		(end 289.775392 -133.349492)
		(width 0.1651)
		(layer "F.Cu")
		(net "PCIE_COMP_B_TO_IOM_B_CLK_2_DP")
	)
	(segment
		(start 353.948746 -33.36417)
		(end 341.37219 -38.34638)
		(width 0.1651)
		(layer "F.Cu")
		(net "PCIE_COMP_B_TO_IOM_B_CLK_2_DP")
	)
	(segment
		(start 308.19471 -75.915012)
		(end 297.58513 -122.74169)
		(width 0.1651)
		(layer "F.Cu")
		(net "PCIE_COMP_B_TO_IOM_B_CLK_2_DP")
	)
	(segment
		(start 289.07232 -134.320534)
		(end 288.781744 -134.7216)
		(width 0.1651)
		(layer "F.Cu")
		(net "PCIE_COMP_B_TO_IOM_B_CLK_2_DP")
	)
	(segment
		(start 288.078672 -135.692642)
		(end 288.10204 -135.838184)
		(width 0.1651)
		(layer "F.Cu")
		(net "PCIE_COMP_B_TO_IOM_B_CLK_2_DP")
	)
	(segment
		(start 305.916838 -64.007746)
		(end 308.19471 -75.915012)
		(width 0.1651)
		(layer "F.Cu")
		(net "PCIE_COMP_B_TO_IOM_B_CLK_2_DP")
	)
	(segment
		(start 339.02015 -38.767258)
		(end 336.668364 -39.188136)
		(width 0.1651)
		(layer "F.Cu")
		(net "PCIE_COMP_B_TO_IOM_B_CLK_2_DP")
	)
	(segment
		(start 280.018236 -138.17092)
		(end 279.954482 -138.083036)
		(width 0.1651)
		(layer "F.Cu")
		(net "PCIE_COMP_B_TO_IOM_B_CLK_2_DP")
	)
	(segment
		(start 314.044076 -44.015914)
		(end 308.462172 -52.777644)
		(width 0.1651)
		(layer "F.Cu")
		(net "PCIE_COMP_B_TO_IOM_B_CLK_2_DP")
	)
	(segment
		(start 279.954482 -138.083036)
		(end 279.954482 -138.082528)
		(width 0.1651)
		(layer "F.Cu")
		(net "PCIE_COMP_B_TO_IOM_B_CLK_2_DP")
	)
	(segment
		(start 290.478718 -132.37845)
		(end 290.188142 -132.779516)
		(width 0.1651)
		(layer "F.Cu")
		(net "PCIE_COMP_B_TO_IOM_B_CLK_2_DP")
	)
	(segment
		(start 297.58513 -122.74169)
		(end 290.624006 -132.355082)
		(width 0.1651)
		(layer "F.Cu")
		(net "PCIE_COMP_B_TO_IOM_B_CLK_2_DP")
	)
	(segment
		(start 290.188142 -132.779516)
		(end 290.21151 -132.925058)
		(width 0.1651)
		(layer "F.Cu")
		(net "PCIE_COMP_B_TO_IOM_B_CLK_2_DP")
	)
	(segment
		(start 322.156582 -33.659318)
		(end 319.6336 -35.241738)
		(width 0.1651)
		(layer "F.Cu")
		(net "PCIE_COMP_B_TO_IOM_B_CLK_2_DP")
	)
	(segment
		(start 341.37219 -38.34638)
		(end 339.02015 -38.767258)
		(width 0.1651)
		(layer "F.Cu")
		(net "PCIE_COMP_B_TO_IOM_B_CLK_2_DP")
	)
	(segment
		(start 319.6336 -35.241738)
		(end 316.821312 -39.656258)
		(width 0.1651)
		(layer "F.Cu")
		(net "PCIE_COMP_B_TO_IOM_B_CLK_2_DP")
	)
	(segment
		(start 289.217862 -134.297166)
		(end 289.07232 -134.320534)
		(width 0.1651)
		(layer "F.Cu")
		(net "PCIE_COMP_B_TO_IOM_B_CLK_2_DP")
	)
	(segment
		(start 388.30377 -31.41218)
		(end 386.35178 -33.36417)
		(width 0.1651)
		(layer "F.Cu")
		(net "PCIE_COMP_B_TO_IOM_B_CLK_2_DP")
	)
	(segment
		(start 288.781744 -134.7216)
		(end 288.805112 -134.867142)
		(width 0.1651)
		(layer "F.Cu")
		(net "PCIE_COMP_B_TO_IOM_B_CLK_2_DP")
	)
	(segment
		(start 306.560474 -61.168026)
		(end 305.916838 -64.007746)
		(width 0.1651)
		(layer "F.Cu")
		(net "PCIE_COMP_B_TO_IOM_B_CLK_2_DP")
	)
	(segment
		(start 289.508184 -133.8961)
		(end 289.217862 -134.297166)
		(width 0.1651)
		(layer "F.Cu")
		(net "PCIE_COMP_B_TO_IOM_B_CLK_2_DP")
	)
	(segment
		(start 329.262486 -33.659318)
		(end 322.156582 -33.659318)
		(width 0.1651)
		(layer "F.Cu")
		(net "PCIE_COMP_B_TO_IOM_B_CLK_2_DP")
	)
	(segment
		(start 389.222996 -29.70403)
		(end 388.967218 -29.70403)
		(width 0.1651)
		(layer "F.Cu")
		(net "PCIE_COMP_B_TO_IOM_B_CLK_2_DP")
	)
	(segment
		(start 288.514536 -135.268208)
		(end 288.369248 -135.291576)
		(width 0.1651)
		(layer "F.Cu")
		(net "PCIE_COMP_B_TO_IOM_B_CLK_2_DP")
	)
	(segment
		(start 290.624006 -132.355082)
		(end 290.478718 -132.37845)
		(width 0.1651)
		(layer "F.Cu")
		(net "PCIE_COMP_B_TO_IOM_B_CLK_2_DP")
	)
	(segment
		(start 280.03246 -138.190224)
		(end 280.031952 -138.189462)
		(width 0.1651)
		(layer "F.Cu")
		(net "PCIE_COMP_B_TO_IOM_B_CLK_2_DP")
	)
	(segment
		(start 283.682948 -138.3538)
		(end 280.221182 -138.3538)
		(width 0.1651)
		(layer "F.Cu")
		(net "PCIE_COMP_B_TO_IOM_B_CLK_2_DP")
	)
	(segment
		(start 287.811464 -136.23925)
		(end 286.203898 -137.353802)
		(width 0.1651)
		(layer "F.Cu")
		(net "PCIE_COMP_B_TO_IOM_B_CLK_2_DP")
	)
	(segment
		(start 288.10204 -135.838184)
		(end 287.811464 -136.23925)
		(width 0.1651)
		(layer "F.Cu")
		(net "PCIE_COMP_B_TO_IOM_B_CLK_2_DP")
	)
	(segment
		(start 280.018744 -138.171174)
		(end 280.018236 -138.17092)
		(width 0.1651)
		(layer "F.Cu")
		(net "PCIE_COMP_B_TO_IOM_B_CLK_2_DP")
	)
	(segment
		(start 332.091792 -37.351716)
		(end 329.262486 -33.659318)
		(width 0.1651)
		(layer "F.Cu")
		(net "PCIE_COMP_B_TO_IOM_B_CLK_2_DP")
	)
	(segment
		(start 286.203898 -137.353802)
		(end 284.682946 -137.353802)
		(width 0.1651)
		(layer "F.Cu")
		(net "PCIE_COMP_B_TO_IOM_B_CLK_2_DP")
	)
	(segment
		(start 284.682946 -137.353802)
		(end 283.682948 -138.3538)
		(width 0.1651)
		(layer "F.Cu")
		(net "PCIE_COMP_B_TO_IOM_B_CLK_2_DP")
	)
	(segment
		(start 280.031952 -138.189462)
		(end 280.018744 -138.171174)
		(width 0.1651)
		(layer "F.Cu")
		(net "PCIE_COMP_B_TO_IOM_B_CLK_2_DP")
	)
	(segment
		(start 288.805112 -134.867142)
		(end 288.514536 -135.268208)
		(width 0.1651)
		(layer "F.Cu")
		(net "PCIE_COMP_B_TO_IOM_B_CLK_2_DP")
	)
	(segment
		(start 280.028142 -137.86104)
		(end 280.75001 -137.499852)
		(width 0.1651)
		(layer "F.Cu")
		(net "PCIE_COMP_B_TO_IOM_B_CLK_2_DP")
	)
	(segment
		(start 308.462172 -52.777644)
		(end 306.560474 -61.168026)
		(width 0.1651)
		(layer "F.Cu")
		(net "PCIE_COMP_B_TO_IOM_B_CLK_2_DP")
	)
	(segment
		(start 289.775392 -133.349492)
		(end 289.48507 -133.750558)
		(width 0.1651)
		(layer "F.Cu")
		(net "PCIE_COMP_B_TO_IOM_B_CLK_2_DP")
	)
	(segment
		(start 290.21151 -132.925058)
		(end 289.920934 -133.326124)
		(width 0.1651)
		(layer "F.Cu")
		(net "PCIE_COMP_B_TO_IOM_B_CLK_2_DP")
	)
	(segment
		(start 386.35178 -33.36417)
		(end 353.948746 -33.36417)
		(width 0.1651)
		(layer "F.Cu")
		(net "PCIE_COMP_B_TO_IOM_B_CLK_2_DP")
	)
	(segment
		(start 280.109422 -138.29665)
		(end 280.03246 -138.190224)
		(width 0.1651)
		(layer "F.Cu")
		(net "PCIE_COMP_B_TO_IOM_B_CLK_2_DP")
	)
	(segment
		(start 289.48507 -133.750558)
		(end 289.508184 -133.8961)
		(width 0.1651)
		(layer "F.Cu")
		(net "PCIE_COMP_B_TO_IOM_B_CLK_2_DP")
	)
	(arc
		(start 388.967218 -29.70403)
		(mid 388.498089 -29.898349)
		(end 388.30377 -30.367478)
		(width 0.1651)
		(layer "F.Cu")
		(net "PCIE_COMP_B_TO_IOM_B_CLK_2_DP")
	)
	(arc
		(start 279.954482 -138.082528)
		(mid 279.94544 -137.956529)
		(end 280.028142 -137.86104)
		(width 0.1651)
		(layer "F.Cu")
		(net "PCIE_COMP_B_TO_IOM_B_CLK_2_DP")
	)
	(arc
		(start 389.349996 -29.57703)
		(mid 389.312799 -29.666833)
		(end 389.222996 -29.70403)
		(width 0.1651)
		(layer "F.Cu")
		(net "PCIE_COMP_B_TO_IOM_B_CLK_2_DP")
	)
	(arc
		(start 280.221182 -138.3538)
		(mid 280.158464 -138.338617)
		(end 280.109422 -138.29665)
		(width 0.1651)
		(layer "F.Cu")
		(net "PCIE_COMP_B_TO_IOM_B_CLK_2_DP")
	)
	(segment
		(start 279.795478 -138.36142)
		(end 279.795224 -138.361166)
		(width 0.1651)
		(layer "F.Cu")
		(net "PCIE_COMP_B_TO_IOM_B_CLK_2_DN")
	)
	(segment
		(start 329.118214 -33.951418)
		(end 322.240656 -33.951418)
		(width 0.1651)
		(layer "F.Cu")
		(net "PCIE_COMP_B_TO_IOM_B_CLK_2_DN")
	)
	(segment
		(start 279.782016 -138.342878)
		(end 279.781508 -138.342116)
		(width 0.1651)
		(layer "F.Cu")
		(net "PCIE_COMP_B_TO_IOM_B_CLK_2_DN")
	)
	(segment
		(start 283.804106 -138.6459)
		(end 280.221182 -138.6459)
		(width 0.1651)
		(layer "F.Cu")
		(net "PCIE_COMP_B_TO_IOM_B_CLK_2_DN")
	)
	(segment
		(start 388.59587 -31.533338)
		(end 386.472938 -33.65627)
		(width 0.1651)
		(layer "F.Cu")
		(net "PCIE_COMP_B_TO_IOM_B_CLK_2_DN")
	)
	(segment
		(start 288.018982 -136.451086)
		(end 286.295338 -137.645902)
		(width 0.1651)
		(layer "F.Cu")
		(net "PCIE_COMP_B_TO_IOM_B_CLK_2_DN")
	)
	(segment
		(start 354.004626 -33.65627)
		(end 341.452454 -38.628828)
		(width 0.1651)
		(layer "F.Cu")
		(net "PCIE_COMP_B_TO_IOM_B_CLK_2_DN")
	)
	(segment
		(start 279.794716 -138.360404)
		(end 279.782016 -138.342878)
		(width 0.1651)
		(layer "F.Cu")
		(net "PCIE_COMP_B_TO_IOM_B_CLK_2_DN")
	)
	(segment
		(start 297.857672 -122.863356)
		(end 297.857418 -122.863356)
		(width 0.1651)
		(layer "F.Cu")
		(net "PCIE_COMP_B_TO_IOM_B_CLK_2_DN")
	)
	(segment
		(start 279.872694 -138.4681)
		(end 279.795478 -138.36142)
		(width 0.1651)
		(layer "F.Cu")
		(net "PCIE_COMP_B_TO_IOM_B_CLK_2_DN")
	)
	(segment
		(start 308.49316 -75.920092)
		(end 297.857164 -122.863102)
		(width 0.1651)
		(layer "F.Cu")
		(net "PCIE_COMP_B_TO_IOM_B_CLK_2_DN")
	)
	(segment
		(start 340.247732 -38.844474)
		(end 340.247478 -38.844728)
		(width 0.1651)
		(layer "F.Cu")
		(net "PCIE_COMP_B_TO_IOM_B_CLK_2_DN")
	)
	(segment
		(start 389.349996 -30.550104)
		(end 389.349996 -30.12313)
		(width 0.1651)
		(layer "F.Cu")
		(net "PCIE_COMP_B_TO_IOM_B_CLK_2_DN")
	)
	(segment
		(start 297.857418 -122.863356)
		(end 297.85691 -122.864626)
		(width 0.1651)
		(layer "F.Cu")
		(net "PCIE_COMP_B_TO_IOM_B_CLK_2_DN")
	)
	(segment
		(start 319.844674 -35.454336)
		(end 308.735984 -52.891944)
		(width 0.1651)
		(layer "F.Cu")
		(net "PCIE_COMP_B_TO_IOM_B_CLK_2_DN")
	)
	(segment
		(start 340.247478 -38.844728)
		(end 336.637376 -39.49065)
		(width 0.1651)
		(layer "F.Cu")
		(net "PCIE_COMP_B_TO_IOM_B_CLK_2_DN")
	)
	(segment
		(start 388.59587 -30.367478)
		(end 388.59587 -31.533338)
		(width 0.1651)
		(layer "F.Cu")
		(net "PCIE_COMP_B_TO_IOM_B_CLK_2_DN")
	)
	(segment
		(start 308.735984 -52.891944)
		(end 306.215288 -64.012826)
		(width 0.1651)
		(layer "F.Cu")
		(net "PCIE_COMP_B_TO_IOM_B_CLK_2_DN")
	)
	(segment
		(start 279.795224 -138.361166)
		(end 279.794716 -138.360404)
		(width 0.1651)
		(layer "F.Cu")
		(net "PCIE_COMP_B_TO_IOM_B_CLK_2_DN")
	)
	(segment
		(start 286.295338 -137.645902)
		(end 284.804104 -137.645902)
		(width 0.1651)
		(layer "F.Cu")
		(net "PCIE_COMP_B_TO_IOM_B_CLK_2_DN")
	)
	(segment
		(start 306.215288 -64.012826)
		(end 308.49316 -75.920092)
		(width 0.1651)
		(layer "F.Cu")
		(net "PCIE_COMP_B_TO_IOM_B_CLK_2_DN")
	)
	(segment
		(start 279.781508 -138.342116)
		(end 279.662382 -138.177778)
		(width 0.1651)
		(layer "F.Cu")
		(net "PCIE_COMP_B_TO_IOM_B_CLK_2_DN")
	)
	(segment
		(start 297.85691 -122.864626)
		(end 288.018982 -136.451086)
		(width 0.1651)
		(layer "F.Cu")
		(net "PCIE_COMP_B_TO_IOM_B_CLK_2_DN")
	)
	(segment
		(start 331.908658 -37.593016)
		(end 329.118214 -33.951418)
		(width 0.1651)
		(layer "F.Cu")
		(net "PCIE_COMP_B_TO_IOM_B_CLK_2_DN")
	)
	(segment
		(start 336.637376 -39.49065)
		(end 331.908658 -37.593016)
		(width 0.1651)
		(layer "F.Cu")
		(net "PCIE_COMP_B_TO_IOM_B_CLK_2_DN")
	)
	(segment
		(start 284.804104 -137.645902)
		(end 283.804106 -138.6459)
		(width 0.1651)
		(layer "F.Cu")
		(net "PCIE_COMP_B_TO_IOM_B_CLK_2_DN")
	)
	(segment
		(start 279.471374 -138.138916)
		(end 278.750014 -138.49985)
		(width 0.1651)
		(layer "F.Cu")
		(net "PCIE_COMP_B_TO_IOM_B_CLK_2_DN")
	)
	(segment
		(start 341.452454 -38.628828)
		(end 340.247732 -38.844474)
		(width 0.1651)
		(layer "F.Cu")
		(net "PCIE_COMP_B_TO_IOM_B_CLK_2_DN")
	)
	(segment
		(start 297.857164 -122.863102)
		(end 297.857672 -122.863356)
		(width 0.1651)
		(layer "F.Cu")
		(net "PCIE_COMP_B_TO_IOM_B_CLK_2_DN")
	)
	(segment
		(start 389.222996 -29.99613)
		(end 388.967218 -29.99613)
		(width 0.1651)
		(layer "F.Cu")
		(net "PCIE_COMP_B_TO_IOM_B_CLK_2_DN")
	)
	(segment
		(start 322.240656 -33.951418)
		(end 319.844674 -35.454336)
		(width 0.1651)
		(layer "F.Cu")
		(net "PCIE_COMP_B_TO_IOM_B_CLK_2_DN")
	)
	(segment
		(start 386.472938 -33.65627)
		(end 354.004626 -33.65627)
		(width 0.1651)
		(layer "F.Cu")
		(net "PCIE_COMP_B_TO_IOM_B_CLK_2_DN")
	)
	(segment
		(start 279.662382 -138.177778)
		(end 279.662382 -138.170412)
		(width 0.1651)
		(layer "F.Cu")
		(net "PCIE_COMP_B_TO_IOM_B_CLK_2_DN")
	)
	(arc
		(start 389.349996 -30.12313)
		(mid 389.312799 -30.033327)
		(end 389.222996 -29.99613)
		(width 0.1651)
		(layer "F.Cu")
		(net "PCIE_COMP_B_TO_IOM_B_CLK_2_DN")
	)
	(arc
		(start 280.221182 -138.6459)
		(mid 280.025559 -138.59889)
		(end 279.872694 -138.4681)
		(width 0.1651)
		(layer "F.Cu")
		(net "PCIE_COMP_B_TO_IOM_B_CLK_2_DN")
	)
	(arc
		(start 279.662382 -138.170412)
		(mid 279.571973 -138.123644)
		(end 279.471374 -138.138916)
		(width 0.1651)
		(layer "F.Cu")
		(net "PCIE_COMP_B_TO_IOM_B_CLK_2_DN")
	)
	(arc
		(start 388.967218 -29.99613)
		(mid 388.704635 -30.104895)
		(end 388.59587 -30.367478)
		(width 0.1651)
		(layer "F.Cu")
		(net "PCIE_COMP_B_TO_IOM_B_CLK_2_DN")
	)
	(segment
		(start 274.635468 -185.764932)
		(end 273.536918 -181.598316)
		(width 0.1397)
		(layer "In9.Cu")
		(net "PCIE_COMP_B_TO_IOM_B_9_DP")
	)
	(segment
		(start 289.268154 -185.266584)
		(end 284.964886 -188.849762)
		(width 0.1397)
		(layer "In9.Cu")
		(net "PCIE_COMP_B_TO_IOM_B_9_DP")
	)
	(segment
		(start 278.584406 -188.942472)
		(end 274.635468 -185.764932)
		(width 0.1397)
		(layer "In9.Cu")
		(net "PCIE_COMP_B_TO_IOM_B_9_DP")
	)
	(segment
		(start 274.828254 -175.524414)
		(end 276.9235 -172.295312)
		(width 0.1397)
		(layer "In9.Cu")
		(net "PCIE_COMP_B_TO_IOM_B_9_DP")
	)
	(segment
		(start 387.586982 -17.85112)
		(end 387.60273 -17.866868)
		(width 0.1397)
		(layer "In9.Cu")
		(net "PCIE_COMP_B_TO_IOM_B_9_DP")
	)
	(segment
		(start 387.692392 -17.903952)
		(end 387.692646 -17.904206)
		(width 0.1397)
		(layer "In9.Cu")
		(net "PCIE_COMP_B_TO_IOM_B_9_DP")
	)
	(segment
		(start 279.354534 -171.353734)
		(end 280.354532 -172.353732)
		(width 0.1397)
		(layer "In9.Cu")
		(net "PCIE_COMP_B_TO_IOM_B_9_DP")
	)
	(segment
		(start 387.692646 -17.904206)
		(end 388.109968 -17.904206)
		(width 0.1397)
		(layer "In9.Cu")
		(net "PCIE_COMP_B_TO_IOM_B_9_DP")
	)
	(segment
		(start 387.549898 -17.349978)
		(end 387.549898 -17.761458)
		(width 0.1397)
		(layer "In9.Cu")
		(net "PCIE_COMP_B_TO_IOM_B_9_DP")
	)
	(segment
		(start 283.994352 -172.184568)
		(end 284.056836 -172.0596)
		(width 0.1397)
		(layer "In9.Cu")
		(net "PCIE_COMP_B_TO_IOM_B_9_DP")
	)
	(segment
		(start 278.07158 -171.549822)
		(end 278.373332 -171.353734)
		(width 0.1397)
		(layer "In9.Cu")
		(net "PCIE_COMP_B_TO_IOM_B_9_DP")
	)
	(segment
		(start 281.62885 -189.914022)
		(end 278.584406 -188.942472)
		(width 0.1397)
		(layer "In9.Cu")
		(net "PCIE_COMP_B_TO_IOM_B_9_DP")
	)
	(segment
		(start 388.406386 -18.026634)
		(end 388.473442 -18.093944)
		(width 0.1397)
		(layer "In9.Cu")
		(net "PCIE_COMP_B_TO_IOM_B_9_DP")
	)
	(segment
		(start 388.59587 -33.267904)
		(end 380.58598 -44.829476)
		(width 0.1397)
		(layer "In9.Cu")
		(net "PCIE_COMP_B_TO_IOM_B_9_DP")
	)
	(segment
		(start 283.994352 -171.872148)
		(end 283.249878 -171.499784)
		(width 0.1397)
		(layer "In9.Cu")
		(net "PCIE_COMP_B_TO_IOM_B_9_DP")
	)
	(segment
		(start 276.9235 -172.295312)
		(end 278.07158 -171.549822)
		(width 0.1397)
		(layer "In9.Cu")
		(net "PCIE_COMP_B_TO_IOM_B_9_DP")
	)
	(segment
		(start 280.354532 -172.353732)
		(end 283.58592 -172.353732)
		(width 0.1397)
		(layer "In9.Cu")
		(net "PCIE_COMP_B_TO_IOM_B_9_DP")
	)
	(segment
		(start 371.366288 -66.388996)
		(end 289.268154 -185.266584)
		(width 0.1397)
		(layer "In9.Cu")
		(net "PCIE_COMP_B_TO_IOM_B_9_DP")
	)
	(segment
		(start 388.59587 -18.390108)
		(end 388.59587 -33.267904)
		(width 0.1397)
		(layer "In9.Cu")
		(net "PCIE_COMP_B_TO_IOM_B_9_DP")
	)
	(segment
		(start 278.373332 -171.353734)
		(end 279.354534 -171.353734)
		(width 0.1397)
		(layer "In9.Cu")
		(net "PCIE_COMP_B_TO_IOM_B_9_DP")
	)
	(segment
		(start 284.964886 -188.849762)
		(end 281.62885 -189.914022)
		(width 0.1397)
		(layer "In9.Cu")
		(net "PCIE_COMP_B_TO_IOM_B_9_DP")
	)
	(segment
		(start 273.536918 -181.598316)
		(end 274.828254 -175.524414)
		(width 0.1397)
		(layer "In9.Cu")
		(net "PCIE_COMP_B_TO_IOM_B_9_DP")
	)
	(segment
		(start 380.58598 -44.829476)
		(end 371.366288 -66.388996)
		(width 0.1397)
		(layer "In9.Cu")
		(net "PCIE_COMP_B_TO_IOM_B_9_DP")
	)
	(arc
		(start 283.58592 -172.353732)
		(mid 283.806956 -172.309765)
		(end 283.994352 -172.184568)
		(width 0.1397)
		(layer "In9.Cu")
		(net "PCIE_COMP_B_TO_IOM_B_9_DP")
	)
	(arc
		(start 388.109968 -17.904206)
		(mid 388.270321 -17.935991)
		(end 388.406386 -18.026634)
		(width 0.1397)
		(layer "In9.Cu")
		(net "PCIE_COMP_B_TO_IOM_B_9_DP")
	)
	(arc
		(start 284.056836 -172.0596)
		(mid 284.064417 -171.952933)
		(end 283.994352 -171.872148)
		(width 0.1397)
		(layer "In9.Cu")
		(net "PCIE_COMP_B_TO_IOM_B_9_DP")
	)
	(arc
		(start 387.60273 -17.866868)
		(mid 387.643881 -17.894301)
		(end 387.692392 -17.903952)
		(width 0.1397)
		(layer "In9.Cu")
		(net "PCIE_COMP_B_TO_IOM_B_9_DP")
	)
	(arc
		(start 387.549898 -17.761458)
		(mid 387.559531 -17.809976)
		(end 387.586982 -17.85112)
		(width 0.1397)
		(layer "In9.Cu")
		(net "PCIE_COMP_B_TO_IOM_B_9_DP")
	)
	(arc
		(start 388.473442 -18.093944)
		(mid 388.564045 -18.229869)
		(end 388.59587 -18.390108)
		(width 0.1397)
		(layer "In9.Cu")
		(net "PCIE_COMP_B_TO_IOM_B_9_DP")
	)
	(segment
		(start 298.880276 -170.570398)
		(end 298.642024 -170.915076)
		(width 0.1397)
		(layer "In9.Cu")
		(net "PCIE_COMP_B_TO_IOM_B_9_DN")
	)
	(segment
		(start 280.233374 -172.645832)
		(end 283.585666 -172.645832)
		(width 0.1397)
		(layer "In9.Cu")
		(net "PCIE_COMP_B_TO_IOM_B_9_DN")
	)
	(segment
		(start 308.048914 -157.311852)
		(end 308.084474 -157.506162)
		(width 0.1397)
		(layer "In9.Cu")
		(net "PCIE_COMP_B_TO_IOM_B_9_DN")
	)
	(segment
		(start 298.642024 -170.915076)
		(end 298.680378 -171.12361)
		(width 0.1397)
		(layer "In9.Cu")
		(net "PCIE_COMP_B_TO_IOM_B_9_DN")
	)
	(segment
		(start 299.973492 -169.251122)
		(end 299.735494 -169.5958)
		(width 0.1397)
		(layer "In9.Cu")
		(net "PCIE_COMP_B_TO_IOM_B_9_DN")
	)
	(segment
		(start 308.286912 -156.96692)
		(end 308.048914 -157.311852)
		(width 0.1397)
		(layer "In9.Cu")
		(net "PCIE_COMP_B_TO_IOM_B_9_DN")
	)
	(segment
		(start 388.19963 -18.23339)
		(end 388.266686 -18.300446)
		(width 0.1397)
		(layer "In9.Cu")
		(net "PCIE_COMP_B_TO_IOM_B_9_DN")
	)
	(segment
		(start 290.547806 -182.653686)
		(end 290.309808 -182.998364)
		(width 0.1397)
		(layer "In9.Cu")
		(net "PCIE_COMP_B_TO_IOM_B_9_DN")
	)
	(segment
		(start 301.028608 -167.723312)
		(end 300.820074 -167.761412)
		(width 0.1397)
		(layer "In9.Cu")
		(net "PCIE_COMP_B_TO_IOM_B_9_DN")
	)
	(segment
		(start 388.30377 -33.176464)
		(end 380.328932 -44.68749)
		(width 0.1397)
		(layer "In9.Cu")
		(net "PCIE_COMP_B_TO_IOM_B_9_DN")
	)
	(segment
		(start 306.81422 -159.345376)
		(end 301.028608 -167.723312)
		(width 0.1397)
		(layer "In9.Cu")
		(net "PCIE_COMP_B_TO_IOM_B_9_DN")
	)
	(segment
		(start 300.620176 -168.314624)
		(end 300.381924 -168.659556)
		(width 0.1397)
		(layer "In9.Cu")
		(net "PCIE_COMP_B_TO_IOM_B_9_DN")
	)
	(segment
		(start 290.309808 -182.998364)
		(end 290.345368 -183.192674)
		(width 0.1397)
		(layer "In9.Cu")
		(net "PCIE_COMP_B_TO_IOM_B_9_DN")
	)
	(segment
		(start 308.084474 -157.506162)
		(end 307.846222 -157.851094)
		(width 0.1397)
		(layer "In9.Cu")
		(net "PCIE_COMP_B_TO_IOM_B_9_DN")
	)
	(segment
		(start 274.893532 -185.597546)
		(end 273.837146 -181.59095)
		(width 0.1397)
		(layer "In9.Cu")
		(net "PCIE_COMP_B_TO_IOM_B_9_DN")
	)
	(segment
		(start 277.134828 -172.50664)
		(end 278.230838 -171.794932)
		(width 0.1397)
		(layer "In9.Cu")
		(net "PCIE_COMP_B_TO_IOM_B_9_DN")
	)
	(segment
		(start 314.53201 -147.923758)
		(end 314.56757 -148.118068)
		(width 0.1397)
		(layer "In9.Cu")
		(net "PCIE_COMP_B_TO_IOM_B_9_DN")
	)
	(segment
		(start 291.615368 -181.35346)
		(end 291.37737 -181.698392)
		(width 0.1397)
		(layer "In9.Cu")
		(net "PCIE_COMP_B_TO_IOM_B_9_DN")
	)
	(segment
		(start 290.742116 -182.618126)
		(end 290.547806 -182.653686)
		(width 0.1397)
		(layer "In9.Cu")
		(net "PCIE_COMP_B_TO_IOM_B_9_DN")
	)
	(segment
		(start 292.01237 -180.778912)
		(end 291.81806 -180.814472)
		(width 0.1397)
		(layer "In9.Cu")
		(net "PCIE_COMP_B_TO_IOM_B_9_DN")
	)
	(segment
		(start 291.81806 -180.814472)
		(end 291.579808 -181.15915)
		(width 0.1397)
		(layer "In9.Cu")
		(net "PCIE_COMP_B_TO_IOM_B_9_DN")
	)
	(segment
		(start 314.56757 -148.118068)
		(end 308.481222 -156.93136)
		(width 0.1397)
		(layer "In9.Cu")
		(net "PCIE_COMP_B_TO_IOM_B_9_DN")
	)
	(segment
		(start 273.837146 -181.59095)
		(end 275.102828 -175.637952)
		(width 0.1397)
		(layer "In9.Cu")
		(net "PCIE_COMP_B_TO_IOM_B_9_DN")
	)
	(segment
		(start 291.579808 -181.15915)
		(end 291.615368 -181.35346)
		(width 0.1397)
		(layer "In9.Cu")
		(net "PCIE_COMP_B_TO_IOM_B_9_DN")
	)
	(segment
		(start 387.549898 -18.750026)
		(end 387.549898 -18.3388)
		(width 0.1397)
		(layer "In9.Cu")
		(net "PCIE_COMP_B_TO_IOM_B_9_DN")
	)
	(segment
		(start 275.102828 -175.637952)
		(end 277.134828 -172.50664)
		(width 0.1397)
		(layer "In9.Cu")
		(net "PCIE_COMP_B_TO_IOM_B_9_DN")
	)
	(segment
		(start 299.08881 -170.532298)
		(end 298.880276 -170.570398)
		(width 0.1397)
		(layer "In9.Cu")
		(net "PCIE_COMP_B_TO_IOM_B_9_DN")
	)
	(segment
		(start 315.599572 -146.623786)
		(end 315.405262 -146.659346)
		(width 0.1397)
		(layer "In9.Cu")
		(net "PCIE_COMP_B_TO_IOM_B_9_DN")
	)
	(segment
		(start 314.770262 -147.578826)
		(end 314.53201 -147.923758)
		(width 0.1397)
		(layer "In9.Cu")
		(net "PCIE_COMP_B_TO_IOM_B_9_DN")
	)
	(segment
		(start 278.459946 -171.645834)
		(end 279.233376 -171.645834)
		(width 0.1397)
		(layer "In9.Cu")
		(net "PCIE_COMP_B_TO_IOM_B_9_DN")
	)
	(segment
		(start 307.41366 -158.231332)
		(end 307.44922 -158.425642)
		(width 0.1397)
		(layer "In9.Cu")
		(net "PCIE_COMP_B_TO_IOM_B_9_DN")
	)
	(segment
		(start 307.211222 -158.770574)
		(end 307.016912 -158.806134)
		(width 0.1397)
		(layer "In9.Cu")
		(net "PCIE_COMP_B_TO_IOM_B_9_DN")
	)
	(segment
		(start 299.326808 -170.187366)
		(end 299.08881 -170.532298)
		(width 0.1397)
		(layer "In9.Cu")
		(net "PCIE_COMP_B_TO_IOM_B_9_DN")
	)
	(segment
		(start 307.846222 -157.851094)
		(end 307.651912 -157.886654)
		(width 0.1397)
		(layer "In9.Cu")
		(net "PCIE_COMP_B_TO_IOM_B_9_DN")
	)
	(segment
		(start 300.820074 -167.761412)
		(end 300.582076 -168.10609)
		(width 0.1397)
		(layer "In9.Cu")
		(net "PCIE_COMP_B_TO_IOM_B_9_DN")
	)
	(segment
		(start 300.582076 -168.10609)
		(end 300.620176 -168.314624)
		(width 0.1397)
		(layer "In9.Cu")
		(net "PCIE_COMP_B_TO_IOM_B_9_DN")
	)
	(segment
		(start 388.30377 -18.390108)
		(end 388.30377 -33.176464)
		(width 0.1397)
		(layer "In9.Cu")
		(net "PCIE_COMP_B_TO_IOM_B_9_DN")
	)
	(segment
		(start 284.236668 -172.353224)
		(end 284.318202 -172.190156)
		(width 0.1397)
		(layer "In9.Cu")
		(net "PCIE_COMP_B_TO_IOM_B_9_DN")
	)
	(segment
		(start 289.710114 -184.112408)
		(end 289.050476 -185.067702)
		(width 0.1397)
		(layer "In9.Cu")
		(net "PCIE_COMP_B_TO_IOM_B_9_DN")
	)
	(segment
		(start 307.44922 -158.425642)
		(end 307.211222 -158.770574)
		(width 0.1397)
		(layer "In9.Cu")
		(net "PCIE_COMP_B_TO_IOM_B_9_DN")
	)
	(segment
		(start 290.944808 -182.078884)
		(end 290.980368 -182.273194)
		(width 0.1397)
		(layer "In9.Cu")
		(net "PCIE_COMP_B_TO_IOM_B_9_DN")
	)
	(segment
		(start 387.586982 -18.249138)
		(end 387.60273 -18.23339)
		(width 0.1397)
		(layer "In9.Cu")
		(net "PCIE_COMP_B_TO_IOM_B_9_DN")
	)
	(segment
		(start 284.82163 -188.58865)
		(end 281.62885 -189.60719)
		(width 0.1397)
		(layer "In9.Cu")
		(net "PCIE_COMP_B_TO_IOM_B_9_DN")
	)
	(segment
		(start 291.37737 -181.698392)
		(end 291.18306 -181.733952)
		(width 0.1397)
		(layer "In9.Cu")
		(net "PCIE_COMP_B_TO_IOM_B_9_DN")
	)
	(segment
		(start 315.202824 -147.198334)
		(end 314.964572 -147.543266)
		(width 0.1397)
		(layer "In9.Cu")
		(net "PCIE_COMP_B_TO_IOM_B_9_DN")
	)
	(segment
		(start 290.980368 -182.273194)
		(end 290.742116 -182.618126)
		(width 0.1397)
		(layer "In9.Cu")
		(net "PCIE_COMP_B_TO_IOM_B_9_DN")
	)
	(segment
		(start 281.62885 -189.60719)
		(end 278.725122 -188.680598)
		(width 0.1397)
		(layer "In9.Cu")
		(net "PCIE_COMP_B_TO_IOM_B_9_DN")
	)
	(segment
		(start 371.108986 -66.24701)
		(end 315.599572 -146.623786)
		(width 0.1397)
		(layer "In9.Cu")
		(net "PCIE_COMP_B_TO_IOM_B_9_DN")
	)
	(segment
		(start 387.692392 -18.196306)
		(end 388.109968 -18.196306)
		(width 0.1397)
		(layer "In9.Cu")
		(net "PCIE_COMP_B_TO_IOM_B_9_DN")
	)
	(segment
		(start 279.233376 -171.645834)
		(end 280.233374 -172.645832)
		(width 0.1397)
		(layer "In9.Cu")
		(net "PCIE_COMP_B_TO_IOM_B_9_DN")
	)
	(segment
		(start 299.935392 -169.042588)
		(end 299.973492 -169.251122)
		(width 0.1397)
		(layer "In9.Cu")
		(net "PCIE_COMP_B_TO_IOM_B_9_DN")
	)
	(segment
		(start 299.52696 -169.6339)
		(end 299.288708 -169.978832)
		(width 0.1397)
		(layer "In9.Cu")
		(net "PCIE_COMP_B_TO_IOM_B_9_DN")
	)
	(segment
		(start 307.016912 -158.806134)
		(end 306.77866 -159.151066)
		(width 0.1397)
		(layer "In9.Cu")
		(net "PCIE_COMP_B_TO_IOM_B_9_DN")
	)
	(segment
		(start 307.651912 -157.886654)
		(end 307.41366 -158.231332)
		(width 0.1397)
		(layer "In9.Cu")
		(net "PCIE_COMP_B_TO_IOM_B_9_DN")
	)
	(segment
		(start 300.381924 -168.659556)
		(end 300.173644 -168.697656)
		(width 0.1397)
		(layer "In9.Cu")
		(net "PCIE_COMP_B_TO_IOM_B_9_DN")
	)
	(segment
		(start 291.18306 -181.733952)
		(end 290.944808 -182.078884)
		(width 0.1397)
		(layer "In9.Cu")
		(net "PCIE_COMP_B_TO_IOM_B_9_DN")
	)
	(segment
		(start 289.912806 -183.573166)
		(end 289.674554 -183.918098)
		(width 0.1397)
		(layer "In9.Cu")
		(net "PCIE_COMP_B_TO_IOM_B_9_DN")
	)
	(segment
		(start 290.345368 -183.192674)
		(end 290.107116 -183.537606)
		(width 0.1397)
		(layer "In9.Cu")
		(net "PCIE_COMP_B_TO_IOM_B_9_DN")
	)
	(segment
		(start 308.481222 -156.93136)
		(end 308.286912 -156.96692)
		(width 0.1397)
		(layer "In9.Cu")
		(net "PCIE_COMP_B_TO_IOM_B_9_DN")
	)
	(segment
		(start 284.505654 -172.127672)
		(end 285.249874 -172.499782)
		(width 0.1397)
		(layer "In9.Cu")
		(net "PCIE_COMP_B_TO_IOM_B_9_DN")
	)
	(segment
		(start 298.680378 -171.12361)
		(end 292.01237 -180.778912)
		(width 0.1397)
		(layer "In9.Cu")
		(net "PCIE_COMP_B_TO_IOM_B_9_DN")
	)
	(segment
		(start 278.725122 -188.680598)
		(end 274.893532 -185.597546)
		(width 0.1397)
		(layer "In9.Cu")
		(net "PCIE_COMP_B_TO_IOM_B_9_DN")
	)
	(segment
		(start 290.107116 -183.537606)
		(end 289.912806 -183.573166)
		(width 0.1397)
		(layer "In9.Cu")
		(net "PCIE_COMP_B_TO_IOM_B_9_DN")
	)
	(segment
		(start 315.405262 -146.659346)
		(end 315.167264 -147.004024)
		(width 0.1397)
		(layer "In9.Cu")
		(net "PCIE_COMP_B_TO_IOM_B_9_DN")
	)
	(segment
		(start 299.288708 -169.978832)
		(end 299.326808 -170.187366)
		(width 0.1397)
		(layer "In9.Cu")
		(net "PCIE_COMP_B_TO_IOM_B_9_DN")
	)
	(segment
		(start 300.173644 -168.697656)
		(end 299.935392 -169.042588)
		(width 0.1397)
		(layer "In9.Cu")
		(net "PCIE_COMP_B_TO_IOM_B_9_DN")
	)
	(segment
		(start 315.167264 -147.004024)
		(end 315.202824 -147.198334)
		(width 0.1397)
		(layer "In9.Cu")
		(net "PCIE_COMP_B_TO_IOM_B_9_DN")
	)
	(segment
		(start 306.77866 -159.151066)
		(end 306.81422 -159.345376)
		(width 0.1397)
		(layer "In9.Cu")
		(net "PCIE_COMP_B_TO_IOM_B_9_DN")
	)
	(segment
		(start 314.964572 -147.543266)
		(end 314.770262 -147.578826)
		(width 0.1397)
		(layer "In9.Cu")
		(net "PCIE_COMP_B_TO_IOM_B_9_DN")
	)
	(segment
		(start 289.674554 -183.918098)
		(end 289.710114 -184.112408)
		(width 0.1397)
		(layer "In9.Cu")
		(net "PCIE_COMP_B_TO_IOM_B_9_DN")
	)
	(segment
		(start 380.328932 -44.68749)
		(end 371.108986 -66.24701)
		(width 0.1397)
		(layer "In9.Cu")
		(net "PCIE_COMP_B_TO_IOM_B_9_DN")
	)
	(segment
		(start 278.230838 -171.794932)
		(end 278.459946 -171.645834)
		(width 0.1397)
		(layer "In9.Cu")
		(net "PCIE_COMP_B_TO_IOM_B_9_DN")
	)
	(segment
		(start 299.735494 -169.5958)
		(end 299.52696 -169.6339)
		(width 0.1397)
		(layer "In9.Cu")
		(net "PCIE_COMP_B_TO_IOM_B_9_DN")
	)
	(segment
		(start 289.050476 -185.067702)
		(end 284.82163 -188.58865)
		(width 0.1397)
		(layer "In9.Cu")
		(net "PCIE_COMP_B_TO_IOM_B_9_DN")
	)
	(arc
		(start 284.318202 -172.190156)
		(mid 284.398987 -172.120091)
		(end 284.505654 -172.127672)
		(width 0.1397)
		(layer "In9.Cu")
		(net "PCIE_COMP_B_TO_IOM_B_9_DN")
	)
	(arc
		(start 387.549898 -18.3388)
		(mid 387.559531 -18.290282)
		(end 387.586982 -18.249138)
		(width 0.1397)
		(layer "In9.Cu")
		(net "PCIE_COMP_B_TO_IOM_B_9_DN")
	)
	(arc
		(start 388.109968 -18.196306)
		(mid 388.158486 -18.205939)
		(end 388.19963 -18.23339)
		(width 0.1397)
		(layer "In9.Cu")
		(net "PCIE_COMP_B_TO_IOM_B_9_DN")
	)
	(arc
		(start 387.60273 -18.23339)
		(mid 387.643881 -18.205957)
		(end 387.692392 -18.196306)
		(width 0.1397)
		(layer "In9.Cu")
		(net "PCIE_COMP_B_TO_IOM_B_9_DN")
	)
	(arc
		(start 388.266686 -18.300446)
		(mid 388.294119 -18.341597)
		(end 388.30377 -18.390108)
		(width 0.1397)
		(layer "In9.Cu")
		(net "PCIE_COMP_B_TO_IOM_B_9_DN")
	)
	(arc
		(start 283.585666 -172.645832)
		(mid 283.942542 -172.569352)
		(end 284.236668 -172.353224)
		(width 0.1397)
		(layer "In9.Cu")
		(net "PCIE_COMP_B_TO_IOM_B_9_DN")
	)
	(segment
		(start 273.230848 -174.496984)
		(end 277.490428 -167.939974)
		(width 0.1397)
		(layer "In9.Cu")
		(net "PCIE_COMP_B_TO_IOM_B_8_DP")
	)
	(segment
		(start 389.38708 -18.851118)
		(end 389.402828 -18.866866)
		(width 0.1397)
		(layer "In9.Cu")
		(net "PCIE_COMP_B_TO_IOM_B_8_DP")
	)
	(segment
		(start 389.492744 -18.904204)
		(end 389.910066 -18.904204)
		(width 0.1397)
		(layer "In9.Cu")
		(net "PCIE_COMP_B_TO_IOM_B_8_DP")
	)
	(segment
		(start 286.024828 -190.080138)
		(end 281.569414 -191.50076)
		(width 0.1397)
		(layer "In9.Cu")
		(net "PCIE_COMP_B_TO_IOM_B_8_DP")
	)
	(segment
		(start 278.136604 -190.404242)
		(end 273.139408 -186.3852)
		(width 0.1397)
		(layer "In9.Cu")
		(net "PCIE_COMP_B_TO_IOM_B_8_DP")
	)
	(segment
		(start 273.228562 -174.500286)
		(end 273.230848 -174.496984)
		(width 0.1397)
		(layer "In9.Cu")
		(net "PCIE_COMP_B_TO_IOM_B_8_DP")
	)
	(segment
		(start 278.39289 -167.353742)
		(end 279.3238 -167.353742)
		(width 0.1397)
		(layer "In9.Cu")
		(net "PCIE_COMP_B_TO_IOM_B_8_DP")
	)
	(segment
		(start 390.206484 -19.026632)
		(end 390.27354 -19.093942)
		(width 0.1397)
		(layer "In9.Cu")
		(net "PCIE_COMP_B_TO_IOM_B_8_DP")
	)
	(segment
		(start 280.323798 -168.35374)
		(end 283.58592 -168.35374)
		(width 0.1397)
		(layer "In9.Cu")
		(net "PCIE_COMP_B_TO_IOM_B_8_DP")
	)
	(segment
		(start 279.3238 -167.353742)
		(end 280.323798 -168.35374)
		(width 0.1397)
		(layer "In9.Cu")
		(net "PCIE_COMP_B_TO_IOM_B_8_DP")
	)
	(segment
		(start 273.139154 -186.3852)
		(end 271.789652 -181.27091)
		(width 0.1397)
		(layer "In9.Cu")
		(net "PCIE_COMP_B_TO_IOM_B_8_DP")
	)
	(segment
		(start 390.395968 -19.390106)
		(end 390.395968 -32.716724)
		(width 0.1397)
		(layer "In9.Cu")
		(net "PCIE_COMP_B_TO_IOM_B_8_DP")
	)
	(segment
		(start 381.35306 -45.834046)
		(end 370.904262 -70.279768)
		(width 0.1397)
		(layer "In9.Cu")
		(net "PCIE_COMP_B_TO_IOM_B_8_DP")
	)
	(segment
		(start 283.994352 -168.184576)
		(end 284.056836 -168.059608)
		(width 0.1397)
		(layer "In9.Cu")
		(net "PCIE_COMP_B_TO_IOM_B_8_DP")
	)
	(segment
		(start 390.371076 -32.796226)
		(end 385.855464 -39.322248)
		(width 0.1397)
		(layer "In9.Cu")
		(net "PCIE_COMP_B_TO_IOM_B_8_DP")
	)
	(segment
		(start 389.49249 -18.90395)
		(end 389.492744 -18.904204)
		(width 0.1397)
		(layer "In9.Cu")
		(net "PCIE_COMP_B_TO_IOM_B_8_DP")
	)
	(segment
		(start 383.994152 -42.012362)
		(end 381.366776 -45.809408)
		(width 0.1397)
		(layer "In9.Cu")
		(net "PCIE_COMP_B_TO_IOM_B_8_DP")
	)
	(segment
		(start 277.490428 -167.939974)
		(end 278.39289 -167.353742)
		(width 0.1397)
		(layer "In9.Cu")
		(net "PCIE_COMP_B_TO_IOM_B_8_DP")
	)
	(segment
		(start 273.139408 -186.3852)
		(end 273.139154 -186.3852)
		(width 0.1397)
		(layer "In9.Cu")
		(net "PCIE_COMP_B_TO_IOM_B_8_DP")
	)
	(segment
		(start 389.349996 -18.35023)
		(end 389.349996 -18.761456)
		(width 0.1397)
		(layer "In9.Cu")
		(net "PCIE_COMP_B_TO_IOM_B_8_DP")
	)
	(segment
		(start 370.904262 -70.279768)
		(end 291.736018 -185.324242)
		(width 0.1397)
		(layer "In9.Cu")
		(net "PCIE_COMP_B_TO_IOM_B_8_DP")
	)
	(segment
		(start 291.736018 -185.324242)
		(end 286.024828 -190.080138)
		(width 0.1397)
		(layer "In9.Cu")
		(net "PCIE_COMP_B_TO_IOM_B_8_DP")
	)
	(segment
		(start 385.855464 -39.322248)
		(end 383.994152 -42.012362)
		(width 0.1397)
		(layer "In9.Cu")
		(net "PCIE_COMP_B_TO_IOM_B_8_DP")
	)
	(segment
		(start 271.789652 -181.27091)
		(end 273.228562 -174.500286)
		(width 0.1397)
		(layer "In9.Cu")
		(net "PCIE_COMP_B_TO_IOM_B_8_DP")
	)
	(segment
		(start 281.569414 -191.50076)
		(end 278.136604 -190.404242)
		(width 0.1397)
		(layer "In9.Cu")
		(net "PCIE_COMP_B_TO_IOM_B_8_DP")
	)
	(segment
		(start 283.994352 -167.872156)
		(end 283.249878 -167.499792)
		(width 0.1397)
		(layer "In9.Cu")
		(net "PCIE_COMP_B_TO_IOM_B_8_DP")
	)
	(arc
		(start 390.27354 -19.093942)
		(mid 390.364143 -19.229867)
		(end 390.395968 -19.390106)
		(width 0.1397)
		(layer "In9.Cu")
		(net "PCIE_COMP_B_TO_IOM_B_8_DP")
	)
	(arc
		(start 389.402828 -18.866866)
		(mid 389.443979 -18.894299)
		(end 389.49249 -18.90395)
		(width 0.1397)
		(layer "In9.Cu")
		(net "PCIE_COMP_B_TO_IOM_B_8_DP")
	)
	(arc
		(start 390.395968 -32.716724)
		(mid 390.389601 -32.758379)
		(end 390.371076 -32.796226)
		(width 0.1397)
		(layer "In9.Cu")
		(net "PCIE_COMP_B_TO_IOM_B_8_DP")
	)
	(arc
		(start 283.58592 -168.35374)
		(mid 283.806956 -168.309773)
		(end 283.994352 -168.184576)
		(width 0.1397)
		(layer "In9.Cu")
		(net "PCIE_COMP_B_TO_IOM_B_8_DP")
	)
	(arc
		(start 381.366776 -45.809408)
		(mid 381.359287 -45.821376)
		(end 381.35306 -45.834046)
		(width 0.1397)
		(layer "In9.Cu")
		(net "PCIE_COMP_B_TO_IOM_B_8_DP")
	)
	(arc
		(start 389.910066 -18.904204)
		(mid 390.070419 -18.935989)
		(end 390.206484 -19.026632)
		(width 0.1397)
		(layer "In9.Cu")
		(net "PCIE_COMP_B_TO_IOM_B_8_DP")
	)
	(arc
		(start 389.349996 -18.761456)
		(mid 389.359629 -18.809974)
		(end 389.38708 -18.851118)
		(width 0.1397)
		(layer "In9.Cu")
		(net "PCIE_COMP_B_TO_IOM_B_8_DP")
	)
	(arc
		(start 284.056836 -168.059608)
		(mid 284.064417 -167.952941)
		(end 283.994352 -167.872156)
		(width 0.1397)
		(layer "In9.Cu")
		(net "PCIE_COMP_B_TO_IOM_B_8_DP")
	)
	(segment
		(start 272.08988 -181.263544)
		(end 273.503136 -174.614332)
		(width 0.1397)
		(layer "In9.Cu")
		(net "PCIE_COMP_B_TO_IOM_B_8_DN")
	)
	(segment
		(start 390.103868 -19.390106)
		(end 390.103868 -32.668972)
		(width 0.1397)
		(layer "In9.Cu")
		(net "PCIE_COMP_B_TO_IOM_B_8_DN")
	)
	(segment
		(start 369.379754 -71.979282)
		(end 369.142264 -72.324722)
		(width 0.1397)
		(layer "In9.Cu")
		(net "PCIE_COMP_B_TO_IOM_B_8_DN")
	)
	(segment
		(start 389.38708 -19.249136)
		(end 389.402828 -19.233388)
		(width 0.1397)
		(layer "In9.Cu")
		(net "PCIE_COMP_B_TO_IOM_B_8_DN")
	)
	(segment
		(start 362.411518 -82.1055)
		(end 362.174028 -82.450686)
		(width 0.1397)
		(layer "In9.Cu")
		(net "PCIE_COMP_B_TO_IOM_B_8_DN")
	)
	(segment
		(start 368.947954 -72.360536)
		(end 368.710464 -72.705722)
		(width 0.1397)
		(layer "In9.Cu")
		(net "PCIE_COMP_B_TO_IOM_B_8_DN")
	)
	(segment
		(start 284.505654 -168.12768)
		(end 285.249874 -168.49979)
		(width 0.1397)
		(layer "In9.Cu")
		(net "PCIE_COMP_B_TO_IOM_B_8_DN")
	)
	(segment
		(start 363.44098 -80.60944)
		(end 363.24667 -80.645254)
		(width 0.1397)
		(layer "In9.Cu")
		(net "PCIE_COMP_B_TO_IOM_B_8_DN")
	)
	(segment
		(start 363.00918 -80.990694)
		(end 363.044994 -81.185004)
		(width 0.1397)
		(layer "In9.Cu")
		(net "PCIE_COMP_B_TO_IOM_B_8_DN")
	)
	(segment
		(start 362.37545 -81.91119)
		(end 362.411518 -82.1055)
		(width 0.1397)
		(layer "In9.Cu")
		(net "PCIE_COMP_B_TO_IOM_B_8_DN")
	)
	(segment
		(start 370.013484 -71.058786)
		(end 369.77574 -71.403972)
		(width 0.1397)
		(layer "In9.Cu")
		(net "PCIE_COMP_B_TO_IOM_B_8_DN")
	)
	(segment
		(start 284.236668 -168.353232)
		(end 284.318202 -168.190164)
		(width 0.1397)
		(layer "In9.Cu")
		(net "PCIE_COMP_B_TO_IOM_B_8_DN")
	)
	(segment
		(start 363.044994 -81.185004)
		(end 362.807504 -81.53019)
		(width 0.1397)
		(layer "In9.Cu")
		(net "PCIE_COMP_B_TO_IOM_B_8_DN")
	)
	(segment
		(start 300.027086 -172.51426)
		(end 299.789342 -172.859446)
		(width 0.1397)
		(layer "In9.Cu")
		(net "PCIE_COMP_B_TO_IOM_B_8_DN")
	)
	(segment
		(start 291.755576 -184.780174)
		(end 291.518086 -185.12536)
		(width 0.1397)
		(layer "In9.Cu")
		(net "PCIE_COMP_B_TO_IOM_B_8_DN")
	)
	(segment
		(start 300.458886 -172.133006)
		(end 300.221396 -172.478192)
		(width 0.1397)
		(layer "In9.Cu")
		(net "PCIE_COMP_B_TO_IOM_B_8_DN")
	)
	(segment
		(start 292.599872 -183.28894)
		(end 292.362128 -183.63438)
		(width 0.1397)
		(layer "In9.Cu")
		(net "PCIE_COMP_B_TO_IOM_B_8_DN")
	)
	(segment
		(start 369.977416 -70.864476)
		(end 370.013484 -71.058786)
		(width 0.1397)
		(layer "In9.Cu")
		(net "PCIE_COMP_B_TO_IOM_B_8_DN")
	)
	(segment
		(start 389.349996 -19.750024)
		(end 389.349996 -19.338798)
		(width 0.1397)
		(layer "In9.Cu")
		(net "PCIE_COMP_B_TO_IOM_B_8_DN")
	)
	(segment
		(start 291.717222 -184.57164)
		(end 291.755576 -184.780174)
		(width 0.1397)
		(layer "In9.Cu")
		(net "PCIE_COMP_B_TO_IOM_B_8_DN")
	)
	(segment
		(start 278.479504 -167.645842)
		(end 279.202642 -167.645842)
		(width 0.1397)
		(layer "In9.Cu")
		(net "PCIE_COMP_B_TO_IOM_B_8_DN")
	)
	(segment
		(start 381.1016 -45.679106)
		(end 370.64696 -70.138036)
		(width 0.1397)
		(layer "In9.Cu")
		(net "PCIE_COMP_B_TO_IOM_B_8_DN")
	)
	(segment
		(start 292.362128 -183.63438)
		(end 292.400736 -183.84266)
		(width 0.1397)
		(layer "In9.Cu")
		(net "PCIE_COMP_B_TO_IOM_B_8_DN")
	)
	(segment
		(start 390.103868 -32.668972)
		(end 381.1016 -45.679106)
		(width 0.1397)
		(layer "In9.Cu")
		(net "PCIE_COMP_B_TO_IOM_B_8_DN")
	)
	(segment
		(start 301.056548 -171.017946)
		(end 301.092362 -171.212256)
		(width 0.1397)
		(layer "In9.Cu")
		(net "PCIE_COMP_B_TO_IOM_B_8_DN")
	)
	(segment
		(start 278.27732 -190.142368)
		(end 273.397472 -186.21756)
		(width 0.1397)
		(layer "In9.Cu")
		(net "PCIE_COMP_B_TO_IOM_B_8_DN")
	)
	(segment
		(start 301.488348 -170.636946)
		(end 301.294038 -170.67276)
		(width 0.1397)
		(layer "In9.Cu")
		(net "PCIE_COMP_B_TO_IOM_B_8_DN")
	)
	(segment
		(start 280.20264 -168.64584)
		(end 283.585666 -168.64584)
		(width 0.1397)
		(layer "In9.Cu")
		(net "PCIE_COMP_B_TO_IOM_B_8_DN")
	)
	(segment
		(start 389.999728 -19.233388)
		(end 390.066784 -19.300444)
		(width 0.1397)
		(layer "In9.Cu")
		(net "PCIE_COMP_B_TO_IOM_B_8_DN")
	)
	(segment
		(start 369.77574 -71.403972)
		(end 369.58143 -71.439786)
		(width 0.1397)
		(layer "In9.Cu")
		(net "PCIE_COMP_B_TO_IOM_B_8_DN")
	)
	(segment
		(start 389.49249 -19.196304)
		(end 389.910066 -19.196304)
		(width 0.1397)
		(layer "In9.Cu")
		(net "PCIE_COMP_B_TO_IOM_B_8_DN")
	)
	(segment
		(start 361.741974 -82.83194)
		(end 361.778042 -83.02625)
		(width 0.1397)
		(layer "In9.Cu")
		(net "PCIE_COMP_B_TO_IOM_B_8_DN")
	)
	(segment
		(start 369.34394 -71.784972)
		(end 369.379754 -71.979282)
		(width 0.1397)
		(layer "In9.Cu")
		(net "PCIE_COMP_B_TO_IOM_B_8_DN")
	)
	(segment
		(start 285.881572 -189.819026)
		(end 281.569414 -191.193928)
		(width 0.1397)
		(layer "In9.Cu")
		(net "PCIE_COMP_B_TO_IOM_B_8_DN")
	)
	(segment
		(start 369.58143 -71.439786)
		(end 369.34394 -71.784972)
		(width 0.1397)
		(layer "In9.Cu")
		(net "PCIE_COMP_B_TO_IOM_B_8_DN")
	)
	(segment
		(start 362.174028 -82.450686)
		(end 361.979718 -82.486754)
		(width 0.1397)
		(layer "In9.Cu")
		(net "PCIE_COMP_B_TO_IOM_B_8_DN")
	)
	(segment
		(start 300.221396 -172.478192)
		(end 300.027086 -172.51426)
		(width 0.1397)
		(layer "In9.Cu")
		(net "PCIE_COMP_B_TO_IOM_B_8_DN")
	)
	(segment
		(start 277.701756 -168.151302)
		(end 278.479504 -167.645842)
		(width 0.1397)
		(layer "In9.Cu")
		(net "PCIE_COMP_B_TO_IOM_B_8_DN")
	)
	(segment
		(start 273.397218 -186.217306)
		(end 272.08988 -181.263544)
		(width 0.1397)
		(layer "In9.Cu")
		(net "PCIE_COMP_B_TO_IOM_B_8_DN")
	)
	(segment
		(start 293.045896 -182.905146)
		(end 292.808152 -183.250586)
		(width 0.1397)
		(layer "In9.Cu")
		(net "PCIE_COMP_B_TO_IOM_B_8_DN")
	)
	(segment
		(start 361.778042 -83.02625)
		(end 301.488348 -170.636946)
		(width 0.1397)
		(layer "In9.Cu")
		(net "PCIE_COMP_B_TO_IOM_B_8_DN")
	)
	(segment
		(start 292.400736 -183.84266)
		(end 292.163246 -184.187846)
		(width 0.1397)
		(layer "In9.Cu")
		(net "PCIE_COMP_B_TO_IOM_B_8_DN")
	)
	(segment
		(start 293.244778 -182.35168)
		(end 293.007288 -182.696866)
		(width 0.1397)
		(layer "In9.Cu")
		(net "PCIE_COMP_B_TO_IOM_B_8_DN")
	)
	(segment
		(start 292.163246 -184.187846)
		(end 291.954712 -184.226454)
		(width 0.1397)
		(layer "In9.Cu")
		(net "PCIE_COMP_B_TO_IOM_B_8_DN")
	)
	(segment
		(start 368.746278 -72.900032)
		(end 364.074456 -79.68869)
		(width 0.1397)
		(layer "In9.Cu")
		(net "PCIE_COMP_B_TO_IOM_B_8_DN")
	)
	(segment
		(start 364.074456 -79.68869)
		(end 363.880146 -79.724758)
		(width 0.1397)
		(layer "In9.Cu")
		(net "PCIE_COMP_B_TO_IOM_B_8_DN")
	)
	(segment
		(start 273.503136 -174.614332)
		(end 277.701756 -168.151302)
		(width 0.1397)
		(layer "In9.Cu")
		(net "PCIE_COMP_B_TO_IOM_B_8_DN")
	)
	(segment
		(start 299.789342 -172.859446)
		(end 299.82541 -173.053756)
		(width 0.1397)
		(layer "In9.Cu")
		(net "PCIE_COMP_B_TO_IOM_B_8_DN")
	)
	(segment
		(start 362.807504 -81.53019)
		(end 362.613194 -81.566004)
		(width 0.1397)
		(layer "In9.Cu")
		(net "PCIE_COMP_B_TO_IOM_B_8_DN")
	)
	(segment
		(start 370.40947 -70.483222)
		(end 370.21516 -70.51929)
		(width 0.1397)
		(layer "In9.Cu")
		(net "PCIE_COMP_B_TO_IOM_B_8_DN")
	)
	(segment
		(start 291.518086 -185.12536)
		(end 285.881572 -189.819026)
		(width 0.1397)
		(layer "In9.Cu")
		(net "PCIE_COMP_B_TO_IOM_B_8_DN")
	)
	(segment
		(start 301.294038 -170.67276)
		(end 301.056548 -171.017946)
		(width 0.1397)
		(layer "In9.Cu")
		(net "PCIE_COMP_B_TO_IOM_B_8_DN")
	)
	(segment
		(start 291.954712 -184.226454)
		(end 291.717222 -184.57164)
		(width 0.1397)
		(layer "In9.Cu")
		(net "PCIE_COMP_B_TO_IOM_B_8_DN")
	)
	(segment
		(start 361.979718 -82.486754)
		(end 361.741974 -82.83194)
		(width 0.1397)
		(layer "In9.Cu")
		(net "PCIE_COMP_B_TO_IOM_B_8_DN")
	)
	(segment
		(start 368.710464 -72.705722)
		(end 368.746278 -72.900032)
		(width 0.1397)
		(layer "In9.Cu")
		(net "PCIE_COMP_B_TO_IOM_B_8_DN")
	)
	(segment
		(start 363.67847 -80.264254)
		(end 363.44098 -80.60944)
		(width 0.1397)
		(layer "In9.Cu")
		(net "PCIE_COMP_B_TO_IOM_B_8_DN")
	)
	(segment
		(start 370.21516 -70.51929)
		(end 369.977416 -70.864476)
		(width 0.1397)
		(layer "In9.Cu")
		(net "PCIE_COMP_B_TO_IOM_B_8_DN")
	)
	(segment
		(start 299.82541 -173.053756)
		(end 293.453312 -182.313072)
		(width 0.1397)
		(layer "In9.Cu")
		(net "PCIE_COMP_B_TO_IOM_B_8_DN")
	)
	(segment
		(start 363.642656 -80.069944)
		(end 363.67847 -80.264254)
		(width 0.1397)
		(layer "In9.Cu")
		(net "PCIE_COMP_B_TO_IOM_B_8_DN")
	)
	(segment
		(start 292.808152 -183.250586)
		(end 292.599872 -183.28894)
		(width 0.1397)
		(layer "In9.Cu")
		(net "PCIE_COMP_B_TO_IOM_B_8_DN")
	)
	(segment
		(start 369.142264 -72.324722)
		(end 368.947954 -72.360536)
		(width 0.1397)
		(layer "In9.Cu")
		(net "PCIE_COMP_B_TO_IOM_B_8_DN")
	)
	(segment
		(start 279.202642 -167.645842)
		(end 280.20264 -168.64584)
		(width 0.1397)
		(layer "In9.Cu")
		(net "PCIE_COMP_B_TO_IOM_B_8_DN")
	)
	(segment
		(start 281.569414 -191.193928)
		(end 278.27732 -190.142368)
		(width 0.1397)
		(layer "In9.Cu")
		(net "PCIE_COMP_B_TO_IOM_B_8_DN")
	)
	(segment
		(start 363.880146 -79.724758)
		(end 363.642656 -80.069944)
		(width 0.1397)
		(layer "In9.Cu")
		(net "PCIE_COMP_B_TO_IOM_B_8_DN")
	)
	(segment
		(start 293.007288 -182.696866)
		(end 293.045896 -182.905146)
		(width 0.1397)
		(layer "In9.Cu")
		(net "PCIE_COMP_B_TO_IOM_B_8_DN")
	)
	(segment
		(start 363.24667 -80.645254)
		(end 363.00918 -80.990694)
		(width 0.1397)
		(layer "In9.Cu")
		(net "PCIE_COMP_B_TO_IOM_B_8_DN")
	)
	(segment
		(start 301.092362 -171.212256)
		(end 300.854872 -171.557442)
		(width 0.1397)
		(layer "In9.Cu")
		(net "PCIE_COMP_B_TO_IOM_B_8_DN")
	)
	(segment
		(start 273.397472 -186.21756)
		(end 273.397218 -186.217306)
		(width 0.1397)
		(layer "In9.Cu")
		(net "PCIE_COMP_B_TO_IOM_B_8_DN")
	)
	(segment
		(start 293.453312 -182.313072)
		(end 293.244778 -182.35168)
		(width 0.1397)
		(layer "In9.Cu")
		(net "PCIE_COMP_B_TO_IOM_B_8_DN")
	)
	(segment
		(start 300.854872 -171.557442)
		(end 300.660562 -171.59351)
		(width 0.1397)
		(layer "In9.Cu")
		(net "PCIE_COMP_B_TO_IOM_B_8_DN")
	)
	(segment
		(start 370.64696 -70.138036)
		(end 370.40947 -70.483222)
		(width 0.1397)
		(layer "In9.Cu")
		(net "PCIE_COMP_B_TO_IOM_B_8_DN")
	)
	(segment
		(start 300.660562 -171.59351)
		(end 300.422818 -171.938696)
		(width 0.1397)
		(layer "In9.Cu")
		(net "PCIE_COMP_B_TO_IOM_B_8_DN")
	)
	(segment
		(start 362.613194 -81.566004)
		(end 362.37545 -81.91119)
		(width 0.1397)
		(layer "In9.Cu")
		(net "PCIE_COMP_B_TO_IOM_B_8_DN")
	)
	(segment
		(start 300.422818 -171.938696)
		(end 300.458886 -172.133006)
		(width 0.1397)
		(layer "In9.Cu")
		(net "PCIE_COMP_B_TO_IOM_B_8_DN")
	)
	(arc
		(start 284.318202 -168.190164)
		(mid 284.398987 -168.120099)
		(end 284.505654 -168.12768)
		(width 0.1397)
		(layer "In9.Cu")
		(net "PCIE_COMP_B_TO_IOM_B_8_DN")
	)
	(arc
		(start 389.349996 -19.338798)
		(mid 389.359629 -19.29028)
		(end 389.38708 -19.249136)
		(width 0.1397)
		(layer "In9.Cu")
		(net "PCIE_COMP_B_TO_IOM_B_8_DN")
	)
	(arc
		(start 389.402828 -19.233388)
		(mid 389.443979 -19.205955)
		(end 389.49249 -19.196304)
		(width 0.1397)
		(layer "In9.Cu")
		(net "PCIE_COMP_B_TO_IOM_B_8_DN")
	)
	(arc
		(start 283.585666 -168.64584)
		(mid 283.942542 -168.56936)
		(end 284.236668 -168.353232)
		(width 0.1397)
		(layer "In9.Cu")
		(net "PCIE_COMP_B_TO_IOM_B_8_DN")
	)
	(arc
		(start 390.066784 -19.300444)
		(mid 390.094217 -19.341595)
		(end 390.103868 -19.390106)
		(width 0.1397)
		(layer "In9.Cu")
		(net "PCIE_COMP_B_TO_IOM_B_8_DN")
	)
	(arc
		(start 389.910066 -19.196304)
		(mid 389.958584 -19.205937)
		(end 389.999728 -19.233388)
		(width 0.1397)
		(layer "In9.Cu")
		(net "PCIE_COMP_B_TO_IOM_B_8_DN")
	)
	(segment
		(start 355.97211 -50.825908)
		(end 366.704118 -34.63798)
		(width 0.1397)
		(layer "In9.Cu")
		(net "PCIE_COMP_B_TO_IOM_B_23_DP")
	)
	(segment
		(start 286.387286 -83.053936)
		(end 313.711844 -77.742288)
		(width 0.1397)
		(layer "In9.Cu")
		(net "PCIE_COMP_B_TO_IOM_B_23_DP")
	)
	(segment
		(start 284.914086 -83.053936)
		(end 286.387286 -83.053936)
		(width 0.1397)
		(layer "In9.Cu")
		(net "PCIE_COMP_B_TO_IOM_B_23_DP")
	)
	(segment
		(start 283.249878 -83.199986)
		(end 283.994098 -83.572096)
		(width 0.1397)
		(layer "In9.Cu")
		(net "PCIE_COMP_B_TO_IOM_B_23_DP")
	)
	(segment
		(start 313.711844 -77.742288)
		(end 355.97211 -50.825908)
		(width 0.1397)
		(layer "In9.Cu")
		(net "PCIE_COMP_B_TO_IOM_B_23_DP")
	)
	(segment
		(start 284.18155 -83.509612)
		(end 284.263084 -83.346544)
		(width 0.1397)
		(layer "In9.Cu")
		(net "PCIE_COMP_B_TO_IOM_B_23_DP")
	)
	(segment
		(start 366.704118 -34.63798)
		(end 366.704118 -19.390106)
		(width 0.1397)
		(layer "In9.Cu")
		(net "PCIE_COMP_B_TO_IOM_B_23_DP")
	)
	(segment
		(start 367.19002 -18.904204)
		(end 367.607342 -18.904204)
		(width 0.1397)
		(layer "In9.Cu")
		(net "PCIE_COMP_B_TO_IOM_B_23_DP")
	)
	(segment
		(start 367.697258 -18.866866)
		(end 367.713006 -18.851118)
		(width 0.1397)
		(layer "In9.Cu")
		(net "PCIE_COMP_B_TO_IOM_B_23_DP")
	)
	(segment
		(start 366.826546 -19.093942)
		(end 366.893602 -19.026632)
		(width 0.1397)
		(layer "In9.Cu")
		(net "PCIE_COMP_B_TO_IOM_B_23_DP")
	)
	(segment
		(start 367.607342 -18.904204)
		(end 367.607596 -18.90395)
		(width 0.1397)
		(layer "In9.Cu")
		(net "PCIE_COMP_B_TO_IOM_B_23_DP")
	)
	(segment
		(start 367.75009 -18.761456)
		(end 367.75009 -18.35023)
		(width 0.1397)
		(layer "In9.Cu")
		(net "PCIE_COMP_B_TO_IOM_B_23_DP")
	)
	(arc
		(start 367.607596 -18.90395)
		(mid 367.656114 -18.894317)
		(end 367.697258 -18.866866)
		(width 0.1397)
		(layer "In9.Cu")
		(net "PCIE_COMP_B_TO_IOM_B_23_DP")
	)
	(arc
		(start 367.713006 -18.851118)
		(mid 367.740439 -18.809967)
		(end 367.75009 -18.761456)
		(width 0.1397)
		(layer "In9.Cu")
		(net "PCIE_COMP_B_TO_IOM_B_23_DP")
	)
	(arc
		(start 366.893602 -19.026632)
		(mid 367.029629 -18.935898)
		(end 367.19002 -18.904204)
		(width 0.1397)
		(layer "In9.Cu")
		(net "PCIE_COMP_B_TO_IOM_B_23_DP")
	)
	(arc
		(start 284.263084 -83.346544)
		(mid 284.557179 -83.130346)
		(end 284.914086 -83.053936)
		(width 0.1397)
		(layer "In9.Cu")
		(net "PCIE_COMP_B_TO_IOM_B_23_DP")
	)
	(arc
		(start 283.994098 -83.572096)
		(mid 284.100765 -83.579677)
		(end 284.18155 -83.509612)
		(width 0.1397)
		(layer "In9.Cu")
		(net "PCIE_COMP_B_TO_IOM_B_23_DP")
	)
	(arc
		(start 366.704118 -19.390106)
		(mid 366.735868 -19.229836)
		(end 366.826546 -19.093942)
		(width 0.1397)
		(layer "In9.Cu")
		(net "PCIE_COMP_B_TO_IOM_B_23_DP")
	)
	(segment
		(start 284.442916 -83.640168)
		(end 284.5054 -83.5152)
		(width 0.1397)
		(layer "In9.Cu")
		(net "PCIE_COMP_B_TO_IOM_B_23_DN")
	)
	(segment
		(start 298.982384 -80.903318)
		(end 299.134276 -81.00568)
		(width 0.1397)
		(layer "In9.Cu")
		(net "PCIE_COMP_B_TO_IOM_B_23_DN")
	)
	(segment
		(start 301.28845 -80.587088)
		(end 301.69993 -80.507078)
		(width 0.1397)
		(layer "In9.Cu")
		(net "PCIE_COMP_B_TO_IOM_B_23_DN")
	)
	(segment
		(start 300.725078 -80.564482)
		(end 301.136558 -80.484472)
		(width 0.1397)
		(layer "In9.Cu")
		(net "PCIE_COMP_B_TO_IOM_B_23_DN")
	)
	(segment
		(start 313.82208 -78.01864)
		(end 356.181406 -51.039014)
		(width 0.1397)
		(layer "In9.Cu")
		(net "PCIE_COMP_B_TO_IOM_B_23_DN")
	)
	(segment
		(start 285.249874 -84.199984)
		(end 284.5054 -83.82762)
		(width 0.1397)
		(layer "In9.Cu")
		(net "PCIE_COMP_B_TO_IOM_B_23_DN")
	)
	(segment
		(start 300.211236 -80.796384)
		(end 300.622716 -80.716374)
		(width 0.1397)
		(layer "In9.Cu")
		(net "PCIE_COMP_B_TO_IOM_B_23_DN")
	)
	(segment
		(start 300.059344 -80.694022)
		(end 300.211236 -80.796384)
		(width 0.1397)
		(layer "In9.Cu")
		(net "PCIE_COMP_B_TO_IOM_B_23_DN")
	)
	(segment
		(start 367.75009 -19.338798)
		(end 367.75009 -19.750024)
		(width 0.1397)
		(layer "In9.Cu")
		(net "PCIE_COMP_B_TO_IOM_B_23_DN")
	)
	(segment
		(start 367.033302 -19.300444)
		(end 367.100358 -19.233388)
		(width 0.1397)
		(layer "In9.Cu")
		(net "PCIE_COMP_B_TO_IOM_B_23_DN")
	)
	(segment
		(start 301.802292 -80.355186)
		(end 313.82208 -78.01864)
		(width 0.1397)
		(layer "In9.Cu")
		(net "PCIE_COMP_B_TO_IOM_B_23_DN")
	)
	(segment
		(start 301.69993 -80.507078)
		(end 301.802292 -80.355186)
		(width 0.1397)
		(layer "In9.Cu")
		(net "PCIE_COMP_B_TO_IOM_B_23_DN")
	)
	(segment
		(start 299.648118 -80.773778)
		(end 300.059344 -80.694022)
		(width 0.1397)
		(layer "In9.Cu")
		(net "PCIE_COMP_B_TO_IOM_B_23_DN")
	)
	(segment
		(start 367.19002 -19.196304)
		(end 367.607596 -19.196304)
		(width 0.1397)
		(layer "In9.Cu")
		(net "PCIE_COMP_B_TO_IOM_B_23_DN")
	)
	(segment
		(start 286.41548 -83.346036)
		(end 298.982384 -80.903318)
		(width 0.1397)
		(layer "In9.Cu")
		(net "PCIE_COMP_B_TO_IOM_B_23_DN")
	)
	(segment
		(start 367.697258 -19.233388)
		(end 367.713006 -19.249136)
		(width 0.1397)
		(layer "In9.Cu")
		(net "PCIE_COMP_B_TO_IOM_B_23_DN")
	)
	(segment
		(start 300.622716 -80.716374)
		(end 300.725078 -80.564482)
		(width 0.1397)
		(layer "In9.Cu")
		(net "PCIE_COMP_B_TO_IOM_B_23_DN")
	)
	(segment
		(start 299.545502 -80.92567)
		(end 299.648118 -80.773778)
		(width 0.1397)
		(layer "In9.Cu")
		(net "PCIE_COMP_B_TO_IOM_B_23_DN")
	)
	(segment
		(start 356.181406 -51.039014)
		(end 366.996218 -34.726118)
		(width 0.1397)
		(layer "In9.Cu")
		(net "PCIE_COMP_B_TO_IOM_B_23_DN")
	)
	(segment
		(start 284.913832 -83.346036)
		(end 286.41548 -83.346036)
		(width 0.1397)
		(layer "In9.Cu")
		(net "PCIE_COMP_B_TO_IOM_B_23_DN")
	)
	(segment
		(start 299.134276 -81.00568)
		(end 299.545502 -80.92567)
		(width 0.1397)
		(layer "In9.Cu")
		(net "PCIE_COMP_B_TO_IOM_B_23_DN")
	)
	(segment
		(start 366.996218 -34.726118)
		(end 366.996218 -19.390106)
		(width 0.1397)
		(layer "In9.Cu")
		(net "PCIE_COMP_B_TO_IOM_B_23_DN")
	)
	(segment
		(start 301.136558 -80.484472)
		(end 301.28845 -80.587088)
		(width 0.1397)
		(layer "In9.Cu")
		(net "PCIE_COMP_B_TO_IOM_B_23_DN")
	)
	(arc
		(start 366.996218 -19.390106)
		(mid 367.005851 -19.341588)
		(end 367.033302 -19.300444)
		(width 0.1397)
		(layer "In9.Cu")
		(net "PCIE_COMP_B_TO_IOM_B_23_DN")
	)
	(arc
		(start 367.100358 -19.233388)
		(mid 367.141509 -19.205955)
		(end 367.19002 -19.196304)
		(width 0.1397)
		(layer "In9.Cu")
		(net "PCIE_COMP_B_TO_IOM_B_23_DN")
	)
	(arc
		(start 284.5054 -83.82762)
		(mid 284.435335 -83.746835)
		(end 284.442916 -83.640168)
		(width 0.1397)
		(layer "In9.Cu")
		(net "PCIE_COMP_B_TO_IOM_B_23_DN")
	)
	(arc
		(start 367.607596 -19.196304)
		(mid 367.656114 -19.205937)
		(end 367.697258 -19.233388)
		(width 0.1397)
		(layer "In9.Cu")
		(net "PCIE_COMP_B_TO_IOM_B_23_DN")
	)
	(arc
		(start 367.713006 -19.249136)
		(mid 367.740439 -19.290287)
		(end 367.75009 -19.338798)
		(width 0.1397)
		(layer "In9.Cu")
		(net "PCIE_COMP_B_TO_IOM_B_23_DN")
	)
	(arc
		(start 284.5054 -83.5152)
		(mid 284.69279 -83.38999)
		(end 284.913832 -83.346036)
		(width 0.1397)
		(layer "In9.Cu")
		(net "PCIE_COMP_B_TO_IOM_B_23_DN")
	)
	(segment
		(start 284.18155 -79.50962)
		(end 284.263338 -79.346552)
		(width 0.1397)
		(layer "In9.Cu")
		(net "PCIE_COMP_B_TO_IOM_B_22_DP")
	)
	(segment
		(start 364.90402 -31.274512)
		(end 364.90402 -18.390108)
		(width 0.1397)
		(layer "In9.Cu")
		(net "PCIE_COMP_B_TO_IOM_B_22_DP")
	)
	(segment
		(start 365.807244 -17.904206)
		(end 365.807498 -17.903952)
		(width 0.1397)
		(layer "In9.Cu")
		(net "PCIE_COMP_B_TO_IOM_B_22_DP")
	)
	(segment
		(start 350.434656 -49.757076)
		(end 350.434656 -49.75733)
		(width 0.1397)
		(layer "In9.Cu")
		(net "PCIE_COMP_B_TO_IOM_B_22_DP")
	)
	(segment
		(start 348.542102 -52.727606)
		(end 350.434656 -49.757076)
		(width 0.1397)
		(layer "In9.Cu")
		(net "PCIE_COMP_B_TO_IOM_B_22_DP")
	)
	(segment
		(start 283.249878 -79.199994)
		(end 283.994098 -79.572104)
		(width 0.1397)
		(layer "In9.Cu")
		(net "PCIE_COMP_B_TO_IOM_B_22_DP")
	)
	(segment
		(start 316.49289 -73.145904)
		(end 348.542102 -52.727606)
		(width 0.1397)
		(layer "In9.Cu")
		(net "PCIE_COMP_B_TO_IOM_B_22_DP")
	)
	(segment
		(start 350.434656 -49.75733)
		(end 352.327464 -46.786292)
		(width 0.1397)
		(layer "In9.Cu")
		(net "PCIE_COMP_B_TO_IOM_B_22_DP")
	)
	(segment
		(start 358.803956 -42.242994)
		(end 364.90402 -31.274512)
		(width 0.1397)
		(layer "In9.Cu")
		(net "PCIE_COMP_B_TO_IOM_B_22_DP")
	)
	(segment
		(start 365.389922 -17.904206)
		(end 365.807244 -17.904206)
		(width 0.1397)
		(layer "In9.Cu")
		(net "PCIE_COMP_B_TO_IOM_B_22_DP")
	)
	(segment
		(start 365.89716 -17.866868)
		(end 365.923576 -17.840452)
		(width 0.1397)
		(layer "In9.Cu")
		(net "PCIE_COMP_B_TO_IOM_B_22_DP")
	)
	(segment
		(start 352.327464 -46.786292)
		(end 358.803956 -42.242994)
		(width 0.1397)
		(layer "In9.Cu")
		(net "PCIE_COMP_B_TO_IOM_B_22_DP")
	)
	(segment
		(start 365.026448 -18.093944)
		(end 365.093504 -18.026634)
		(width 0.1397)
		(layer "In9.Cu")
		(net "PCIE_COMP_B_TO_IOM_B_22_DP")
	)
	(segment
		(start 365.949992 -17.776698)
		(end 365.949992 -17.349978)
		(width 0.1397)
		(layer "In9.Cu")
		(net "PCIE_COMP_B_TO_IOM_B_22_DP")
	)
	(segment
		(start 284.913324 -79.053944)
		(end 286.098234 -79.053944)
		(width 0.1397)
		(layer "In9.Cu")
		(net "PCIE_COMP_B_TO_IOM_B_22_DP")
	)
	(segment
		(start 286.098234 -79.053944)
		(end 316.49289 -73.145904)
		(width 0.1397)
		(layer "In9.Cu")
		(net "PCIE_COMP_B_TO_IOM_B_22_DP")
	)
	(arc
		(start 364.90402 -18.390108)
		(mid 364.93577 -18.229838)
		(end 365.026448 -18.093944)
		(width 0.1397)
		(layer "In9.Cu")
		(net "PCIE_COMP_B_TO_IOM_B_22_DP")
	)
	(arc
		(start 284.263338 -79.346552)
		(mid 284.556986 -79.130649)
		(end 284.913324 -79.053944)
		(width 0.1397)
		(layer "In9.Cu")
		(net "PCIE_COMP_B_TO_IOM_B_22_DP")
	)
	(arc
		(start 365.093504 -18.026634)
		(mid 365.229531 -17.9359)
		(end 365.389922 -17.904206)
		(width 0.1397)
		(layer "In9.Cu")
		(net "PCIE_COMP_B_TO_IOM_B_22_DP")
	)
	(arc
		(start 365.923576 -17.840452)
		(mid 365.943121 -17.811201)
		(end 365.949992 -17.776698)
		(width 0.1397)
		(layer "In9.Cu")
		(net "PCIE_COMP_B_TO_IOM_B_22_DP")
	)
	(arc
		(start 365.807498 -17.903952)
		(mid 365.856016 -17.894319)
		(end 365.89716 -17.866868)
		(width 0.1397)
		(layer "In9.Cu")
		(net "PCIE_COMP_B_TO_IOM_B_22_DP")
	)
	(arc
		(start 283.994098 -79.572104)
		(mid 284.100765 -79.579685)
		(end 284.18155 -79.50962)
		(width 0.1397)
		(layer "In9.Cu")
		(net "PCIE_COMP_B_TO_IOM_B_22_DP")
	)
	(segment
		(start 301.609252 -76.336652)
		(end 316.603126 -73.422256)
		(width 0.1397)
		(layer "In9.Cu")
		(net "PCIE_COMP_B_TO_IOM_B_22_DN")
	)
	(segment
		(start 359.026714 -42.443654)
		(end 365.19612 -31.350458)
		(width 0.1397)
		(layer "In9.Cu")
		(net "PCIE_COMP_B_TO_IOM_B_22_DN")
	)
	(segment
		(start 300.532038 -76.546202)
		(end 300.943518 -76.466192)
		(width 0.1397)
		(layer "In9.Cu")
		(net "PCIE_COMP_B_TO_IOM_B_22_DN")
	)
	(segment
		(start 299.352462 -76.90739)
		(end 299.455078 -76.755498)
		(width 0.1397)
		(layer "In9.Cu")
		(net "PCIE_COMP_B_TO_IOM_B_22_DN")
	)
	(segment
		(start 298.789344 -76.884784)
		(end 298.941236 -76.9874)
		(width 0.1397)
		(layer "In9.Cu")
		(net "PCIE_COMP_B_TO_IOM_B_22_DN")
	)
	(segment
		(start 299.455078 -76.755498)
		(end 299.866304 -76.675488)
		(width 0.1397)
		(layer "In9.Cu")
		(net "PCIE_COMP_B_TO_IOM_B_22_DN")
	)
	(segment
		(start 286.126428 -79.346044)
		(end 298.789344 -76.884784)
		(width 0.1397)
		(layer "In9.Cu")
		(net "PCIE_COMP_B_TO_IOM_B_22_DN")
	)
	(segment
		(start 284.442916 -79.640176)
		(end 284.505654 -79.515208)
		(width 0.1397)
		(layer "In9.Cu")
		(net "PCIE_COMP_B_TO_IOM_B_22_DN")
	)
	(segment
		(start 301.09541 -76.568554)
		(end 301.50689 -76.488544)
		(width 0.1397)
		(layer "In9.Cu")
		(net "PCIE_COMP_B_TO_IOM_B_22_DN")
	)
	(segment
		(start 300.429676 -76.698094)
		(end 300.532038 -76.546202)
		(width 0.1397)
		(layer "In9.Cu")
		(net "PCIE_COMP_B_TO_IOM_B_22_DN")
	)
	(segment
		(start 365.89716 -18.23339)
		(end 365.912908 -18.249138)
		(width 0.1397)
		(layer "In9.Cu")
		(net "PCIE_COMP_B_TO_IOM_B_22_DN")
	)
	(segment
		(start 284.913578 -79.346044)
		(end 286.126428 -79.346044)
		(width 0.1397)
		(layer "In9.Cu")
		(net "PCIE_COMP_B_TO_IOM_B_22_DN")
	)
	(segment
		(start 300.943518 -76.466192)
		(end 301.09541 -76.568554)
		(width 0.1397)
		(layer "In9.Cu")
		(net "PCIE_COMP_B_TO_IOM_B_22_DN")
	)
	(segment
		(start 365.19612 -31.350458)
		(end 365.19612 -18.390108)
		(width 0.1397)
		(layer "In9.Cu")
		(net "PCIE_COMP_B_TO_IOM_B_22_DN")
	)
	(segment
		(start 285.249874 -80.199992)
		(end 284.5054 -79.827628)
		(width 0.1397)
		(layer "In9.Cu")
		(net "PCIE_COMP_B_TO_IOM_B_22_DN")
	)
	(segment
		(start 298.941236 -76.9874)
		(end 299.352462 -76.90739)
		(width 0.1397)
		(layer "In9.Cu")
		(net "PCIE_COMP_B_TO_IOM_B_22_DN")
	)
	(segment
		(start 365.233204 -18.300446)
		(end 365.30026 -18.23339)
		(width 0.1397)
		(layer "In9.Cu")
		(net "PCIE_COMP_B_TO_IOM_B_22_DN")
	)
	(segment
		(start 316.603126 -73.422256)
		(end 348.753684 -52.939188)
		(width 0.1397)
		(layer "In9.Cu")
		(net "PCIE_COMP_B_TO_IOM_B_22_DN")
	)
	(segment
		(start 365.949992 -18.3388)
		(end 365.949992 -18.750026)
		(width 0.1397)
		(layer "In9.Cu")
		(net "PCIE_COMP_B_TO_IOM_B_22_DN")
	)
	(segment
		(start 348.753684 -52.939188)
		(end 352.542856 -46.992286)
		(width 0.1397)
		(layer "In9.Cu")
		(net "PCIE_COMP_B_TO_IOM_B_22_DN")
	)
	(segment
		(start 352.542856 -46.992286)
		(end 359.026714 -42.443654)
		(width 0.1397)
		(layer "In9.Cu")
		(net "PCIE_COMP_B_TO_IOM_B_22_DN")
	)
	(segment
		(start 365.389922 -18.196306)
		(end 365.807498 -18.196306)
		(width 0.1397)
		(layer "In9.Cu")
		(net "PCIE_COMP_B_TO_IOM_B_22_DN")
	)
	(segment
		(start 301.50689 -76.488544)
		(end 301.609252 -76.336652)
		(width 0.1397)
		(layer "In9.Cu")
		(net "PCIE_COMP_B_TO_IOM_B_22_DN")
	)
	(segment
		(start 300.018196 -76.77785)
		(end 300.429676 -76.698094)
		(width 0.1397)
		(layer "In9.Cu")
		(net "PCIE_COMP_B_TO_IOM_B_22_DN")
	)
	(segment
		(start 299.866304 -76.675488)
		(end 300.018196 -76.77785)
		(width 0.1397)
		(layer "In9.Cu")
		(net "PCIE_COMP_B_TO_IOM_B_22_DN")
	)
	(arc
		(start 365.19612 -18.390108)
		(mid 365.205753 -18.34159)
		(end 365.233204 -18.300446)
		(width 0.1397)
		(layer "In9.Cu")
		(net "PCIE_COMP_B_TO_IOM_B_22_DN")
	)
	(arc
		(start 365.30026 -18.23339)
		(mid 365.341411 -18.205957)
		(end 365.389922 -18.196306)
		(width 0.1397)
		(layer "In9.Cu")
		(net "PCIE_COMP_B_TO_IOM_B_22_DN")
	)
	(arc
		(start 284.505654 -79.515208)
		(mid 284.69281 -79.390095)
		(end 284.913578 -79.346044)
		(width 0.1397)
		(layer "In9.Cu")
		(net "PCIE_COMP_B_TO_IOM_B_22_DN")
	)
	(arc
		(start 365.807498 -18.196306)
		(mid 365.856016 -18.205939)
		(end 365.89716 -18.23339)
		(width 0.1397)
		(layer "In9.Cu")
		(net "PCIE_COMP_B_TO_IOM_B_22_DN")
	)
	(arc
		(start 365.912908 -18.249138)
		(mid 365.940341 -18.290289)
		(end 365.949992 -18.3388)
		(width 0.1397)
		(layer "In9.Cu")
		(net "PCIE_COMP_B_TO_IOM_B_22_DN")
	)
	(arc
		(start 284.5054 -79.827628)
		(mid 284.435335 -79.746843)
		(end 284.442916 -79.640176)
		(width 0.1397)
		(layer "In9.Cu")
		(net "PCIE_COMP_B_TO_IOM_B_22_DN")
	)
	(segment
		(start 361.233974 -34.38652)
		(end 363.103922 -31.025338)
		(width 0.1397)
		(layer "In9.Cu")
		(net "PCIE_COMP_B_TO_IOM_B_21_DP")
	)
	(segment
		(start 364.007146 -18.904204)
		(end 364.0074 -18.90395)
		(width 0.1397)
		(layer "In9.Cu")
		(net "PCIE_COMP_B_TO_IOM_B_21_DP")
	)
	(segment
		(start 286.417004 -74.876406)
		(end 298.396406 -66.947288)
		(width 0.1397)
		(layer "In9.Cu")
		(net "PCIE_COMP_B_TO_IOM_B_21_DP")
	)
	(segment
		(start 364.149894 -18.761456)
		(end 364.149894 -18.35023)
		(width 0.1397)
		(layer "In9.Cu")
		(net "PCIE_COMP_B_TO_IOM_B_21_DP")
	)
	(segment
		(start 344.343482 -45.192442)
		(end 361.233974 -34.38652)
		(width 0.1397)
		(layer "In9.Cu")
		(net "PCIE_COMP_B_TO_IOM_B_21_DP")
	)
	(segment
		(start 364.097062 -18.866866)
		(end 364.11281 -18.851118)
		(width 0.1397)
		(layer "In9.Cu")
		(net "PCIE_COMP_B_TO_IOM_B_21_DP")
	)
	(segment
		(start 283.249878 -75.200002)
		(end 283.994098 -75.572112)
		(width 0.1397)
		(layer "In9.Cu")
		(net "PCIE_COMP_B_TO_IOM_B_21_DP")
	)
	(segment
		(start 363.103922 -31.025338)
		(end 363.103922 -19.390106)
		(width 0.1397)
		(layer "In9.Cu")
		(net "PCIE_COMP_B_TO_IOM_B_21_DP")
	)
	(segment
		(start 298.396406 -66.947034)
		(end 307.486304 -60.931044)
		(width 0.1397)
		(layer "In9.Cu")
		(net "PCIE_COMP_B_TO_IOM_B_21_DP")
	)
	(segment
		(start 363.589824 -18.904204)
		(end 364.007146 -18.904204)
		(width 0.1397)
		(layer "In9.Cu")
		(net "PCIE_COMP_B_TO_IOM_B_21_DP")
	)
	(segment
		(start 284.914086 -75.053952)
		(end 285.54426 -75.053952)
		(width 0.1397)
		(layer "In9.Cu")
		(net "PCIE_COMP_B_TO_IOM_B_21_DP")
	)
	(segment
		(start 307.486304 -60.931044)
		(end 344.343482 -45.192442)
		(width 0.1397)
		(layer "In9.Cu")
		(net "PCIE_COMP_B_TO_IOM_B_21_DP")
	)
	(segment
		(start 363.22635 -19.093942)
		(end 363.293406 -19.026632)
		(width 0.1397)
		(layer "In9.Cu")
		(net "PCIE_COMP_B_TO_IOM_B_21_DP")
	)
	(segment
		(start 285.54426 -75.053952)
		(end 286.417004 -74.876406)
		(width 0.1397)
		(layer "In9.Cu")
		(net "PCIE_COMP_B_TO_IOM_B_21_DP")
	)
	(segment
		(start 298.396406 -66.947288)
		(end 298.396406 -66.947034)
		(width 0.1397)
		(layer "In9.Cu")
		(net "PCIE_COMP_B_TO_IOM_B_21_DP")
	)
	(segment
		(start 284.18155 -75.509628)
		(end 284.263084 -75.34656)
		(width 0.1397)
		(layer "In9.Cu")
		(net "PCIE_COMP_B_TO_IOM_B_21_DP")
	)
	(arc
		(start 363.103922 -19.390106)
		(mid 363.135672 -19.229836)
		(end 363.22635 -19.093942)
		(width 0.1397)
		(layer "In9.Cu")
		(net "PCIE_COMP_B_TO_IOM_B_21_DP")
	)
	(arc
		(start 283.994098 -75.572112)
		(mid 284.100765 -75.579693)
		(end 284.18155 -75.509628)
		(width 0.1397)
		(layer "In9.Cu")
		(net "PCIE_COMP_B_TO_IOM_B_21_DP")
	)
	(arc
		(start 364.11281 -18.851118)
		(mid 364.140243 -18.809967)
		(end 364.149894 -18.761456)
		(width 0.1397)
		(layer "In9.Cu")
		(net "PCIE_COMP_B_TO_IOM_B_21_DP")
	)
	(arc
		(start 284.263084 -75.34656)
		(mid 284.557179 -75.130362)
		(end 284.914086 -75.053952)
		(width 0.1397)
		(layer "In9.Cu")
		(net "PCIE_COMP_B_TO_IOM_B_21_DP")
	)
	(arc
		(start 364.0074 -18.90395)
		(mid 364.055918 -18.894317)
		(end 364.097062 -18.866866)
		(width 0.1397)
		(layer "In9.Cu")
		(net "PCIE_COMP_B_TO_IOM_B_21_DP")
	)
	(arc
		(start 363.293406 -19.026632)
		(mid 363.429433 -18.935898)
		(end 363.589824 -18.904204)
		(width 0.1397)
		(layer "In9.Cu")
		(net "PCIE_COMP_B_TO_IOM_B_21_DP")
	)
	(segment
		(start 289.797744 -73.144634)
		(end 289.83432 -72.965056)
		(width 0.1397)
		(layer "In9.Cu")
		(net "PCIE_COMP_B_TO_IOM_B_21_DN")
	)
	(segment
		(start 363.433106 -19.300444)
		(end 363.500162 -19.233388)
		(width 0.1397)
		(layer "In9.Cu")
		(net "PCIE_COMP_B_TO_IOM_B_21_DN")
	)
	(segment
		(start 344.480642 -45.451522)
		(end 361.453684 -34.593022)
		(width 0.1397)
		(layer "In9.Cu")
		(net "PCIE_COMP_B_TO_IOM_B_21_DN")
	)
	(segment
		(start 289.83432 -72.965056)
		(end 290.183824 -72.733916)
		(width 0.1397)
		(layer "In9.Cu")
		(net "PCIE_COMP_B_TO_IOM_B_21_DN")
	)
	(segment
		(start 290.749228 -72.35952)
		(end 291.098732 -72.128126)
		(width 0.1397)
		(layer "In9.Cu")
		(net "PCIE_COMP_B_TO_IOM_B_21_DN")
	)
	(segment
		(start 290.363148 -72.770492)
		(end 290.712652 -72.539098)
		(width 0.1397)
		(layer "In9.Cu")
		(net "PCIE_COMP_B_TO_IOM_B_21_DN")
	)
	(segment
		(start 363.396022 -31.101284)
		(end 363.396022 -19.390106)
		(width 0.1397)
		(layer "In9.Cu")
		(net "PCIE_COMP_B_TO_IOM_B_21_DN")
	)
	(segment
		(start 307.625496 -61.189362)
		(end 344.480642 -45.451522)
		(width 0.1397)
		(layer "In9.Cu")
		(net "PCIE_COMP_B_TO_IOM_B_21_DN")
	)
	(segment
		(start 289.44824 -73.376028)
		(end 289.797744 -73.144634)
		(width 0.1397)
		(layer "In9.Cu")
		(net "PCIE_COMP_B_TO_IOM_B_21_DN")
	)
	(segment
		(start 285.249874 -76.2)
		(end 284.5054 -75.827636)
		(width 0.1397)
		(layer "In9.Cu")
		(net "PCIE_COMP_B_TO_IOM_B_21_DN")
	)
	(segment
		(start 290.183824 -72.733916)
		(end 290.363148 -72.770492)
		(width 0.1397)
		(layer "In9.Cu")
		(net "PCIE_COMP_B_TO_IOM_B_21_DN")
	)
	(segment
		(start 289.268662 -73.339452)
		(end 289.44824 -73.376028)
		(width 0.1397)
		(layer "In9.Cu")
		(net "PCIE_COMP_B_TO_IOM_B_21_DN")
	)
	(segment
		(start 364.097062 -19.233388)
		(end 364.11281 -19.249136)
		(width 0.1397)
		(layer "In9.Cu")
		(net "PCIE_COMP_B_TO_IOM_B_21_DN")
	)
	(segment
		(start 291.098732 -72.128126)
		(end 291.27831 -72.164702)
		(width 0.1397)
		(layer "In9.Cu")
		(net "PCIE_COMP_B_TO_IOM_B_21_DN")
	)
	(segment
		(start 286.53105 -75.151488)
		(end 289.268662 -73.339452)
		(width 0.1397)
		(layer "In9.Cu")
		(net "PCIE_COMP_B_TO_IOM_B_21_DN")
	)
	(segment
		(start 364.149894 -19.338798)
		(end 364.149894 -19.750024)
		(width 0.1397)
		(layer "In9.Cu")
		(net "PCIE_COMP_B_TO_IOM_B_21_DN")
	)
	(segment
		(start 363.589824 -19.196304)
		(end 364.0074 -19.196304)
		(width 0.1397)
		(layer "In9.Cu")
		(net "PCIE_COMP_B_TO_IOM_B_21_DN")
	)
	(segment
		(start 291.27831 -72.164702)
		(end 291.627814 -71.933308)
		(width 0.1397)
		(layer "In9.Cu")
		(net "PCIE_COMP_B_TO_IOM_B_21_DN")
	)
	(segment
		(start 284.442916 -75.640184)
		(end 284.5054 -75.515216)
		(width 0.1397)
		(layer "In9.Cu")
		(net "PCIE_COMP_B_TO_IOM_B_21_DN")
	)
	(segment
		(start 284.913832 -75.346052)
		(end 285.573724 -75.346052)
		(width 0.1397)
		(layer "In9.Cu")
		(net "PCIE_COMP_B_TO_IOM_B_21_DN")
	)
	(segment
		(start 291.627814 -71.933308)
		(end 291.664136 -71.753984)
		(width 0.1397)
		(layer "In9.Cu")
		(net "PCIE_COMP_B_TO_IOM_B_21_DN")
	)
	(segment
		(start 298.55795 -67.191128)
		(end 307.625496 -61.189362)
		(width 0.1397)
		(layer "In9.Cu")
		(net "PCIE_COMP_B_TO_IOM_B_21_DN")
	)
	(segment
		(start 361.453684 -34.593022)
		(end 363.396022 -31.101284)
		(width 0.1397)
		(layer "In9.Cu")
		(net "PCIE_COMP_B_TO_IOM_B_21_DN")
	)
	(segment
		(start 285.573724 -75.346052)
		(end 286.53105 -75.151488)
		(width 0.1397)
		(layer "In9.Cu")
		(net "PCIE_COMP_B_TO_IOM_B_21_DN")
	)
	(segment
		(start 291.664136 -71.753984)
		(end 298.55795 -67.191128)
		(width 0.1397)
		(layer "In9.Cu")
		(net "PCIE_COMP_B_TO_IOM_B_21_DN")
	)
	(segment
		(start 290.712652 -72.539098)
		(end 290.749228 -72.35952)
		(width 0.1397)
		(layer "In9.Cu")
		(net "PCIE_COMP_B_TO_IOM_B_21_DN")
	)
	(arc
		(start 363.500162 -19.233388)
		(mid 363.541313 -19.205955)
		(end 363.589824 -19.196304)
		(width 0.1397)
		(layer "In9.Cu")
		(net "PCIE_COMP_B_TO_IOM_B_21_DN")
	)
	(arc
		(start 284.5054 -75.515216)
		(mid 284.69279 -75.390006)
		(end 284.913832 -75.346052)
		(width 0.1397)
		(layer "In9.Cu")
		(net "PCIE_COMP_B_TO_IOM_B_21_DN")
	)
	(arc
		(start 363.396022 -19.390106)
		(mid 363.405655 -19.341588)
		(end 363.433106 -19.300444)
		(width 0.1397)
		(layer "In9.Cu")
		(net "PCIE_COMP_B_TO_IOM_B_21_DN")
	)
	(arc
		(start 364.11281 -19.249136)
		(mid 364.140243 -19.290287)
		(end 364.149894 -19.338798)
		(width 0.1397)
		(layer "In9.Cu")
		(net "PCIE_COMP_B_TO_IOM_B_21_DN")
	)
	(arc
		(start 364.0074 -19.196304)
		(mid 364.055918 -19.205937)
		(end 364.097062 -19.233388)
		(width 0.1397)
		(layer "In9.Cu")
		(net "PCIE_COMP_B_TO_IOM_B_21_DN")
	)
	(arc
		(start 284.5054 -75.827636)
		(mid 284.435335 -75.746851)
		(end 284.442916 -75.640184)
		(width 0.1397)
		(layer "In9.Cu")
		(net "PCIE_COMP_B_TO_IOM_B_21_DN")
	)
	(segment
		(start 362.297218 -17.866868)
		(end 362.323634 -17.840452)
		(width 0.1397)
		(layer "In9.Cu")
		(net "PCIE_COMP_B_TO_IOM_B_20_DP")
	)
	(segment
		(start 284.914086 -71.05396)
		(end 285.878778 -71.05396)
		(width 0.1397)
		(layer "In9.Cu")
		(net "PCIE_COMP_B_TO_IOM_B_20_DP")
	)
	(segment
		(start 362.207302 -17.904206)
		(end 362.207556 -17.903952)
		(width 0.1397)
		(layer "In9.Cu")
		(net "PCIE_COMP_B_TO_IOM_B_20_DP")
	)
	(segment
		(start 349.897192 -39.60241)
		(end 360.788712 -32.661606)
		(width 0.1397)
		(layer "In9.Cu")
		(net "PCIE_COMP_B_TO_IOM_B_20_DP")
	)
	(segment
		(start 284.18155 -71.509636)
		(end 284.263084 -71.346568)
		(width 0.1397)
		(layer "In9.Cu")
		(net "PCIE_COMP_B_TO_IOM_B_20_DP")
	)
	(segment
		(start 361.426506 -18.093944)
		(end 361.493562 -18.026634)
		(width 0.1397)
		(layer "In9.Cu")
		(net "PCIE_COMP_B_TO_IOM_B_20_DP")
	)
	(segment
		(start 362.35005 -17.776698)
		(end 362.35005 -17.349978)
		(width 0.1397)
		(layer "In9.Cu")
		(net "PCIE_COMP_B_TO_IOM_B_20_DP")
	)
	(segment
		(start 360.788712 -32.661606)
		(end 361.304078 -31.734506)
		(width 0.1397)
		(layer "In9.Cu")
		(net "PCIE_COMP_B_TO_IOM_B_20_DP")
	)
	(segment
		(start 361.78998 -17.904206)
		(end 362.207302 -17.904206)
		(width 0.1397)
		(layer "In9.Cu")
		(net "PCIE_COMP_B_TO_IOM_B_20_DP")
	)
	(segment
		(start 361.304078 -31.734506)
		(end 361.304078 -18.390108)
		(width 0.1397)
		(layer "In9.Cu")
		(net "PCIE_COMP_B_TO_IOM_B_20_DP")
	)
	(segment
		(start 286.51581 -70.923912)
		(end 304.639218 -58.928508)
		(width 0.1397)
		(layer "In9.Cu")
		(net "PCIE_COMP_B_TO_IOM_B_20_DP")
	)
	(segment
		(start 283.249878 -71.20001)
		(end 283.994098 -71.57212)
		(width 0.1397)
		(layer "In9.Cu")
		(net "PCIE_COMP_B_TO_IOM_B_20_DP")
	)
	(segment
		(start 304.639218 -58.928508)
		(end 349.897192 -39.60241)
		(width 0.1397)
		(layer "In9.Cu")
		(net "PCIE_COMP_B_TO_IOM_B_20_DP")
	)
	(segment
		(start 285.878778 -71.05396)
		(end 286.51581 -70.923912)
		(width 0.1397)
		(layer "In9.Cu")
		(net "PCIE_COMP_B_TO_IOM_B_20_DP")
	)
	(arc
		(start 362.207556 -17.903952)
		(mid 362.256074 -17.894319)
		(end 362.297218 -17.866868)
		(width 0.1397)
		(layer "In9.Cu")
		(net "PCIE_COMP_B_TO_IOM_B_20_DP")
	)
	(arc
		(start 362.323634 -17.840452)
		(mid 362.343179 -17.811201)
		(end 362.35005 -17.776698)
		(width 0.1397)
		(layer "In9.Cu")
		(net "PCIE_COMP_B_TO_IOM_B_20_DP")
	)
	(arc
		(start 361.304078 -18.390108)
		(mid 361.335828 -18.229838)
		(end 361.426506 -18.093944)
		(width 0.1397)
		(layer "In9.Cu")
		(net "PCIE_COMP_B_TO_IOM_B_20_DP")
	)
	(arc
		(start 283.994098 -71.57212)
		(mid 284.100765 -71.579701)
		(end 284.18155 -71.509636)
		(width 0.1397)
		(layer "In9.Cu")
		(net "PCIE_COMP_B_TO_IOM_B_20_DP")
	)
	(arc
		(start 284.263084 -71.346568)
		(mid 284.557179 -71.13037)
		(end 284.914086 -71.05396)
		(width 0.1397)
		(layer "In9.Cu")
		(net "PCIE_COMP_B_TO_IOM_B_20_DP")
	)
	(arc
		(start 361.493562 -18.026634)
		(mid 361.629589 -17.9359)
		(end 361.78998 -17.904206)
		(width 0.1397)
		(layer "In9.Cu")
		(net "PCIE_COMP_B_TO_IOM_B_20_DP")
	)
	(segment
		(start 362.297218 -18.23339)
		(end 362.312966 -18.249138)
		(width 0.1397)
		(layer "In9.Cu")
		(net "PCIE_COMP_B_TO_IOM_B_20_DN")
	)
	(segment
		(start 361.008168 -32.868362)
		(end 361.596178 -31.810452)
		(width 0.1397)
		(layer "In9.Cu")
		(net "PCIE_COMP_B_TO_IOM_B_20_DN")
	)
	(segment
		(start 290.125912 -69.040248)
		(end 290.475416 -68.809108)
		(width 0.1397)
		(layer "In9.Cu")
		(net "PCIE_COMP_B_TO_IOM_B_20_DN")
	)
	(segment
		(start 350.033844 -39.861744)
		(end 350.054164 -39.849044)
		(width 0.1397)
		(layer "In9.Cu")
		(net "PCIE_COMP_B_TO_IOM_B_20_DN")
	)
	(segment
		(start 288.645346 -70.02018)
		(end 288.681922 -69.840856)
		(width 0.1397)
		(layer "In9.Cu")
		(net "PCIE_COMP_B_TO_IOM_B_20_DN")
	)
	(segment
		(start 285.908242 -71.34606)
		(end 286.629856 -71.198994)
		(width 0.1397)
		(layer "In9.Cu")
		(net "PCIE_COMP_B_TO_IOM_B_20_DN")
	)
	(segment
		(start 285.249874 -72.200008)
		(end 284.5054 -71.827644)
		(width 0.1397)
		(layer "In9.Cu")
		(net "PCIE_COMP_B_TO_IOM_B_20_DN")
	)
	(segment
		(start 284.913832 -71.34606)
		(end 285.908242 -71.34606)
		(width 0.1397)
		(layer "In9.Cu")
		(net "PCIE_COMP_B_TO_IOM_B_20_DN")
	)
	(segment
		(start 289.211004 -69.646038)
		(end 289.560508 -69.414644)
		(width 0.1397)
		(layer "In9.Cu")
		(net "PCIE_COMP_B_TO_IOM_B_20_DN")
	)
	(segment
		(start 362.35005 -18.3388)
		(end 362.35005 -18.750026)
		(width 0.1397)
		(layer "In9.Cu")
		(net "PCIE_COMP_B_TO_IOM_B_20_DN")
	)
	(segment
		(start 289.59683 -69.235066)
		(end 289.946334 -69.003926)
		(width 0.1397)
		(layer "In9.Cu")
		(net "PCIE_COMP_B_TO_IOM_B_20_DN")
	)
	(segment
		(start 284.442916 -71.640192)
		(end 284.5054 -71.515224)
		(width 0.1397)
		(layer "In9.Cu")
		(net "PCIE_COMP_B_TO_IOM_B_20_DN")
	)
	(segment
		(start 361.78998 -18.196306)
		(end 362.207556 -18.196306)
		(width 0.1397)
		(layer "In9.Cu")
		(net "PCIE_COMP_B_TO_IOM_B_20_DN")
	)
	(segment
		(start 361.596178 -31.810452)
		(end 361.596178 -18.390108)
		(width 0.1397)
		(layer "In9.Cu")
		(net "PCIE_COMP_B_TO_IOM_B_20_DN")
	)
	(segment
		(start 361.633262 -18.300446)
		(end 361.700318 -18.23339)
		(width 0.1397)
		(layer "In9.Cu")
		(net "PCIE_COMP_B_TO_IOM_B_20_DN")
	)
	(segment
		(start 290.511992 -68.62953)
		(end 304.77841 -59.186826)
		(width 0.1397)
		(layer "In9.Cu")
		(net "PCIE_COMP_B_TO_IOM_B_20_DN")
	)
	(segment
		(start 286.629856 -71.198994)
		(end 288.116518 -70.214998)
		(width 0.1397)
		(layer "In9.Cu")
		(net "PCIE_COMP_B_TO_IOM_B_20_DN")
	)
	(segment
		(start 350.054164 -39.849044)
		(end 350.054164 -39.84879)
		(width 0.1397)
		(layer "In9.Cu")
		(net "PCIE_COMP_B_TO_IOM_B_20_DN")
	)
	(segment
		(start 289.946334 -69.003926)
		(end 290.125912 -69.040248)
		(width 0.1397)
		(layer "In9.Cu")
		(net "PCIE_COMP_B_TO_IOM_B_20_DN")
	)
	(segment
		(start 288.681922 -69.840856)
		(end 289.031426 -69.609462)
		(width 0.1397)
		(layer "In9.Cu")
		(net "PCIE_COMP_B_TO_IOM_B_20_DN")
	)
	(segment
		(start 288.295842 -70.251574)
		(end 288.645346 -70.02018)
		(width 0.1397)
		(layer "In9.Cu")
		(net "PCIE_COMP_B_TO_IOM_B_20_DN")
	)
	(segment
		(start 350.054164 -39.84879)
		(end 361.008168 -32.868362)
		(width 0.1397)
		(layer "In9.Cu")
		(net "PCIE_COMP_B_TO_IOM_B_20_DN")
	)
	(segment
		(start 290.475416 -68.809108)
		(end 290.511992 -68.62953)
		(width 0.1397)
		(layer "In9.Cu")
		(net "PCIE_COMP_B_TO_IOM_B_20_DN")
	)
	(segment
		(start 304.77841 -59.186826)
		(end 350.033844 -39.861744)
		(width 0.1397)
		(layer "In9.Cu")
		(net "PCIE_COMP_B_TO_IOM_B_20_DN")
	)
	(segment
		(start 288.116518 -70.214998)
		(end 288.295842 -70.251574)
		(width 0.1397)
		(layer "In9.Cu")
		(net "PCIE_COMP_B_TO_IOM_B_20_DN")
	)
	(segment
		(start 289.560508 -69.414644)
		(end 289.59683 -69.235066)
		(width 0.1397)
		(layer "In9.Cu")
		(net "PCIE_COMP_B_TO_IOM_B_20_DN")
	)
	(segment
		(start 289.031426 -69.609462)
		(end 289.211004 -69.646038)
		(width 0.1397)
		(layer "In9.Cu")
		(net "PCIE_COMP_B_TO_IOM_B_20_DN")
	)
	(arc
		(start 362.312966 -18.249138)
		(mid 362.340399 -18.290289)
		(end 362.35005 -18.3388)
		(width 0.1397)
		(layer "In9.Cu")
		(net "PCIE_COMP_B_TO_IOM_B_20_DN")
	)
	(arc
		(start 361.596178 -18.390108)
		(mid 361.605811 -18.34159)
		(end 361.633262 -18.300446)
		(width 0.1397)
		(layer "In9.Cu")
		(net "PCIE_COMP_B_TO_IOM_B_20_DN")
	)
	(arc
		(start 284.5054 -71.827644)
		(mid 284.435335 -71.746859)
		(end 284.442916 -71.640192)
		(width 0.1397)
		(layer "In9.Cu")
		(net "PCIE_COMP_B_TO_IOM_B_20_DN")
	)
	(arc
		(start 284.5054 -71.515224)
		(mid 284.69279 -71.390014)
		(end 284.913832 -71.34606)
		(width 0.1397)
		(layer "In9.Cu")
		(net "PCIE_COMP_B_TO_IOM_B_20_DN")
	)
	(arc
		(start 362.207556 -18.196306)
		(mid 362.256074 -18.205939)
		(end 362.297218 -18.23339)
		(width 0.1397)
		(layer "In9.Cu")
		(net "PCIE_COMP_B_TO_IOM_B_20_DN")
	)
	(arc
		(start 361.700318 -18.23339)
		(mid 361.741469 -18.205957)
		(end 361.78998 -18.196306)
		(width 0.1397)
		(layer "In9.Cu")
		(net "PCIE_COMP_B_TO_IOM_B_20_DN")
	)
	(segment
		(start 360.512868 -18.851118)
		(end 360.49712 -18.866866)
		(width 0.1397)
		(layer "In9.Cu")
		(net "PCIE_COMP_B_TO_IOM_B_19_DP")
	)
	(segment
		(start 283.994098 -67.572128)
		(end 283.249878 -67.200018)
		(width 0.1397)
		(layer "In9.Cu")
		(net "PCIE_COMP_B_TO_IOM_B_19_DP")
	)
	(segment
		(start 359.50398 -30.91307)
		(end 358.647492 -32.454088)
		(width 0.1397)
		(layer "In9.Cu")
		(net "PCIE_COMP_B_TO_IOM_B_19_DP")
	)
	(segment
		(start 359.50398 -19.390106)
		(end 359.50398 -30.91307)
		(width 0.1397)
		(layer "In9.Cu")
		(net "PCIE_COMP_B_TO_IOM_B_19_DP")
	)
	(segment
		(start 285.647638 -67.053968)
		(end 284.914086 -67.053968)
		(width 0.1397)
		(layer "In9.Cu")
		(net "PCIE_COMP_B_TO_IOM_B_19_DP")
	)
	(segment
		(start 286.642048 -66.3956)
		(end 285.647638 -67.053968)
		(width 0.1397)
		(layer "In9.Cu")
		(net "PCIE_COMP_B_TO_IOM_B_19_DP")
	)
	(segment
		(start 352.08845 -36.633658)
		(end 339.700616 -39.51986)
		(width 0.1397)
		(layer "In9.Cu")
		(net "PCIE_COMP_B_TO_IOM_B_19_DP")
	)
	(segment
		(start 360.407458 -18.90395)
		(end 360.407204 -18.904204)
		(width 0.1397)
		(layer "In9.Cu")
		(net "PCIE_COMP_B_TO_IOM_B_19_DP")
	)
	(segment
		(start 358.647492 -32.454088)
		(end 352.08845 -36.633658)
		(width 0.1397)
		(layer "In9.Cu")
		(net "PCIE_COMP_B_TO_IOM_B_19_DP")
	)
	(segment
		(start 360.549952 -18.35023)
		(end 360.549952 -18.761456)
		(width 0.1397)
		(layer "In9.Cu")
		(net "PCIE_COMP_B_TO_IOM_B_19_DP")
	)
	(segment
		(start 360.407204 -18.904204)
		(end 359.989882 -18.904204)
		(width 0.1397)
		(layer "In9.Cu")
		(net "PCIE_COMP_B_TO_IOM_B_19_DP")
	)
	(segment
		(start 284.263084 -67.346576)
		(end 284.18155 -67.509644)
		(width 0.1397)
		(layer "In9.Cu")
		(net "PCIE_COMP_B_TO_IOM_B_19_DP")
	)
	(segment
		(start 339.700616 -39.51986)
		(end 286.642048 -66.3956)
		(width 0.1397)
		(layer "In9.Cu")
		(net "PCIE_COMP_B_TO_IOM_B_19_DP")
	)
	(segment
		(start 359.693464 -19.026632)
		(end 359.626408 -19.093942)
		(width 0.1397)
		(layer "In9.Cu")
		(net "PCIE_COMP_B_TO_IOM_B_19_DP")
	)
	(arc
		(start 284.18155 -67.509644)
		(mid 284.100765 -67.579709)
		(end 283.994098 -67.572128)
		(width 0.1397)
		(layer "In9.Cu")
		(net "PCIE_COMP_B_TO_IOM_B_19_DP")
	)
	(arc
		(start 359.626408 -19.093942)
		(mid 359.535805 -19.229867)
		(end 359.50398 -19.390106)
		(width 0.1397)
		(layer "In9.Cu")
		(net "PCIE_COMP_B_TO_IOM_B_19_DP")
	)
	(arc
		(start 359.989882 -18.904204)
		(mid 359.829529 -18.935989)
		(end 359.693464 -19.026632)
		(width 0.1397)
		(layer "In9.Cu")
		(net "PCIE_COMP_B_TO_IOM_B_19_DP")
	)
	(arc
		(start 360.549952 -18.761456)
		(mid 360.540319 -18.809974)
		(end 360.512868 -18.851118)
		(width 0.1397)
		(layer "In9.Cu")
		(net "PCIE_COMP_B_TO_IOM_B_19_DP")
	)
	(arc
		(start 360.49712 -18.866866)
		(mid 360.455969 -18.894299)
		(end 360.407458 -18.90395)
		(width 0.1397)
		(layer "In9.Cu")
		(net "PCIE_COMP_B_TO_IOM_B_19_DP")
	)
	(arc
		(start 284.914086 -67.053968)
		(mid 284.55721 -67.130448)
		(end 284.263084 -67.346576)
		(width 0.1397)
		(layer "In9.Cu")
		(net "PCIE_COMP_B_TO_IOM_B_19_DP")
	)
	(segment
		(start 352.245422 -36.880292)
		(end 352.203512 -36.906962)
		(width 0.1397)
		(layer "In9.Cu")
		(net "PCIE_COMP_B_TO_IOM_B_19_DN")
	)
	(segment
		(start 284.5054 -67.827652)
		(end 285.249874 -68.200016)
		(width 0.1397)
		(layer "In9.Cu")
		(net "PCIE_COMP_B_TO_IOM_B_19_DN")
	)
	(segment
		(start 360.407458 -19.196304)
		(end 359.989882 -19.196304)
		(width 0.1397)
		(layer "In9.Cu")
		(net "PCIE_COMP_B_TO_IOM_B_19_DN")
	)
	(segment
		(start 290.106354 -65.113408)
		(end 289.932364 -65.056512)
		(width 0.1397)
		(layer "In9.Cu")
		(net "PCIE_COMP_B_TO_IOM_B_19_DN")
	)
	(segment
		(start 287.974532 -66.048128)
		(end 286.789114 -66.648584)
		(width 0.1397)
		(layer "In9.Cu")
		(net "PCIE_COMP_B_TO_IOM_B_19_DN")
	)
	(segment
		(start 289.932364 -65.056512)
		(end 289.558476 -65.245742)
		(width 0.1397)
		(layer "In9.Cu")
		(net "PCIE_COMP_B_TO_IOM_B_19_DN")
	)
	(segment
		(start 352.203512 -36.906962)
		(end 339.8012 -39.796466)
		(width 0.1397)
		(layer "In9.Cu")
		(net "PCIE_COMP_B_TO_IOM_B_19_DN")
	)
	(segment
		(start 360.512868 -19.249136)
		(end 360.49712 -19.233388)
		(width 0.1397)
		(layer "In9.Cu")
		(net "PCIE_COMP_B_TO_IOM_B_19_DN")
	)
	(segment
		(start 288.953448 -65.55232)
		(end 288.57956 -65.74155)
		(width 0.1397)
		(layer "In9.Cu")
		(net "PCIE_COMP_B_TO_IOM_B_19_DN")
	)
	(segment
		(start 285.735776 -67.346068)
		(end 284.913832 -67.346068)
		(width 0.1397)
		(layer "In9.Cu")
		(net "PCIE_COMP_B_TO_IOM_B_19_DN")
	)
	(segment
		(start 289.127692 -65.609216)
		(end 288.953448 -65.55232)
		(width 0.1397)
		(layer "In9.Cu")
		(net "PCIE_COMP_B_TO_IOM_B_19_DN")
	)
	(segment
		(start 359.90022 -19.233388)
		(end 359.833164 -19.300444)
		(width 0.1397)
		(layer "In9.Cu")
		(net "PCIE_COMP_B_TO_IOM_B_19_DN")
	)
	(segment
		(start 360.549952 -19.750024)
		(end 360.549952 -19.338798)
		(width 0.1397)
		(layer "In9.Cu")
		(net "PCIE_COMP_B_TO_IOM_B_19_DN")
	)
	(segment
		(start 288.148776 -66.105024)
		(end 287.974532 -66.048128)
		(width 0.1397)
		(layer "In9.Cu")
		(net "PCIE_COMP_B_TO_IOM_B_19_DN")
	)
	(segment
		(start 290.537392 -64.749934)
		(end 290.480242 -64.924178)
		(width 0.1397)
		(layer "In9.Cu")
		(net "PCIE_COMP_B_TO_IOM_B_19_DN")
	)
	(segment
		(start 289.501326 -65.419986)
		(end 289.127692 -65.609216)
		(width 0.1397)
		(layer "In9.Cu")
		(net "PCIE_COMP_B_TO_IOM_B_19_DN")
	)
	(segment
		(start 359.79608 -19.390106)
		(end 359.79608 -30.989016)
		(width 0.1397)
		(layer "In9.Cu")
		(net "PCIE_COMP_B_TO_IOM_B_19_DN")
	)
	(segment
		(start 284.5054 -67.515232)
		(end 284.442916 -67.6402)
		(width 0.1397)
		(layer "In9.Cu")
		(net "PCIE_COMP_B_TO_IOM_B_19_DN")
	)
	(segment
		(start 359.79608 -30.989016)
		(end 358.866948 -32.660844)
		(width 0.1397)
		(layer "In9.Cu")
		(net "PCIE_COMP_B_TO_IOM_B_19_DN")
	)
	(segment
		(start 352.245422 -36.880038)
		(end 352.245422 -36.880292)
		(width 0.1397)
		(layer "In9.Cu")
		(net "PCIE_COMP_B_TO_IOM_B_19_DN")
	)
	(segment
		(start 289.558476 -65.245742)
		(end 289.501326 -65.419986)
		(width 0.1397)
		(layer "In9.Cu")
		(net "PCIE_COMP_B_TO_IOM_B_19_DN")
	)
	(segment
		(start 288.522664 -65.915794)
		(end 288.148776 -66.105024)
		(width 0.1397)
		(layer "In9.Cu")
		(net "PCIE_COMP_B_TO_IOM_B_19_DN")
	)
	(segment
		(start 290.480242 -64.924178)
		(end 290.106354 -65.113408)
		(width 0.1397)
		(layer "In9.Cu")
		(net "PCIE_COMP_B_TO_IOM_B_19_DN")
	)
	(segment
		(start 339.8012 -39.796466)
		(end 290.537392 -64.749934)
		(width 0.1397)
		(layer "In9.Cu")
		(net "PCIE_COMP_B_TO_IOM_B_19_DN")
	)
	(segment
		(start 358.866948 -32.660844)
		(end 352.245422 -36.880038)
		(width 0.1397)
		(layer "In9.Cu")
		(net "PCIE_COMP_B_TO_IOM_B_19_DN")
	)
	(segment
		(start 288.57956 -65.74155)
		(end 288.522664 -65.915794)
		(width 0.1397)
		(layer "In9.Cu")
		(net "PCIE_COMP_B_TO_IOM_B_19_DN")
	)
	(segment
		(start 286.789114 -66.648584)
		(end 285.735776 -67.346068)
		(width 0.1397)
		(layer "In9.Cu")
		(net "PCIE_COMP_B_TO_IOM_B_19_DN")
	)
	(arc
		(start 359.833164 -19.300444)
		(mid 359.805731 -19.341595)
		(end 359.79608 -19.390106)
		(width 0.1397)
		(layer "In9.Cu")
		(net "PCIE_COMP_B_TO_IOM_B_19_DN")
	)
	(arc
		(start 284.442916 -67.6402)
		(mid 284.435335 -67.746867)
		(end 284.5054 -67.827652)
		(width 0.1397)
		(layer "In9.Cu")
		(net "PCIE_COMP_B_TO_IOM_B_19_DN")
	)
	(arc
		(start 360.49712 -19.233388)
		(mid 360.455969 -19.205955)
		(end 360.407458 -19.196304)
		(width 0.1397)
		(layer "In9.Cu")
		(net "PCIE_COMP_B_TO_IOM_B_19_DN")
	)
	(arc
		(start 360.549952 -19.338798)
		(mid 360.540319 -19.29028)
		(end 360.512868 -19.249136)
		(width 0.1397)
		(layer "In9.Cu")
		(net "PCIE_COMP_B_TO_IOM_B_19_DN")
	)
	(arc
		(start 284.913832 -67.346068)
		(mid 284.692796 -67.390035)
		(end 284.5054 -67.515232)
		(width 0.1397)
		(layer "In9.Cu")
		(net "PCIE_COMP_B_TO_IOM_B_19_DN")
	)
	(arc
		(start 359.989882 -19.196304)
		(mid 359.941364 -19.205937)
		(end 359.90022 -19.233388)
		(width 0.1397)
		(layer "In9.Cu")
		(net "PCIE_COMP_B_TO_IOM_B_19_DN")
	)
	(segment
		(start 286.75584 -62.802516)
		(end 285.520638 -63.053976)
		(width 0.1397)
		(layer "In9.Cu")
		(net "PCIE_COMP_B_TO_IOM_B_18_DP")
	)
	(segment
		(start 358.60736 -17.904206)
		(end 358.190038 -17.904206)
		(width 0.1397)
		(layer "In9.Cu")
		(net "PCIE_COMP_B_TO_IOM_B_18_DP")
	)
	(segment
		(start 352.720402 -34.716974)
		(end 352.720402 -34.717228)
		(width 0.1397)
		(layer "In9.Cu")
		(net "PCIE_COMP_B_TO_IOM_B_18_DP")
	)
	(segment
		(start 357.704136 -18.390108)
		(end 357.704136 -31.23692)
		(width 0.1397)
		(layer "In9.Cu")
		(net "PCIE_COMP_B_TO_IOM_B_18_DP")
	)
	(segment
		(start 284.263084 -63.346584)
		(end 284.18155 -63.509652)
		(width 0.1397)
		(layer "In9.Cu")
		(net "PCIE_COMP_B_TO_IOM_B_18_DP")
	)
	(segment
		(start 357.704136 -31.23692)
		(end 357.441246 -31.709106)
		(width 0.1397)
		(layer "In9.Cu")
		(net "PCIE_COMP_B_TO_IOM_B_18_DP")
	)
	(segment
		(start 357.441246 -31.709106)
		(end 352.720402 -34.716974)
		(width 0.1397)
		(layer "In9.Cu")
		(net "PCIE_COMP_B_TO_IOM_B_18_DP")
	)
	(segment
		(start 357.89362 -18.026634)
		(end 357.826564 -18.093944)
		(width 0.1397)
		(layer "In9.Cu")
		(net "PCIE_COMP_B_TO_IOM_B_18_DP")
	)
	(segment
		(start 358.750108 -17.349978)
		(end 358.750108 -17.776698)
		(width 0.1397)
		(layer "In9.Cu")
		(net "PCIE_COMP_B_TO_IOM_B_18_DP")
	)
	(segment
		(start 358.723692 -17.840452)
		(end 358.697276 -17.866868)
		(width 0.1397)
		(layer "In9.Cu")
		(net "PCIE_COMP_B_TO_IOM_B_18_DP")
	)
	(segment
		(start 352.720402 -34.717228)
		(end 340.665562 -37.525452)
		(width 0.1397)
		(layer "In9.Cu")
		(net "PCIE_COMP_B_TO_IOM_B_18_DP")
	)
	(segment
		(start 358.607614 -17.903952)
		(end 358.60736 -17.904206)
		(width 0.1397)
		(layer "In9.Cu")
		(net "PCIE_COMP_B_TO_IOM_B_18_DP")
	)
	(segment
		(start 283.994098 -63.572136)
		(end 283.249878 -63.200026)
		(width 0.1397)
		(layer "In9.Cu")
		(net "PCIE_COMP_B_TO_IOM_B_18_DP")
	)
	(segment
		(start 302.255936 -52.542948)
		(end 286.75584 -62.802516)
		(width 0.1397)
		(layer "In9.Cu")
		(net "PCIE_COMP_B_TO_IOM_B_18_DP")
	)
	(segment
		(start 340.665562 -37.525452)
		(end 302.255936 -52.542948)
		(width 0.1397)
		(layer "In9.Cu")
		(net "PCIE_COMP_B_TO_IOM_B_18_DP")
	)
	(segment
		(start 285.520638 -63.053976)
		(end 284.914086 -63.053976)
		(width 0.1397)
		(layer "In9.Cu")
		(net "PCIE_COMP_B_TO_IOM_B_18_DP")
	)
	(arc
		(start 357.826564 -18.093944)
		(mid 357.735961 -18.229869)
		(end 357.704136 -18.390108)
		(width 0.1397)
		(layer "In9.Cu")
		(net "PCIE_COMP_B_TO_IOM_B_18_DP")
	)
	(arc
		(start 284.18155 -63.509652)
		(mid 284.100765 -63.579717)
		(end 283.994098 -63.572136)
		(width 0.1397)
		(layer "In9.Cu")
		(net "PCIE_COMP_B_TO_IOM_B_18_DP")
	)
	(arc
		(start 284.914086 -63.053976)
		(mid 284.55721 -63.130456)
		(end 284.263084 -63.346584)
		(width 0.1397)
		(layer "In9.Cu")
		(net "PCIE_COMP_B_TO_IOM_B_18_DP")
	)
	(arc
		(start 358.697276 -17.866868)
		(mid 358.656125 -17.894301)
		(end 358.607614 -17.903952)
		(width 0.1397)
		(layer "In9.Cu")
		(net "PCIE_COMP_B_TO_IOM_B_18_DP")
	)
	(arc
		(start 358.190038 -17.904206)
		(mid 358.029685 -17.935991)
		(end 357.89362 -18.026634)
		(width 0.1397)
		(layer "In9.Cu")
		(net "PCIE_COMP_B_TO_IOM_B_18_DP")
	)
	(arc
		(start 358.750108 -17.776698)
		(mid 358.743244 -17.811205)
		(end 358.723692 -17.840452)
		(width 0.1397)
		(layer "In9.Cu")
		(net "PCIE_COMP_B_TO_IOM_B_18_DP")
	)
	(segment
		(start 289.976814 -61.176408)
		(end 289.79749 -61.139832)
		(width 0.1397)
		(layer "In9.Cu")
		(net "PCIE_COMP_B_TO_IOM_B_18_DN")
	)
	(segment
		(start 290.891976 -60.570618)
		(end 290.712398 -60.534296)
		(width 0.1397)
		(layer "In9.Cu")
		(net "PCIE_COMP_B_TO_IOM_B_18_DN")
	)
	(segment
		(start 352.835464 -34.990532)
		(end 352.835718 -34.990532)
		(width 0.1397)
		(layer "In9.Cu")
		(net "PCIE_COMP_B_TO_IOM_B_18_DN")
	)
	(segment
		(start 289.061906 -61.781944)
		(end 288.882328 -61.745368)
		(width 0.1397)
		(layer "In9.Cu")
		(net "PCIE_COMP_B_TO_IOM_B_18_DN")
	)
	(segment
		(start 357.996236 -18.390108)
		(end 357.996236 -31.312866)
		(width 0.1397)
		(layer "In9.Cu")
		(net "PCIE_COMP_B_TO_IOM_B_18_DN")
	)
	(segment
		(start 358.713024 -18.249138)
		(end 358.697276 -18.23339)
		(width 0.1397)
		(layer "In9.Cu")
		(net "PCIE_COMP_B_TO_IOM_B_18_DN")
	)
	(segment
		(start 290.712398 -60.534296)
		(end 290.362894 -60.765436)
		(width 0.1397)
		(layer "In9.Cu")
		(net "PCIE_COMP_B_TO_IOM_B_18_DN")
	)
	(segment
		(start 291.24148 -60.339478)
		(end 290.891976 -60.570618)
		(width 0.1397)
		(layer "In9.Cu")
		(net "PCIE_COMP_B_TO_IOM_B_18_DN")
	)
	(segment
		(start 291.277802 -60.1599)
		(end 291.24148 -60.339478)
		(width 0.1397)
		(layer "In9.Cu")
		(net "PCIE_COMP_B_TO_IOM_B_18_DN")
	)
	(segment
		(start 352.835464 -34.990278)
		(end 352.835464 -34.990532)
		(width 0.1397)
		(layer "In9.Cu")
		(net "PCIE_COMP_B_TO_IOM_B_18_DN")
	)
	(segment
		(start 355.237796 -33.459674)
		(end 352.835464 -34.990278)
		(width 0.1397)
		(layer "In9.Cu")
		(net "PCIE_COMP_B_TO_IOM_B_18_DN")
	)
	(segment
		(start 357.996236 -31.312866)
		(end 357.660702 -31.915862)
		(width 0.1397)
		(layer "In9.Cu")
		(net "PCIE_COMP_B_TO_IOM_B_18_DN")
	)
	(segment
		(start 289.79749 -61.139832)
		(end 289.447986 -61.371226)
		(width 0.1397)
		(layer "In9.Cu")
		(net "PCIE_COMP_B_TO_IOM_B_18_DN")
	)
	(segment
		(start 358.750108 -18.750026)
		(end 358.750108 -18.3388)
		(width 0.1397)
		(layer "In9.Cu")
		(net "PCIE_COMP_B_TO_IOM_B_18_DN")
	)
	(segment
		(start 340.75243 -37.80536)
		(end 302.391318 -52.803806)
		(width 0.1397)
		(layer "In9.Cu")
		(net "PCIE_COMP_B_TO_IOM_B_18_DN")
	)
	(segment
		(start 358.100376 -18.23339)
		(end 358.03332 -18.300446)
		(width 0.1397)
		(layer "In9.Cu")
		(net "PCIE_COMP_B_TO_IOM_B_18_DN")
	)
	(segment
		(start 302.391318 -52.803806)
		(end 291.277802 -60.1599)
		(width 0.1397)
		(layer "In9.Cu")
		(net "PCIE_COMP_B_TO_IOM_B_18_DN")
	)
	(segment
		(start 352.835718 -34.990532)
		(end 340.75243 -37.80536)
		(width 0.1397)
		(layer "In9.Cu")
		(net "PCIE_COMP_B_TO_IOM_B_18_DN")
	)
	(segment
		(start 284.5054 -63.82766)
		(end 285.249874 -64.200024)
		(width 0.1397)
		(layer "In9.Cu")
		(net "PCIE_COMP_B_TO_IOM_B_18_DN")
	)
	(segment
		(start 286.869886 -63.077598)
		(end 285.550102 -63.346076)
		(width 0.1397)
		(layer "In9.Cu")
		(net "PCIE_COMP_B_TO_IOM_B_18_DN")
	)
	(segment
		(start 284.5054 -63.51524)
		(end 284.442916 -63.640208)
		(width 0.1397)
		(layer "In9.Cu")
		(net "PCIE_COMP_B_TO_IOM_B_18_DN")
	)
	(segment
		(start 285.550102 -63.346076)
		(end 284.913832 -63.346076)
		(width 0.1397)
		(layer "In9.Cu")
		(net "PCIE_COMP_B_TO_IOM_B_18_DN")
	)
	(segment
		(start 290.362894 -60.765436)
		(end 290.326318 -60.945014)
		(width 0.1397)
		(layer "In9.Cu")
		(net "PCIE_COMP_B_TO_IOM_B_18_DN")
	)
	(segment
		(start 289.41141 -61.550804)
		(end 289.061906 -61.781944)
		(width 0.1397)
		(layer "In9.Cu")
		(net "PCIE_COMP_B_TO_IOM_B_18_DN")
	)
	(segment
		(start 290.326318 -60.945014)
		(end 289.976814 -61.176408)
		(width 0.1397)
		(layer "In9.Cu")
		(net "PCIE_COMP_B_TO_IOM_B_18_DN")
	)
	(segment
		(start 357.660702 -31.915862)
		(end 355.237796 -33.459674)
		(width 0.1397)
		(layer "In9.Cu")
		(net "PCIE_COMP_B_TO_IOM_B_18_DN")
	)
	(segment
		(start 358.607614 -18.196306)
		(end 358.190038 -18.196306)
		(width 0.1397)
		(layer "In9.Cu")
		(net "PCIE_COMP_B_TO_IOM_B_18_DN")
	)
	(segment
		(start 289.447986 -61.371226)
		(end 289.41141 -61.550804)
		(width 0.1397)
		(layer "In9.Cu")
		(net "PCIE_COMP_B_TO_IOM_B_18_DN")
	)
	(segment
		(start 288.882328 -61.745368)
		(end 286.869886 -63.077598)
		(width 0.1397)
		(layer "In9.Cu")
		(net "PCIE_COMP_B_TO_IOM_B_18_DN")
	)
	(arc
		(start 358.697276 -18.23339)
		(mid 358.656125 -18.205957)
		(end 358.607614 -18.196306)
		(width 0.1397)
		(layer "In9.Cu")
		(net "PCIE_COMP_B_TO_IOM_B_18_DN")
	)
	(arc
		(start 358.750108 -18.3388)
		(mid 358.740475 -18.290282)
		(end 358.713024 -18.249138)
		(width 0.1397)
		(layer "In9.Cu")
		(net "PCIE_COMP_B_TO_IOM_B_18_DN")
	)
	(arc
		(start 284.442916 -63.640208)
		(mid 284.435335 -63.746875)
		(end 284.5054 -63.82766)
		(width 0.1397)
		(layer "In9.Cu")
		(net "PCIE_COMP_B_TO_IOM_B_18_DN")
	)
	(arc
		(start 284.913832 -63.346076)
		(mid 284.692796 -63.390043)
		(end 284.5054 -63.51524)
		(width 0.1397)
		(layer "In9.Cu")
		(net "PCIE_COMP_B_TO_IOM_B_18_DN")
	)
	(arc
		(start 358.190038 -18.196306)
		(mid 358.14152 -18.205939)
		(end 358.100376 -18.23339)
		(width 0.1397)
		(layer "In9.Cu")
		(net "PCIE_COMP_B_TO_IOM_B_18_DN")
	)
	(arc
		(start 358.03332 -18.300446)
		(mid 358.005887 -18.341597)
		(end 357.996236 -18.390108)
		(width 0.1397)
		(layer "In9.Cu")
		(net "PCIE_COMP_B_TO_IOM_B_18_DN")
	)
	(segment
		(start 284.263084 -59.346592)
		(end 284.18155 -59.50966)
		(width 0.1397)
		(layer "In9.Cu")
		(net "PCIE_COMP_B_TO_IOM_B_17_DP")
	)
	(segment
		(start 285.372302 -59.053984)
		(end 284.913832 -59.053984)
		(width 0.1397)
		(layer "In9.Cu")
		(net "PCIE_COMP_B_TO_IOM_B_17_DP")
	)
	(segment
		(start 355.904038 -19.390106)
		(end 355.904038 -30.728158)
		(width 0.1397)
		(layer "In9.Cu")
		(net "PCIE_COMP_B_TO_IOM_B_17_DP")
	)
	(segment
		(start 355.75748 -30.991556)
		(end 352.081084 -33.570418)
		(width 0.1397)
		(layer "In9.Cu")
		(net "PCIE_COMP_B_TO_IOM_B_17_DP")
	)
	(segment
		(start 355.904038 -30.728158)
		(end 355.75748 -30.991556)
		(width 0.1397)
		(layer "In9.Cu")
		(net "PCIE_COMP_B_TO_IOM_B_17_DP")
	)
	(segment
		(start 283.994098 -59.572144)
		(end 283.249878 -59.200034)
		(width 0.1397)
		(layer "In9.Cu")
		(net "PCIE_COMP_B_TO_IOM_B_17_DP")
	)
	(segment
		(start 352.081084 -33.570418)
		(end 336.744564 -37.143436)
		(width 0.1397)
		(layer "In9.Cu")
		(net "PCIE_COMP_B_TO_IOM_B_17_DP")
	)
	(segment
		(start 294.6146 -53.60289)
		(end 286.817816 -58.760614)
		(width 0.1397)
		(layer "In9.Cu")
		(net "PCIE_COMP_B_TO_IOM_B_17_DP")
	)
	(segment
		(start 356.912926 -18.851118)
		(end 356.897178 -18.866866)
		(width 0.1397)
		(layer "In9.Cu")
		(net "PCIE_COMP_B_TO_IOM_B_17_DP")
	)
	(segment
		(start 356.807262 -18.904204)
		(end 356.38994 -18.904204)
		(width 0.1397)
		(layer "In9.Cu")
		(net "PCIE_COMP_B_TO_IOM_B_17_DP")
	)
	(segment
		(start 356.807516 -18.90395)
		(end 356.807262 -18.904204)
		(width 0.1397)
		(layer "In9.Cu")
		(net "PCIE_COMP_B_TO_IOM_B_17_DP")
	)
	(segment
		(start 356.95001 -18.35023)
		(end 356.95001 -18.761456)
		(width 0.1397)
		(layer "In9.Cu")
		(net "PCIE_COMP_B_TO_IOM_B_17_DP")
	)
	(segment
		(start 336.744564 -37.143436)
		(end 294.6146 -53.60289)
		(width 0.1397)
		(layer "In9.Cu")
		(net "PCIE_COMP_B_TO_IOM_B_17_DP")
	)
	(segment
		(start 286.817816 -58.760614)
		(end 285.372302 -59.053984)
		(width 0.1397)
		(layer "In9.Cu")
		(net "PCIE_COMP_B_TO_IOM_B_17_DP")
	)
	(arc
		(start 356.38994 -18.904204)
		(mid 356.046355 -19.046521)
		(end 355.904038 -19.390106)
		(width 0.1397)
		(layer "In9.Cu")
		(net "PCIE_COMP_B_TO_IOM_B_17_DP")
	)
	(arc
		(start 356.95001 -18.761456)
		(mid 356.940377 -18.809974)
		(end 356.912926 -18.851118)
		(width 0.1397)
		(layer "In9.Cu")
		(net "PCIE_COMP_B_TO_IOM_B_17_DP")
	)
	(arc
		(start 284.913832 -59.053984)
		(mid 284.557094 -59.130516)
		(end 284.263084 -59.346592)
		(width 0.1397)
		(layer "In9.Cu")
		(net "PCIE_COMP_B_TO_IOM_B_17_DP")
	)
	(arc
		(start 356.897178 -18.866866)
		(mid 356.856027 -18.894299)
		(end 356.807516 -18.90395)
		(width 0.1397)
		(layer "In9.Cu")
		(net "PCIE_COMP_B_TO_IOM_B_17_DP")
	)
	(arc
		(start 284.18155 -59.50966)
		(mid 284.100765 -59.579725)
		(end 283.994098 -59.572144)
		(width 0.1397)
		(layer "In9.Cu")
		(net "PCIE_COMP_B_TO_IOM_B_17_DP")
	)
	(segment
		(start 355.980238 -31.192216)
		(end 352.202496 -33.842198)
		(width 0.1397)
		(layer "In9.Cu")
		(net "PCIE_COMP_B_TO_IOM_B_17_DN")
	)
	(segment
		(start 294.749728 -53.863748)
		(end 292.364668 -55.441596)
		(width 0.1397)
		(layer "In9.Cu")
		(net "PCIE_COMP_B_TO_IOM_B_17_DN")
	)
	(segment
		(start 289.968686 -57.026556)
		(end 286.931608 -59.035696)
		(width 0.1397)
		(layer "In9.Cu")
		(net "PCIE_COMP_B_TO_IOM_B_17_DN")
	)
	(segment
		(start 290.497768 -56.831992)
		(end 290.148264 -57.063132)
		(width 0.1397)
		(layer "In9.Cu")
		(net "PCIE_COMP_B_TO_IOM_B_17_DN")
	)
	(segment
		(start 356.912926 -19.249136)
		(end 356.897178 -19.233388)
		(width 0.1397)
		(layer "In9.Cu")
		(net "PCIE_COMP_B_TO_IOM_B_17_DN")
	)
	(segment
		(start 356.95001 -19.750024)
		(end 356.95001 -19.338798)
		(width 0.1397)
		(layer "In9.Cu")
		(net "PCIE_COMP_B_TO_IOM_B_17_DN")
	)
	(segment
		(start 356.807516 -19.196304)
		(end 356.38994 -19.196304)
		(width 0.1397)
		(layer "In9.Cu")
		(net "PCIE_COMP_B_TO_IOM_B_17_DN")
	)
	(segment
		(start 291.978588 -55.852314)
		(end 291.79901 -55.815738)
		(width 0.1397)
		(layer "In9.Cu")
		(net "PCIE_COMP_B_TO_IOM_B_17_DN")
	)
	(segment
		(start 336.831432 -37.423344)
		(end 294.749728 -53.863748)
		(width 0.1397)
		(layer "In9.Cu")
		(net "PCIE_COMP_B_TO_IOM_B_17_DN")
	)
	(segment
		(start 290.883848 -56.421274)
		(end 290.534344 -56.652414)
		(width 0.1397)
		(layer "In9.Cu")
		(net "PCIE_COMP_B_TO_IOM_B_17_DN")
	)
	(segment
		(start 286.931608 -59.035696)
		(end 285.401766 -59.346084)
		(width 0.1397)
		(layer "In9.Cu")
		(net "PCIE_COMP_B_TO_IOM_B_17_DN")
	)
	(segment
		(start 356.196138 -30.804104)
		(end 355.980238 -31.192216)
		(width 0.1397)
		(layer "In9.Cu")
		(net "PCIE_COMP_B_TO_IOM_B_17_DN")
	)
	(segment
		(start 290.534344 -56.652414)
		(end 290.497768 -56.831992)
		(width 0.1397)
		(layer "In9.Cu")
		(net "PCIE_COMP_B_TO_IOM_B_17_DN")
	)
	(segment
		(start 291.449506 -56.046878)
		(end 291.41293 -56.226456)
		(width 0.1397)
		(layer "In9.Cu")
		(net "PCIE_COMP_B_TO_IOM_B_17_DN")
	)
	(segment
		(start 284.5054 -59.827668)
		(end 285.249874 -60.200032)
		(width 0.1397)
		(layer "In9.Cu")
		(net "PCIE_COMP_B_TO_IOM_B_17_DN")
	)
	(segment
		(start 291.063426 -56.457596)
		(end 290.883848 -56.421274)
		(width 0.1397)
		(layer "In9.Cu")
		(net "PCIE_COMP_B_TO_IOM_B_17_DN")
	)
	(segment
		(start 285.401766 -59.346084)
		(end 284.913832 -59.346084)
		(width 0.1397)
		(layer "In9.Cu")
		(net "PCIE_COMP_B_TO_IOM_B_17_DN")
	)
	(segment
		(start 292.364668 -55.441596)
		(end 292.328092 -55.621174)
		(width 0.1397)
		(layer "In9.Cu")
		(net "PCIE_COMP_B_TO_IOM_B_17_DN")
	)
	(segment
		(start 284.5054 -59.515248)
		(end 284.442916 -59.640216)
		(width 0.1397)
		(layer "In9.Cu")
		(net "PCIE_COMP_B_TO_IOM_B_17_DN")
	)
	(segment
		(start 290.148264 -57.063132)
		(end 289.968686 -57.026556)
		(width 0.1397)
		(layer "In9.Cu")
		(net "PCIE_COMP_B_TO_IOM_B_17_DN")
	)
	(segment
		(start 291.41293 -56.226456)
		(end 291.063426 -56.457596)
		(width 0.1397)
		(layer "In9.Cu")
		(net "PCIE_COMP_B_TO_IOM_B_17_DN")
	)
	(segment
		(start 356.196138 -19.390106)
		(end 356.196138 -30.804104)
		(width 0.1397)
		(layer "In9.Cu")
		(net "PCIE_COMP_B_TO_IOM_B_17_DN")
	)
	(segment
		(start 291.79901 -55.815738)
		(end 291.449506 -56.046878)
		(width 0.1397)
		(layer "In9.Cu")
		(net "PCIE_COMP_B_TO_IOM_B_17_DN")
	)
	(segment
		(start 352.202496 -33.842198)
		(end 336.831432 -37.423344)
		(width 0.1397)
		(layer "In9.Cu")
		(net "PCIE_COMP_B_TO_IOM_B_17_DN")
	)
	(segment
		(start 292.328092 -55.621174)
		(end 291.978588 -55.852314)
		(width 0.1397)
		(layer "In9.Cu")
		(net "PCIE_COMP_B_TO_IOM_B_17_DN")
	)
	(arc
		(start 284.913832 -59.346084)
		(mid 284.692796 -59.390051)
		(end 284.5054 -59.515248)
		(width 0.1397)
		(layer "In9.Cu")
		(net "PCIE_COMP_B_TO_IOM_B_17_DN")
	)
	(arc
		(start 356.38994 -19.196304)
		(mid 356.252901 -19.253067)
		(end 356.196138 -19.390106)
		(width 0.1397)
		(layer "In9.Cu")
		(net "PCIE_COMP_B_TO_IOM_B_17_DN")
	)
	(arc
		(start 284.442916 -59.640216)
		(mid 284.435335 -59.746883)
		(end 284.5054 -59.827668)
		(width 0.1397)
		(layer "In9.Cu")
		(net "PCIE_COMP_B_TO_IOM_B_17_DN")
	)
	(arc
		(start 356.897178 -19.233388)
		(mid 356.856027 -19.205955)
		(end 356.807516 -19.196304)
		(width 0.1397)
		(layer "In9.Cu")
		(net "PCIE_COMP_B_TO_IOM_B_17_DN")
	)
	(arc
		(start 356.95001 -19.338798)
		(mid 356.940377 -19.29028)
		(end 356.912926 -19.249136)
		(width 0.1397)
		(layer "In9.Cu")
		(net "PCIE_COMP_B_TO_IOM_B_17_DN")
	)
	(segment
		(start 291.219636 -52.178712)
		(end 291.21989 -52.178712)
		(width 0.1397)
		(layer "In9.Cu")
		(net "PCIE_COMP_B_TO_IOM_B_16_DP")
	)
	(segment
		(start 291.21989 -52.178712)
		(end 285.543752 -55.053992)
		(width 0.1397)
		(layer "In9.Cu")
		(net "PCIE_COMP_B_TO_IOM_B_16_DP")
	)
	(segment
		(start 332.205584 -26.291794)
		(end 326.315832 -34.400744)
		(width 0.1397)
		(layer "In9.Cu")
		(net "PCIE_COMP_B_TO_IOM_B_16_DP")
	)
	(segment
		(start 355.112828 -17.81048)
		(end 355.055424 -17.867884)
		(width 0.1397)
		(layer "In9.Cu")
		(net "PCIE_COMP_B_TO_IOM_B_16_DP")
	)
	(segment
		(start 353.817428 -17.904968)
		(end 332.205584 -26.291794)
		(width 0.1397)
		(layer "In9.Cu")
		(net "PCIE_COMP_B_TO_IOM_B_16_DP")
	)
	(segment
		(start 285.543752 -55.053992)
		(end 284.914086 -55.053992)
		(width 0.1397)
		(layer "In9.Cu")
		(net "PCIE_COMP_B_TO_IOM_B_16_DP")
	)
	(segment
		(start 326.315832 -34.400744)
		(end 291.219636 -52.178712)
		(width 0.1397)
		(layer "In9.Cu")
		(net "PCIE_COMP_B_TO_IOM_B_16_DP")
	)
	(segment
		(start 355.149912 -17.349978)
		(end 355.149912 -17.720818)
		(width 0.1397)
		(layer "In9.Cu")
		(net "PCIE_COMP_B_TO_IOM_B_16_DP")
	)
	(segment
		(start 283.994098 -55.572152)
		(end 283.249878 -55.200042)
		(width 0.1397)
		(layer "In9.Cu")
		(net "PCIE_COMP_B_TO_IOM_B_16_DP")
	)
	(segment
		(start 354.965762 -17.904968)
		(end 353.817428 -17.904968)
		(width 0.1397)
		(layer "In9.Cu")
		(net "PCIE_COMP_B_TO_IOM_B_16_DP")
	)
	(segment
		(start 284.263084 -55.3466)
		(end 284.18155 -55.509668)
		(width 0.1397)
		(layer "In9.Cu")
		(net "PCIE_COMP_B_TO_IOM_B_16_DP")
	)
	(arc
		(start 355.149912 -17.720818)
		(mid 355.140279 -17.769336)
		(end 355.112828 -17.81048)
		(width 0.1397)
		(layer "In9.Cu")
		(net "PCIE_COMP_B_TO_IOM_B_16_DP")
	)
	(arc
		(start 284.18155 -55.509668)
		(mid 284.100765 -55.579733)
		(end 283.994098 -55.572152)
		(width 0.1397)
		(layer "In9.Cu")
		(net "PCIE_COMP_B_TO_IOM_B_16_DP")
	)
	(arc
		(start 355.055424 -17.867884)
		(mid 355.014273 -17.895317)
		(end 354.965762 -17.904968)
		(width 0.1397)
		(layer "In9.Cu")
		(net "PCIE_COMP_B_TO_IOM_B_16_DP")
	)
	(arc
		(start 284.914086 -55.053992)
		(mid 284.55721 -55.130472)
		(end 284.263084 -55.3466)
		(width 0.1397)
		(layer "In9.Cu")
		(net "PCIE_COMP_B_TO_IOM_B_16_DP")
	)
	(segment
		(start 288.735008 -53.764942)
		(end 285.613602 -55.346092)
		(width 0.1397)
		(layer "In9.Cu")
		(net "PCIE_COMP_B_TO_IOM_B_16_DN")
	)
	(segment
		(start 290.35502 -52.944268)
		(end 290.293552 -53.132228)
		(width 0.1397)
		(layer "In9.Cu")
		(net "PCIE_COMP_B_TO_IOM_B_16_DN")
	)
	(segment
		(start 290.728908 -52.755038)
		(end 290.35502 -52.944268)
		(width 0.1397)
		(layer "In9.Cu")
		(net "PCIE_COMP_B_TO_IOM_B_16_DN")
	)
	(segment
		(start 343.131902 -22.365208)
		(end 332.391512 -26.533094)
		(width 0.1397)
		(layer "In9.Cu")
		(net "PCIE_COMP_B_TO_IOM_B_16_DN")
	)
	(segment
		(start 284.5054 -55.827676)
		(end 285.249874 -56.20004)
		(width 0.1397)
		(layer "In9.Cu")
		(net "PCIE_COMP_B_TO_IOM_B_16_DN")
	)
	(segment
		(start 290.916614 -52.816506)
		(end 290.728908 -52.755038)
		(width 0.1397)
		(layer "In9.Cu")
		(net "PCIE_COMP_B_TO_IOM_B_16_DN")
	)
	(segment
		(start 289.35807 -53.449474)
		(end 289.296602 -53.63718)
		(width 0.1397)
		(layer "In9.Cu")
		(net "PCIE_COMP_B_TO_IOM_B_16_DN")
	)
	(segment
		(start 285.613602 -55.346092)
		(end 284.913832 -55.346092)
		(width 0.1397)
		(layer "In9.Cu")
		(net "PCIE_COMP_B_TO_IOM_B_16_DN")
	)
	(segment
		(start 290.293552 -53.132228)
		(end 289.919664 -53.321458)
		(width 0.1397)
		(layer "In9.Cu")
		(net "PCIE_COMP_B_TO_IOM_B_16_DN")
	)
	(segment
		(start 355.149912 -18.750026)
		(end 355.149912 -18.38325)
		(width 0.1397)
		(layer "In9.Cu")
		(net "PCIE_COMP_B_TO_IOM_B_16_DN")
	)
	(segment
		(start 289.731958 -53.25999)
		(end 289.35807 -53.449474)
		(width 0.1397)
		(layer "In9.Cu")
		(net "PCIE_COMP_B_TO_IOM_B_16_DN")
	)
	(segment
		(start 353.872292 -18.197068)
		(end 343.131902 -22.365462)
		(width 0.1397)
		(layer "In9.Cu")
		(net "PCIE_COMP_B_TO_IOM_B_16_DN")
	)
	(segment
		(start 332.391512 -26.533094)
		(end 326.510904 -34.629598)
		(width 0.1397)
		(layer "In9.Cu")
		(net "PCIE_COMP_B_TO_IOM_B_16_DN")
	)
	(segment
		(start 288.922714 -53.82641)
		(end 288.735008 -53.764942)
		(width 0.1397)
		(layer "In9.Cu")
		(net "PCIE_COMP_B_TO_IOM_B_16_DN")
	)
	(segment
		(start 355.112828 -18.293588)
		(end 355.053392 -18.234152)
		(width 0.1397)
		(layer "In9.Cu")
		(net "PCIE_COMP_B_TO_IOM_B_16_DN")
	)
	(segment
		(start 289.296602 -53.63718)
		(end 288.922714 -53.82641)
		(width 0.1397)
		(layer "In9.Cu")
		(net "PCIE_COMP_B_TO_IOM_B_16_DN")
	)
	(segment
		(start 291.35197 -52.439316)
		(end 291.290502 -52.627022)
		(width 0.1397)
		(layer "In9.Cu")
		(net "PCIE_COMP_B_TO_IOM_B_16_DN")
	)
	(segment
		(start 343.131902 -22.365462)
		(end 343.131902 -22.365208)
		(width 0.1397)
		(layer "In9.Cu")
		(net "PCIE_COMP_B_TO_IOM_B_16_DN")
	)
	(segment
		(start 289.919664 -53.321458)
		(end 289.731958 -53.25999)
		(width 0.1397)
		(layer "In9.Cu")
		(net "PCIE_COMP_B_TO_IOM_B_16_DN")
	)
	(segment
		(start 326.510904 -34.629598)
		(end 291.35197 -52.439316)
		(width 0.1397)
		(layer "In9.Cu")
		(net "PCIE_COMP_B_TO_IOM_B_16_DN")
	)
	(segment
		(start 284.5054 -55.515256)
		(end 284.442916 -55.640224)
		(width 0.1397)
		(layer "In9.Cu")
		(net "PCIE_COMP_B_TO_IOM_B_16_DN")
	)
	(segment
		(start 354.96373 -18.197068)
		(end 353.872292 -18.197068)
		(width 0.1397)
		(layer "In9.Cu")
		(net "PCIE_COMP_B_TO_IOM_B_16_DN")
	)
	(segment
		(start 291.290502 -52.627022)
		(end 290.916614 -52.816506)
		(width 0.1397)
		(layer "In9.Cu")
		(net "PCIE_COMP_B_TO_IOM_B_16_DN")
	)
	(arc
		(start 355.053392 -18.234152)
		(mid 355.012241 -18.206719)
		(end 354.96373 -18.197068)
		(width 0.1397)
		(layer "In9.Cu")
		(net "PCIE_COMP_B_TO_IOM_B_16_DN")
	)
	(arc
		(start 284.913832 -55.346092)
		(mid 284.692796 -55.390059)
		(end 284.5054 -55.515256)
		(width 0.1397)
		(layer "In9.Cu")
		(net "PCIE_COMP_B_TO_IOM_B_16_DN")
	)
	(arc
		(start 355.149912 -18.38325)
		(mid 355.140279 -18.334732)
		(end 355.112828 -18.293588)
		(width 0.1397)
		(layer "In9.Cu")
		(net "PCIE_COMP_B_TO_IOM_B_16_DN")
	)
	(arc
		(start 284.442916 -55.640224)
		(mid 284.435335 -55.746891)
		(end 284.5054 -55.827676)
		(width 0.1397)
		(layer "In9.Cu")
		(net "PCIE_COMP_B_TO_IOM_B_16_DN")
	)
	(segment
		(start 376.750072 -17.761458)
		(end 376.750072 -17.349978)
		(width 0.1397)
		(layer "In9.Cu")
		(net "PCIE_COMP_B_TO_IOM_B_15_DP")
	)
	(segment
		(start 278.11476 -51.054)
		(end 277.261574 -51.618642)
		(width 0.1397)
		(layer "In9.Cu")
		(net "PCIE_COMP_B_TO_IOM_B_15_DP")
	)
	(segment
		(start 280.510996 -90.456766)
		(end 283.445712 -91.10726)
		(width 0.1397)
		(layer "In9.Cu")
		(net "PCIE_COMP_B_TO_IOM_B_15_DP")
	)
	(segment
		(start 280.330656 -52.053998)
		(end 279.330658 -51.054)
		(width 0.1397)
		(layer "In9.Cu")
		(net "PCIE_COMP_B_TO_IOM_B_15_DP")
	)
	(segment
		(start 276.159722 -86.207346)
		(end 277.772622 -88.644476)
		(width 0.1397)
		(layer "In9.Cu")
		(net "PCIE_COMP_B_TO_IOM_B_15_DP")
	)
	(segment
		(start 377.310142 -17.904206)
		(end 376.89282 -17.904206)
		(width 0.1397)
		(layer "In9.Cu")
		(net "PCIE_COMP_B_TO_IOM_B_15_DP")
	)
	(segment
		(start 376.802904 -17.866868)
		(end 376.787156 -17.85112)
		(width 0.1397)
		(layer "In9.Cu")
		(net "PCIE_COMP_B_TO_IOM_B_15_DP")
	)
	(segment
		(start 377.673616 -18.093944)
		(end 377.60656 -18.026634)
		(width 0.1397)
		(layer "In9.Cu")
		(net "PCIE_COMP_B_TO_IOM_B_15_DP")
	)
	(segment
		(start 276.832822 -52.265834)
		(end 272.692876 -70.559168)
		(width 0.1397)
		(layer "In9.Cu")
		(net "PCIE_COMP_B_TO_IOM_B_15_DP")
	)
	(segment
		(start 376.89282 -17.904206)
		(end 376.892566 -17.903952)
		(width 0.1397)
		(layer "In9.Cu")
		(net "PCIE_COMP_B_TO_IOM_B_15_DP")
	)
	(segment
		(start 363.49051 -44.045886)
		(end 374.10009 -36.845748)
		(width 0.1397)
		(layer "In9.Cu")
		(net "PCIE_COMP_B_TO_IOM_B_15_DP")
	)
	(segment
		(start 277.772622 -88.644476)
		(end 280.510996 -90.456766)
		(width 0.1397)
		(layer "In9.Cu")
		(net "PCIE_COMP_B_TO_IOM_B_15_DP")
	)
	(segment
		(start 374.10009 -36.845748)
		(end 377.796044 -31.048706)
		(width 0.1397)
		(layer "In9.Cu")
		(net "PCIE_COMP_B_TO_IOM_B_15_DP")
	)
	(segment
		(start 377.796044 -31.048706)
		(end 377.796044 -18.390108)
		(width 0.1397)
		(layer "In9.Cu")
		(net "PCIE_COMP_B_TO_IOM_B_15_DP")
	)
	(segment
		(start 357.485442 -53.0733)
		(end 357.537766 -53.039772)
		(width 0.1397)
		(layer "In9.Cu")
		(net "PCIE_COMP_B_TO_IOM_B_15_DP")
	)
	(segment
		(start 305.357022 -86.283546)
		(end 357.485442 -53.0733)
		(width 0.1397)
		(layer "In9.Cu")
		(net "PCIE_COMP_B_TO_IOM_B_15_DP")
	)
	(segment
		(start 284.056836 -51.759866)
		(end 283.994352 -51.884834)
		(width 0.1397)
		(layer "In9.Cu")
		(net "PCIE_COMP_B_TO_IOM_B_15_DP")
	)
	(segment
		(start 283.58592 -52.053998)
		(end 280.330656 -52.053998)
		(width 0.1397)
		(layer "In9.Cu")
		(net "PCIE_COMP_B_TO_IOM_B_15_DP")
	)
	(segment
		(start 283.249878 -51.20005)
		(end 283.994352 -51.572414)
		(width 0.1397)
		(layer "In9.Cu")
		(net "PCIE_COMP_B_TO_IOM_B_15_DP")
	)
	(segment
		(start 279.330658 -51.054)
		(end 278.11476 -51.054)
		(width 0.1397)
		(layer "In9.Cu")
		(net "PCIE_COMP_B_TO_IOM_B_15_DP")
	)
	(segment
		(start 277.261574 -51.618642)
		(end 276.832822 -52.265834)
		(width 0.1397)
		(layer "In9.Cu")
		(net "PCIE_COMP_B_TO_IOM_B_15_DP")
	)
	(segment
		(start 283.445712 -91.10726)
		(end 305.357022 -86.283546)
		(width 0.1397)
		(layer "In9.Cu")
		(net "PCIE_COMP_B_TO_IOM_B_15_DP")
	)
	(segment
		(start 272.692876 -70.559168)
		(end 276.159722 -86.207346)
		(width 0.1397)
		(layer "In9.Cu")
		(net "PCIE_COMP_B_TO_IOM_B_15_DP")
	)
	(segment
		(start 357.537766 -53.039772)
		(end 363.49051 -44.045886)
		(width 0.1397)
		(layer "In9.Cu")
		(net "PCIE_COMP_B_TO_IOM_B_15_DP")
	)
	(arc
		(start 376.892566 -17.903952)
		(mid 376.844048 -17.894319)
		(end 376.802904 -17.866868)
		(width 0.1397)
		(layer "In9.Cu")
		(net "PCIE_COMP_B_TO_IOM_B_15_DP")
	)
	(arc
		(start 283.994352 -51.572414)
		(mid 284.064417 -51.653199)
		(end 284.056836 -51.759866)
		(width 0.1397)
		(layer "In9.Cu")
		(net "PCIE_COMP_B_TO_IOM_B_15_DP")
	)
	(arc
		(start 377.60656 -18.026634)
		(mid 377.470533 -17.9359)
		(end 377.310142 -17.904206)
		(width 0.1397)
		(layer "In9.Cu")
		(net "PCIE_COMP_B_TO_IOM_B_15_DP")
	)
	(arc
		(start 377.796044 -18.390108)
		(mid 377.764294 -18.229838)
		(end 377.673616 -18.093944)
		(width 0.1397)
		(layer "In9.Cu")
		(net "PCIE_COMP_B_TO_IOM_B_15_DP")
	)
	(arc
		(start 283.994352 -51.884834)
		(mid 283.806962 -52.010044)
		(end 283.58592 -52.053998)
		(width 0.1397)
		(layer "In9.Cu")
		(net "PCIE_COMP_B_TO_IOM_B_15_DP")
	)
	(arc
		(start 376.787156 -17.85112)
		(mid 376.759723 -17.809969)
		(end 376.750072 -17.761458)
		(width 0.1397)
		(layer "In9.Cu")
		(net "PCIE_COMP_B_TO_IOM_B_15_DP")
	)
	(segment
		(start 285.628842 -90.32748)
		(end 286.03829 -90.23731)
		(width 0.1397)
		(layer "In9.Cu")
		(net "PCIE_COMP_B_TO_IOM_B_15_DN")
	)
	(segment
		(start 286.55391 -89.98077)
		(end 286.72028 -90.087196)
		(width 0.1397)
		(layer "In9.Cu")
		(net "PCIE_COMP_B_TO_IOM_B_15_DN")
	)
	(segment
		(start 273.238976 -69.470016)
		(end 273.344386 -69.636894)
		(width 0.1397)
		(layer "In9.Cu")
		(net "PCIE_COMP_B_TO_IOM_B_15_DN")
	)
	(segment
		(start 273.992086 -66.775584)
		(end 273.824954 -66.880994)
		(width 0.1397)
		(layer "In9.Cu")
		(net "PCIE_COMP_B_TO_IOM_B_15_DN")
	)
	(segment
		(start 280.209498 -52.346098)
		(end 279.2095 -51.3461)
		(width 0.1397)
		(layer "In9.Cu")
		(net "PCIE_COMP_B_TO_IOM_B_15_DN")
	)
	(segment
		(start 275.627338 -81.76133)
		(end 275.718016 -82.170524)
		(width 0.1397)
		(layer "In9.Cu")
		(net "PCIE_COMP_B_TO_IOM_B_15_DN")
	)
	(segment
		(start 276.187154 -84.980272)
		(end 276.36597 -85.094064)
		(width 0.1397)
		(layer "In9.Cu")
		(net "PCIE_COMP_B_TO_IOM_B_15_DN")
	)
	(segment
		(start 287.645348 -89.740486)
		(end 287.811718 -89.846912)
		(width 0.1397)
		(layer "In9.Cu")
		(net "PCIE_COMP_B_TO_IOM_B_15_DN")
	)
	(segment
		(start 287.811718 -89.846912)
		(end 294.685212 -88.33358)
		(width 0.1397)
		(layer "In9.Cu")
		(net "PCIE_COMP_B_TO_IOM_B_15_DN")
	)
	(segment
		(start 273.59102 -68.54698)
		(end 273.498564 -68.955666)
		(width 0.1397)
		(layer "In9.Cu")
		(net "PCIE_COMP_B_TO_IOM_B_15_DN")
	)
	(segment
		(start 373.88673 -36.637214)
		(end 373.886222 -36.63696)
		(width 0.1397)
		(layer "In9.Cu")
		(net "PCIE_COMP_B_TO_IOM_B_15_DN")
	)
	(segment
		(start 285.249874 -52.200048)
		(end 284.505654 -51.827938)
		(width 0.1397)
		(layer "In9.Cu")
		(net "PCIE_COMP_B_TO_IOM_B_15_DN")
	)
	(segment
		(start 276.43328 -86.091268)
		(end 277.983442 -88.433656)
		(width 0.1397)
		(layer "In9.Cu")
		(net "PCIE_COMP_B_TO_IOM_B_15_DN")
	)
	(segment
		(start 272.992342 -70.55993)
		(end 275.448776 -81.647284)
		(width 0.1397)
		(layer "In9.Cu")
		(net "PCIE_COMP_B_TO_IOM_B_15_DN")
	)
	(segment
		(start 376.802904 -18.23339)
		(end 376.787156 -18.249138)
		(width 0.1397)
		(layer "In9.Cu")
		(net "PCIE_COMP_B_TO_IOM_B_15_DN")
	)
	(segment
		(start 376.750072 -18.3388)
		(end 376.750072 -18.750026)
		(width 0.1397)
		(layer "In9.Cu")
		(net "PCIE_COMP_B_TO_IOM_B_15_DN")
	)
	(segment
		(start 273.837908 -67.456812)
		(end 273.745198 -67.865752)
		(width 0.1397)
		(layer "In9.Cu")
		(net "PCIE_COMP_B_TO_IOM_B_15_DN")
	)
	(segment
		(start 276.456648 -85.503258)
		(end 276.342602 -85.682074)
		(width 0.1397)
		(layer "In9.Cu")
		(net "PCIE_COMP_B_TO_IOM_B_15_DN")
	)
	(segment
		(start 275.448776 -81.647284)
		(end 275.627338 -81.76133)
		(width 0.1397)
		(layer "In9.Cu")
		(net "PCIE_COMP_B_TO_IOM_B_15_DN")
	)
	(segment
		(start 295.367456 -88.183466)
		(end 295.77665 -88.093296)
		(width 0.1397)
		(layer "In9.Cu")
		(net "PCIE_COMP_B_TO_IOM_B_15_DN")
	)
	(segment
		(start 275.85035 -83.460082)
		(end 275.941028 -83.869276)
		(width 0.1397)
		(layer "In9.Cu")
		(net "PCIE_COMP_B_TO_IOM_B_15_DN")
	)
	(segment
		(start 283.445966 -90.808048)
		(end 284.946852 -90.477594)
		(width 0.1397)
		(layer "In9.Cu")
		(net "PCIE_COMP_B_TO_IOM_B_15_DN")
	)
	(segment
		(start 273.57832 -67.971162)
		(end 273.48561 -68.379848)
		(width 0.1397)
		(layer "In9.Cu")
		(net "PCIE_COMP_B_TO_IOM_B_15_DN")
	)
	(segment
		(start 276.342602 -85.682074)
		(end 276.43328 -86.091268)
		(width 0.1397)
		(layer "In9.Cu")
		(net "PCIE_COMP_B_TO_IOM_B_15_DN")
	)
	(segment
		(start 280.627074 -90.183208)
		(end 283.445966 -90.808048)
		(width 0.1397)
		(layer "In9.Cu")
		(net "PCIE_COMP_B_TO_IOM_B_15_DN")
	)
	(segment
		(start 273.084798 -70.151244)
		(end 272.992342 -70.55993)
		(width 0.1397)
		(layer "In9.Cu")
		(net "PCIE_COMP_B_TO_IOM_B_15_DN")
	)
	(segment
		(start 277.472394 -51.829462)
		(end 277.106126 -52.382674)
		(width 0.1397)
		(layer "In9.Cu")
		(net "PCIE_COMP_B_TO_IOM_B_15_DN")
	)
	(segment
		(start 294.791638 -88.16721)
		(end 295.200832 -88.07704)
		(width 0.1397)
		(layer "In9.Cu")
		(net "PCIE_COMP_B_TO_IOM_B_15_DN")
	)
	(segment
		(start 373.886222 -36.63696)
		(end 377.503944 -30.963362)
		(width 0.1397)
		(layer "In9.Cu")
		(net "PCIE_COMP_B_TO_IOM_B_15_DN")
	)
	(segment
		(start 277.106126 -52.382674)
		(end 273.979132 -66.199766)
		(width 0.1397)
		(layer "In9.Cu")
		(net "PCIE_COMP_B_TO_IOM_B_15_DN")
	)
	(segment
		(start 278.202898 -51.3461)
		(end 277.472394 -51.829462)
		(width 0.1397)
		(layer "In9.Cu")
		(net "PCIE_COMP_B_TO_IOM_B_15_DN")
	)
	(segment
		(start 286.144462 -90.07094)
		(end 286.55391 -89.98077)
		(width 0.1397)
		(layer "In9.Cu")
		(net "PCIE_COMP_B_TO_IOM_B_15_DN")
	)
	(segment
		(start 305.243484 -86.009226)
		(end 357.32847 -52.826666)
		(width 0.1397)
		(layer "In9.Cu")
		(net "PCIE_COMP_B_TO_IOM_B_15_DN")
	)
	(segment
		(start 275.941028 -83.869276)
		(end 276.119844 -83.983322)
		(width 0.1397)
		(layer "In9.Cu")
		(net "PCIE_COMP_B_TO_IOM_B_15_DN")
	)
	(segment
		(start 287.129728 -89.997026)
		(end 287.236154 -89.830656)
		(width 0.1397)
		(layer "In9.Cu")
		(net "PCIE_COMP_B_TO_IOM_B_15_DN")
	)
	(segment
		(start 363.278674 -43.83659)
		(end 373.88673 -36.637214)
		(width 0.1397)
		(layer "In9.Cu")
		(net "PCIE_COMP_B_TO_IOM_B_15_DN")
	)
	(segment
		(start 283.585666 -52.346098)
		(end 280.209498 -52.346098)
		(width 0.1397)
		(layer "In9.Cu")
		(net "PCIE_COMP_B_TO_IOM_B_15_DN")
	)
	(segment
		(start 377.46686 -18.300446)
		(end 377.399804 -18.23339)
		(width 0.1397)
		(layer "In9.Cu")
		(net "PCIE_COMP_B_TO_IOM_B_15_DN")
	)
	(segment
		(start 285.462472 -90.221054)
		(end 285.628842 -90.32748)
		(width 0.1397)
		(layer "In9.Cu")
		(net "PCIE_COMP_B_TO_IOM_B_15_DN")
	)
	(segment
		(start 273.48561 -68.379848)
		(end 273.59102 -68.54698)
		(width 0.1397)
		(layer "In9.Cu")
		(net "PCIE_COMP_B_TO_IOM_B_15_DN")
	)
	(segment
		(start 279.2095 -51.3461)
		(end 278.202898 -51.3461)
		(width 0.1397)
		(layer "In9.Cu")
		(net "PCIE_COMP_B_TO_IOM_B_15_DN")
	)
	(segment
		(start 285.053024 -90.311224)
		(end 285.462472 -90.221054)
		(width 0.1397)
		(layer "In9.Cu")
		(net "PCIE_COMP_B_TO_IOM_B_15_DN")
	)
	(segment
		(start 277.983442 -88.433656)
		(end 280.627074 -90.183208)
		(width 0.1397)
		(layer "In9.Cu")
		(net "PCIE_COMP_B_TO_IOM_B_15_DN")
	)
	(segment
		(start 295.200832 -88.07704)
		(end 295.367456 -88.183466)
		(width 0.1397)
		(layer "In9.Cu")
		(net "PCIE_COMP_B_TO_IOM_B_15_DN")
	)
	(segment
		(start 377.310142 -18.196306)
		(end 376.892566 -18.196306)
		(width 0.1397)
		(layer "In9.Cu")
		(net "PCIE_COMP_B_TO_IOM_B_15_DN")
	)
	(segment
		(start 275.873718 -82.872326)
		(end 275.964142 -83.28152)
		(width 0.1397)
		(layer "In9.Cu")
		(net "PCIE_COMP_B_TO_IOM_B_15_DN")
	)
	(segment
		(start 273.344386 -69.636894)
		(end 273.25193 -70.045834)
		(width 0.1397)
		(layer "In9.Cu")
		(net "PCIE_COMP_B_TO_IOM_B_15_DN")
	)
	(segment
		(start 273.732498 -67.289934)
		(end 273.837908 -67.456812)
		(width 0.1397)
		(layer "In9.Cu")
		(net "PCIE_COMP_B_TO_IOM_B_15_DN")
	)
	(segment
		(start 275.964142 -83.28152)
		(end 275.85035 -83.460082)
		(width 0.1397)
		(layer "In9.Cu")
		(net "PCIE_COMP_B_TO_IOM_B_15_DN")
	)
	(segment
		(start 273.498564 -68.955666)
		(end 273.331432 -69.061076)
		(width 0.1397)
		(layer "In9.Cu")
		(net "PCIE_COMP_B_TO_IOM_B_15_DN")
	)
	(segment
		(start 273.331432 -69.061076)
		(end 273.238976 -69.470016)
		(width 0.1397)
		(layer "In9.Cu")
		(net "PCIE_COMP_B_TO_IOM_B_15_DN")
	)
	(segment
		(start 276.210268 -84.392262)
		(end 276.096476 -84.571078)
		(width 0.1397)
		(layer "In9.Cu")
		(net "PCIE_COMP_B_TO_IOM_B_15_DN")
	)
	(segment
		(start 287.236154 -89.830656)
		(end 287.645348 -89.740486)
		(width 0.1397)
		(layer "In9.Cu")
		(net "PCIE_COMP_B_TO_IOM_B_15_DN")
	)
	(segment
		(start 294.685212 -88.33358)
		(end 294.791638 -88.16721)
		(width 0.1397)
		(layer "In9.Cu")
		(net "PCIE_COMP_B_TO_IOM_B_15_DN")
	)
	(segment
		(start 276.119844 -83.983322)
		(end 276.210268 -84.392262)
		(width 0.1397)
		(layer "In9.Cu")
		(net "PCIE_COMP_B_TO_IOM_B_15_DN")
	)
	(segment
		(start 286.03829 -90.23731)
		(end 286.144462 -90.07094)
		(width 0.1397)
		(layer "In9.Cu")
		(net "PCIE_COMP_B_TO_IOM_B_15_DN")
	)
	(segment
		(start 296.458894 -87.943182)
		(end 305.243484 -86.009226)
		(width 0.1397)
		(layer "In9.Cu")
		(net "PCIE_COMP_B_TO_IOM_B_15_DN")
	)
	(segment
		(start 357.32847 -52.826666)
		(end 363.278674 -43.83659)
		(width 0.1397)
		(layer "In9.Cu")
		(net "PCIE_COMP_B_TO_IOM_B_15_DN")
	)
	(segment
		(start 274.084542 -66.366898)
		(end 273.992086 -66.775584)
		(width 0.1397)
		(layer "In9.Cu")
		(net "PCIE_COMP_B_TO_IOM_B_15_DN")
	)
	(segment
		(start 296.29227 -87.836756)
		(end 296.458894 -87.943182)
		(width 0.1397)
		(layer "In9.Cu")
		(net "PCIE_COMP_B_TO_IOM_B_15_DN")
	)
	(segment
		(start 273.745198 -67.865752)
		(end 273.57832 -67.971162)
		(width 0.1397)
		(layer "In9.Cu")
		(net "PCIE_COMP_B_TO_IOM_B_15_DN")
	)
	(segment
		(start 276.096476 -84.571078)
		(end 276.187154 -84.980272)
		(width 0.1397)
		(layer "In9.Cu")
		(net "PCIE_COMP_B_TO_IOM_B_15_DN")
	)
	(segment
		(start 275.694902 -82.75828)
		(end 275.873718 -82.872326)
		(width 0.1397)
		(layer "In9.Cu")
		(net "PCIE_COMP_B_TO_IOM_B_15_DN")
	)
	(segment
		(start 284.946852 -90.477594)
		(end 285.053024 -90.311224)
		(width 0.1397)
		(layer "In9.Cu")
		(net "PCIE_COMP_B_TO_IOM_B_15_DN")
	)
	(segment
		(start 284.318202 -51.890422)
		(end 284.236668 -52.05349)
		(width 0.1397)
		(layer "In9.Cu")
		(net "PCIE_COMP_B_TO_IOM_B_15_DN")
	)
	(segment
		(start 273.979132 -66.199766)
		(end 274.084542 -66.366898)
		(width 0.1397)
		(layer "In9.Cu")
		(net "PCIE_COMP_B_TO_IOM_B_15_DN")
	)
	(segment
		(start 276.36597 -85.094064)
		(end 276.456648 -85.503258)
		(width 0.1397)
		(layer "In9.Cu")
		(net "PCIE_COMP_B_TO_IOM_B_15_DN")
	)
	(segment
		(start 286.72028 -90.087196)
		(end 287.129728 -89.997026)
		(width 0.1397)
		(layer "In9.Cu")
		(net "PCIE_COMP_B_TO_IOM_B_15_DN")
	)
	(segment
		(start 295.883076 -87.926926)
		(end 296.29227 -87.836756)
		(width 0.1397)
		(layer "In9.Cu")
		(net "PCIE_COMP_B_TO_IOM_B_15_DN")
	)
	(segment
		(start 275.718016 -82.170524)
		(end 275.604224 -82.349086)
		(width 0.1397)
		(layer "In9.Cu")
		(net "PCIE_COMP_B_TO_IOM_B_15_DN")
	)
	(segment
		(start 275.604224 -82.349086)
		(end 275.694902 -82.75828)
		(width 0.1397)
		(layer "In9.Cu")
		(net "PCIE_COMP_B_TO_IOM_B_15_DN")
	)
	(segment
		(start 377.503944 -30.963362)
		(end 377.503944 -18.390108)
		(width 0.1397)
		(layer "In9.Cu")
		(net "PCIE_COMP_B_TO_IOM_B_15_DN")
	)
	(segment
		(start 295.77665 -88.093296)
		(end 295.883076 -87.926926)
		(width 0.1397)
		(layer "In9.Cu")
		(net "PCIE_COMP_B_TO_IOM_B_15_DN")
	)
	(segment
		(start 273.824954 -66.880994)
		(end 273.732498 -67.289934)
		(width 0.1397)
		(layer "In9.Cu")
		(net "PCIE_COMP_B_TO_IOM_B_15_DN")
	)
	(segment
		(start 273.25193 -70.045834)
		(end 273.084798 -70.151244)
		(width 0.1397)
		(layer "In9.Cu")
		(net "PCIE_COMP_B_TO_IOM_B_15_DN")
	)
	(arc
		(start 284.505654 -51.827938)
		(mid 284.398987 -51.820357)
		(end 284.318202 -51.890422)
		(width 0.1397)
		(layer "In9.Cu")
		(net "PCIE_COMP_B_TO_IOM_B_15_DN")
	)
	(arc
		(start 377.503944 -18.390108)
		(mid 377.494311 -18.34159)
		(end 377.46686 -18.300446)
		(width 0.1397)
		(layer "In9.Cu")
		(net "PCIE_COMP_B_TO_IOM_B_15_DN")
	)
	(arc
		(start 376.787156 -18.249138)
		(mid 376.759723 -18.290289)
		(end 376.750072 -18.3388)
		(width 0.1397)
		(layer "In9.Cu")
		(net "PCIE_COMP_B_TO_IOM_B_15_DN")
	)
	(arc
		(start 376.892566 -18.196306)
		(mid 376.844048 -18.205939)
		(end 376.802904 -18.23339)
		(width 0.1397)
		(layer "In9.Cu")
		(net "PCIE_COMP_B_TO_IOM_B_15_DN")
	)
	(arc
		(start 284.236668 -52.05349)
		(mid 283.942573 -52.269688)
		(end 283.585666 -52.346098)
		(width 0.1397)
		(layer "In9.Cu")
		(net "PCIE_COMP_B_TO_IOM_B_15_DN")
	)
	(arc
		(start 377.399804 -18.23339)
		(mid 377.358653 -18.205957)
		(end 377.310142 -18.196306)
		(width 0.1397)
		(layer "In9.Cu")
		(net "PCIE_COMP_B_TO_IOM_B_15_DN")
	)
	(segment
		(start 379.595888 -32.496506)
		(end 379.595888 -19.390106)
		(width 0.1397)
		(layer "In9.Cu")
		(net "PCIE_COMP_B_TO_IOM_B_14_DP")
	)
	(segment
		(start 379.109986 -18.904204)
		(end 378.692664 -18.904204)
		(width 0.1397)
		(layer "In9.Cu")
		(net "PCIE_COMP_B_TO_IOM_B_14_DP")
	)
	(segment
		(start 276.070568 -89.621868)
		(end 279.819354 -92.103956)
		(width 0.1397)
		(layer "In9.Cu")
		(net "PCIE_COMP_B_TO_IOM_B_14_DP")
	)
	(segment
		(start 284.056836 -47.759874)
		(end 283.994352 -47.884842)
		(width 0.1397)
		(layer "In9.Cu")
		(net "PCIE_COMP_B_TO_IOM_B_14_DP")
	)
	(segment
		(start 305.021488 -87.985346)
		(end 371.026436 -45.935646)
		(width 0.1397)
		(layer "In9.Cu")
		(net "PCIE_COMP_B_TO_IOM_B_14_DP")
	)
	(segment
		(start 283.068268 -92.824046)
		(end 305.021488 -87.985346)
		(width 0.1397)
		(layer "In9.Cu")
		(net "PCIE_COMP_B_TO_IOM_B_14_DP")
	)
	(segment
		(start 274.522692 -87.278972)
		(end 276.070568 -89.621868)
		(width 0.1397)
		(layer "In9.Cu")
		(net "PCIE_COMP_B_TO_IOM_B_14_DP")
	)
	(segment
		(start 283.58592 -48.054006)
		(end 280.343864 -48.054006)
		(width 0.1397)
		(layer "In9.Cu")
		(net "PCIE_COMP_B_TO_IOM_B_14_DP")
	)
	(segment
		(start 278.2443 -47.054008)
		(end 277.829264 -47.138336)
		(width 0.1397)
		(layer "In9.Cu")
		(net "PCIE_COMP_B_TO_IOM_B_14_DP")
	)
	(segment
		(start 279.819354 -92.103956)
		(end 283.068268 -92.824046)
		(width 0.1397)
		(layer "In9.Cu")
		(net "PCIE_COMP_B_TO_IOM_B_14_DP")
	)
	(segment
		(start 283.249878 -47.200058)
		(end 283.994352 -47.572422)
		(width 0.1397)
		(layer "In9.Cu")
		(net "PCIE_COMP_B_TO_IOM_B_14_DP")
	)
	(segment
		(start 378.549916 -18.761456)
		(end 378.549916 -18.35023)
		(width 0.1397)
		(layer "In9.Cu")
		(net "PCIE_COMP_B_TO_IOM_B_14_DP")
	)
	(segment
		(start 378.692664 -18.904204)
		(end 378.69241 -18.90395)
		(width 0.1397)
		(layer "In9.Cu")
		(net "PCIE_COMP_B_TO_IOM_B_14_DP")
	)
	(segment
		(start 276.721062 -47.87265)
		(end 275.375624 -49.90592)
		(width 0.1397)
		(layer "In9.Cu")
		(net "PCIE_COMP_B_TO_IOM_B_14_DP")
	)
	(segment
		(start 280.343864 -48.054006)
		(end 279.343866 -47.054008)
		(width 0.1397)
		(layer "In9.Cu")
		(net "PCIE_COMP_B_TO_IOM_B_14_DP")
	)
	(segment
		(start 275.375624 -49.90592)
		(end 270.761206 -70.293992)
		(width 0.1397)
		(layer "In9.Cu")
		(net "PCIE_COMP_B_TO_IOM_B_14_DP")
	)
	(segment
		(start 270.761206 -70.293992)
		(end 274.522692 -87.278972)
		(width 0.1397)
		(layer "In9.Cu")
		(net "PCIE_COMP_B_TO_IOM_B_14_DP")
	)
	(segment
		(start 379.47346 -19.093942)
		(end 379.406404 -19.026632)
		(width 0.1397)
		(layer "In9.Cu")
		(net "PCIE_COMP_B_TO_IOM_B_14_DP")
	)
	(segment
		(start 277.829264 -47.138336)
		(end 276.721062 -47.87265)
		(width 0.1397)
		(layer "In9.Cu")
		(net "PCIE_COMP_B_TO_IOM_B_14_DP")
	)
	(segment
		(start 371.026436 -45.935646)
		(end 379.595888 -32.496506)
		(width 0.1397)
		(layer "In9.Cu")
		(net "PCIE_COMP_B_TO_IOM_B_14_DP")
	)
	(segment
		(start 279.343866 -47.054008)
		(end 278.2443 -47.054008)
		(width 0.1397)
		(layer "In9.Cu")
		(net "PCIE_COMP_B_TO_IOM_B_14_DP")
	)
	(segment
		(start 378.602748 -18.866866)
		(end 378.587 -18.851118)
		(width 0.1397)
		(layer "In9.Cu")
		(net "PCIE_COMP_B_TO_IOM_B_14_DP")
	)
	(arc
		(start 378.587 -18.851118)
		(mid 378.559567 -18.809967)
		(end 378.549916 -18.761456)
		(width 0.1397)
		(layer "In9.Cu")
		(net "PCIE_COMP_B_TO_IOM_B_14_DP")
	)
	(arc
		(start 283.994352 -47.884842)
		(mid 283.806962 -48.010052)
		(end 283.58592 -48.054006)
		(width 0.1397)
		(layer "In9.Cu")
		(net "PCIE_COMP_B_TO_IOM_B_14_DP")
	)
	(arc
		(start 379.406404 -19.026632)
		(mid 379.270377 -18.935898)
		(end 379.109986 -18.904204)
		(width 0.1397)
		(layer "In9.Cu")
		(net "PCIE_COMP_B_TO_IOM_B_14_DP")
	)
	(arc
		(start 283.994352 -47.572422)
		(mid 284.064417 -47.653207)
		(end 284.056836 -47.759874)
		(width 0.1397)
		(layer "In9.Cu")
		(net "PCIE_COMP_B_TO_IOM_B_14_DP")
	)
	(arc
		(start 379.595888 -19.390106)
		(mid 379.564138 -19.229836)
		(end 379.47346 -19.093942)
		(width 0.1397)
		(layer "In9.Cu")
		(net "PCIE_COMP_B_TO_IOM_B_14_DP")
	)
	(arc
		(start 378.69241 -18.90395)
		(mid 378.643892 -18.894317)
		(end 378.602748 -18.866866)
		(width 0.1397)
		(layer "In9.Cu")
		(net "PCIE_COMP_B_TO_IOM_B_14_DP")
	)
	(segment
		(start 284.943804 -91.968574)
		(end 285.110174 -92.074746)
		(width 0.1397)
		(layer "In9.Cu")
		(net "PCIE_COMP_B_TO_IOM_B_14_DN")
	)
	(segment
		(start 271.659604 -68.281804)
		(end 271.566894 -68.69049)
		(width 0.1397)
		(layer "In9.Cu")
		(net "PCIE_COMP_B_TO_IOM_B_14_DN")
	)
	(segment
		(start 274.081494 -83.241896)
		(end 273.967702 -83.420712)
		(width 0.1397)
		(layer "In9.Cu")
		(net "PCIE_COMP_B_TO_IOM_B_14_DN")
	)
	(segment
		(start 370.814854 -45.72381)
		(end 375.059194 -39.067486)
		(width 0.1397)
		(layer "In9.Cu")
		(net "PCIE_COMP_B_TO_IOM_B_14_DN")
	)
	(segment
		(start 286.201612 -91.834208)
		(end 286.61106 -91.744038)
		(width 0.1397)
		(layer "In9.Cu")
		(net "PCIE_COMP_B_TO_IOM_B_14_DN")
	)
	(segment
		(start 271.153128 -69.886068)
		(end 271.060672 -70.294754)
		(width 0.1397)
		(layer "In9.Cu")
		(net "PCIE_COMP_B_TO_IOM_B_14_DN")
	)
	(segment
		(start 271.307306 -69.20484)
		(end 271.412716 -69.371718)
		(width 0.1397)
		(layer "In9.Cu")
		(net "PCIE_COMP_B_TO_IOM_B_14_DN")
	)
	(segment
		(start 286.61106 -91.744038)
		(end 286.717232 -91.577668)
		(width 0.1397)
		(layer "In9.Cu")
		(net "PCIE_COMP_B_TO_IOM_B_14_DN")
	)
	(segment
		(start 271.800828 -67.024758)
		(end 271.906238 -67.191636)
		(width 0.1397)
		(layer "In9.Cu")
		(net "PCIE_COMP_B_TO_IOM_B_14_DN")
	)
	(segment
		(start 274.729194 -86.16569)
		(end 274.819872 -86.574884)
		(width 0.1397)
		(layer "In9.Cu")
		(net "PCIE_COMP_B_TO_IOM_B_14_DN")
	)
	(segment
		(start 274.213828 -84.531708)
		(end 274.304506 -84.940902)
		(width 0.1397)
		(layer "In9.Cu")
		(net "PCIE_COMP_B_TO_IOM_B_14_DN")
	)
	(segment
		(start 285.110174 -92.074746)
		(end 285.519622 -91.984576)
		(width 0.1397)
		(layer "In9.Cu")
		(net "PCIE_COMP_B_TO_IOM_B_14_DN")
	)
	(segment
		(start 271.566894 -68.69049)
		(end 271.400016 -68.7959)
		(width 0.1397)
		(layer "In9.Cu")
		(net "PCIE_COMP_B_TO_IOM_B_14_DN")
	)
	(segment
		(start 271.893284 -66.615818)
		(end 271.801336 -67.022726)
		(width 0.1397)
		(layer "In9.Cu")
		(net "PCIE_COMP_B_TO_IOM_B_14_DN")
	)
	(segment
		(start 285.625794 -91.818206)
		(end 286.035242 -91.727782)
		(width 0.1397)
		(layer "In9.Cu")
		(net "PCIE_COMP_B_TO_IOM_B_14_DN")
	)
	(segment
		(start 273.99107 -82.832702)
		(end 274.081494 -83.241896)
		(width 0.1397)
		(layer "In9.Cu")
		(net "PCIE_COMP_B_TO_IOM_B_14_DN")
	)
	(segment
		(start 378.549916 -19.338798)
		(end 378.549916 -19.750024)
		(width 0.1397)
		(layer "In9.Cu")
		(net "PCIE_COMP_B_TO_IOM_B_14_DN")
	)
	(segment
		(start 271.801336 -67.022726)
		(end 271.800828 -67.024758)
		(width 0.1397)
		(layer "In9.Cu")
		(net "PCIE_COMP_B_TO_IOM_B_14_DN")
	)
	(segment
		(start 286.035242 -91.727782)
		(end 286.201612 -91.834208)
		(width 0.1397)
		(layer "In9.Cu")
		(net "PCIE_COMP_B_TO_IOM_B_14_DN")
	)
	(segment
		(start 379.266704 -19.300444)
		(end 379.199648 -19.233388)
		(width 0.1397)
		(layer "In9.Cu")
		(net "PCIE_COMP_B_TO_IOM_B_14_DN")
	)
	(segment
		(start 284.428184 -92.225114)
		(end 284.53461 -92.058744)
		(width 0.1397)
		(layer "In9.Cu")
		(net "PCIE_COMP_B_TO_IOM_B_14_DN")
	)
	(segment
		(start 370.815108 -45.72381)
		(end 370.814854 -45.72381)
		(width 0.1397)
		(layer "In9.Cu")
		(net "PCIE_COMP_B_TO_IOM_B_14_DN")
	)
	(segment
		(start 280.222706 -48.346106)
		(end 279.222708 -47.346108)
		(width 0.1397)
		(layer "In9.Cu")
		(net "PCIE_COMP_B_TO_IOM_B_14_DN")
	)
	(segment
		(start 276.931882 -48.08347)
		(end 275.648928 -50.022506)
		(width 0.1397)
		(layer "In9.Cu")
		(net "PCIE_COMP_B_TO_IOM_B_14_DN")
	)
	(segment
		(start 271.32026 -69.780658)
		(end 271.153128 -69.886068)
		(width 0.1397)
		(layer "In9.Cu")
		(net "PCIE_COMP_B_TO_IOM_B_14_DN")
	)
	(segment
		(start 375.059194 -39.06774)
		(end 379.303788 -32.411162)
		(width 0.1397)
		(layer "In9.Cu")
		(net "PCIE_COMP_B_TO_IOM_B_14_DN")
	)
	(segment
		(start 279.222708 -47.346108)
		(end 278.273764 -47.346108)
		(width 0.1397)
		(layer "In9.Cu")
		(net "PCIE_COMP_B_TO_IOM_B_14_DN")
	)
	(segment
		(start 295.432226 -89.799668)
		(end 295.538652 -89.633298)
		(width 0.1397)
		(layer "In9.Cu")
		(net "PCIE_COMP_B_TO_IOM_B_14_DN")
	)
	(segment
		(start 272.047462 -65.93459)
		(end 272.152872 -66.101722)
		(width 0.1397)
		(layer "In9.Cu")
		(net "PCIE_COMP_B_TO_IOM_B_14_DN")
	)
	(segment
		(start 296.114216 -89.6493)
		(end 296.523664 -89.55913)
		(width 0.1397)
		(layer "In9.Cu")
		(net "PCIE_COMP_B_TO_IOM_B_14_DN")
	)
	(segment
		(start 284.53461 -92.058744)
		(end 284.943804 -91.968574)
		(width 0.1397)
		(layer "In9.Cu")
		(net "PCIE_COMP_B_TO_IOM_B_14_DN")
	)
	(segment
		(start 287.12668 -91.487244)
		(end 287.29305 -91.59367)
		(width 0.1397)
		(layer "In9.Cu")
		(net "PCIE_COMP_B_TO_IOM_B_14_DN")
	)
	(segment
		(start 271.399762 -68.796916)
		(end 271.307306 -69.20484)
		(width 0.1397)
		(layer "In9.Cu")
		(net "PCIE_COMP_B_TO_IOM_B_14_DN")
	)
	(segment
		(start 272.152872 -66.101722)
		(end 272.060416 -66.510408)
		(width 0.1397)
		(layer "In9.Cu")
		(net "PCIE_COMP_B_TO_IOM_B_14_DN")
	)
	(segment
		(start 274.550378 -86.051898)
		(end 274.729194 -86.16569)
		(width 0.1397)
		(layer "In9.Cu")
		(net "PCIE_COMP_B_TO_IOM_B_14_DN")
	)
	(segment
		(start 274.32762 -84.352892)
		(end 274.213828 -84.531708)
		(width 0.1397)
		(layer "In9.Cu")
		(net "PCIE_COMP_B_TO_IOM_B_14_DN")
	)
	(segment
		(start 297.205654 -89.408762)
		(end 304.90795 -87.711026)
		(width 0.1397)
		(layer "In9.Cu")
		(net "PCIE_COMP_B_TO_IOM_B_14_DN")
	)
	(segment
		(start 271.400016 -68.7959)
		(end 271.399762 -68.796916)
		(width 0.1397)
		(layer "In9.Cu")
		(net "PCIE_COMP_B_TO_IOM_B_14_DN")
	)
	(segment
		(start 285.519622 -91.984576)
		(end 285.625794 -91.818206)
		(width 0.1397)
		(layer "In9.Cu")
		(net "PCIE_COMP_B_TO_IOM_B_14_DN")
	)
	(segment
		(start 274.573746 -85.463888)
		(end 274.4597 -85.642704)
		(width 0.1397)
		(layer "In9.Cu")
		(net "PCIE_COMP_B_TO_IOM_B_14_DN")
	)
	(segment
		(start 274.483068 -85.054694)
		(end 274.573746 -85.463888)
		(width 0.1397)
		(layer "In9.Cu")
		(net "PCIE_COMP_B_TO_IOM_B_14_DN")
	)
	(segment
		(start 285.249874 -48.200056)
		(end 284.505654 -47.827946)
		(width 0.1397)
		(layer "In9.Cu")
		(net "PCIE_COMP_B_TO_IOM_B_14_DN")
	)
	(segment
		(start 274.796504 -87.162894)
		(end 276.281642 -89.411048)
		(width 0.1397)
		(layer "In9.Cu")
		(net "PCIE_COMP_B_TO_IOM_B_14_DN")
	)
	(segment
		(start 271.813782 -67.600576)
		(end 271.64665 -67.705986)
		(width 0.1397)
		(layer "In9.Cu")
		(net "PCIE_COMP_B_TO_IOM_B_14_DN")
	)
	(segment
		(start 284.318202 -47.89043)
		(end 284.236668 -48.053498)
		(width 0.1397)
		(layer "In9.Cu")
		(net "PCIE_COMP_B_TO_IOM_B_14_DN")
	)
	(segment
		(start 271.060672 -70.294754)
		(end 273.812254 -82.71891)
		(width 0.1397)
		(layer "In9.Cu")
		(net "PCIE_COMP_B_TO_IOM_B_14_DN")
	)
	(segment
		(start 296.523664 -89.55913)
		(end 296.629836 -89.39276)
		(width 0.1397)
		(layer "In9.Cu")
		(net "PCIE_COMP_B_TO_IOM_B_14_DN")
	)
	(segment
		(start 296.629836 -89.39276)
		(end 297.039284 -89.302336)
		(width 0.1397)
		(layer "In9.Cu")
		(net "PCIE_COMP_B_TO_IOM_B_14_DN")
	)
	(segment
		(start 274.705826 -86.7537)
		(end 274.796504 -87.162894)
		(width 0.1397)
		(layer "In9.Cu")
		(net "PCIE_COMP_B_TO_IOM_B_14_DN")
	)
	(segment
		(start 274.4597 -85.642704)
		(end 274.550378 -86.051898)
		(width 0.1397)
		(layer "In9.Cu")
		(net "PCIE_COMP_B_TO_IOM_B_14_DN")
	)
	(segment
		(start 275.648928 -50.022506)
		(end 272.047462 -65.93459)
		(width 0.1397)
		(layer "In9.Cu")
		(net "PCIE_COMP_B_TO_IOM_B_14_DN")
	)
	(segment
		(start 295.947846 -89.542874)
		(end 296.114216 -89.6493)
		(width 0.1397)
		(layer "In9.Cu")
		(net "PCIE_COMP_B_TO_IOM_B_14_DN")
	)
	(segment
		(start 277.94331 -47.413418)
		(end 276.931882 -48.08347)
		(width 0.1397)
		(layer "In9.Cu")
		(net "PCIE_COMP_B_TO_IOM_B_14_DN")
	)
	(segment
		(start 279.935432 -91.830398)
		(end 283.068522 -92.524834)
		(width 0.1397)
		(layer "In9.Cu")
		(net "PCIE_COMP_B_TO_IOM_B_14_DN")
	)
	(segment
		(start 271.554194 -68.114672)
		(end 271.659604 -68.281804)
		(width 0.1397)
		(layer "In9.Cu")
		(net "PCIE_COMP_B_TO_IOM_B_14_DN")
	)
	(segment
		(start 378.602748 -19.233388)
		(end 378.587 -19.249136)
		(width 0.1397)
		(layer "In9.Cu")
		(net "PCIE_COMP_B_TO_IOM_B_14_DN")
	)
	(segment
		(start 273.812254 -82.71891)
		(end 273.99107 -82.832702)
		(width 0.1397)
		(layer "In9.Cu")
		(net "PCIE_COMP_B_TO_IOM_B_14_DN")
	)
	(segment
		(start 274.304506 -84.940902)
		(end 274.483068 -85.054694)
		(width 0.1397)
		(layer "In9.Cu")
		(net "PCIE_COMP_B_TO_IOM_B_14_DN")
	)
	(segment
		(start 304.90795 -87.711026)
		(end 370.815108 -45.72381)
		(width 0.1397)
		(layer "In9.Cu")
		(net "PCIE_COMP_B_TO_IOM_B_14_DN")
	)
	(segment
		(start 272.060416 -66.510408)
		(end 271.893284 -66.615818)
		(width 0.1397)
		(layer "In9.Cu")
		(net "PCIE_COMP_B_TO_IOM_B_14_DN")
	)
	(segment
		(start 379.303788 -32.411162)
		(end 379.303788 -19.390106)
		(width 0.1397)
		(layer "In9.Cu")
		(net "PCIE_COMP_B_TO_IOM_B_14_DN")
	)
	(segment
		(start 271.64665 -67.705986)
		(end 271.554194 -68.114672)
		(width 0.1397)
		(layer "In9.Cu")
		(net "PCIE_COMP_B_TO_IOM_B_14_DN")
	)
	(segment
		(start 278.273764 -47.346108)
		(end 277.94331 -47.413418)
		(width 0.1397)
		(layer "In9.Cu")
		(net "PCIE_COMP_B_TO_IOM_B_14_DN")
	)
	(segment
		(start 283.585666 -48.346106)
		(end 280.222706 -48.346106)
		(width 0.1397)
		(layer "In9.Cu")
		(net "PCIE_COMP_B_TO_IOM_B_14_DN")
	)
	(segment
		(start 274.05838 -83.829906)
		(end 274.236942 -83.943698)
		(width 0.1397)
		(layer "In9.Cu")
		(net "PCIE_COMP_B_TO_IOM_B_14_DN")
	)
	(segment
		(start 286.717232 -91.577668)
		(end 287.12668 -91.487244)
		(width 0.1397)
		(layer "In9.Cu")
		(net "PCIE_COMP_B_TO_IOM_B_14_DN")
	)
	(segment
		(start 283.068522 -92.524834)
		(end 284.428184 -92.225114)
		(width 0.1397)
		(layer "In9.Cu")
		(net "PCIE_COMP_B_TO_IOM_B_14_DN")
	)
	(segment
		(start 271.906238 -67.191636)
		(end 271.813782 -67.600576)
		(width 0.1397)
		(layer "In9.Cu")
		(net "PCIE_COMP_B_TO_IOM_B_14_DN")
	)
	(segment
		(start 375.059194 -39.067486)
		(end 375.059194 -39.06774)
		(width 0.1397)
		(layer "In9.Cu")
		(net "PCIE_COMP_B_TO_IOM_B_14_DN")
	)
	(segment
		(start 274.819872 -86.574884)
		(end 274.705826 -86.7537)
		(width 0.1397)
		(layer "In9.Cu")
		(net "PCIE_COMP_B_TO_IOM_B_14_DN")
	)
	(segment
		(start 295.538652 -89.633298)
		(end 295.947846 -89.542874)
		(width 0.1397)
		(layer "In9.Cu")
		(net "PCIE_COMP_B_TO_IOM_B_14_DN")
	)
	(segment
		(start 273.967702 -83.420712)
		(end 274.05838 -83.829906)
		(width 0.1397)
		(layer "In9.Cu")
		(net "PCIE_COMP_B_TO_IOM_B_14_DN")
	)
	(segment
		(start 271.412716 -69.371718)
		(end 271.32026 -69.780658)
		(width 0.1397)
		(layer "In9.Cu")
		(net "PCIE_COMP_B_TO_IOM_B_14_DN")
	)
	(segment
		(start 287.29305 -91.59367)
		(end 295.432226 -89.799668)
		(width 0.1397)
		(layer "In9.Cu")
		(net "PCIE_COMP_B_TO_IOM_B_14_DN")
	)
	(segment
		(start 274.236942 -83.943698)
		(end 274.32762 -84.352892)
		(width 0.1397)
		(layer "In9.Cu")
		(net "PCIE_COMP_B_TO_IOM_B_14_DN")
	)
	(segment
		(start 379.109986 -19.196304)
		(end 378.69241 -19.196304)
		(width 0.1397)
		(layer "In9.Cu")
		(net "PCIE_COMP_B_TO_IOM_B_14_DN")
	)
	(segment
		(start 276.281642 -89.411048)
		(end 279.935432 -91.830398)
		(width 0.1397)
		(layer "In9.Cu")
		(net "PCIE_COMP_B_TO_IOM_B_14_DN")
	)
	(segment
		(start 297.039284 -89.302336)
		(end 297.205654 -89.408762)
		(width 0.1397)
		(layer "In9.Cu")
		(net "PCIE_COMP_B_TO_IOM_B_14_DN")
	)
	(arc
		(start 284.236668 -48.053498)
		(mid 283.942573 -48.269696)
		(end 283.585666 -48.346106)
		(width 0.1397)
		(layer "In9.Cu")
		(net "PCIE_COMP_B_TO_IOM_B_14_DN")
	)
	(arc
		(start 378.587 -19.249136)
		(mid 378.559567 -19.290287)
		(end 378.549916 -19.338798)
		(width 0.1397)
		(layer "In9.Cu")
		(net "PCIE_COMP_B_TO_IOM_B_14_DN")
	)
	(arc
		(start 379.199648 -19.233388)
		(mid 379.158497 -19.205955)
		(end 379.109986 -19.196304)
		(width 0.1397)
		(layer "In9.Cu")
		(net "PCIE_COMP_B_TO_IOM_B_14_DN")
	)
	(arc
		(start 378.69241 -19.196304)
		(mid 378.643892 -19.205937)
		(end 378.602748 -19.233388)
		(width 0.1397)
		(layer "In9.Cu")
		(net "PCIE_COMP_B_TO_IOM_B_14_DN")
	)
	(arc
		(start 379.303788 -19.390106)
		(mid 379.294155 -19.341588)
		(end 379.266704 -19.300444)
		(width 0.1397)
		(layer "In9.Cu")
		(net "PCIE_COMP_B_TO_IOM_B_14_DN")
	)
	(arc
		(start 284.505654 -47.827946)
		(mid 284.398987 -47.820365)
		(end 284.318202 -47.89043)
		(width 0.1397)
		(layer "In9.Cu")
		(net "PCIE_COMP_B_TO_IOM_B_14_DN")
	)
	(segment
		(start 272.48231 -87.503762)
		(end 274.745196 -90.922602)
		(width 0.1397)
		(layer "In9.Cu")
		(net "PCIE_COMP_B_TO_IOM_B_13_DP")
	)
	(segment
		(start 268.875256 -71.228712)
		(end 272.48231 -87.503762)
		(width 0.1397)
		(layer "In9.Cu")
		(net "PCIE_COMP_B_TO_IOM_B_13_DP")
	)
	(segment
		(start 276.794468 -43.812714)
		(end 274.188174 -47.74946)
		(width 0.1397)
		(layer "In9.Cu")
		(net "PCIE_COMP_B_TO_IOM_B_13_DP")
	)
	(segment
		(start 381.395986 -32.583374)
		(end 381.395986 -18.390108)
		(width 0.1397)
		(layer "In9.Cu")
		(net "PCIE_COMP_B_TO_IOM_B_13_DP")
	)
	(segment
		(start 381.273558 -18.093944)
		(end 381.206502 -18.026634)
		(width 0.1397)
		(layer "In9.Cu")
		(net "PCIE_COMP_B_TO_IOM_B_13_DP")
	)
	(segment
		(start 380.492762 -17.904206)
		(end 380.492508 -17.903952)
		(width 0.1397)
		(layer "In9.Cu")
		(net "PCIE_COMP_B_TO_IOM_B_13_DP")
	)
	(segment
		(start 279.331674 -43.054016)
		(end 277.985474 -43.054016)
		(width 0.1397)
		(layer "In9.Cu")
		(net "PCIE_COMP_B_TO_IOM_B_13_DP")
	)
	(segment
		(start 380.910084 -17.904206)
		(end 380.492762 -17.904206)
		(width 0.1397)
		(layer "In9.Cu")
		(net "PCIE_COMP_B_TO_IOM_B_13_DP")
	)
	(segment
		(start 277.985474 -43.054016)
		(end 276.794468 -43.812714)
		(width 0.1397)
		(layer "In9.Cu")
		(net "PCIE_COMP_B_TO_IOM_B_13_DP")
	)
	(segment
		(start 283.58592 -44.054014)
		(end 280.331672 -44.054014)
		(width 0.1397)
		(layer "In9.Cu")
		(net "PCIE_COMP_B_TO_IOM_B_13_DP")
	)
	(segment
		(start 312.911744 -88.09101)
		(end 372.783862 -46.091602)
		(width 0.1397)
		(layer "In9.Cu")
		(net "PCIE_COMP_B_TO_IOM_B_13_DP")
	)
	(segment
		(start 284.056836 -43.759882)
		(end 283.994352 -43.88485)
		(width 0.1397)
		(layer "In9.Cu")
		(net "PCIE_COMP_B_TO_IOM_B_13_DP")
	)
	(segment
		(start 283.249878 -43.200066)
		(end 283.994352 -43.57243)
		(width 0.1397)
		(layer "In9.Cu")
		(net "PCIE_COMP_B_TO_IOM_B_13_DP")
	)
	(segment
		(start 280.331672 -44.054014)
		(end 279.331674 -43.054016)
		(width 0.1397)
		(layer "In9.Cu")
		(net "PCIE_COMP_B_TO_IOM_B_13_DP")
	)
	(segment
		(start 274.188174 -47.74946)
		(end 268.875256 -71.228712)
		(width 0.1397)
		(layer "In9.Cu")
		(net "PCIE_COMP_B_TO_IOM_B_13_DP")
	)
	(segment
		(start 372.783862 -46.091602)
		(end 381.395986 -32.583374)
		(width 0.1397)
		(layer "In9.Cu")
		(net "PCIE_COMP_B_TO_IOM_B_13_DP")
	)
	(segment
		(start 278.859488 -93.646752)
		(end 283.251656 -94.620334)
		(width 0.1397)
		(layer "In9.Cu")
		(net "PCIE_COMP_B_TO_IOM_B_13_DP")
	)
	(segment
		(start 283.251656 -94.620334)
		(end 312.911744 -88.09101)
		(width 0.1397)
		(layer "In9.Cu")
		(net "PCIE_COMP_B_TO_IOM_B_13_DP")
	)
	(segment
		(start 274.745196 -90.922602)
		(end 278.859488 -93.646752)
		(width 0.1397)
		(layer "In9.Cu")
		(net "PCIE_COMP_B_TO_IOM_B_13_DP")
	)
	(segment
		(start 380.350014 -17.761458)
		(end 380.350014 -17.349978)
		(width 0.1397)
		(layer "In9.Cu")
		(net "PCIE_COMP_B_TO_IOM_B_13_DP")
	)
	(segment
		(start 380.402846 -17.866868)
		(end 380.387098 -17.85112)
		(width 0.1397)
		(layer "In9.Cu")
		(net "PCIE_COMP_B_TO_IOM_B_13_DP")
	)
	(arc
		(start 283.994352 -43.88485)
		(mid 283.806962 -44.01006)
		(end 283.58592 -44.054014)
		(width 0.1397)
		(layer "In9.Cu")
		(net "PCIE_COMP_B_TO_IOM_B_13_DP")
	)
	(arc
		(start 380.492508 -17.903952)
		(mid 380.44399 -17.894319)
		(end 380.402846 -17.866868)
		(width 0.1397)
		(layer "In9.Cu")
		(net "PCIE_COMP_B_TO_IOM_B_13_DP")
	)
	(arc
		(start 283.994352 -43.57243)
		(mid 284.064417 -43.653215)
		(end 284.056836 -43.759882)
		(width 0.1397)
		(layer "In9.Cu")
		(net "PCIE_COMP_B_TO_IOM_B_13_DP")
	)
	(arc
		(start 381.395986 -18.390108)
		(mid 381.364236 -18.229838)
		(end 381.273558 -18.093944)
		(width 0.1397)
		(layer "In9.Cu")
		(net "PCIE_COMP_B_TO_IOM_B_13_DP")
	)
	(arc
		(start 381.206502 -18.026634)
		(mid 381.070475 -17.9359)
		(end 380.910084 -17.904206)
		(width 0.1397)
		(layer "In9.Cu")
		(net "PCIE_COMP_B_TO_IOM_B_13_DP")
	)
	(arc
		(start 380.387098 -17.85112)
		(mid 380.359665 -17.809969)
		(end 380.350014 -17.761458)
		(width 0.1397)
		(layer "In9.Cu")
		(net "PCIE_COMP_B_TO_IOM_B_13_DP")
	)
	(segment
		(start 272.28673 -84.577936)
		(end 272.172684 -84.756498)
		(width 0.1397)
		(layer "In9.Cu")
		(net "PCIE_COMP_B_TO_IOM_B_13_DN")
	)
	(segment
		(start 272.04035 -83.46694)
		(end 271.926558 -83.645502)
		(width 0.1397)
		(layer "In9.Cu")
		(net "PCIE_COMP_B_TO_IOM_B_13_DN")
	)
	(segment
		(start 272.778982 -86.799674)
		(end 272.66519 -86.97849)
		(width 0.1397)
		(layer "In9.Cu")
		(net "PCIE_COMP_B_TO_IOM_B_13_DN")
	)
	(segment
		(start 269.43431 -70.715378)
		(end 269.267178 -70.820788)
		(width 0.1397)
		(layer "In9.Cu")
		(net "PCIE_COMP_B_TO_IOM_B_13_DN")
	)
	(segment
		(start 269.66799 -69.049392)
		(end 269.7734 -69.216524)
		(width 0.1397)
		(layer "In9.Cu")
		(net "PCIE_COMP_B_TO_IOM_B_13_DN")
	)
	(segment
		(start 269.760446 -68.640706)
		(end 269.66799 -69.049392)
		(width 0.1397)
		(layer "In9.Cu")
		(net "PCIE_COMP_B_TO_IOM_B_13_DN")
	)
	(segment
		(start 269.927578 -68.535296)
		(end 269.760446 -68.640706)
		(width 0.1397)
		(layer "In9.Cu")
		(net "PCIE_COMP_B_TO_IOM_B_13_DN")
	)
	(segment
		(start 280.210514 -44.346114)
		(end 279.210516 -43.346116)
		(width 0.1397)
		(layer "In9.Cu")
		(net "PCIE_COMP_B_TO_IOM_B_13_DN")
	)
	(segment
		(start 284.743906 -93.9927)
		(end 285.1531 -93.90253)
		(width 0.1397)
		(layer "In9.Cu")
		(net "PCIE_COMP_B_TO_IOM_B_13_DN")
	)
	(segment
		(start 270.174212 -67.445128)
		(end 270.00708 -67.550538)
		(width 0.1397)
		(layer "In9.Cu")
		(net "PCIE_COMP_B_TO_IOM_B_13_DN")
	)
	(segment
		(start 274.461478 -47.8663)
		(end 270.161258 -66.86931)
		(width 0.1397)
		(layer "In9.Cu")
		(net "PCIE_COMP_B_TO_IOM_B_13_DN")
	)
	(segment
		(start 269.914624 -67.959224)
		(end 270.020034 -68.126356)
		(width 0.1397)
		(layer "In9.Cu")
		(net "PCIE_COMP_B_TO_IOM_B_13_DN")
	)
	(segment
		(start 279.210516 -43.346116)
		(end 278.070818 -43.346116)
		(width 0.1397)
		(layer "In9.Cu")
		(net "PCIE_COMP_B_TO_IOM_B_13_DN")
	)
	(segment
		(start 269.526766 -70.306438)
		(end 269.43431 -70.715378)
		(width 0.1397)
		(layer "In9.Cu")
		(net "PCIE_COMP_B_TO_IOM_B_13_DN")
	)
	(segment
		(start 380.402846 -18.23339)
		(end 380.387098 -18.249138)
		(width 0.1397)
		(layer "In9.Cu")
		(net "PCIE_COMP_B_TO_IOM_B_13_DN")
	)
	(segment
		(start 274.956016 -90.711782)
		(end 278.975566 -93.37294)
		(width 0.1397)
		(layer "In9.Cu")
		(net "PCIE_COMP_B_TO_IOM_B_13_DN")
	)
	(segment
		(start 285.668974 -93.64599)
		(end 285.835344 -93.752416)
		(width 0.1397)
		(layer "In9.Cu")
		(net "PCIE_COMP_B_TO_IOM_B_13_DN")
	)
	(segment
		(start 271.926558 -83.645502)
		(end 272.017236 -84.054696)
		(width 0.1397)
		(layer "In9.Cu")
		(net "PCIE_COMP_B_TO_IOM_B_13_DN")
	)
	(segment
		(start 283.585666 -44.346114)
		(end 280.210514 -44.346114)
		(width 0.1397)
		(layer "In9.Cu")
		(net "PCIE_COMP_B_TO_IOM_B_13_DN")
	)
	(segment
		(start 296.554906 -91.392502)
		(end 296.661332 -91.226132)
		(width 0.1397)
		(layer "In9.Cu")
		(net "PCIE_COMP_B_TO_IOM_B_13_DN")
	)
	(segment
		(start 272.263362 -85.165692)
		(end 272.442178 -85.279738)
		(width 0.1397)
		(layer "In9.Cu")
		(net "PCIE_COMP_B_TO_IOM_B_13_DN")
	)
	(segment
		(start 271.949672 -83.057746)
		(end 272.04035 -83.46694)
		(width 0.1397)
		(layer "In9.Cu")
		(net "PCIE_COMP_B_TO_IOM_B_13_DN")
	)
	(segment
		(start 272.196052 -84.168742)
		(end 272.28673 -84.577936)
		(width 0.1397)
		(layer "In9.Cu")
		(net "PCIE_COMP_B_TO_IOM_B_13_DN")
	)
	(segment
		(start 295.569894 -91.466416)
		(end 295.979088 -91.376246)
		(width 0.1397)
		(layer "In9.Cu")
		(net "PCIE_COMP_B_TO_IOM_B_13_DN")
	)
	(segment
		(start 286.926782 -93.512132)
		(end 295.463468 -91.632786)
		(width 0.1397)
		(layer "In9.Cu")
		(net "PCIE_COMP_B_TO_IOM_B_13_DN")
	)
	(segment
		(start 272.442178 -85.279738)
		(end 272.532856 -85.688932)
		(width 0.1397)
		(layer "In9.Cu")
		(net "PCIE_COMP_B_TO_IOM_B_13_DN")
	)
	(segment
		(start 278.975566 -93.373194)
		(end 283.25191 -94.321122)
		(width 0.1397)
		(layer "In9.Cu")
		(net "PCIE_COMP_B_TO_IOM_B_13_DN")
	)
	(segment
		(start 286.350964 -93.495876)
		(end 286.760412 -93.405706)
		(width 0.1397)
		(layer "In9.Cu")
		(net "PCIE_COMP_B_TO_IOM_B_13_DN")
	)
	(segment
		(start 269.421356 -70.139306)
		(end 269.526766 -70.306438)
		(width 0.1397)
		(layer "In9.Cu")
		(net "PCIE_COMP_B_TO_IOM_B_13_DN")
	)
	(segment
		(start 272.172684 -84.756498)
		(end 272.263362 -85.165692)
		(width 0.1397)
		(layer "In9.Cu")
		(net "PCIE_COMP_B_TO_IOM_B_13_DN")
	)
	(segment
		(start 272.017236 -84.054696)
		(end 272.196052 -84.168742)
		(width 0.1397)
		(layer "In9.Cu")
		(net "PCIE_COMP_B_TO_IOM_B_13_DN")
	)
	(segment
		(start 312.791856 -87.818214)
		(end 372.568724 -45.885608)
		(width 0.1397)
		(layer "In9.Cu")
		(net "PCIE_COMP_B_TO_IOM_B_13_DN")
	)
	(segment
		(start 296.145712 -91.482672)
		(end 296.554906 -91.392502)
		(width 0.1397)
		(layer "In9.Cu")
		(net "PCIE_COMP_B_TO_IOM_B_13_DN")
	)
	(segment
		(start 295.979088 -91.376246)
		(end 296.145712 -91.482672)
		(width 0.1397)
		(layer "In9.Cu")
		(net "PCIE_COMP_B_TO_IOM_B_13_DN")
	)
	(segment
		(start 284.318202 -43.890438)
		(end 284.236668 -44.053506)
		(width 0.1397)
		(layer "In9.Cu")
		(net "PCIE_COMP_B_TO_IOM_B_13_DN")
	)
	(segment
		(start 269.174722 -71.229474)
		(end 271.77111 -82.943954)
		(width 0.1397)
		(layer "In9.Cu")
		(net "PCIE_COMP_B_TO_IOM_B_13_DN")
	)
	(segment
		(start 372.568724 -45.885608)
		(end 381.103886 -32.49803)
		(width 0.1397)
		(layer "In9.Cu")
		(net "PCIE_COMP_B_TO_IOM_B_13_DN")
	)
	(segment
		(start 272.755868 -87.387684)
		(end 274.956016 -90.711782)
		(width 0.1397)
		(layer "In9.Cu")
		(net "PCIE_COMP_B_TO_IOM_B_13_DN")
	)
	(segment
		(start 381.066802 -18.300446)
		(end 380.999746 -18.23339)
		(width 0.1397)
		(layer "In9.Cu")
		(net "PCIE_COMP_B_TO_IOM_B_13_DN")
	)
	(segment
		(start 284.168088 -93.976444)
		(end 284.577536 -93.886274)
		(width 0.1397)
		(layer "In9.Cu")
		(net "PCIE_COMP_B_TO_IOM_B_13_DN")
	)
	(segment
		(start 277.003764 -44.02582)
		(end 274.461478 -47.8663)
		(width 0.1397)
		(layer "In9.Cu")
		(net "PCIE_COMP_B_TO_IOM_B_13_DN")
	)
	(segment
		(start 380.350014 -18.3388)
		(end 380.350014 -18.750026)
		(width 0.1397)
		(layer "In9.Cu")
		(net "PCIE_COMP_B_TO_IOM_B_13_DN")
	)
	(segment
		(start 272.66519 -86.97849)
		(end 272.755868 -87.387684)
		(width 0.1397)
		(layer "In9.Cu")
		(net "PCIE_COMP_B_TO_IOM_B_13_DN")
	)
	(segment
		(start 286.244538 -93.662246)
		(end 286.350964 -93.495876)
		(width 0.1397)
		(layer "In9.Cu")
		(net "PCIE_COMP_B_TO_IOM_B_13_DN")
	)
	(segment
		(start 278.070818 -43.346116)
		(end 277.003764 -44.02582)
		(width 0.1397)
		(layer "In9.Cu")
		(net "PCIE_COMP_B_TO_IOM_B_13_DN")
	)
	(segment
		(start 270.020034 -68.126356)
		(end 269.927578 -68.535296)
		(width 0.1397)
		(layer "In9.Cu")
		(net "PCIE_COMP_B_TO_IOM_B_13_DN")
	)
	(segment
		(start 380.910084 -18.196306)
		(end 380.492508 -18.196306)
		(width 0.1397)
		(layer "In9.Cu")
		(net "PCIE_COMP_B_TO_IOM_B_13_DN")
	)
	(segment
		(start 272.532856 -85.688932)
		(end 272.419064 -85.867494)
		(width 0.1397)
		(layer "In9.Cu")
		(net "PCIE_COMP_B_TO_IOM_B_13_DN")
	)
	(segment
		(start 270.161258 -66.86931)
		(end 270.266668 -67.036442)
		(width 0.1397)
		(layer "In9.Cu")
		(net "PCIE_COMP_B_TO_IOM_B_13_DN")
	)
	(segment
		(start 295.463468 -91.632786)
		(end 295.569894 -91.466416)
		(width 0.1397)
		(layer "In9.Cu")
		(net "PCIE_COMP_B_TO_IOM_B_13_DN")
	)
	(segment
		(start 269.267178 -70.820788)
		(end 269.174722 -71.229474)
		(width 0.1397)
		(layer "In9.Cu")
		(net "PCIE_COMP_B_TO_IOM_B_13_DN")
	)
	(segment
		(start 284.061662 -94.142814)
		(end 284.168088 -93.976444)
		(width 0.1397)
		(layer "In9.Cu")
		(net "PCIE_COMP_B_TO_IOM_B_13_DN")
	)
	(segment
		(start 285.1531 -93.90253)
		(end 285.259526 -93.73616)
		(width 0.1397)
		(layer "In9.Cu")
		(net "PCIE_COMP_B_TO_IOM_B_13_DN")
	)
	(segment
		(start 285.259526 -93.73616)
		(end 285.668974 -93.64599)
		(width 0.1397)
		(layer "In9.Cu")
		(net "PCIE_COMP_B_TO_IOM_B_13_DN")
	)
	(segment
		(start 270.266668 -67.036442)
		(end 270.174212 -67.445128)
		(width 0.1397)
		(layer "In9.Cu")
		(net "PCIE_COMP_B_TO_IOM_B_13_DN")
	)
	(segment
		(start 272.419064 -85.867494)
		(end 272.509742 -86.276688)
		(width 0.1397)
		(layer "In9.Cu")
		(net "PCIE_COMP_B_TO_IOM_B_13_DN")
	)
	(segment
		(start 297.23715 -91.242388)
		(end 312.791856 -87.818214)
		(width 0.1397)
		(layer "In9.Cu")
		(net "PCIE_COMP_B_TO_IOM_B_13_DN")
	)
	(segment
		(start 269.7734 -69.216524)
		(end 269.680944 -69.62521)
		(width 0.1397)
		(layer "In9.Cu")
		(net "PCIE_COMP_B_TO_IOM_B_13_DN")
	)
	(segment
		(start 272.688304 -86.39048)
		(end 272.778982 -86.799674)
		(width 0.1397)
		(layer "In9.Cu")
		(net "PCIE_COMP_B_TO_IOM_B_13_DN")
	)
	(segment
		(start 285.249874 -44.200064)
		(end 284.505654 -43.827954)
		(width 0.1397)
		(layer "In9.Cu")
		(net "PCIE_COMP_B_TO_IOM_B_13_DN")
	)
	(segment
		(start 296.661332 -91.226132)
		(end 297.07078 -91.135962)
		(width 0.1397)
		(layer "In9.Cu")
		(net "PCIE_COMP_B_TO_IOM_B_13_DN")
	)
	(segment
		(start 269.513812 -69.73062)
		(end 269.421356 -70.139306)
		(width 0.1397)
		(layer "In9.Cu")
		(net "PCIE_COMP_B_TO_IOM_B_13_DN")
	)
	(segment
		(start 270.00708 -67.550538)
		(end 269.914624 -67.959224)
		(width 0.1397)
		(layer "In9.Cu")
		(net "PCIE_COMP_B_TO_IOM_B_13_DN")
	)
	(segment
		(start 271.77111 -82.943954)
		(end 271.949672 -83.057746)
		(width 0.1397)
		(layer "In9.Cu")
		(net "PCIE_COMP_B_TO_IOM_B_13_DN")
	)
	(segment
		(start 284.577536 -93.886274)
		(end 284.743906 -93.9927)
		(width 0.1397)
		(layer "In9.Cu")
		(net "PCIE_COMP_B_TO_IOM_B_13_DN")
	)
	(segment
		(start 283.25191 -94.321122)
		(end 284.061662 -94.142814)
		(width 0.1397)
		(layer "In9.Cu")
		(net "PCIE_COMP_B_TO_IOM_B_13_DN")
	)
	(segment
		(start 269.680944 -69.62521)
		(end 269.513812 -69.73062)
		(width 0.1397)
		(layer "In9.Cu")
		(net "PCIE_COMP_B_TO_IOM_B_13_DN")
	)
	(segment
		(start 381.103886 -32.49803)
		(end 381.103886 -18.390108)
		(width 0.1397)
		(layer "In9.Cu")
		(net "PCIE_COMP_B_TO_IOM_B_13_DN")
	)
	(segment
		(start 285.835344 -93.752416)
		(end 286.244538 -93.662246)
		(width 0.1397)
		(layer "In9.Cu")
		(net "PCIE_COMP_B_TO_IOM_B_13_DN")
	)
	(segment
		(start 278.975566 -93.37294)
		(end 278.975566 -93.373194)
		(width 0.1397)
		(layer "In9.Cu")
		(net "PCIE_COMP_B_TO_IOM_B_13_DN")
	)
	(segment
		(start 297.07078 -91.135962)
		(end 297.23715 -91.242388)
		(width 0.1397)
		(layer "In9.Cu")
		(net "PCIE_COMP_B_TO_IOM_B_13_DN")
	)
	(segment
		(start 272.509742 -86.276688)
		(end 272.688304 -86.39048)
		(width 0.1397)
		(layer "In9.Cu")
		(net "PCIE_COMP_B_TO_IOM_B_13_DN")
	)
	(segment
		(start 286.760412 -93.405706)
		(end 286.926782 -93.512132)
		(width 0.1397)
		(layer "In9.Cu")
		(net "PCIE_COMP_B_TO_IOM_B_13_DN")
	)
	(arc
		(start 380.492508 -18.196306)
		(mid 380.44399 -18.205939)
		(end 380.402846 -18.23339)
		(width 0.1397)
		(layer "In9.Cu")
		(net "PCIE_COMP_B_TO_IOM_B_13_DN")
	)
	(arc
		(start 380.387098 -18.249138)
		(mid 380.359665 -18.290289)
		(end 380.350014 -18.3388)
		(width 0.1397)
		(layer "In9.Cu")
		(net "PCIE_COMP_B_TO_IOM_B_13_DN")
	)
	(arc
		(start 381.103886 -18.390108)
		(mid 381.094253 -18.34159)
		(end 381.066802 -18.300446)
		(width 0.1397)
		(layer "In9.Cu")
		(net "PCIE_COMP_B_TO_IOM_B_13_DN")
	)
	(arc
		(start 284.505654 -43.827954)
		(mid 284.398987 -43.820373)
		(end 284.318202 -43.890438)
		(width 0.1397)
		(layer "In9.Cu")
		(net "PCIE_COMP_B_TO_IOM_B_13_DN")
	)
	(arc
		(start 284.236668 -44.053506)
		(mid 283.942573 -44.269704)
		(end 283.585666 -44.346114)
		(width 0.1397)
		(layer "In9.Cu")
		(net "PCIE_COMP_B_TO_IOM_B_13_DN")
	)
	(arc
		(start 380.999746 -18.23339)
		(mid 380.958595 -18.205957)
		(end 380.910084 -18.196306)
		(width 0.1397)
		(layer "In9.Cu")
		(net "PCIE_COMP_B_TO_IOM_B_13_DN")
	)
	(segment
		(start 266.824968 -71.80453)
		(end 270.184118 -86.96579)
		(width 0.1397)
		(layer "In9.Cu")
		(net "PCIE_COMP_B_TO_IOM_B_12_DP")
	)
	(segment
		(start 272.719546 -45.749464)
		(end 266.824968 -71.80453)
		(width 0.1397)
		(layer "In9.Cu")
		(net "PCIE_COMP_B_TO_IOM_B_12_DP")
	)
	(segment
		(start 277.920958 -39.054024)
		(end 276.591268 -39.901114)
		(width 0.1397)
		(layer "In9.Cu")
		(net "PCIE_COMP_B_TO_IOM_B_12_DP")
	)
	(segment
		(start 373.555514 -47.912274)
		(end 383.196084 -32.793432)
		(width 0.1397)
		(layer "In9.Cu")
		(net "PCIE_COMP_B_TO_IOM_B_12_DP")
	)
	(segment
		(start 382.150112 -18.761456)
		(end 382.150112 -18.35023)
		(width 0.1397)
		(layer "In9.Cu")
		(net "PCIE_COMP_B_TO_IOM_B_12_DP")
	)
	(segment
		(start 382.202944 -18.866866)
		(end 382.187196 -18.851118)
		(width 0.1397)
		(layer "In9.Cu")
		(net "PCIE_COMP_B_TO_IOM_B_12_DP")
	)
	(segment
		(start 280.396188 -40.054022)
		(end 279.39619 -39.054024)
		(width 0.1397)
		(layer "In9.Cu")
		(net "PCIE_COMP_B_TO_IOM_B_12_DP")
	)
	(segment
		(start 383.073656 -19.093942)
		(end 383.0066 -19.026632)
		(width 0.1397)
		(layer "In9.Cu")
		(net "PCIE_COMP_B_TO_IOM_B_12_DP")
	)
	(segment
		(start 270.184118 -86.96579)
		(end 273.77263 -92.387928)
		(width 0.1397)
		(layer "In9.Cu")
		(net "PCIE_COMP_B_TO_IOM_B_12_DP")
	)
	(segment
		(start 283.58592 -40.054022)
		(end 280.396188 -40.054022)
		(width 0.1397)
		(layer "In9.Cu")
		(net "PCIE_COMP_B_TO_IOM_B_12_DP")
	)
	(segment
		(start 273.77263 -92.387928)
		(end 277.7236 -95.003112)
		(width 0.1397)
		(layer "In9.Cu")
		(net "PCIE_COMP_B_TO_IOM_B_12_DP")
	)
	(segment
		(start 283.456634 -96.274128)
		(end 314.240164 -89.521284)
		(width 0.1397)
		(layer "In9.Cu")
		(net "PCIE_COMP_B_TO_IOM_B_12_DP")
	)
	(segment
		(start 277.7236 -95.003112)
		(end 283.456634 -96.274128)
		(width 0.1397)
		(layer "In9.Cu")
		(net "PCIE_COMP_B_TO_IOM_B_12_DP")
	)
	(segment
		(start 383.196084 -32.793432)
		(end 383.196084 -19.390106)
		(width 0.1397)
		(layer "In9.Cu")
		(net "PCIE_COMP_B_TO_IOM_B_12_DP")
	)
	(segment
		(start 276.591268 -39.901114)
		(end 272.719546 -45.749464)
		(width 0.1397)
		(layer "In9.Cu")
		(net "PCIE_COMP_B_TO_IOM_B_12_DP")
	)
	(segment
		(start 382.710182 -18.904204)
		(end 382.29286 -18.904204)
		(width 0.1397)
		(layer "In9.Cu")
		(net "PCIE_COMP_B_TO_IOM_B_12_DP")
	)
	(segment
		(start 382.29286 -18.904204)
		(end 382.292606 -18.90395)
		(width 0.1397)
		(layer "In9.Cu")
		(net "PCIE_COMP_B_TO_IOM_B_12_DP")
	)
	(segment
		(start 283.249878 -39.200074)
		(end 283.994352 -39.572438)
		(width 0.1397)
		(layer "In9.Cu")
		(net "PCIE_COMP_B_TO_IOM_B_12_DP")
	)
	(segment
		(start 284.056836 -39.75989)
		(end 283.994352 -39.884858)
		(width 0.1397)
		(layer "In9.Cu")
		(net "PCIE_COMP_B_TO_IOM_B_12_DP")
	)
	(segment
		(start 279.39619 -39.054024)
		(end 277.920958 -39.054024)
		(width 0.1397)
		(layer "In9.Cu")
		(net "PCIE_COMP_B_TO_IOM_B_12_DP")
	)
	(segment
		(start 314.240164 -89.521284)
		(end 373.555514 -47.912274)
		(width 0.1397)
		(layer "In9.Cu")
		(net "PCIE_COMP_B_TO_IOM_B_12_DP")
	)
	(arc
		(start 382.292606 -18.90395)
		(mid 382.244088 -18.894317)
		(end 382.202944 -18.866866)
		(width 0.1397)
		(layer "In9.Cu")
		(net "PCIE_COMP_B_TO_IOM_B_12_DP")
	)
	(arc
		(start 283.994352 -39.572438)
		(mid 284.064417 -39.653223)
		(end 284.056836 -39.75989)
		(width 0.1397)
		(layer "In9.Cu")
		(net "PCIE_COMP_B_TO_IOM_B_12_DP")
	)
	(arc
		(start 283.994352 -39.884858)
		(mid 283.806962 -40.010068)
		(end 283.58592 -40.054022)
		(width 0.1397)
		(layer "In9.Cu")
		(net "PCIE_COMP_B_TO_IOM_B_12_DP")
	)
	(arc
		(start 383.196084 -19.390106)
		(mid 383.164334 -19.229836)
		(end 383.073656 -19.093942)
		(width 0.1397)
		(layer "In9.Cu")
		(net "PCIE_COMP_B_TO_IOM_B_12_DP")
	)
	(arc
		(start 382.187196 -18.851118)
		(mid 382.159763 -18.809967)
		(end 382.150112 -18.761456)
		(width 0.1397)
		(layer "In9.Cu")
		(net "PCIE_COMP_B_TO_IOM_B_12_DP")
	)
	(arc
		(start 383.0066 -19.026632)
		(mid 382.870573 -18.935898)
		(end 382.710182 -18.904204)
		(width 0.1397)
		(layer "In9.Cu")
		(net "PCIE_COMP_B_TO_IOM_B_12_DP")
	)
	(segment
		(start 382.903984 -32.708088)
		(end 373.340376 -47.70628)
		(width 0.1397)
		(layer "In9.Cu")
		(net "PCIE_COMP_B_TO_IOM_B_12_DN")
	)
	(segment
		(start 269.651734 -82.519774)
		(end 269.473172 -82.405728)
		(width 0.1397)
		(layer "In9.Cu")
		(net "PCIE_COMP_B_TO_IOM_B_12_DN")
	)
	(segment
		(start 270.390366 -85.852508)
		(end 270.21155 -85.738716)
		(width 0.1397)
		(layer "In9.Cu")
		(net "PCIE_COMP_B_TO_IOM_B_12_DN")
	)
	(segment
		(start 267.384022 -71.291196)
		(end 267.476478 -70.882256)
		(width 0.1397)
		(layer "In9.Cu")
		(net "PCIE_COMP_B_TO_IOM_B_12_DN")
	)
	(segment
		(start 314.120276 -89.248488)
		(end 297.173904 -92.965778)
		(width 0.1397)
		(layer "In9.Cu")
		(net "PCIE_COMP_B_TO_IOM_B_12_DN")
	)
	(segment
		(start 286.012636 -95.414338)
		(end 285.846012 -95.307658)
		(width 0.1397)
		(layer "In9.Cu")
		(net "PCIE_COMP_B_TO_IOM_B_12_DN")
	)
	(segment
		(start 270.143986 -84.741766)
		(end 269.965424 -84.62772)
		(width 0.1397)
		(layer "In9.Cu")
		(net "PCIE_COMP_B_TO_IOM_B_12_DN")
	)
	(segment
		(start 268.11097 -67.445128)
		(end 272.99285 -45.866304)
		(width 0.1397)
		(layer "In9.Cu")
		(net "PCIE_COMP_B_TO_IOM_B_12_DN")
	)
	(segment
		(start 267.371068 -70.715124)
		(end 267.463524 -70.306438)
		(width 0.1397)
		(layer "In9.Cu")
		(net "PCIE_COMP_B_TO_IOM_B_12_DN")
	)
	(segment
		(start 269.742412 -82.928968)
		(end 269.651734 -82.519774)
		(width 0.1397)
		(layer "In9.Cu")
		(net "PCIE_COMP_B_TO_IOM_B_12_DN")
	)
	(segment
		(start 284.345126 -95.637096)
		(end 284.2387 -95.803466)
		(width 0.1397)
		(layer "In9.Cu")
		(net "PCIE_COMP_B_TO_IOM_B_12_DN")
	)
	(segment
		(start 269.874746 -84.218526)
		(end 269.988538 -84.039964)
		(width 0.1397)
		(layer "In9.Cu")
		(net "PCIE_COMP_B_TO_IOM_B_12_DN")
	)
	(segment
		(start 269.62862 -83.10753)
		(end 269.742412 -82.928968)
		(width 0.1397)
		(layer "In9.Cu")
		(net "PCIE_COMP_B_TO_IOM_B_12_DN")
	)
	(segment
		(start 296.082212 -93.2053)
		(end 295.915842 -93.098874)
		(width 0.1397)
		(layer "In9.Cu")
		(net "PCIE_COMP_B_TO_IOM_B_12_DN")
	)
	(segment
		(start 295.399968 -93.354906)
		(end 287.104074 -95.174816)
		(width 0.1397)
		(layer "In9.Cu")
		(net "PCIE_COMP_B_TO_IOM_B_12_DN")
	)
	(segment
		(start 382.903984 -19.390106)
		(end 382.903984 -32.708088)
		(width 0.1397)
		(layer "In9.Cu")
		(net "PCIE_COMP_B_TO_IOM_B_12_DN")
	)
	(segment
		(start 273.98345 -92.177108)
		(end 270.457676 -86.849712)
		(width 0.1397)
		(layer "In9.Cu")
		(net "PCIE_COMP_B_TO_IOM_B_12_DN")
	)
	(segment
		(start 287.104074 -95.174816)
		(end 286.937704 -95.06839)
		(width 0.1397)
		(layer "In9.Cu")
		(net "PCIE_COMP_B_TO_IOM_B_12_DN")
	)
	(segment
		(start 269.988538 -84.039964)
		(end 269.89786 -83.63077)
		(width 0.1397)
		(layer "In9.Cu")
		(net "PCIE_COMP_B_TO_IOM_B_12_DN")
	)
	(segment
		(start 267.21689 -71.396606)
		(end 267.384022 -71.291196)
		(width 0.1397)
		(layer "In9.Cu")
		(net "PCIE_COMP_B_TO_IOM_B_12_DN")
	)
	(segment
		(start 295.506394 -93.188536)
		(end 295.399968 -93.354906)
		(width 0.1397)
		(layer "In9.Cu")
		(net "PCIE_COMP_B_TO_IOM_B_12_DN")
	)
	(segment
		(start 270.120872 -85.329522)
		(end 270.234664 -85.150706)
		(width 0.1397)
		(layer "In9.Cu")
		(net "PCIE_COMP_B_TO_IOM_B_12_DN")
	)
	(segment
		(start 382.292606 -19.196304)
		(end 382.710182 -19.196304)
		(width 0.1397)
		(layer "In9.Cu")
		(net "PCIE_COMP_B_TO_IOM_B_12_DN")
	)
	(segment
		(start 382.799844 -19.233388)
		(end 382.8669 -19.300444)
		(width 0.1397)
		(layer "In9.Cu")
		(net "PCIE_COMP_B_TO_IOM_B_12_DN")
	)
	(segment
		(start 284.236668 -40.053514)
		(end 284.318202 -39.890446)
		(width 0.1397)
		(layer "In9.Cu")
		(net "PCIE_COMP_B_TO_IOM_B_12_DN")
	)
	(segment
		(start 286.937704 -95.06839)
		(end 286.52851 -95.158052)
		(width 0.1397)
		(layer "In9.Cu")
		(net "PCIE_COMP_B_TO_IOM_B_12_DN")
	)
	(segment
		(start 270.48079 -86.261702)
		(end 270.390366 -85.852508)
		(width 0.1397)
		(layer "In9.Cu")
		(net "PCIE_COMP_B_TO_IOM_B_12_DN")
	)
	(segment
		(start 285.436818 -95.397574)
		(end 285.330138 -95.563944)
		(width 0.1397)
		(layer "In9.Cu")
		(net "PCIE_COMP_B_TO_IOM_B_12_DN")
	)
	(segment
		(start 269.719298 -83.516724)
		(end 269.62862 -83.10753)
		(width 0.1397)
		(layer "In9.Cu")
		(net "PCIE_COMP_B_TO_IOM_B_12_DN")
	)
	(segment
		(start 286.52851 -95.158052)
		(end 286.42183 -95.324422)
		(width 0.1397)
		(layer "In9.Cu")
		(net "PCIE_COMP_B_TO_IOM_B_12_DN")
	)
	(segment
		(start 296.49166 -93.115384)
		(end 296.082212 -93.2053)
		(width 0.1397)
		(layer "In9.Cu")
		(net "PCIE_COMP_B_TO_IOM_B_12_DN")
	)
	(segment
		(start 267.864336 -68.535042)
		(end 267.956792 -68.126356)
		(width 0.1397)
		(layer "In9.Cu")
		(net "PCIE_COMP_B_TO_IOM_B_12_DN")
	)
	(segment
		(start 267.87729 -69.111114)
		(end 267.969746 -68.702174)
		(width 0.1397)
		(layer "In9.Cu")
		(net "PCIE_COMP_B_TO_IOM_B_12_DN")
	)
	(segment
		(start 270.234664 -85.150706)
		(end 270.143986 -84.741766)
		(width 0.1397)
		(layer "In9.Cu")
		(net "PCIE_COMP_B_TO_IOM_B_12_DN")
	)
	(segment
		(start 267.617702 -69.62521)
		(end 267.710158 -69.216524)
		(width 0.1397)
		(layer "In9.Cu")
		(net "PCIE_COMP_B_TO_IOM_B_12_DN")
	)
	(segment
		(start 279.275032 -39.346124)
		(end 280.27503 -40.346122)
		(width 0.1397)
		(layer "In9.Cu")
		(net "PCIE_COMP_B_TO_IOM_B_12_DN")
	)
	(segment
		(start 284.754574 -95.54718)
		(end 284.345126 -95.637096)
		(width 0.1397)
		(layer "In9.Cu")
		(net "PCIE_COMP_B_TO_IOM_B_12_DN")
	)
	(segment
		(start 296.598086 -92.949014)
		(end 296.49166 -93.115384)
		(width 0.1397)
		(layer "In9.Cu")
		(net "PCIE_COMP_B_TO_IOM_B_12_DN")
	)
	(segment
		(start 280.27503 -40.346122)
		(end 283.585666 -40.346122)
		(width 0.1397)
		(layer "In9.Cu")
		(net "PCIE_COMP_B_TO_IOM_B_12_DN")
	)
	(segment
		(start 268.21638 -67.61226)
		(end 268.11097 -67.445128)
		(width 0.1397)
		(layer "In9.Cu")
		(net "PCIE_COMP_B_TO_IOM_B_12_DN")
	)
	(segment
		(start 343.730326 -68.477384)
		(end 314.120276 -89.248488)
		(width 0.1397)
		(layer "In9.Cu")
		(net "PCIE_COMP_B_TO_IOM_B_12_DN")
	)
	(segment
		(start 278.006302 -39.346124)
		(end 279.275032 -39.346124)
		(width 0.1397)
		(layer "In9.Cu")
		(net "PCIE_COMP_B_TO_IOM_B_12_DN")
	)
	(segment
		(start 277.839678 -94.729554)
		(end 273.98345 -92.177108)
		(width 0.1397)
		(layer "In9.Cu")
		(net "PCIE_COMP_B_TO_IOM_B_12_DN")
	)
	(segment
		(start 267.723112 -69.792342)
		(end 267.617702 -69.62521)
		(width 0.1397)
		(layer "In9.Cu")
		(net "PCIE_COMP_B_TO_IOM_B_12_DN")
	)
	(segment
		(start 382.187196 -19.249136)
		(end 382.202944 -19.233388)
		(width 0.1397)
		(layer "In9.Cu")
		(net "PCIE_COMP_B_TO_IOM_B_12_DN")
	)
	(segment
		(start 297.173904 -92.965778)
		(end 297.007534 -92.859352)
		(width 0.1397)
		(layer "In9.Cu")
		(net "PCIE_COMP_B_TO_IOM_B_12_DN")
	)
	(segment
		(start 284.920944 -95.65386)
		(end 284.754574 -95.54718)
		(width 0.1397)
		(layer "In9.Cu")
		(net "PCIE_COMP_B_TO_IOM_B_12_DN")
	)
	(segment
		(start 269.965424 -84.62772)
		(end 269.874746 -84.218526)
		(width 0.1397)
		(layer "In9.Cu")
		(net "PCIE_COMP_B_TO_IOM_B_12_DN")
	)
	(segment
		(start 284.505654 -39.827962)
		(end 285.249874 -40.200072)
		(width 0.1397)
		(layer "In9.Cu")
		(net "PCIE_COMP_B_TO_IOM_B_12_DN")
	)
	(segment
		(start 297.007534 -92.859352)
		(end 296.598086 -92.949014)
		(width 0.1397)
		(layer "In9.Cu")
		(net "PCIE_COMP_B_TO_IOM_B_12_DN")
	)
	(segment
		(start 286.42183 -95.324422)
		(end 286.012636 -95.414338)
		(width 0.1397)
		(layer "In9.Cu")
		(net "PCIE_COMP_B_TO_IOM_B_12_DN")
	)
	(segment
		(start 269.473172 -82.405728)
		(end 267.124434 -71.805292)
		(width 0.1397)
		(layer "In9.Cu")
		(net "PCIE_COMP_B_TO_IOM_B_12_DN")
	)
	(segment
		(start 382.150112 -19.750024)
		(end 382.150112 -19.338798)
		(width 0.1397)
		(layer "In9.Cu")
		(net "PCIE_COMP_B_TO_IOM_B_12_DN")
	)
	(segment
		(start 283.456888 -95.974916)
		(end 277.839678 -94.729554)
		(width 0.1397)
		(layer "In9.Cu")
		(net "PCIE_COMP_B_TO_IOM_B_12_DN")
	)
	(segment
		(start 267.956792 -68.126356)
		(end 268.123924 -68.020946)
		(width 0.1397)
		(layer "In9.Cu")
		(net "PCIE_COMP_B_TO_IOM_B_12_DN")
	)
	(segment
		(start 285.330138 -95.563944)
		(end 284.920944 -95.65386)
		(width 0.1397)
		(layer "In9.Cu")
		(net "PCIE_COMP_B_TO_IOM_B_12_DN")
	)
	(segment
		(start 270.21155 -85.738716)
		(end 270.120872 -85.329522)
		(width 0.1397)
		(layer "In9.Cu")
		(net "PCIE_COMP_B_TO_IOM_B_12_DN")
	)
	(segment
		(start 284.2387 -95.803466)
		(end 283.456888 -95.974916)
		(width 0.1397)
		(layer "In9.Cu")
		(net "PCIE_COMP_B_TO_IOM_B_12_DN")
	)
	(segment
		(start 267.124434 -71.805292)
		(end 267.21689 -71.396606)
		(width 0.1397)
		(layer "In9.Cu")
		(net "PCIE_COMP_B_TO_IOM_B_12_DN")
	)
	(segment
		(start 270.366998 -86.440518)
		(end 270.48079 -86.261702)
		(width 0.1397)
		(layer "In9.Cu")
		(net "PCIE_COMP_B_TO_IOM_B_12_DN")
	)
	(segment
		(start 373.340376 -47.70628)
		(end 343.730326 -68.47713)
		(width 0.1397)
		(layer "In9.Cu")
		(net "PCIE_COMP_B_TO_IOM_B_12_DN")
	)
	(segment
		(start 295.915842 -93.098874)
		(end 295.506394 -93.188536)
		(width 0.1397)
		(layer "In9.Cu")
		(net "PCIE_COMP_B_TO_IOM_B_12_DN")
	)
	(segment
		(start 285.846012 -95.307658)
		(end 285.436818 -95.397574)
		(width 0.1397)
		(layer "In9.Cu")
		(net "PCIE_COMP_B_TO_IOM_B_12_DN")
	)
	(segment
		(start 272.99285 -45.866304)
		(end 276.800564 -40.11422)
		(width 0.1397)
		(layer "In9.Cu")
		(net "PCIE_COMP_B_TO_IOM_B_12_DN")
	)
	(segment
		(start 276.800564 -40.11422)
		(end 278.006302 -39.346124)
		(width 0.1397)
		(layer "In9.Cu")
		(net "PCIE_COMP_B_TO_IOM_B_12_DN")
	)
	(segment
		(start 267.710158 -69.216524)
		(end 267.87729 -69.111114)
		(width 0.1397)
		(layer "In9.Cu")
		(net "PCIE_COMP_B_TO_IOM_B_12_DN")
	)
	(segment
		(start 270.457676 -86.849712)
		(end 270.366998 -86.440518)
		(width 0.1397)
		(layer "In9.Cu")
		(net "PCIE_COMP_B_TO_IOM_B_12_DN")
	)
	(segment
		(start 267.969746 -68.702174)
		(end 267.864336 -68.535042)
		(width 0.1397)
		(layer "In9.Cu")
		(net "PCIE_COMP_B_TO_IOM_B_12_DN")
	)
	(segment
		(start 267.463524 -70.306438)
		(end 267.630656 -70.201028)
		(width 0.1397)
		(layer "In9.Cu")
		(net "PCIE_COMP_B_TO_IOM_B_12_DN")
	)
	(segment
		(start 267.630656 -70.201028)
		(end 267.723112 -69.792342)
		(width 0.1397)
		(layer "In9.Cu")
		(net "PCIE_COMP_B_TO_IOM_B_12_DN")
	)
	(segment
		(start 343.730326 -68.47713)
		(end 343.730326 -68.477384)
		(width 0.1397)
		(layer "In9.Cu")
		(net "PCIE_COMP_B_TO_IOM_B_12_DN")
	)
	(segment
		(start 267.476478 -70.882256)
		(end 267.371068 -70.715124)
		(width 0.1397)
		(layer "In9.Cu")
		(net "PCIE_COMP_B_TO_IOM_B_12_DN")
	)
	(segment
		(start 269.89786 -83.63077)
		(end 269.719298 -83.516724)
		(width 0.1397)
		(layer "In9.Cu")
		(net "PCIE_COMP_B_TO_IOM_B_12_DN")
	)
	(segment
		(start 268.123924 -68.020946)
		(end 268.21638 -67.61226)
		(width 0.1397)
		(layer "In9.Cu")
		(net "PCIE_COMP_B_TO_IOM_B_12_DN")
	)
	(arc
		(start 382.150112 -19.338798)
		(mid 382.159745 -19.29028)
		(end 382.187196 -19.249136)
		(width 0.1397)
		(layer "In9.Cu")
		(net "PCIE_COMP_B_TO_IOM_B_12_DN")
	)
	(arc
		(start 382.8669 -19.300444)
		(mid 382.894333 -19.341595)
		(end 382.903984 -19.390106)
		(width 0.1397)
		(layer "In9.Cu")
		(net "PCIE_COMP_B_TO_IOM_B_12_DN")
	)
	(arc
		(start 284.318202 -39.890446)
		(mid 284.398987 -39.820381)
		(end 284.505654 -39.827962)
		(width 0.1397)
		(layer "In9.Cu")
		(net "PCIE_COMP_B_TO_IOM_B_12_DN")
	)
	(arc
		(start 382.202944 -19.233388)
		(mid 382.244095 -19.205955)
		(end 382.292606 -19.196304)
		(width 0.1397)
		(layer "In9.Cu")
		(net "PCIE_COMP_B_TO_IOM_B_12_DN")
	)
	(arc
		(start 283.585666 -40.346122)
		(mid 283.942542 -40.269642)
		(end 284.236668 -40.053514)
		(width 0.1397)
		(layer "In9.Cu")
		(net "PCIE_COMP_B_TO_IOM_B_12_DN")
	)
	(arc
		(start 382.710182 -19.196304)
		(mid 382.7587 -19.205937)
		(end 382.799844 -19.233388)
		(width 0.1397)
		(layer "In9.Cu")
		(net "PCIE_COMP_B_TO_IOM_B_12_DN")
	)
	(segment
		(start 281.780488 -186.888882)
		(end 279.823672 -186.262772)
		(width 0.1397)
		(layer "In9.Cu")
		(net "PCIE_COMP_B_TO_IOM_B_11_DP")
	)
	(segment
		(start 384.09245 -17.903952)
		(end 384.092704 -17.904206)
		(width 0.1397)
		(layer "In9.Cu")
		(net "PCIE_COMP_B_TO_IOM_B_11_DP")
	)
	(segment
		(start 369.321588 -63.156338)
		(end 285.968186 -184.398666)
		(width 0.1397)
		(layer "In9.Cu")
		(net "PCIE_COMP_B_TO_IOM_B_11_DP")
	)
	(segment
		(start 277.70201 -184.557416)
		(end 277.203408 -182.66791)
		(width 0.1397)
		(layer "In9.Cu")
		(net "PCIE_COMP_B_TO_IOM_B_11_DP")
	)
	(segment
		(start 279.823672 -186.262772)
		(end 277.70201 -184.557416)
		(width 0.1397)
		(layer "In9.Cu")
		(net "PCIE_COMP_B_TO_IOM_B_11_DP")
	)
	(segment
		(start 377.292362 -44.513754)
		(end 369.321588 -63.156338)
		(width 0.1397)
		(layer "In9.Cu")
		(net "PCIE_COMP_B_TO_IOM_B_11_DP")
	)
	(segment
		(start 283.591508 -186.309508)
		(end 281.780488 -186.888882)
		(width 0.1397)
		(layer "In9.Cu")
		(net "PCIE_COMP_B_TO_IOM_B_11_DP")
	)
	(segment
		(start 384.092704 -17.904206)
		(end 384.510026 -17.904206)
		(width 0.1397)
		(layer "In9.Cu")
		(net "PCIE_COMP_B_TO_IOM_B_11_DP")
	)
	(segment
		(start 383.949956 -17.349978)
		(end 383.949956 -17.761458)
		(width 0.1397)
		(layer "In9.Cu")
		(net "PCIE_COMP_B_TO_IOM_B_11_DP")
	)
	(segment
		(start 283.994352 -179.872132)
		(end 283.249878 -179.499768)
		(width 0.1397)
		(layer "In9.Cu")
		(net "PCIE_COMP_B_TO_IOM_B_11_DP")
	)
	(segment
		(start 383.98704 -17.85112)
		(end 384.002788 -17.866868)
		(width 0.1397)
		(layer "In9.Cu")
		(net "PCIE_COMP_B_TO_IOM_B_11_DP")
	)
	(segment
		(start 384.995928 -33.386776)
		(end 377.292362 -44.513754)
		(width 0.1397)
		(layer "In9.Cu")
		(net "PCIE_COMP_B_TO_IOM_B_11_DP")
	)
	(segment
		(start 280.139394 -180.353716)
		(end 283.58592 -180.353716)
		(width 0.1397)
		(layer "In9.Cu")
		(net "PCIE_COMP_B_TO_IOM_B_11_DP")
	)
	(segment
		(start 384.995928 -18.390108)
		(end 384.995928 -33.386776)
		(width 0.1397)
		(layer "In9.Cu")
		(net "PCIE_COMP_B_TO_IOM_B_11_DP")
	)
	(segment
		(start 277.203408 -182.66791)
		(end 277.55723 -181.826408)
		(width 0.1397)
		(layer "In9.Cu")
		(net "PCIE_COMP_B_TO_IOM_B_11_DP")
	)
	(segment
		(start 283.994352 -180.184552)
		(end 284.056836 -180.059584)
		(width 0.1397)
		(layer "In9.Cu")
		(net "PCIE_COMP_B_TO_IOM_B_11_DP")
	)
	(segment
		(start 279.139142 -181.353968)
		(end 280.139394 -180.353716)
		(width 0.1397)
		(layer "In9.Cu")
		(net "PCIE_COMP_B_TO_IOM_B_11_DP")
	)
	(segment
		(start 278.314404 -181.353968)
		(end 279.139142 -181.353968)
		(width 0.1397)
		(layer "In9.Cu")
		(net "PCIE_COMP_B_TO_IOM_B_11_DP")
	)
	(segment
		(start 277.55723 -181.826408)
		(end 278.314404 -181.353968)
		(width 0.1397)
		(layer "In9.Cu")
		(net "PCIE_COMP_B_TO_IOM_B_11_DP")
	)
	(segment
		(start 384.806444 -18.026634)
		(end 384.8735 -18.093944)
		(width 0.1397)
		(layer "In9.Cu")
		(net "PCIE_COMP_B_TO_IOM_B_11_DP")
	)
	(segment
		(start 285.968186 -184.398666)
		(end 283.591508 -186.309508)
		(width 0.1397)
		(layer "In9.Cu")
		(net "PCIE_COMP_B_TO_IOM_B_11_DP")
	)
	(arc
		(start 384.002788 -17.866868)
		(mid 384.043939 -17.894301)
		(end 384.09245 -17.903952)
		(width 0.1397)
		(layer "In9.Cu")
		(net "PCIE_COMP_B_TO_IOM_B_11_DP")
	)
	(arc
		(start 284.056836 -180.059584)
		(mid 284.064417 -179.952917)
		(end 283.994352 -179.872132)
		(width 0.1397)
		(layer "In9.Cu")
		(net "PCIE_COMP_B_TO_IOM_B_11_DP")
	)
	(arc
		(start 283.58592 -180.353716)
		(mid 283.806956 -180.309749)
		(end 283.994352 -180.184552)
		(width 0.1397)
		(layer "In9.Cu")
		(net "PCIE_COMP_B_TO_IOM_B_11_DP")
	)
	(arc
		(start 383.949956 -17.761458)
		(mid 383.959589 -17.809976)
		(end 383.98704 -17.85112)
		(width 0.1397)
		(layer "In9.Cu")
		(net "PCIE_COMP_B_TO_IOM_B_11_DP")
	)
	(arc
		(start 384.510026 -17.904206)
		(mid 384.670379 -17.935991)
		(end 384.806444 -18.026634)
		(width 0.1397)
		(layer "In9.Cu")
		(net "PCIE_COMP_B_TO_IOM_B_11_DP")
	)
	(arc
		(start 384.8735 -18.093944)
		(mid 384.964103 -18.229869)
		(end 384.995928 -18.390108)
		(width 0.1397)
		(layer "In9.Cu")
		(net "PCIE_COMP_B_TO_IOM_B_11_DP")
	)
	(segment
		(start 285.751778 -184.197752)
		(end 283.450792 -186.047634)
		(width 0.1397)
		(layer "In9.Cu")
		(net "PCIE_COMP_B_TO_IOM_B_11_DN")
	)
	(segment
		(start 296.935906 -167.92956)
		(end 296.727372 -167.968168)
		(width 0.1397)
		(layer "In9.Cu")
		(net "PCIE_COMP_B_TO_IOM_B_11_DN")
	)
	(segment
		(start 377.035314 -44.371768)
		(end 369.064286 -63.014606)
		(width 0.1397)
		(layer "In9.Cu")
		(net "PCIE_COMP_B_TO_IOM_B_11_DN")
	)
	(segment
		(start 304.999898 -156.19984)
		(end 304.805588 -156.235908)
		(width 0.1397)
		(layer "In9.Cu")
		(net "PCIE_COMP_B_TO_IOM_B_11_DN")
	)
	(segment
		(start 303.971198 -157.696408)
		(end 298.22521 -166.054278)
		(width 0.1397)
		(layer "In9.Cu")
		(net "PCIE_COMP_B_TO_IOM_B_11_DN")
	)
	(segment
		(start 312.229246 -145.437606)
		(end 312.265314 -145.631916)
		(width 0.1397)
		(layer "In9.Cu")
		(net "PCIE_COMP_B_TO_IOM_B_11_DN")
	)
	(segment
		(start 280.260552 -180.645816)
		(end 283.585666 -180.645816)
		(width 0.1397)
		(layer "In9.Cu")
		(net "PCIE_COMP_B_TO_IOM_B_11_DN")
	)
	(segment
		(start 279.017984 -181.646068)
		(end 279.018238 -181.646322)
		(width 0.1397)
		(layer "In9.Cu")
		(net "PCIE_COMP_B_TO_IOM_B_11_DN")
	)
	(segment
		(start 304.36693 -157.120844)
		(end 304.17262 -157.156912)
		(width 0.1397)
		(layer "In9.Cu")
		(net "PCIE_COMP_B_TO_IOM_B_11_DN")
	)
	(segment
		(start 384.703828 -18.390108)
		(end 384.703828 -33.295336)
		(width 0.1397)
		(layer "In9.Cu")
		(net "PCIE_COMP_B_TO_IOM_B_11_DN")
	)
	(segment
		(start 284.505654 -180.127656)
		(end 285.249874 -180.499766)
		(width 0.1397)
		(layer "In9.Cu")
		(net "PCIE_COMP_B_TO_IOM_B_11_DN")
	)
	(segment
		(start 288.424874 -180.30952)
		(end 285.751778 -184.197752)
		(width 0.1397)
		(layer "In9.Cu")
		(net "PCIE_COMP_B_TO_IOM_B_11_DN")
	)
	(segment
		(start 304.604166 -156.775404)
		(end 304.36693 -157.120844)
		(width 0.1397)
		(layer "In9.Cu")
		(net "PCIE_COMP_B_TO_IOM_B_11_DN")
	)
	(segment
		(start 288.626296 -179.770024)
		(end 288.388806 -180.11521)
		(width 0.1397)
		(layer "In9.Cu")
		(net "PCIE_COMP_B_TO_IOM_B_11_DN")
	)
	(segment
		(start 289.453828 -178.812952)
		(end 289.259518 -178.84902)
		(width 0.1397)
		(layer "In9.Cu")
		(net "PCIE_COMP_B_TO_IOM_B_11_DN")
	)
	(segment
		(start 297.77944 -166.438072)
		(end 297.818048 -166.646606)
		(width 0.1397)
		(layer "In9.Cu")
		(net "PCIE_COMP_B_TO_IOM_B_11_DN")
	)
	(segment
		(start 297.134788 -167.37584)
		(end 297.173396 -167.584374)
		(width 0.1397)
		(layer "In9.Cu")
		(net "PCIE_COMP_B_TO_IOM_B_11_DN")
	)
	(segment
		(start 289.022028 -179.19446)
		(end 289.058096 -179.388516)
		(width 0.1397)
		(layer "In9.Cu")
		(net "PCIE_COMP_B_TO_IOM_B_11_DN")
	)
	(segment
		(start 305.20132 -155.660344)
		(end 305.237388 -155.854654)
		(width 0.1397)
		(layer "In9.Cu")
		(net "PCIE_COMP_B_TO_IOM_B_11_DN")
	)
	(segment
		(start 383.98704 -18.249138)
		(end 384.002788 -18.23339)
		(width 0.1397)
		(layer "In9.Cu")
		(net "PCIE_COMP_B_TO_IOM_B_11_DN")
	)
	(segment
		(start 290.525708 -177.007012)
		(end 290.288218 -177.352452)
		(width 0.1397)
		(layer "In9.Cu")
		(net "PCIE_COMP_B_TO_IOM_B_11_DN")
	)
	(segment
		(start 277.511256 -182.6895)
		(end 277.790656 -182.02529)
		(width 0.1397)
		(layer "In9.Cu")
		(net "PCIE_COMP_B_TO_IOM_B_11_DN")
	)
	(segment
		(start 288.820606 -179.733956)
		(end 288.626296 -179.770024)
		(width 0.1397)
		(layer "In9.Cu")
		(net "PCIE_COMP_B_TO_IOM_B_11_DN")
	)
	(segment
		(start 384.09245 -18.196306)
		(end 384.510026 -18.196306)
		(width 0.1397)
		(layer "In9.Cu")
		(net "PCIE_COMP_B_TO_IOM_B_11_DN")
	)
	(segment
		(start 289.259518 -178.84902)
		(end 289.022028 -179.19446)
		(width 0.1397)
		(layer "In9.Cu")
		(net "PCIE_COMP_B_TO_IOM_B_11_DN")
	)
	(segment
		(start 290.720018 -176.971198)
		(end 290.525708 -177.007012)
		(width 0.1397)
		(layer "In9.Cu")
		(net "PCIE_COMP_B_TO_IOM_B_11_DN")
	)
	(segment
		(start 296.490136 -168.313608)
		(end 296.528744 -168.521888)
		(width 0.1397)
		(layer "In9.Cu")
		(net "PCIE_COMP_B_TO_IOM_B_11_DN")
	)
	(segment
		(start 289.058096 -179.388516)
		(end 288.820606 -179.733956)
		(width 0.1397)
		(layer "In9.Cu")
		(net "PCIE_COMP_B_TO_IOM_B_11_DN")
	)
	(segment
		(start 298.22521 -166.054278)
		(end 298.01693 -166.092886)
		(width 0.1397)
		(layer "In9.Cu")
		(net "PCIE_COMP_B_TO_IOM_B_11_DN")
	)
	(segment
		(start 284.236668 -180.353208)
		(end 284.318202 -180.19014)
		(width 0.1397)
		(layer "In9.Cu")
		(net "PCIE_COMP_B_TO_IOM_B_11_DN")
	)
	(segment
		(start 305.63312 -155.278836)
		(end 305.43881 -155.314904)
		(width 0.1397)
		(layer "In9.Cu")
		(net "PCIE_COMP_B_TO_IOM_B_11_DN")
	)
	(segment
		(start 304.805588 -156.235908)
		(end 304.568352 -156.581348)
		(width 0.1397)
		(layer "In9.Cu")
		(net "PCIE_COMP_B_TO_IOM_B_11_DN")
	)
	(segment
		(start 279.964388 -186.000898)
		(end 277.960074 -184.389776)
		(width 0.1397)
		(layer "In9.Cu")
		(net "PCIE_COMP_B_TO_IOM_B_11_DN")
	)
	(segment
		(start 281.780488 -186.58205)
		(end 279.964388 -186.000898)
		(width 0.1397)
		(layer "In9.Cu")
		(net "PCIE_COMP_B_TO_IOM_B_11_DN")
	)
	(segment
		(start 290.288218 -177.352452)
		(end 290.324286 -177.546762)
		(width 0.1397)
		(layer "In9.Cu")
		(net "PCIE_COMP_B_TO_IOM_B_11_DN")
	)
	(segment
		(start 277.960074 -184.389776)
		(end 277.511256 -182.6895)
		(width 0.1397)
		(layer "In9.Cu")
		(net "PCIE_COMP_B_TO_IOM_B_11_DN")
	)
	(segment
		(start 304.568352 -156.581348)
		(end 304.604166 -156.775404)
		(width 0.1397)
		(layer "In9.Cu")
		(net "PCIE_COMP_B_TO_IOM_B_11_DN")
	)
	(segment
		(start 295.845484 -169.251376)
		(end 295.884092 -169.459656)
		(width 0.1397)
		(layer "In9.Cu")
		(net "PCIE_COMP_B_TO_IOM_B_11_DN")
	)
	(segment
		(start 311.833514 -146.01317)
		(end 311.596278 -146.35861)
		(width 0.1397)
		(layer "In9.Cu")
		(net "PCIE_COMP_B_TO_IOM_B_11_DN")
	)
	(segment
		(start 290.086796 -177.891948)
		(end 289.892486 -177.928016)
		(width 0.1397)
		(layer "In9.Cu")
		(net "PCIE_COMP_B_TO_IOM_B_11_DN")
	)
	(segment
		(start 383.949956 -18.750026)
		(end 383.949956 -18.3388)
		(width 0.1397)
		(layer "In9.Cu")
		(net "PCIE_COMP_B_TO_IOM_B_11_DN")
	)
	(segment
		(start 312.265314 -145.631916)
		(end 312.027824 -145.977102)
		(width 0.1397)
		(layer "In9.Cu")
		(net "PCIE_COMP_B_TO_IOM_B_11_DN")
	)
	(segment
		(start 312.466736 -145.092166)
		(end 312.229246 -145.437606)
		(width 0.1397)
		(layer "In9.Cu")
		(net "PCIE_COMP_B_TO_IOM_B_11_DN")
	)
	(segment
		(start 296.727372 -167.968168)
		(end 296.490136 -168.313608)
		(width 0.1397)
		(layer "In9.Cu")
		(net "PCIE_COMP_B_TO_IOM_B_11_DN")
	)
	(segment
		(start 290.324286 -177.546762)
		(end 290.086796 -177.891948)
		(width 0.1397)
		(layer "In9.Cu")
		(net "PCIE_COMP_B_TO_IOM_B_11_DN")
	)
	(segment
		(start 277.790656 -182.02529)
		(end 278.398224 -181.646068)
		(width 0.1397)
		(layer "In9.Cu")
		(net "PCIE_COMP_B_TO_IOM_B_11_DN")
	)
	(segment
		(start 305.43881 -155.314904)
		(end 305.20132 -155.660344)
		(width 0.1397)
		(layer "In9.Cu")
		(net "PCIE_COMP_B_TO_IOM_B_11_DN")
	)
	(segment
		(start 312.661046 -145.056352)
		(end 312.466736 -145.092166)
		(width 0.1397)
		(layer "In9.Cu")
		(net "PCIE_COMP_B_TO_IOM_B_11_DN")
	)
	(segment
		(start 288.388806 -180.11521)
		(end 288.424874 -180.30952)
		(width 0.1397)
		(layer "In9.Cu")
		(net "PCIE_COMP_B_TO_IOM_B_11_DN")
	)
	(segment
		(start 298.01693 -166.092886)
		(end 297.77944 -166.438072)
		(width 0.1397)
		(layer "In9.Cu")
		(net "PCIE_COMP_B_TO_IOM_B_11_DN")
	)
	(segment
		(start 384.703828 -33.295336)
		(end 377.035314 -44.371768)
		(width 0.1397)
		(layer "In9.Cu")
		(net "PCIE_COMP_B_TO_IOM_B_11_DN")
	)
	(segment
		(start 289.892486 -177.928016)
		(end 289.65525 -178.273456)
		(width 0.1397)
		(layer "In9.Cu")
		(net "PCIE_COMP_B_TO_IOM_B_11_DN")
	)
	(segment
		(start 296.291254 -168.867328)
		(end 296.08272 -168.905936)
		(width 0.1397)
		(layer "In9.Cu")
		(net "PCIE_COMP_B_TO_IOM_B_11_DN")
	)
	(segment
		(start 296.528744 -168.521888)
		(end 296.291254 -168.867328)
		(width 0.1397)
		(layer "In9.Cu")
		(net "PCIE_COMP_B_TO_IOM_B_11_DN")
	)
	(segment
		(start 384.599688 -18.23339)
		(end 384.666744 -18.300446)
		(width 0.1397)
		(layer "In9.Cu")
		(net "PCIE_COMP_B_TO_IOM_B_11_DN")
	)
	(segment
		(start 283.450792 -186.047634)
		(end 281.780488 -186.58205)
		(width 0.1397)
		(layer "In9.Cu")
		(net "PCIE_COMP_B_TO_IOM_B_11_DN")
	)
	(segment
		(start 297.173396 -167.584374)
		(end 296.935906 -167.92956)
		(width 0.1397)
		(layer "In9.Cu")
		(net "PCIE_COMP_B_TO_IOM_B_11_DN")
	)
	(segment
		(start 305.237388 -155.854654)
		(end 304.999898 -156.19984)
		(width 0.1397)
		(layer "In9.Cu")
		(net "PCIE_COMP_B_TO_IOM_B_11_DN")
	)
	(segment
		(start 279.018238 -181.646322)
		(end 279.260046 -181.646322)
		(width 0.1397)
		(layer "In9.Cu")
		(net "PCIE_COMP_B_TO_IOM_B_11_DN")
	)
	(segment
		(start 304.17262 -157.156912)
		(end 303.93513 -157.502098)
		(width 0.1397)
		(layer "In9.Cu")
		(net "PCIE_COMP_B_TO_IOM_B_11_DN")
	)
	(segment
		(start 289.65525 -178.273456)
		(end 289.691064 -178.467766)
		(width 0.1397)
		(layer "In9.Cu")
		(net "PCIE_COMP_B_TO_IOM_B_11_DN")
	)
	(segment
		(start 278.398224 -181.646068)
		(end 279.017984 -181.646068)
		(width 0.1397)
		(layer "In9.Cu")
		(net "PCIE_COMP_B_TO_IOM_B_11_DN")
	)
	(segment
		(start 296.08272 -168.905936)
		(end 295.845484 -169.251376)
		(width 0.1397)
		(layer "In9.Cu")
		(net "PCIE_COMP_B_TO_IOM_B_11_DN")
	)
	(segment
		(start 295.884092 -169.459656)
		(end 290.720018 -176.971198)
		(width 0.1397)
		(layer "In9.Cu")
		(net "PCIE_COMP_B_TO_IOM_B_11_DN")
	)
	(segment
		(start 312.027824 -145.977102)
		(end 311.833514 -146.01317)
		(width 0.1397)
		(layer "In9.Cu")
		(net "PCIE_COMP_B_TO_IOM_B_11_DN")
	)
	(segment
		(start 369.064286 -63.014606)
		(end 312.661046 -145.056352)
		(width 0.1397)
		(layer "In9.Cu")
		(net "PCIE_COMP_B_TO_IOM_B_11_DN")
	)
	(segment
		(start 289.691064 -178.467766)
		(end 289.453828 -178.812952)
		(width 0.1397)
		(layer "In9.Cu")
		(net "PCIE_COMP_B_TO_IOM_B_11_DN")
	)
	(segment
		(start 311.596278 -146.35861)
		(end 311.632092 -146.55292)
		(width 0.1397)
		(layer "In9.Cu")
		(net "PCIE_COMP_B_TO_IOM_B_11_DN")
	)
	(segment
		(start 297.818048 -166.646606)
		(end 297.580558 -166.992046)
		(width 0.1397)
		(layer "In9.Cu")
		(net "PCIE_COMP_B_TO_IOM_B_11_DN")
	)
	(segment
		(start 297.580558 -166.992046)
		(end 297.372278 -167.030654)
		(width 0.1397)
		(layer "In9.Cu")
		(net "PCIE_COMP_B_TO_IOM_B_11_DN")
	)
	(segment
		(start 303.93513 -157.502098)
		(end 303.971198 -157.696408)
		(width 0.1397)
		(layer "In9.Cu")
		(net "PCIE_COMP_B_TO_IOM_B_11_DN")
	)
	(segment
		(start 311.632092 -146.55292)
		(end 305.63312 -155.278836)
		(width 0.1397)
		(layer "In9.Cu")
		(net "PCIE_COMP_B_TO_IOM_B_11_DN")
	)
	(segment
		(start 297.372278 -167.030654)
		(end 297.134788 -167.37584)
		(width 0.1397)
		(layer "In9.Cu")
		(net "PCIE_COMP_B_TO_IOM_B_11_DN")
	)
	(segment
		(start 279.260046 -181.646322)
		(end 280.260552 -180.645816)
		(width 0.1397)
		(layer "In9.Cu")
		(net "PCIE_COMP_B_TO_IOM_B_11_DN")
	)
	(arc
		(start 384.510026 -18.196306)
		(mid 384.558544 -18.205939)
		(end 384.599688 -18.23339)
		(width 0.1397)
		(layer "In9.Cu")
		(net "PCIE_COMP_B_TO_IOM_B_11_DN")
	)
	(arc
		(start 383.949956 -18.3388)
		(mid 383.959589 -18.290282)
		(end 383.98704 -18.249138)
		(width 0.1397)
		(layer "In9.Cu")
		(net "PCIE_COMP_B_TO_IOM_B_11_DN")
	)
	(arc
		(start 284.318202 -180.19014)
		(mid 284.398987 -180.120075)
		(end 284.505654 -180.127656)
		(width 0.1397)
		(layer "In9.Cu")
		(net "PCIE_COMP_B_TO_IOM_B_11_DN")
	)
	(arc
		(start 283.585666 -180.645816)
		(mid 283.942542 -180.569336)
		(end 284.236668 -180.353208)
		(width 0.1397)
		(layer "In9.Cu")
		(net "PCIE_COMP_B_TO_IOM_B_11_DN")
	)
	(arc
		(start 384.666744 -18.300446)
		(mid 384.694177 -18.341597)
		(end 384.703828 -18.390108)
		(width 0.1397)
		(layer "In9.Cu")
		(net "PCIE_COMP_B_TO_IOM_B_11_DN")
	)
	(arc
		(start 384.002788 -18.23339)
		(mid 384.043939 -18.205957)
		(end 384.09245 -18.196306)
		(width 0.1397)
		(layer "In9.Cu")
		(net "PCIE_COMP_B_TO_IOM_B_11_DN")
	)
	(segment
		(start 279.1206 -187.456826)
		(end 276.244812 -185.14314)
		(width 0.1397)
		(layer "In9.Cu")
		(net "PCIE_COMP_B_TO_IOM_B_10_DP")
	)
	(segment
		(start 378.726446 -45.017182)
		(end 370.657628 -63.890906)
		(width 0.1397)
		(layer "In9.Cu")
		(net "PCIE_COMP_B_TO_IOM_B_10_DP")
	)
	(segment
		(start 283.994352 -175.87214)
		(end 283.249878 -175.499776)
		(width 0.1397)
		(layer "In9.Cu")
		(net "PCIE_COMP_B_TO_IOM_B_10_DP")
	)
	(segment
		(start 276.244812 -185.14314)
		(end 275.30552 -181.583838)
		(width 0.1397)
		(layer "In9.Cu")
		(net "PCIE_COMP_B_TO_IOM_B_10_DP")
	)
	(segment
		(start 283.994352 -176.18456)
		(end 284.056836 -176.059592)
		(width 0.1397)
		(layer "In9.Cu")
		(net "PCIE_COMP_B_TO_IOM_B_10_DP")
	)
	(segment
		(start 385.892802 -18.904204)
		(end 386.310124 -18.904204)
		(width 0.1397)
		(layer "In9.Cu")
		(net "PCIE_COMP_B_TO_IOM_B_10_DP")
	)
	(segment
		(start 385.892548 -18.90395)
		(end 385.892802 -18.904204)
		(width 0.1397)
		(layer "In9.Cu")
		(net "PCIE_COMP_B_TO_IOM_B_10_DP")
	)
	(segment
		(start 370.657628 -63.890906)
		(end 287.320228 -184.998106)
		(width 0.1397)
		(layer "In9.Cu")
		(net "PCIE_COMP_B_TO_IOM_B_10_DP")
	)
	(segment
		(start 386.796026 -19.390106)
		(end 386.796026 -33.357058)
		(width 0.1397)
		(layer "In9.Cu")
		(net "PCIE_COMP_B_TO_IOM_B_10_DP")
	)
	(segment
		(start 385.787138 -18.851118)
		(end 385.802886 -18.866866)
		(width 0.1397)
		(layer "In9.Cu")
		(net "PCIE_COMP_B_TO_IOM_B_10_DP")
	)
	(segment
		(start 276.077934 -177.950622)
		(end 277.435818 -175.858424)
		(width 0.1397)
		(layer "In9.Cu")
		(net "PCIE_COMP_B_TO_IOM_B_10_DP")
	)
	(segment
		(start 386.606542 -19.026632)
		(end 386.673598 -19.093942)
		(width 0.1397)
		(layer "In9.Cu")
		(net "PCIE_COMP_B_TO_IOM_B_10_DP")
	)
	(segment
		(start 278.21382 -175.353726)
		(end 279.265126 -175.353726)
		(width 0.1397)
		(layer "In9.Cu")
		(net "PCIE_COMP_B_TO_IOM_B_10_DP")
	)
	(segment
		(start 277.435818 -175.858424)
		(end 278.21382 -175.353726)
		(width 0.1397)
		(layer "In9.Cu")
		(net "PCIE_COMP_B_TO_IOM_B_10_DP")
	)
	(segment
		(start 279.265126 -175.353726)
		(end 280.265124 -176.353724)
		(width 0.1397)
		(layer "In9.Cu")
		(net "PCIE_COMP_B_TO_IOM_B_10_DP")
	)
	(segment
		(start 386.796026 -33.357058)
		(end 378.726446 -45.017182)
		(width 0.1397)
		(layer "In9.Cu")
		(net "PCIE_COMP_B_TO_IOM_B_10_DP")
	)
	(segment
		(start 385.750054 -18.35023)
		(end 385.750054 -18.761456)
		(width 0.1397)
		(layer "In9.Cu")
		(net "PCIE_COMP_B_TO_IOM_B_10_DP")
	)
	(segment
		(start 280.265124 -176.353724)
		(end 283.58592 -176.353724)
		(width 0.1397)
		(layer "In9.Cu")
		(net "PCIE_COMP_B_TO_IOM_B_10_DP")
	)
	(segment
		(start 275.30552 -181.583838)
		(end 276.077934 -177.950622)
		(width 0.1397)
		(layer "In9.Cu")
		(net "PCIE_COMP_B_TO_IOM_B_10_DP")
	)
	(segment
		(start 287.318958 -184.998106)
		(end 284.137354 -187.557156)
		(width 0.1397)
		(layer "In9.Cu")
		(net "PCIE_COMP_B_TO_IOM_B_10_DP")
	)
	(segment
		(start 284.137354 -187.557156)
		(end 281.784298 -188.30798)
		(width 0.1397)
		(layer "In9.Cu")
		(net "PCIE_COMP_B_TO_IOM_B_10_DP")
	)
	(segment
		(start 287.320228 -184.998106)
		(end 287.318958 -184.998106)
		(width 0.1397)
		(layer "In9.Cu")
		(net "PCIE_COMP_B_TO_IOM_B_10_DP")
	)
	(segment
		(start 281.784298 -188.30798)
		(end 279.1206 -187.456826)
		(width 0.1397)
		(layer "In9.Cu")
		(net "PCIE_COMP_B_TO_IOM_B_10_DP")
	)
	(arc
		(start 386.673598 -19.093942)
		(mid 386.764201 -19.229867)
		(end 386.796026 -19.390106)
		(width 0.1397)
		(layer "In9.Cu")
		(net "PCIE_COMP_B_TO_IOM_B_10_DP")
	)
	(arc
		(start 386.310124 -18.904204)
		(mid 386.470477 -18.935989)
		(end 386.606542 -19.026632)
		(width 0.1397)
		(layer "In9.Cu")
		(net "PCIE_COMP_B_TO_IOM_B_10_DP")
	)
	(arc
		(start 385.750054 -18.761456)
		(mid 385.759687 -18.809974)
		(end 385.787138 -18.851118)
		(width 0.1397)
		(layer "In9.Cu")
		(net "PCIE_COMP_B_TO_IOM_B_10_DP")
	)
	(arc
		(start 283.58592 -176.353724)
		(mid 283.806956 -176.309757)
		(end 283.994352 -176.18456)
		(width 0.1397)
		(layer "In9.Cu")
		(net "PCIE_COMP_B_TO_IOM_B_10_DP")
	)
	(arc
		(start 284.056836 -176.059592)
		(mid 284.064417 -175.952925)
		(end 283.994352 -175.87214)
		(width 0.1397)
		(layer "In9.Cu")
		(net "PCIE_COMP_B_TO_IOM_B_10_DP")
	)
	(arc
		(start 385.802886 -18.866866)
		(mid 385.844037 -18.894299)
		(end 385.892548 -18.90395)
		(width 0.1397)
		(layer "In9.Cu")
		(net "PCIE_COMP_B_TO_IOM_B_10_DP")
	)
	(segment
		(start 276.352508 -178.06416)
		(end 277.647146 -176.069752)
		(width 0.1397)
		(layer "In9.Cu")
		(net "PCIE_COMP_B_TO_IOM_B_10_DN")
	)
	(segment
		(start 275.605748 -181.576472)
		(end 276.352508 -178.06416)
		(width 0.1397)
		(layer "In9.Cu")
		(net "PCIE_COMP_B_TO_IOM_B_10_DN")
	)
	(segment
		(start 299.47489 -166.817548)
		(end 299.26661 -166.855902)
		(width 0.1397)
		(layer "In9.Cu")
		(net "PCIE_COMP_B_TO_IOM_B_10_DN")
	)
	(segment
		(start 280.143966 -176.645824)
		(end 283.585666 -176.645824)
		(width 0.1397)
		(layer "In9.Cu")
		(net "PCIE_COMP_B_TO_IOM_B_10_DN")
	)
	(segment
		(start 305.132994 -158.595568)
		(end 299.47489 -166.817548)
		(width 0.1397)
		(layer "In9.Cu")
		(net "PCIE_COMP_B_TO_IOM_B_10_DN")
	)
	(segment
		(start 385.787138 -19.249136)
		(end 385.802886 -19.233388)
		(width 0.1397)
		(layer "In9.Cu")
		(net "PCIE_COMP_B_TO_IOM_B_10_DN")
	)
	(segment
		(start 288.968434 -182.085742)
		(end 288.774124 -182.121556)
		(width 0.1397)
		(layer "In9.Cu")
		(net "PCIE_COMP_B_TO_IOM_B_10_DN")
	)
	(segment
		(start 306.795932 -156.178758)
		(end 306.601876 -156.214572)
		(width 0.1397)
		(layer "In9.Cu")
		(net "PCIE_COMP_B_TO_IOM_B_10_DN")
	)
	(segment
		(start 283.996638 -187.295282)
		(end 281.784298 -188.001148)
		(width 0.1397)
		(layer "In9.Cu")
		(net "PCIE_COMP_B_TO_IOM_B_10_DN")
	)
	(segment
		(start 313.97829 -145.74139)
		(end 313.784234 -145.777458)
		(width 0.1397)
		(layer "In9.Cu")
		(net "PCIE_COMP_B_TO_IOM_B_10_DN")
	)
	(segment
		(start 298.422314 -168.347136)
		(end 298.184824 -168.692322)
		(width 0.1397)
		(layer "In9.Cu")
		(net "PCIE_COMP_B_TO_IOM_B_10_DN")
	)
	(segment
		(start 290.041076 -180.28031)
		(end 289.803586 -180.625496)
		(width 0.1397)
		(layer "In9.Cu")
		(net "PCIE_COMP_B_TO_IOM_B_10_DN")
	)
	(segment
		(start 298.184824 -168.692322)
		(end 297.97629 -168.73093)
		(width 0.1397)
		(layer "In9.Cu")
		(net "PCIE_COMP_B_TO_IOM_B_10_DN")
	)
	(segment
		(start 313.54649 -146.122644)
		(end 313.582304 -146.316954)
		(width 0.1397)
		(layer "In9.Cu")
		(net "PCIE_COMP_B_TO_IOM_B_10_DN")
	)
	(segment
		(start 288.572448 -182.661052)
		(end 288.334958 -183.006238)
		(width 0.1397)
		(layer "In9.Cu")
		(net "PCIE_COMP_B_TO_IOM_B_10_DN")
	)
	(segment
		(start 386.399786 -19.233388)
		(end 386.466842 -19.300444)
		(width 0.1397)
		(layer "In9.Cu")
		(net "PCIE_COMP_B_TO_IOM_B_10_DN")
	)
	(segment
		(start 287.938972 -183.581802)
		(end 287.10255 -184.797192)
		(width 0.1397)
		(layer "In9.Cu")
		(net "PCIE_COMP_B_TO_IOM_B_10_DN")
	)
	(segment
		(start 305.730656 -157.480508)
		(end 305.76647 -157.674818)
		(width 0.1397)
		(layer "In9.Cu")
		(net "PCIE_COMP_B_TO_IOM_B_10_DN")
	)
	(segment
		(start 305.52898 -158.020004)
		(end 305.33467 -158.056072)
		(width 0.1397)
		(layer "In9.Cu")
		(net "PCIE_COMP_B_TO_IOM_B_10_DN")
	)
	(segment
		(start 288.774124 -182.121556)
		(end 288.536634 -182.466742)
		(width 0.1397)
		(layer "In9.Cu")
		(net "PCIE_COMP_B_TO_IOM_B_10_DN")
	)
	(segment
		(start 279.143968 -175.645826)
		(end 280.143966 -176.645824)
		(width 0.1397)
		(layer "In9.Cu")
		(net "PCIE_COMP_B_TO_IOM_B_10_DN")
	)
	(segment
		(start 297.539664 -169.629836)
		(end 297.331384 -169.66819)
		(width 0.1397)
		(layer "In9.Cu")
		(net "PCIE_COMP_B_TO_IOM_B_10_DN")
	)
	(segment
		(start 290.235386 -180.244242)
		(end 290.041076 -180.28031)
		(width 0.1397)
		(layer "In9.Cu")
		(net "PCIE_COMP_B_TO_IOM_B_10_DN")
	)
	(segment
		(start 289.803586 -180.625496)
		(end 289.8394 -180.819806)
		(width 0.1397)
		(layer "In9.Cu")
		(net "PCIE_COMP_B_TO_IOM_B_10_DN")
	)
	(segment
		(start 284.236668 -176.353216)
		(end 284.318202 -176.190148)
		(width 0.1397)
		(layer "In9.Cu")
		(net "PCIE_COMP_B_TO_IOM_B_10_DN")
	)
	(segment
		(start 284.505654 -176.127664)
		(end 285.249874 -176.499774)
		(width 0.1397)
		(layer "In9.Cu")
		(net "PCIE_COMP_B_TO_IOM_B_10_DN")
	)
	(segment
		(start 279.26157 -187.194952)
		(end 276.502876 -184.9755)
		(width 0.1397)
		(layer "In9.Cu")
		(net "PCIE_COMP_B_TO_IOM_B_10_DN")
	)
	(segment
		(start 306.601876 -156.214572)
		(end 306.364132 -156.559758)
		(width 0.1397)
		(layer "In9.Cu")
		(net "PCIE_COMP_B_TO_IOM_B_10_DN")
	)
	(segment
		(start 306.162456 -157.099508)
		(end 305.968146 -157.135322)
		(width 0.1397)
		(layer "In9.Cu")
		(net "PCIE_COMP_B_TO_IOM_B_10_DN")
	)
	(segment
		(start 386.503926 -33.265618)
		(end 378.469398 -44.875196)
		(width 0.1397)
		(layer "In9.Cu")
		(net "PCIE_COMP_B_TO_IOM_B_10_DN")
	)
	(segment
		(start 299.26661 -166.855902)
		(end 299.028866 -167.201342)
		(width 0.1397)
		(layer "In9.Cu")
		(net "PCIE_COMP_B_TO_IOM_B_10_DN")
	)
	(segment
		(start 313.784234 -145.777458)
		(end 313.54649 -146.122644)
		(width 0.1397)
		(layer "In9.Cu")
		(net "PCIE_COMP_B_TO_IOM_B_10_DN")
	)
	(segment
		(start 298.62145 -167.793416)
		(end 298.38396 -168.138602)
		(width 0.1397)
		(layer "In9.Cu")
		(net "PCIE_COMP_B_TO_IOM_B_10_DN")
	)
	(segment
		(start 288.536634 -182.466742)
		(end 288.572448 -182.661052)
		(width 0.1397)
		(layer "In9.Cu")
		(net "PCIE_COMP_B_TO_IOM_B_10_DN")
	)
	(segment
		(start 277.647146 -176.069752)
		(end 278.300434 -175.645826)
		(width 0.1397)
		(layer "In9.Cu")
		(net "PCIE_COMP_B_TO_IOM_B_10_DN")
	)
	(segment
		(start 299.067474 -167.409622)
		(end 298.82973 -167.754808)
		(width 0.1397)
		(layer "In9.Cu")
		(net "PCIE_COMP_B_TO_IOM_B_10_DN")
	)
	(segment
		(start 305.968146 -157.135322)
		(end 305.730656 -157.480508)
		(width 0.1397)
		(layer "In9.Cu")
		(net "PCIE_COMP_B_TO_IOM_B_10_DN")
	)
	(segment
		(start 276.502876 -184.9755)
		(end 275.606002 -181.576472)
		(width 0.1397)
		(layer "In9.Cu")
		(net "PCIE_COMP_B_TO_IOM_B_10_DN")
	)
	(segment
		(start 298.38396 -168.138602)
		(end 298.422314 -168.347136)
		(width 0.1397)
		(layer "In9.Cu")
		(net "PCIE_COMP_B_TO_IOM_B_10_DN")
	)
	(segment
		(start 297.09364 -170.013376)
		(end 297.132248 -170.22191)
		(width 0.1397)
		(layer "In9.Cu")
		(net "PCIE_COMP_B_TO_IOM_B_10_DN")
	)
	(segment
		(start 288.140648 -183.042306)
		(end 287.902904 -183.387492)
		(width 0.1397)
		(layer "In9.Cu")
		(net "PCIE_COMP_B_TO_IOM_B_10_DN")
	)
	(segment
		(start 289.205924 -181.740302)
		(end 288.968434 -182.085742)
		(width 0.1397)
		(layer "In9.Cu")
		(net "PCIE_COMP_B_TO_IOM_B_10_DN")
	)
	(segment
		(start 299.028866 -167.201342)
		(end 299.067474 -167.409622)
		(width 0.1397)
		(layer "In9.Cu")
		(net "PCIE_COMP_B_TO_IOM_B_10_DN")
	)
	(segment
		(start 278.300434 -175.645826)
		(end 279.143968 -175.645826)
		(width 0.1397)
		(layer "In9.Cu")
		(net "PCIE_COMP_B_TO_IOM_B_10_DN")
	)
	(segment
		(start 385.750054 -19.750024)
		(end 385.750054 -19.338798)
		(width 0.1397)
		(layer "In9.Cu")
		(net "PCIE_COMP_B_TO_IOM_B_10_DN")
	)
	(segment
		(start 298.82973 -167.754808)
		(end 298.62145 -167.793416)
		(width 0.1397)
		(layer "In9.Cu")
		(net "PCIE_COMP_B_TO_IOM_B_10_DN")
	)
	(segment
		(start 287.10255 -184.797192)
		(end 283.996638 -187.295282)
		(width 0.1397)
		(layer "In9.Cu")
		(net "PCIE_COMP_B_TO_IOM_B_10_DN")
	)
	(segment
		(start 297.97629 -168.73093)
		(end 297.7388 -169.076116)
		(width 0.1397)
		(layer "In9.Cu")
		(net "PCIE_COMP_B_TO_IOM_B_10_DN")
	)
	(segment
		(start 288.334958 -183.006238)
		(end 288.140648 -183.042306)
		(width 0.1397)
		(layer "In9.Cu")
		(net "PCIE_COMP_B_TO_IOM_B_10_DN")
	)
	(segment
		(start 297.331384 -169.66819)
		(end 297.09364 -170.013376)
		(width 0.1397)
		(layer "In9.Cu")
		(net "PCIE_COMP_B_TO_IOM_B_10_DN")
	)
	(segment
		(start 313.344814 -146.66214)
		(end 313.150504 -146.697954)
		(width 0.1397)
		(layer "In9.Cu")
		(net "PCIE_COMP_B_TO_IOM_B_10_DN")
	)
	(segment
		(start 281.784298 -188.001148)
		(end 279.26157 -187.194952)
		(width 0.1397)
		(layer "In9.Cu")
		(net "PCIE_COMP_B_TO_IOM_B_10_DN")
	)
	(segment
		(start 289.8394 -180.819806)
		(end 289.60191 -181.164992)
		(width 0.1397)
		(layer "In9.Cu")
		(net "PCIE_COMP_B_TO_IOM_B_10_DN")
	)
	(segment
		(start 312.948828 -147.23745)
		(end 306.795932 -156.178758)
		(width 0.1397)
		(layer "In9.Cu")
		(net "PCIE_COMP_B_TO_IOM_B_10_DN")
	)
	(segment
		(start 297.132248 -170.22191)
		(end 290.235386 -180.244242)
		(width 0.1397)
		(layer "In9.Cu")
		(net "PCIE_COMP_B_TO_IOM_B_10_DN")
	)
	(segment
		(start 312.913014 -147.043394)
		(end 312.948828 -147.23745)
		(width 0.1397)
		(layer "In9.Cu")
		(net "PCIE_COMP_B_TO_IOM_B_10_DN")
	)
	(segment
		(start 287.902904 -183.387492)
		(end 287.938972 -183.581802)
		(width 0.1397)
		(layer "In9.Cu")
		(net "PCIE_COMP_B_TO_IOM_B_10_DN")
	)
	(segment
		(start 385.892548 -19.196304)
		(end 386.310124 -19.196304)
		(width 0.1397)
		(layer "In9.Cu")
		(net "PCIE_COMP_B_TO_IOM_B_10_DN")
	)
	(segment
		(start 289.60191 -181.164992)
		(end 289.4076 -181.200806)
		(width 0.1397)
		(layer "In9.Cu")
		(net "PCIE_COMP_B_TO_IOM_B_10_DN")
	)
	(segment
		(start 306.399946 -156.754068)
		(end 306.162456 -157.099508)
		(width 0.1397)
		(layer "In9.Cu")
		(net "PCIE_COMP_B_TO_IOM_B_10_DN")
	)
	(segment
		(start 305.33467 -158.056072)
		(end 305.096926 -158.401258)
		(width 0.1397)
		(layer "In9.Cu")
		(net "PCIE_COMP_B_TO_IOM_B_10_DN")
	)
	(segment
		(start 306.364132 -156.559758)
		(end 306.399946 -156.754068)
		(width 0.1397)
		(layer "In9.Cu")
		(net "PCIE_COMP_B_TO_IOM_B_10_DN")
	)
	(segment
		(start 275.606002 -181.576472)
		(end 275.605748 -181.576472)
		(width 0.1397)
		(layer "In9.Cu")
		(net "PCIE_COMP_B_TO_IOM_B_10_DN")
	)
	(segment
		(start 289.4076 -181.200806)
		(end 289.17011 -181.546246)
		(width 0.1397)
		(layer "In9.Cu")
		(net "PCIE_COMP_B_TO_IOM_B_10_DN")
	)
	(segment
		(start 370.400326 -63.749174)
		(end 313.97829 -145.74139)
		(width 0.1397)
		(layer "In9.Cu")
		(net "PCIE_COMP_B_TO_IOM_B_10_DN")
	)
	(segment
		(start 378.469398 -44.875196)
		(end 370.400326 -63.749174)
		(width 0.1397)
		(layer "In9.Cu")
		(net "PCIE_COMP_B_TO_IOM_B_10_DN")
	)
	(segment
		(start 386.503926 -19.390106)
		(end 386.503926 -33.265618)
		(width 0.1397)
		(layer "In9.Cu")
		(net "PCIE_COMP_B_TO_IOM_B_10_DN")
	)
	(segment
		(start 305.76647 -157.674818)
		(end 305.52898 -158.020004)
		(width 0.1397)
		(layer "In9.Cu")
		(net "PCIE_COMP_B_TO_IOM_B_10_DN")
	)
	(segment
		(start 297.7388 -169.076116)
		(end 297.777408 -169.284396)
		(width 0.1397)
		(layer "In9.Cu")
		(net "PCIE_COMP_B_TO_IOM_B_10_DN")
	)
	(segment
		(start 297.777408 -169.284396)
		(end 297.539664 -169.629836)
		(width 0.1397)
		(layer "In9.Cu")
		(net "PCIE_COMP_B_TO_IOM_B_10_DN")
	)
	(segment
		(start 313.582304 -146.316954)
		(end 313.344814 -146.66214)
		(width 0.1397)
		(layer "In9.Cu")
		(net "PCIE_COMP_B_TO_IOM_B_10_DN")
	)
	(segment
		(start 305.096926 -158.401258)
		(end 305.132994 -158.595568)
		(width 0.1397)
		(layer "In9.Cu")
		(net "PCIE_COMP_B_TO_IOM_B_10_DN")
	)
	(segment
		(start 313.150504 -146.697954)
		(end 312.913014 -147.043394)
		(width 0.1397)
		(layer "In9.Cu")
		(net "PCIE_COMP_B_TO_IOM_B_10_DN")
	)
	(segment
		(start 289.17011 -181.546246)
		(end 289.205924 -181.740302)
		(width 0.1397)
		(layer "In9.Cu")
		(net "PCIE_COMP_B_TO_IOM_B_10_DN")
	)
	(arc
		(start 284.318202 -176.190148)
		(mid 284.398987 -176.120083)
		(end 284.505654 -176.127664)
		(width 0.1397)
		(layer "In9.Cu")
		(net "PCIE_COMP_B_TO_IOM_B_10_DN")
	)
	(arc
		(start 385.750054 -19.338798)
		(mid 385.759687 -19.29028)
		(end 385.787138 -19.249136)
		(width 0.1397)
		(layer "In9.Cu")
		(net "PCIE_COMP_B_TO_IOM_B_10_DN")
	)
	(arc
		(start 386.466842 -19.300444)
		(mid 386.494275 -19.341595)
		(end 386.503926 -19.390106)
		(width 0.1397)
		(layer "In9.Cu")
		(net "PCIE_COMP_B_TO_IOM_B_10_DN")
	)
	(arc
		(start 385.802886 -19.233388)
		(mid 385.844037 -19.205955)
		(end 385.892548 -19.196304)
		(width 0.1397)
		(layer "In9.Cu")
		(net "PCIE_COMP_B_TO_IOM_B_10_DN")
	)
	(arc
		(start 386.310124 -19.196304)
		(mid 386.358642 -19.205937)
		(end 386.399786 -19.233388)
		(width 0.1397)
		(layer "In9.Cu")
		(net "PCIE_COMP_B_TO_IOM_B_10_DN")
	)
	(arc
		(start 283.585666 -176.645824)
		(mid 283.942542 -176.569344)
		(end 284.236668 -176.353216)
		(width 0.1397)
		(layer "In9.Cu")
		(net "PCIE_COMP_B_TO_IOM_B_10_DN")
	)
	(segment
		(start 282.570682 -17.200118)
		(end 282.0924 -17.6784)
		(width 0.17145)
		(layer "F.Cu")
		(net "PCIE_COMP_B_RST_5")
	)
	(segment
		(start 279.1968 -21.209)
		(end 275.741384 -21.209)
		(width 0.17145)
		(layer "F.Cu")
		(net "PCIE_COMP_B_RST_5")
	)
	(segment
		(start 281.1272 -20.2184)
		(end 280.1874 -20.2184)
		(width 0.17145)
		(layer "F.Cu")
		(net "PCIE_COMP_B_RST_5")
	)
	(segment
		(start 274.716494 -20.18411)
		(end 272.693892 -20.18411)
		(width 0.17145)
		(layer "F.Cu")
		(net "PCIE_COMP_B_RST_5")
	)
	(segment
		(start 280.1874 -20.2184)
		(end 279.1968 -21.209)
		(width 0.17145)
		(layer "F.Cu")
		(net "PCIE_COMP_B_RST_5")
	)
	(segment
		(start 282.0924 -17.6784)
		(end 282.0924 -19.2532)
		(width 0.17145)
		(layer "F.Cu")
		(net "PCIE_COMP_B_RST_5")
	)
	(segment
		(start 272.693892 -20.18411)
		(end 270.853916 -20.18411)
		(width 0.17145)
		(layer "F.Cu")
		(net "PCIE_COMP_B_RST_5")
	)
	(segment
		(start 275.741384 -21.209)
		(end 274.716494 -20.18411)
		(width 0.17145)
		(layer "F.Cu")
		(net "PCIE_COMP_B_RST_5")
	)
	(segment
		(start 282.0924 -19.2532)
		(end 281.1272 -20.2184)
		(width 0.17145)
		(layer "F.Cu")
		(net "PCIE_COMP_B_RST_5")
	)
	(segment
		(start 283.249878 -17.200118)
		(end 282.570682 -17.200118)
		(width 0.17145)
		(layer "F.Cu")
		(net "PCIE_COMP_B_RST_5")
	)
	(via
		(at 272.693892 -20.18411)
		(size 0.6604)
		(drill 0.3302)
		(layers "F.Cu" "B.Cu")
		(net "PCIE_COMP_B_RST_5")
	)
	(segment
		(start 283.249878 -139.499848)
		(end 282.697428 -140.052298)
		(width 0.17145)
		(layer "F.Cu")
		(net "PCIE_COMP_B_PCIE_RST_1")
	)
	(segment
		(start 281.851354 -140.052298)
		(end 281.390852 -140.5128)
		(width 0.17145)
		(layer "F.Cu")
		(net "PCIE_COMP_B_PCIE_RST_1")
	)
	(segment
		(start 279.284938 -141.491462)
		(end 267.6398 -141.491462)
		(width 0.17145)
		(layer "F.Cu")
		(net "PCIE_COMP_B_PCIE_RST_1")
	)
	(segment
		(start 281.390852 -140.5128)
		(end 280.2636 -140.5128)
		(width 0.17145)
		(layer "F.Cu")
		(net "PCIE_COMP_B_PCIE_RST_1")
	)
	(segment
		(start 266.69111 -141.491462)
		(end 267.6398 -141.491462)
		(width 0.17145)
		(layer "F.Cu")
		(net "PCIE_COMP_B_PCIE_RST_1")
	)
	(segment
		(start 280.2636 -140.5128)
		(end 279.284938 -141.491462)
		(width 0.17145)
		(layer "F.Cu")
		(net "PCIE_COMP_B_PCIE_RST_1")
	)
	(segment
		(start 282.697428 -140.052298)
		(end 281.851354 -140.052298)
		(width 0.17145)
		(layer "F.Cu")
		(net "PCIE_COMP_B_PCIE_RST_1")
	)
	(via
		(at 267.6398 -141.491462)
		(size 0.6604)
		(drill 0.3302)
		(layers "F.Cu" "B.Cu")
		(net "PCIE_COMP_B_PCIE_RST_1")
	)
	(segment
		(start 279.837642 -17.52219)
		(end 279.837642 -17.529556)
		(width 0.1651)
		(layer "F.Cu")
		(net "PCIE_COMP_B_CLK_P5")
	)
	(segment
		(start 272.321528 -16.425672)
		(end 272.949924 -17.054068)
		(width 0.1651)
		(layer "F.Cu")
		(net "PCIE_COMP_B_CLK_P5")
	)
	(segment
		(start 279.623012 -17.226534)
		(end 279.837642 -17.52219)
		(width 0.1651)
		(layer "F.Cu")
		(net "PCIE_COMP_B_CLK_P5")
	)
	(segment
		(start 280.02865 -17.561052)
		(end 280.75001 -17.200118)
		(width 0.1651)
		(layer "F.Cu")
		(net "PCIE_COMP_B_CLK_P5")
	)
	(segment
		(start 272.949924 -17.054068)
		(end 279.283668 -17.054068)
		(width 0.1651)
		(layer "F.Cu")
		(net "PCIE_COMP_B_CLK_P5")
	)
	(arc
		(start 279.837642 -17.529556)
		(mid 279.928051 -17.576324)
		(end 280.02865 -17.561052)
		(width 0.1651)
		(layer "F.Cu")
		(net "PCIE_COMP_B_CLK_P5")
	)
	(arc
		(start 279.283668 -17.054068)
		(mid 279.474053 -17.099548)
		(end 279.623012 -17.226534)
		(width 0.1651)
		(layer "F.Cu")
		(net "PCIE_COMP_B_CLK_P5")
	)
	(segment
		(start 272.848832 -17.346168)
		(end 279.283668 -17.346168)
		(width 0.1651)
		(layer "F.Cu")
		(net "PCIE_COMP_B_CLK_N5")
	)
	(segment
		(start 272.321528 -17.873472)
		(end 272.848832 -17.346168)
		(width 0.1651)
		(layer "F.Cu")
		(net "PCIE_COMP_B_CLK_N5")
	)
	(segment
		(start 279.471882 -17.838928)
		(end 278.750014 -18.200116)
		(width 0.1651)
		(layer "F.Cu")
		(net "PCIE_COMP_B_CLK_N5")
	)
	(segment
		(start 279.386538 -17.398492)
		(end 279.545542 -17.617186)
		(width 0.1651)
		(layer "F.Cu")
		(net "PCIE_COMP_B_CLK_N5")
	)
	(segment
		(start 279.545542 -17.617186)
		(end 279.545542 -17.61744)
		(width 0.1651)
		(layer "F.Cu")
		(net "PCIE_COMP_B_CLK_N5")
	)
	(arc
		(start 279.545542 -17.61744)
		(mid 279.554584 -17.743439)
		(end 279.471882 -17.838928)
		(width 0.1651)
		(layer "F.Cu")
		(net "PCIE_COMP_B_CLK_N5")
	)
	(arc
		(start 279.283668 -17.346168)
		(mid 279.341422 -17.35993)
		(end 279.386538 -17.398492)
		(width 0.1651)
		(layer "F.Cu")
		(net "PCIE_COMP_B_CLK_N5")
	)
	(segment
		(start 263.52627 -112.43691)
		(end 263.52627 -99.68865)
		(width 0.17145)
		(layer "F.Cu")
		(net "PCIE_COMP_A_TO_SCC_A_RST_0")
	)
	(segment
		(start 289.102292 -211.276692)
		(end 263.68502 -185.85942)
		(width 0.17145)
		(layer "F.Cu")
		(net "PCIE_COMP_A_TO_SCC_A_RST_0")
	)
	(segment
		(start 263.52627 -99.68865)
		(end 265.504168 -97.710752)
		(width 0.17145)
		(layer "F.Cu")
		(net "PCIE_COMP_A_TO_SCC_A_RST_0")
	)
	(segment
		(start 233.1593 -109.9693)
		(end 225.14433 -117.98427)
		(width 0.17145)
		(layer "F.Cu")
		(net "PCIE_COMP_A_TO_SCC_A_RST_0")
	)
	(segment
		(start 224.2058 -117.98427)
		(end 223.061022 -117.98427)
		(width 0.17145)
		(layer "F.Cu")
		(net "PCIE_COMP_A_TO_SCC_A_RST_0")
	)
	(segment
		(start 236.727492 -109.499908)
		(end 236.2581 -109.9693)
		(width 0.17145)
		(layer "F.Cu")
		(net "PCIE_COMP_A_TO_SCC_A_RST_0")
	)
	(segment
		(start 238.05007 -109.499908)
		(end 236.727492 -109.499908)
		(width 0.17145)
		(layer "F.Cu")
		(net "PCIE_COMP_A_TO_SCC_A_RST_0")
	)
	(segment
		(start 289.102292 -211.435696)
		(end 289.102292 -211.276692)
		(width 0.17145)
		(layer "F.Cu")
		(net "PCIE_COMP_A_TO_SCC_A_RST_0")
	)
	(segment
		(start 263.68502 -185.85942)
		(end 263.68502 -185.269886)
		(width 0.17145)
		(layer "F.Cu")
		(net "PCIE_COMP_A_TO_SCC_A_RST_0")
	)
	(segment
		(start 223.061022 -117.98427)
		(end 223.061022 -118.797578)
		(width 0.17145)
		(layer "F.Cu")
		(net "PCIE_COMP_A_TO_SCC_A_RST_0")
	)
	(segment
		(start 236.2581 -109.9693)
		(end 233.1593 -109.9693)
		(width 0.17145)
		(layer "F.Cu")
		(net "PCIE_COMP_A_TO_SCC_A_RST_0")
	)
	(segment
		(start 263.674098 -112.584738)
		(end 263.52627 -112.43691)
		(width 0.17145)
		(layer "F.Cu")
		(net "PCIE_COMP_A_TO_SCC_A_RST_0")
	)
	(segment
		(start 263.68502 -185.269886)
		(end 263.674098 -185.258964)
		(width 0.17145)
		(layer "F.Cu")
		(net "PCIE_COMP_A_TO_SCC_A_RST_0")
	)
	(segment
		(start 263.674098 -185.258964)
		(end 263.674098 -112.584738)
		(width 0.17145)
		(layer "F.Cu")
		(net "PCIE_COMP_A_TO_SCC_A_RST_0")
	)
	(segment
		(start 225.14433 -117.98427)
		(end 224.2058 -117.98427)
		(width 0.17145)
		(layer "F.Cu")
		(net "PCIE_COMP_A_TO_SCC_A_RST_0")
	)
	(via
		(at 289.102292 -211.435696)
		(size 0.5588)
		(drill 0.3048)
		(layers "F.Cu" "B.Cu")
		(net "PCIE_COMP_A_TO_SCC_A_RST_0")
	)
	(via
		(at 224.2058 -117.98427)
		(size 0.6604)
		(drill 0.3302)
		(layers "F.Cu" "B.Cu")
		(net "PCIE_COMP_A_TO_SCC_A_RST_0")
	)
	(via
		(at 223.061022 -118.797578)
		(size 0.5588)
		(drill 0.3048)
		(layers "F.Cu" "B.Cu")
		(net "PCIE_COMP_A_TO_SCC_A_RST_0")
	)
	(via
		(at 265.504168 -97.710752)
		(size 0.5588)
		(drill 0.3048)
		(layers "F.Cu" "B.Cu")
		(net "PCIE_COMP_A_TO_SCC_A_RST_0")
	)
	(segment
		(start 231.0384 -104.011222)
		(end 236.742224 -98.307398)
		(width 0.13335)
		(layer "In2.Cu")
		(net "PCIE_COMP_A_TO_SCC_A_RST_0")
	)
	(segment
		(start 223.061022 -118.797578)
		(end 231.0384 -110.8202)
		(width 0.13335)
		(layer "In2.Cu")
		(net "PCIE_COMP_A_TO_SCC_A_RST_0")
	)
	(segment
		(start 236.742224 -98.307398)
		(end 264.907522 -98.307398)
		(width 0.13335)
		(layer "In2.Cu")
		(net "PCIE_COMP_A_TO_SCC_A_RST_0")
	)
	(segment
		(start 231.0384 -110.8202)
		(end 231.0384 -104.011222)
		(width 0.13335)
		(layer "In2.Cu")
		(net "PCIE_COMP_A_TO_SCC_A_RST_0")
	)
	(segment
		(start 264.907522 -98.307398)
		(end 265.504168 -97.710752)
		(width 0.13335)
		(layer "In2.Cu")
		(net "PCIE_COMP_A_TO_SCC_A_RST_0")
	)
	(segment
		(start 285.121858 -251.96673)
		(end 288.666174 -251.96673)
		(width 0.12065)
		(layer "In4.Cu")
		(net "PCIE_COMP_A_TO_SCC_A_RST_0")
	)
	(segment
		(start 288.666174 -251.96673)
		(end 289.102292 -251.530612)
		(width 0.12065)
		(layer "In4.Cu")
		(net "PCIE_COMP_A_TO_SCC_A_RST_0")
	)
	(segment
		(start 284.236668 -252.85192)
		(end 285.121858 -251.96673)
		(width 0.12065)
		(layer "In4.Cu")
		(net "PCIE_COMP_A_TO_SCC_A_RST_0")
	)
	(segment
		(start 284.236668 -252.902212)
		(end 284.236668 -252.85192)
		(width 0.12065)
		(layer "In4.Cu")
		(net "PCIE_COMP_A_TO_SCC_A_RST_0")
	)
	(segment
		(start 289.102292 -251.530612)
		(end 289.102292 -211.435696)
		(width 0.12065)
		(layer "In4.Cu")
		(net "PCIE_COMP_A_TO_SCC_A_RST_0")
	)
	(segment
		(start 217.719148 -137.486136)
		(end 226.804474 -120.744996)
		(width 0.1651)
		(layer "F.Cu")
		(net "PCIE_COMP_A_TO_SCC_A_CLK_0_DP")
	)
	(segment
		(start 275.528024 -262.236204)
		(end 269.5321 -258.288536)
		(width 0.1651)
		(layer "F.Cu")
		(net "PCIE_COMP_A_TO_SCC_A_CLK_0_DP")
	)
	(segment
		(start 262.899398 -253.921514)
		(end 218.740228 -180.532532)
		(width 0.1651)
		(layer "F.Cu")
		(net "PCIE_COMP_A_TO_SCC_A_CLK_0_DP")
	)
	(segment
		(start 226.804474 -120.744996)
		(end 235.36783 -115.645946)
		(width 0.1651)
		(layer "F.Cu")
		(net "PCIE_COMP_A_TO_SCC_A_CLK_0_DP")
	)
	(segment
		(start 237.335314 -114.193828)
		(end 237.254542 -114.08283)
		(width 0.1651)
		(layer "F.Cu")
		(net "PCIE_COMP_A_TO_SCC_A_CLK_0_DP")
	)
	(segment
		(start 237.403132 -114.2873)
		(end 237.335314 -114.193828)
		(width 0.1651)
		(layer "F.Cu")
		(net "PCIE_COMP_A_TO_SCC_A_CLK_0_DP")
	)
	(segment
		(start 237.328202 -113.861088)
		(end 238.05007 -113.4999)
		(width 0.1651)
		(layer "F.Cu")
		(net "PCIE_COMP_A_TO_SCC_A_CLK_0_DP")
	)
	(segment
		(start 236.695996 -115.645946)
		(end 237.383828 -114.958368)
		(width 0.1651)
		(layer "F.Cu")
		(net "PCIE_COMP_A_TO_SCC_A_CLK_0_DP")
	)
	(segment
		(start 283.682694 -263.575292)
		(end 283.682694 -263.14781)
		(width 0.1651)
		(layer "F.Cu")
		(net "PCIE_COMP_A_TO_SCC_A_CLK_0_DP")
	)
	(segment
		(start 269.5321 -258.288536)
		(end 262.899398 -253.921514)
		(width 0.1651)
		(layer "F.Cu")
		(net "PCIE_COMP_A_TO_SCC_A_CLK_0_DP")
	)
	(segment
		(start 283.19095 -262.656066)
		(end 276.165564 -262.656066)
		(width 0.1651)
		(layer "F.Cu")
		(net "PCIE_COMP_A_TO_SCC_A_CLK_0_DP")
	)
	(segment
		(start 213.348316 -158.962598)
		(end 217.719148 -137.486136)
		(width 0.1651)
		(layer "F.Cu")
		(net "PCIE_COMP_A_TO_SCC_A_CLK_0_DP")
	)
	(segment
		(start 276.165564 -262.656066)
		(end 275.528024 -262.236204)
		(width 0.1651)
		(layer "F.Cu")
		(net "PCIE_COMP_A_TO_SCC_A_CLK_0_DP")
	)
	(segment
		(start 284.236668 -263.702292)
		(end 283.809694 -263.702292)
		(width 0.1651)
		(layer "F.Cu")
		(net "PCIE_COMP_A_TO_SCC_A_CLK_0_DP")
	)
	(segment
		(start 235.36783 -115.645946)
		(end 236.695996 -115.645946)
		(width 0.1651)
		(layer "F.Cu")
		(net "PCIE_COMP_A_TO_SCC_A_CLK_0_DP")
	)
	(segment
		(start 218.740228 -180.532532)
		(end 213.348316 -158.962598)
		(width 0.1651)
		(layer "F.Cu")
		(net "PCIE_COMP_A_TO_SCC_A_CLK_0_DP")
	)
	(segment
		(start 237.254542 -114.08283)
		(end 237.254542 -114.082576)
		(width 0.1651)
		(layer "F.Cu")
		(net "PCIE_COMP_A_TO_SCC_A_CLK_0_DP")
	)
	(arc
		(start 283.809694 -263.702292)
		(mid 283.719891 -263.665095)
		(end 283.682694 -263.575292)
		(width 0.1651)
		(layer "F.Cu")
		(net "PCIE_COMP_A_TO_SCC_A_CLK_0_DP")
	)
	(arc
		(start 283.682694 -263.14781)
		(mid 283.538666 -262.800094)
		(end 283.19095 -262.656066)
		(width 0.1651)
		(layer "F.Cu")
		(net "PCIE_COMP_A_TO_SCC_A_CLK_0_DP")
	)
	(arc
		(start 237.254542 -114.082576)
		(mid 237.2455 -113.956577)
		(end 237.328202 -113.861088)
		(width 0.1651)
		(layer "F.Cu")
		(net "PCIE_COMP_A_TO_SCC_A_CLK_0_DP")
	)
	(arc
		(start 237.383828 -114.958368)
		(mid 237.526818 -114.626687)
		(end 237.403132 -114.2873)
		(width 0.1651)
		(layer "F.Cu")
		(net "PCIE_COMP_A_TO_SCC_A_CLK_0_DP")
	)
	(segment
		(start 276.077934 -262.948166)
		(end 262.683244 -254.129032)
		(width 0.1651)
		(layer "F.Cu")
		(net "PCIE_COMP_A_TO_SCC_A_CLK_0_DN")
	)
	(segment
		(start 283.390594 -263.575292)
		(end 283.390594 -263.14781)
		(width 0.1651)
		(layer "F.Cu")
		(net "PCIE_COMP_A_TO_SCC_A_CLK_0_DN")
	)
	(segment
		(start 236.574838 -115.353846)
		(end 237.177072 -114.751612)
		(width 0.1651)
		(layer "F.Cu")
		(net "PCIE_COMP_A_TO_SCC_A_CLK_0_DN")
	)
	(segment
		(start 235.287312 -115.353846)
		(end 236.574838 -115.353846)
		(width 0.1651)
		(layer "F.Cu")
		(net "PCIE_COMP_A_TO_SCC_A_CLK_0_DN")
	)
	(segment
		(start 282.83662 -263.702292)
		(end 283.263594 -263.702292)
		(width 0.1651)
		(layer "F.Cu")
		(net "PCIE_COMP_A_TO_SCC_A_CLK_0_DN")
	)
	(segment
		(start 232.726992 -116.878354)
		(end 233.152696 -116.624862)
		(width 0.1651)
		(layer "F.Cu")
		(net "PCIE_COMP_A_TO_SCC_A_CLK_0_DN")
	)
	(segment
		(start 283.19095 -262.948166)
		(end 276.077934 -262.948166)
		(width 0.1651)
		(layer "F.Cu")
		(net "PCIE_COMP_A_TO_SCC_A_CLK_0_DN")
	)
	(segment
		(start 233.774742 -116.25453)
		(end 235.287312 -115.353846)
		(width 0.1651)
		(layer "F.Cu")
		(net "PCIE_COMP_A_TO_SCC_A_CLK_0_DN")
	)
	(segment
		(start 237.177072 -114.473482)
		(end 236.962442 -114.177826)
		(width 0.1651)
		(layer "F.Cu")
		(net "PCIE_COMP_A_TO_SCC_A_CLK_0_DN")
	)
	(segment
		(start 232.1052 -117.248686)
		(end 232.144824 -117.091968)
		(width 0.1651)
		(layer "F.Cu")
		(net "PCIE_COMP_A_TO_SCC_A_CLK_0_DN")
	)
	(segment
		(start 232.144824 -117.091968)
		(end 232.570528 -116.838476)
		(width 0.1651)
		(layer "F.Cu")
		(net "PCIE_COMP_A_TO_SCC_A_CLK_0_DN")
	)
	(segment
		(start 217.441526 -137.385044)
		(end 226.58578 -120.534938)
		(width 0.1651)
		(layer "F.Cu")
		(net "PCIE_COMP_A_TO_SCC_A_CLK_0_DN")
	)
	(segment
		(start 233.152696 -116.624862)
		(end 233.19232 -116.468144)
		(width 0.1651)
		(layer "F.Cu")
		(net "PCIE_COMP_A_TO_SCC_A_CLK_0_DN")
	)
	(segment
		(start 218.467432 -180.645816)
		(end 213.04885 -158.969202)
		(width 0.1651)
		(layer "F.Cu")
		(net "PCIE_COMP_A_TO_SCC_A_CLK_0_DN")
	)
	(segment
		(start 233.19232 -116.468144)
		(end 233.618024 -116.214906)
		(width 0.1651)
		(layer "F.Cu")
		(net "PCIE_COMP_A_TO_SCC_A_CLK_0_DN")
	)
	(segment
		(start 233.618024 -116.214906)
		(end 233.774742 -116.25453)
		(width 0.1651)
		(layer "F.Cu")
		(net "PCIE_COMP_A_TO_SCC_A_CLK_0_DN")
	)
	(segment
		(start 213.04885 -158.969202)
		(end 217.441526 -137.385044)
		(width 0.1651)
		(layer "F.Cu")
		(net "PCIE_COMP_A_TO_SCC_A_CLK_0_DN")
	)
	(segment
		(start 236.962442 -114.177826)
		(end 236.962442 -114.17046)
		(width 0.1651)
		(layer "F.Cu")
		(net "PCIE_COMP_A_TO_SCC_A_CLK_0_DN")
	)
	(segment
		(start 226.58578 -120.534938)
		(end 232.104946 -117.248686)
		(width 0.1651)
		(layer "F.Cu")
		(net "PCIE_COMP_A_TO_SCC_A_CLK_0_DN")
	)
	(segment
		(start 262.683244 -254.129032)
		(end 218.467432 -180.645816)
		(width 0.1651)
		(layer "F.Cu")
		(net "PCIE_COMP_A_TO_SCC_A_CLK_0_DN")
	)
	(segment
		(start 236.771434 -114.138964)
		(end 236.050074 -114.499898)
		(width 0.1651)
		(layer "F.Cu")
		(net "PCIE_COMP_A_TO_SCC_A_CLK_0_DN")
	)
	(segment
		(start 232.570528 -116.838476)
		(end 232.726992 -116.878354)
		(width 0.1651)
		(layer "F.Cu")
		(net "PCIE_COMP_A_TO_SCC_A_CLK_0_DN")
	)
	(segment
		(start 232.104946 -117.248686)
		(end 232.1052 -117.248686)
		(width 0.1651)
		(layer "F.Cu")
		(net "PCIE_COMP_A_TO_SCC_A_CLK_0_DN")
	)
	(arc
		(start 283.263594 -263.702292)
		(mid 283.353397 -263.665095)
		(end 283.390594 -263.575292)
		(width 0.1651)
		(layer "F.Cu")
		(net "PCIE_COMP_A_TO_SCC_A_CLK_0_DN")
	)
	(arc
		(start 283.390594 -263.14781)
		(mid 283.33212 -263.00664)
		(end 283.19095 -262.948166)
		(width 0.1651)
		(layer "F.Cu")
		(net "PCIE_COMP_A_TO_SCC_A_CLK_0_DN")
	)
	(arc
		(start 237.177072 -114.751612)
		(mid 237.234622 -114.612584)
		(end 237.177072 -114.473482)
		(width 0.1651)
		(layer "F.Cu")
		(net "PCIE_COMP_A_TO_SCC_A_CLK_0_DN")
	)
	(arc
		(start 236.962442 -114.17046)
		(mid 236.872033 -114.123692)
		(end 236.771434 -114.138964)
		(width 0.1651)
		(layer "F.Cu")
		(net "PCIE_COMP_A_TO_SCC_A_CLK_0_DN")
	)
	(segment
		(start 241.194844 -164.395658)
		(end 241.325908 -164.1348)
		(width 0.127)
		(layer "In7.Cu")
		(net "PCIE_COMP_A_TO_SCC_A_7_DP")
	)
	(segment
		(start 286.435546 -251.86259)
		(end 288.069782 -251.86259)
		(width 0.127)
		(layer "In7.Cu")
		(net "PCIE_COMP_A_TO_SCC_A_7_DP")
	)
	(segment
		(start 289.909504 -233.09453)
		(end 289.992054 -232.72242)
		(width 0.127)
		(layer "In7.Cu")
		(net "PCIE_COMP_A_TO_SCC_A_7_DP")
	)
	(segment
		(start 290.521136 -230.33609)
		(end 288.79673 -222.557594)
		(width 0.127)
		(layer "In7.Cu")
		(net "PCIE_COMP_A_TO_SCC_A_7_DP")
	)
	(segment
		(start 287.237424 -245.149116)
		(end 287.123378 -244.9703)
		(width 0.127)
		(layer "In7.Cu")
		(net "PCIE_COMP_A_TO_SCC_A_7_DP")
	)
	(segment
		(start 287.435798 -243.561616)
		(end 287.61436 -243.447824)
		(width 0.127)
		(layer "In7.Cu")
		(net "PCIE_COMP_A_TO_SCC_A_7_DP")
	)
	(segment
		(start 290.139374 -232.057956)
		(end 290.221924 -231.685846)
		(width 0.127)
		(layer "In7.Cu")
		(net "PCIE_COMP_A_TO_SCC_A_7_DP")
	)
	(segment
		(start 287.61436 -243.447824)
		(end 287.69691 -243.075968)
		(width 0.127)
		(layer "In7.Cu")
		(net "PCIE_COMP_A_TO_SCC_A_7_DP")
	)
	(segment
		(start 289.992054 -232.72242)
		(end 289.878262 -232.543604)
		(width 0.127)
		(layer "In7.Cu")
		(net "PCIE_COMP_A_TO_SCC_A_7_DP")
	)
	(segment
		(start 289.960558 -232.171748)
		(end 290.139374 -232.057956)
		(width 0.127)
		(layer "In7.Cu")
		(net "PCIE_COMP_A_TO_SCC_A_7_DP")
	)
	(segment
		(start 287.123378 -244.9703)
		(end 287.205928 -244.59819)
		(width 0.127)
		(layer "In7.Cu")
		(net "PCIE_COMP_A_TO_SCC_A_7_DP")
	)
	(segment
		(start 287.69691 -243.075968)
		(end 287.583118 -242.897152)
		(width 0.127)
		(layer "In7.Cu")
		(net "PCIE_COMP_A_TO_SCC_A_7_DP")
	)
	(segment
		(start 288.393632 -251.638816)
		(end 288.54654 -251.140214)
		(width 0.127)
		(layer "In7.Cu")
		(net "PCIE_COMP_A_TO_SCC_A_7_DP")
	)
	(segment
		(start 287.84423 -242.41125)
		(end 289.762184 -233.758994)
		(width 0.127)
		(layer "In7.Cu")
		(net "PCIE_COMP_A_TO_SCC_A_7_DP")
	)
	(segment
		(start 290.108132 -231.50703)
		(end 290.190428 -231.135174)
		(width 0.127)
		(layer "In7.Cu")
		(net "PCIE_COMP_A_TO_SCC_A_7_DP")
	)
	(segment
		(start 290.221924 -231.685846)
		(end 290.108132 -231.50703)
		(width 0.127)
		(layer "In7.Cu")
		(net "PCIE_COMP_A_TO_SCC_A_7_DP")
	)
	(segment
		(start 243.187474 -165.639496)
		(end 241.949478 -165.639496)
		(width 0.127)
		(layer "In7.Cu")
		(net "PCIE_COMP_A_TO_SCC_A_7_DP")
	)
	(segment
		(start 288.54654 -251.13996)
		(end 287.154874 -245.520972)
		(width 0.127)
		(layer "In7.Cu")
		(net "PCIE_COMP_A_TO_SCC_A_7_DP")
	)
	(segment
		(start 258.923536 -175.664368)
		(end 243.187474 -165.639496)
		(width 0.127)
		(layer "In7.Cu")
		(net "PCIE_COMP_A_TO_SCC_A_7_DP")
	)
	(segment
		(start 287.384744 -244.484398)
		(end 287.46704 -244.112542)
		(width 0.127)
		(layer "In7.Cu")
		(net "PCIE_COMP_A_TO_SCC_A_7_DP")
	)
	(segment
		(start 241.325908 -164.134546)
		(end 241.326162 -164.134546)
		(width 0.127)
		(layer "In7.Cu")
		(net "PCIE_COMP_A_TO_SCC_A_7_DP")
	)
	(segment
		(start 289.730942 -233.208322)
		(end 289.909504 -233.09453)
		(width 0.127)
		(layer "In7.Cu")
		(net "PCIE_COMP_A_TO_SCC_A_7_DP")
	)
	(segment
		(start 286.276288 -251.229368)
		(end 286.276288 -251.703332)
		(width 0.127)
		(layer "In7.Cu")
		(net "PCIE_COMP_A_TO_SCC_A_7_DP")
	)
	(segment
		(start 288.79673 -222.557594)
		(end 258.923536 -175.664368)
		(width 0.127)
		(layer "In7.Cu")
		(net "PCIE_COMP_A_TO_SCC_A_7_DP")
	)
	(segment
		(start 288.069782 -251.86259)
		(end 288.393632 -251.638816)
		(width 0.127)
		(layer "In7.Cu")
		(net "PCIE_COMP_A_TO_SCC_A_7_DP")
	)
	(segment
		(start 287.205928 -244.59819)
		(end 287.384744 -244.484398)
		(width 0.127)
		(layer "In7.Cu")
		(net "PCIE_COMP_A_TO_SCC_A_7_DP")
	)
	(segment
		(start 241.326162 -164.134546)
		(end 241.367818 -164.051488)
		(width 0.127)
		(layer "In7.Cu")
		(net "PCIE_COMP_A_TO_SCC_A_7_DP")
	)
	(segment
		(start 287.154874 -245.520972)
		(end 287.237424 -245.149116)
		(width 0.127)
		(layer "In7.Cu")
		(net "PCIE_COMP_A_TO_SCC_A_7_DP")
	)
	(segment
		(start 287.583118 -242.897152)
		(end 287.665414 -242.525296)
		(width 0.127)
		(layer "In7.Cu")
		(net "PCIE_COMP_A_TO_SCC_A_7_DP")
	)
	(segment
		(start 287.665414 -242.525296)
		(end 287.84423 -242.41125)
		(width 0.127)
		(layer "In7.Cu")
		(net "PCIE_COMP_A_TO_SCC_A_7_DP")
	)
	(segment
		(start 241.325908 -164.1348)
		(end 241.325908 -164.134546)
		(width 0.127)
		(layer "In7.Cu")
		(net "PCIE_COMP_A_TO_SCC_A_7_DP")
	)
	(segment
		(start 241.311176 -163.881054)
		(end 240.549938 -163.4998)
		(width 0.127)
		(layer "In7.Cu")
		(net "PCIE_COMP_A_TO_SCC_A_7_DP")
	)
	(segment
		(start 287.46704 -244.112542)
		(end 287.353248 -243.933726)
		(width 0.127)
		(layer "In7.Cu")
		(net "PCIE_COMP_A_TO_SCC_A_7_DP")
	)
	(segment
		(start 290.369244 -231.021382)
		(end 290.521136 -230.33609)
		(width 0.127)
		(layer "In7.Cu")
		(net "PCIE_COMP_A_TO_SCC_A_7_DP")
	)
	(segment
		(start 289.648392 -233.580178)
		(end 289.730942 -233.208322)
		(width 0.127)
		(layer "In7.Cu")
		(net "PCIE_COMP_A_TO_SCC_A_7_DP")
	)
	(segment
		(start 241.949478 -165.639496)
		(end 241.23269 -164.922708)
		(width 0.127)
		(layer "In7.Cu")
		(net "PCIE_COMP_A_TO_SCC_A_7_DP")
	)
	(segment
		(start 290.190428 -231.135174)
		(end 290.369244 -231.021382)
		(width 0.127)
		(layer "In7.Cu")
		(net "PCIE_COMP_A_TO_SCC_A_7_DP")
	)
	(segment
		(start 289.878262 -232.543604)
		(end 289.960558 -232.171748)
		(width 0.127)
		(layer "In7.Cu")
		(net "PCIE_COMP_A_TO_SCC_A_7_DP")
	)
	(segment
		(start 288.54654 -251.140214)
		(end 288.54654 -251.13996)
		(width 0.127)
		(layer "In7.Cu")
		(net "PCIE_COMP_A_TO_SCC_A_7_DP")
	)
	(segment
		(start 287.353248 -243.933726)
		(end 287.435798 -243.561616)
		(width 0.127)
		(layer "In7.Cu")
		(net "PCIE_COMP_A_TO_SCC_A_7_DP")
	)
	(segment
		(start 289.762184 -233.758994)
		(end 289.648392 -233.580178)
		(width 0.127)
		(layer "In7.Cu")
		(net "PCIE_COMP_A_TO_SCC_A_7_DP")
	)
	(segment
		(start 286.836612 -251.102368)
		(end 286.403288 -251.102368)
		(width 0.127)
		(layer "In7.Cu")
		(net "PCIE_COMP_A_TO_SCC_A_7_DP")
	)
	(arc
		(start 241.23269 -164.922708)
		(mid 241.115568 -164.666265)
		(end 241.194844 -164.395658)
		(width 0.127)
		(layer "In7.Cu")
		(net "PCIE_COMP_A_TO_SCC_A_7_DP")
	)
	(arc
		(start 286.276288 -251.703332)
		(mid 286.322934 -251.815944)
		(end 286.435546 -251.86259)
		(width 0.127)
		(layer "In7.Cu")
		(net "PCIE_COMP_A_TO_SCC_A_7_DP")
	)
	(arc
		(start 286.403288 -251.102368)
		(mid 286.313485 -251.139565)
		(end 286.276288 -251.229368)
		(width 0.127)
		(layer "In7.Cu")
		(net "PCIE_COMP_A_TO_SCC_A_7_DP")
	)
	(arc
		(start 241.367818 -164.051488)
		(mid 241.374795 -163.95454)
		(end 241.311176 -163.881054)
		(width 0.127)
		(layer "In7.Cu")
		(net "PCIE_COMP_A_TO_SCC_A_7_DP")
	)
	(segment
		(start 287.441894 -245.517416)
		(end 290.807394 -230.33609)
		(width 0.127)
		(layer "In7.Cu")
		(net "PCIE_COMP_A_TO_SCC_A_7_DN")
	)
	(segment
		(start 241.858546 -165.153086)
		(end 241.858292 -165.153086)
		(width 0.127)
		(layer "In7.Cu")
		(net "PCIE_COMP_A_TO_SCC_A_7_DN")
	)
	(segment
		(start 251.205746 -170.41622)
		(end 243.269008 -165.360096)
		(width 0.127)
		(layer "In7.Cu")
		(net "PCIE_COMP_A_TO_SCC_A_7_DN")
	)
	(segment
		(start 241.858292 -165.153086)
		(end 241.430302 -164.725096)
		(width 0.127)
		(layer "In7.Cu")
		(net "PCIE_COMP_A_TO_SCC_A_7_DN")
	)
	(segment
		(start 288.632392 -251.813568)
		(end 288.836608 -251.147834)
		(width 0.127)
		(layer "In7.Cu")
		(net "PCIE_COMP_A_TO_SCC_A_7_DN")
	)
	(segment
		(start 288.836608 -251.147834)
		(end 288.836354 -251.14758)
		(width 0.127)
		(layer "In7.Cu")
		(net "PCIE_COMP_A_TO_SCC_A_7_DN")
	)
	(segment
		(start 286.435546 -252.14199)
		(end 288.157158 -252.14199)
		(width 0.127)
		(layer "In7.Cu")
		(net "PCIE_COMP_A_TO_SCC_A_7_DN")
	)
	(segment
		(start 259.125974 -175.46193)
		(end 251.205746 -170.41622)
		(width 0.127)
		(layer "In7.Cu")
		(net "PCIE_COMP_A_TO_SCC_A_7_DN")
	)
	(segment
		(start 241.589052 -164.233606)
		(end 241.61242 -164.187632)
		(width 0.127)
		(layer "In7.Cu")
		(net "PCIE_COMP_A_TO_SCC_A_7_DN")
	)
	(segment
		(start 241.800634 -164.12464)
		(end 242.549934 -164.499798)
		(width 0.127)
		(layer "In7.Cu")
		(net "PCIE_COMP_A_TO_SCC_A_7_DN")
	)
	(segment
		(start 243.269008 -165.360096)
		(end 242.065302 -165.360096)
		(width 0.127)
		(layer "In7.Cu")
		(net "PCIE_COMP_A_TO_SCC_A_7_DN")
	)
	(segment
		(start 241.576098 -164.259768)
		(end 241.589052 -164.233606)
		(width 0.127)
		(layer "In7.Cu")
		(net "PCIE_COMP_A_TO_SCC_A_7_DN")
	)
	(segment
		(start 241.430302 -164.549836)
		(end 241.576098 -164.259768)
		(width 0.127)
		(layer "In7.Cu")
		(net "PCIE_COMP_A_TO_SCC_A_7_DN")
	)
	(segment
		(start 274.095972 -198.960994)
		(end 259.125974 -175.46193)
		(width 0.127)
		(layer "In7.Cu")
		(net "PCIE_COMP_A_TO_SCC_A_7_DN")
	)
	(segment
		(start 285.996888 -251.229368)
		(end 285.996888 -251.703332)
		(width 0.127)
		(layer "In7.Cu")
		(net "PCIE_COMP_A_TO_SCC_A_7_DN")
	)
	(segment
		(start 285.436564 -251.102368)
		(end 285.869888 -251.102368)
		(width 0.127)
		(layer "In7.Cu")
		(net "PCIE_COMP_A_TO_SCC_A_7_DN")
	)
	(segment
		(start 290.807394 -230.33609)
		(end 289.059112 -222.448882)
		(width 0.127)
		(layer "In7.Cu")
		(net "PCIE_COMP_A_TO_SCC_A_7_DN")
	)
	(segment
		(start 289.059112 -222.448882)
		(end 274.095972 -198.960994)
		(width 0.127)
		(layer "In7.Cu")
		(net "PCIE_COMP_A_TO_SCC_A_7_DN")
	)
	(segment
		(start 288.157158 -252.14199)
		(end 288.632392 -251.813568)
		(width 0.127)
		(layer "In7.Cu")
		(net "PCIE_COMP_A_TO_SCC_A_7_DN")
	)
	(segment
		(start 242.065302 -165.360096)
		(end 241.858546 -165.153086)
		(width 0.127)
		(layer "In7.Cu")
		(net "PCIE_COMP_A_TO_SCC_A_7_DN")
	)
	(segment
		(start 288.836354 -251.14758)
		(end 287.441894 -245.517416)
		(width 0.127)
		(layer "In7.Cu")
		(net "PCIE_COMP_A_TO_SCC_A_7_DN")
	)
	(arc
		(start 285.996888 -251.703332)
		(mid 286.125368 -252.01351)
		(end 286.435546 -252.14199)
		(width 0.127)
		(layer "In7.Cu")
		(net "PCIE_COMP_A_TO_SCC_A_7_DN")
	)
	(arc
		(start 241.61242 -164.187632)
		(mid 241.693444 -164.117043)
		(end 241.800634 -164.12464)
		(width 0.127)
		(layer "In7.Cu")
		(net "PCIE_COMP_A_TO_SCC_A_7_DN")
	)
	(arc
		(start 241.430302 -164.725096)
		(mid 241.394004 -164.637466)
		(end 241.430302 -164.549836)
		(width 0.127)
		(layer "In7.Cu")
		(net "PCIE_COMP_A_TO_SCC_A_7_DN")
	)
	(arc
		(start 285.869888 -251.102368)
		(mid 285.959691 -251.139565)
		(end 285.996888 -251.229368)
		(width 0.127)
		(layer "In7.Cu")
		(net "PCIE_COMP_A_TO_SCC_A_7_DN")
	)
	(segment
		(start 288.689288 -244.647466)
		(end 288.868104 -244.533674)
		(width 0.127)
		(layer "In7.Cu")
		(net "PCIE_COMP_A_TO_SCC_A_6_DP")
	)
	(segment
		(start 241.325908 -160.134808)
		(end 241.325908 -160.134554)
		(width 0.127)
		(layer "In7.Cu")
		(net "PCIE_COMP_A_TO_SCC_A_6_DP")
	)
	(segment
		(start 288.720784 -245.198392)
		(end 288.606738 -245.019576)
		(width 0.127)
		(layer "In7.Cu")
		(net "PCIE_COMP_A_TO_SCC_A_6_DP")
	)
	(segment
		(start 288.918904 -243.610892)
		(end 289.09772 -243.4971)
		(width 0.127)
		(layer "In7.Cu")
		(net "PCIE_COMP_A_TO_SCC_A_6_DP")
	)
	(segment
		(start 291.44214 -232.919524)
		(end 291.328348 -232.740708)
		(width 0.127)
		(layer "In7.Cu")
		(net "PCIE_COMP_A_TO_SCC_A_6_DP")
	)
	(segment
		(start 289.09772 -243.4971)
		(end 289.18027 -243.125244)
		(width 0.127)
		(layer "In7.Cu")
		(net "PCIE_COMP_A_TO_SCC_A_6_DP")
	)
	(segment
		(start 291.328348 -232.740708)
		(end 291.410898 -232.368852)
		(width 0.127)
		(layer "In7.Cu")
		(net "PCIE_COMP_A_TO_SCC_A_6_DP")
	)
	(segment
		(start 289.18027 -243.125244)
		(end 289.066224 -242.946428)
		(width 0.127)
		(layer "In7.Cu")
		(net "PCIE_COMP_A_TO_SCC_A_6_DP")
	)
	(segment
		(start 288.836608 -243.983002)
		(end 288.918904 -243.610892)
		(width 0.127)
		(layer "In7.Cu")
		(net "PCIE_COMP_A_TO_SCC_A_6_DP")
	)
	(segment
		(start 241.325908 -160.134554)
		(end 241.326162 -160.134554)
		(width 0.127)
		(layer "In7.Cu")
		(net "PCIE_COMP_A_TO_SCC_A_6_DP")
	)
	(segment
		(start 241.311176 -159.881062)
		(end 240.549938 -159.499808)
		(width 0.127)
		(layer "In7.Cu")
		(net "PCIE_COMP_A_TO_SCC_A_6_DP")
	)
	(segment
		(start 289.03803 -253.662434)
		(end 289.429444 -253.392178)
		(width 0.127)
		(layer "In7.Cu")
		(net "PCIE_COMP_A_TO_SCC_A_6_DP")
	)
	(segment
		(start 291.359844 -233.29138)
		(end 291.44214 -232.919524)
		(width 0.127)
		(layer "In7.Cu")
		(net "PCIE_COMP_A_TO_SCC_A_6_DP")
	)
	(segment
		(start 287.435544 -253.662434)
		(end 289.03803 -253.662434)
		(width 0.127)
		(layer "In7.Cu")
		(net "PCIE_COMP_A_TO_SCC_A_6_DP")
	)
	(segment
		(start 241.194844 -160.395412)
		(end 241.325908 -160.134808)
		(width 0.127)
		(layer "In7.Cu")
		(net "PCIE_COMP_A_TO_SCC_A_6_DP")
	)
	(segment
		(start 290.035996 -251.167138)
		(end 290.03625 -251.166884)
		(width 0.127)
		(layer "In7.Cu")
		(net "PCIE_COMP_A_TO_SCC_A_6_DP")
	)
	(segment
		(start 287.276286 -253.029212)
		(end 287.276286 -253.503176)
		(width 0.127)
		(layer "In7.Cu")
		(net "PCIE_COMP_A_TO_SCC_A_6_DP")
	)
	(segment
		(start 288.9504 -244.161818)
		(end 288.836608 -243.983002)
		(width 0.127)
		(layer "In7.Cu")
		(net "PCIE_COMP_A_TO_SCC_A_6_DP")
	)
	(segment
		(start 291.58946 -232.254806)
		(end 291.67201 -231.88295)
		(width 0.127)
		(layer "In7.Cu")
		(net "PCIE_COMP_A_TO_SCC_A_6_DP")
	)
	(segment
		(start 291.410898 -232.368852)
		(end 291.58946 -232.254806)
		(width 0.127)
		(layer "In7.Cu")
		(net "PCIE_COMP_A_TO_SCC_A_6_DP")
	)
	(segment
		(start 241.94135 -161.639504)
		(end 241.23269 -160.930844)
		(width 0.127)
		(layer "In7.Cu")
		(net "PCIE_COMP_A_TO_SCC_A_6_DP")
	)
	(segment
		(start 291.67201 -231.88295)
		(end 291.558218 -231.704134)
		(width 0.127)
		(layer "In7.Cu")
		(net "PCIE_COMP_A_TO_SCC_A_6_DP")
	)
	(segment
		(start 288.638234 -245.570248)
		(end 288.720784 -245.198392)
		(width 0.127)
		(layer "In7.Cu")
		(net "PCIE_COMP_A_TO_SCC_A_6_DP")
	)
	(segment
		(start 290.03625 -251.166884)
		(end 290.035996 -251.166884)
		(width 0.127)
		(layer "In7.Cu")
		(net "PCIE_COMP_A_TO_SCC_A_6_DP")
	)
	(segment
		(start 289.939222 -221.133162)
		(end 258.22275 -171.346114)
		(width 0.127)
		(layer "In7.Cu")
		(net "PCIE_COMP_A_TO_SCC_A_6_DP")
	)
	(segment
		(start 289.429444 -253.392178)
		(end 290.035996 -251.167138)
		(width 0.127)
		(layer "In7.Cu")
		(net "PCIE_COMP_A_TO_SCC_A_6_DP")
	)
	(segment
		(start 291.098732 -233.777282)
		(end 291.181028 -233.405426)
		(width 0.127)
		(layer "In7.Cu")
		(net "PCIE_COMP_A_TO_SCC_A_6_DP")
	)
	(segment
		(start 291.989002 -230.452676)
		(end 289.939222 -221.133162)
		(width 0.127)
		(layer "In7.Cu")
		(net "PCIE_COMP_A_TO_SCC_A_6_DP")
	)
	(segment
		(start 291.212524 -233.956098)
		(end 291.098732 -233.777282)
		(width 0.127)
		(layer "In7.Cu")
		(net "PCIE_COMP_A_TO_SCC_A_6_DP")
	)
	(segment
		(start 289.148774 -242.574318)
		(end 289.32759 -242.460526)
		(width 0.127)
		(layer "In7.Cu")
		(net "PCIE_COMP_A_TO_SCC_A_6_DP")
	)
	(segment
		(start 289.32759 -242.460526)
		(end 291.212524 -233.956098)
		(width 0.127)
		(layer "In7.Cu")
		(net "PCIE_COMP_A_TO_SCC_A_6_DP")
	)
	(segment
		(start 290.035996 -251.166884)
		(end 288.638234 -245.570248)
		(width 0.127)
		(layer "In7.Cu")
		(net "PCIE_COMP_A_TO_SCC_A_6_DP")
	)
	(segment
		(start 288.868104 -244.533674)
		(end 288.9504 -244.161818)
		(width 0.127)
		(layer "In7.Cu")
		(net "PCIE_COMP_A_TO_SCC_A_6_DP")
	)
	(segment
		(start 258.22275 -171.346114)
		(end 242.987068 -161.639504)
		(width 0.127)
		(layer "In7.Cu")
		(net "PCIE_COMP_A_TO_SCC_A_6_DP")
	)
	(segment
		(start 242.987068 -161.639504)
		(end 241.94135 -161.639504)
		(width 0.127)
		(layer "In7.Cu")
		(net "PCIE_COMP_A_TO_SCC_A_6_DP")
	)
	(segment
		(start 291.640514 -231.332278)
		(end 291.81933 -231.218232)
		(width 0.127)
		(layer "In7.Cu")
		(net "PCIE_COMP_A_TO_SCC_A_6_DP")
	)
	(segment
		(start 289.066224 -242.946428)
		(end 289.148774 -242.574318)
		(width 0.127)
		(layer "In7.Cu")
		(net "PCIE_COMP_A_TO_SCC_A_6_DP")
	)
	(segment
		(start 291.558218 -231.704134)
		(end 291.640514 -231.332278)
		(width 0.127)
		(layer "In7.Cu")
		(net "PCIE_COMP_A_TO_SCC_A_6_DP")
	)
	(segment
		(start 287.83661 -252.902212)
		(end 287.403286 -252.902212)
		(width 0.127)
		(layer "In7.Cu")
		(net "PCIE_COMP_A_TO_SCC_A_6_DP")
	)
	(segment
		(start 291.81933 -231.218232)
		(end 291.989002 -230.452676)
		(width 0.127)
		(layer "In7.Cu")
		(net "PCIE_COMP_A_TO_SCC_A_6_DP")
	)
	(segment
		(start 291.181028 -233.405426)
		(end 291.359844 -233.29138)
		(width 0.127)
		(layer "In7.Cu")
		(net "PCIE_COMP_A_TO_SCC_A_6_DP")
	)
	(segment
		(start 288.606738 -245.019576)
		(end 288.689288 -244.647466)
		(width 0.127)
		(layer "In7.Cu")
		(net "PCIE_COMP_A_TO_SCC_A_6_DP")
	)
	(segment
		(start 241.326162 -160.134554)
		(end 241.367818 -160.051496)
		(width 0.127)
		(layer "In7.Cu")
		(net "PCIE_COMP_A_TO_SCC_A_6_DP")
	)
	(arc
		(start 241.367818 -160.051496)
		(mid 241.374795 -159.954548)
		(end 241.311176 -159.881062)
		(width 0.127)
		(layer "In7.Cu")
		(net "PCIE_COMP_A_TO_SCC_A_6_DP")
	)
	(arc
		(start 287.276286 -253.503176)
		(mid 287.322932 -253.615788)
		(end 287.435544 -253.662434)
		(width 0.127)
		(layer "In7.Cu")
		(net "PCIE_COMP_A_TO_SCC_A_6_DP")
	)
	(arc
		(start 287.403286 -252.902212)
		(mid 287.313483 -252.939409)
		(end 287.276286 -253.029212)
		(width 0.127)
		(layer "In7.Cu")
		(net "PCIE_COMP_A_TO_SCC_A_6_DP")
	)
	(arc
		(start 241.23269 -160.930844)
		(mid 241.113698 -160.670187)
		(end 241.194844 -160.395412)
		(width 0.127)
		(layer "In7.Cu")
		(net "PCIE_COMP_A_TO_SCC_A_6_DP")
	)
	(segment
		(start 290.335462 -251.211334)
		(end 288.925508 -245.566438)
		(width 0.127)
		(layer "In7.Cu")
		(net "PCIE_COMP_A_TO_SCC_A_6_DN")
	)
	(segment
		(start 241.430302 -160.549844)
		(end 241.576098 -160.259776)
		(width 0.127)
		(layer "In7.Cu")
		(net "PCIE_COMP_A_TO_SCC_A_6_DN")
	)
	(segment
		(start 290.295584 -251.277882)
		(end 290.335462 -251.211334)
		(width 0.127)
		(layer "In7.Cu")
		(net "PCIE_COMP_A_TO_SCC_A_6_DN")
	)
	(segment
		(start 241.576098 -160.259776)
		(end 241.589052 -160.233614)
		(width 0.127)
		(layer "In7.Cu")
		(net "PCIE_COMP_A_TO_SCC_A_6_DN")
	)
	(segment
		(start 258.425188 -171.143676)
		(end 243.068602 -161.360104)
		(width 0.127)
		(layer "In7.Cu")
		(net "PCIE_COMP_A_TO_SCC_A_6_DN")
	)
	(segment
		(start 241.589052 -160.233614)
		(end 241.61242 -160.18764)
		(width 0.127)
		(layer "In7.Cu")
		(net "PCIE_COMP_A_TO_SCC_A_6_DN")
	)
	(segment
		(start 288.925508 -245.566438)
		(end 292.27526 -230.45293)
		(width 0.127)
		(layer "In7.Cu")
		(net "PCIE_COMP_A_TO_SCC_A_6_DN")
	)
	(segment
		(start 241.800634 -160.124648)
		(end 242.549934 -160.499806)
		(width 0.127)
		(layer "In7.Cu")
		(net "PCIE_COMP_A_TO_SCC_A_6_DN")
	)
	(segment
		(start 289.672268 -253.564136)
		(end 290.295584 -251.277882)
		(width 0.127)
		(layer "In7.Cu")
		(net "PCIE_COMP_A_TO_SCC_A_6_DN")
	)
	(segment
		(start 243.068602 -161.360104)
		(end 242.057174 -161.360104)
		(width 0.127)
		(layer "In7.Cu")
		(net "PCIE_COMP_A_TO_SCC_A_6_DN")
	)
	(segment
		(start 289.125152 -253.941834)
		(end 289.672268 -253.564136)
		(width 0.127)
		(layer "In7.Cu")
		(net "PCIE_COMP_A_TO_SCC_A_6_DN")
	)
	(segment
		(start 286.996886 -253.029212)
		(end 286.996886 -253.503176)
		(width 0.127)
		(layer "In7.Cu")
		(net "PCIE_COMP_A_TO_SCC_A_6_DN")
	)
	(segment
		(start 287.435544 -253.941834)
		(end 289.125152 -253.941834)
		(width 0.127)
		(layer "In7.Cu")
		(net "PCIE_COMP_A_TO_SCC_A_6_DN")
	)
	(segment
		(start 242.057174 -161.360104)
		(end 241.430302 -160.733232)
		(width 0.127)
		(layer "In7.Cu")
		(net "PCIE_COMP_A_TO_SCC_A_6_DN")
	)
	(segment
		(start 292.27526 -230.45293)
		(end 290.201604 -221.024704)
		(width 0.127)
		(layer "In7.Cu")
		(net "PCIE_COMP_A_TO_SCC_A_6_DN")
	)
	(segment
		(start 290.201604 -221.024704)
		(end 258.425188 -171.143676)
		(width 0.127)
		(layer "In7.Cu")
		(net "PCIE_COMP_A_TO_SCC_A_6_DN")
	)
	(segment
		(start 286.436562 -252.902212)
		(end 286.869886 -252.902212)
		(width 0.127)
		(layer "In7.Cu")
		(net "PCIE_COMP_A_TO_SCC_A_6_DN")
	)
	(arc
		(start 286.869886 -252.902212)
		(mid 286.959689 -252.939409)
		(end 286.996886 -253.029212)
		(width 0.127)
		(layer "In7.Cu")
		(net "PCIE_COMP_A_TO_SCC_A_6_DN")
	)
	(arc
		(start 286.996886 -253.503176)
		(mid 287.125366 -253.813354)
		(end 287.435544 -253.941834)
		(width 0.127)
		(layer "In7.Cu")
		(net "PCIE_COMP_A_TO_SCC_A_6_DN")
	)
	(arc
		(start 241.430302 -160.733232)
		(mid 241.392321 -160.641538)
		(end 241.430302 -160.549844)
		(width 0.127)
		(layer "In7.Cu")
		(net "PCIE_COMP_A_TO_SCC_A_6_DN")
	)
	(arc
		(start 241.61242 -160.18764)
		(mid 241.693444 -160.117051)
		(end 241.800634 -160.124648)
		(width 0.127)
		(layer "In7.Cu")
		(net "PCIE_COMP_A_TO_SCC_A_6_DN")
	)
	(segment
		(start 292.56355 -234.14101)
		(end 292.6461 -233.7689)
		(width 0.127)
		(layer "In7.Cu")
		(net "PCIE_COMP_A_TO_SCC_A_5_DP")
	)
	(segment
		(start 241.194844 -156.39542)
		(end 241.325908 -156.134816)
		(width 0.127)
		(layer "In7.Cu")
		(net "PCIE_COMP_A_TO_SCC_A_5_DP")
	)
	(segment
		(start 241.325908 -156.134816)
		(end 241.325908 -156.134562)
		(width 0.127)
		(layer "In7.Cu")
		(net "PCIE_COMP_A_TO_SCC_A_5_DP")
	)
	(segment
		(start 290.859718 -253.346458)
		(end 291.04082 -252.757432)
		(width 0.127)
		(layer "In7.Cu")
		(net "PCIE_COMP_A_TO_SCC_A_5_DP")
	)
	(segment
		(start 290.050982 -246.164354)
		(end 290.133532 -245.792498)
		(width 0.127)
		(layer "In7.Cu")
		(net "PCIE_COMP_A_TO_SCC_A_5_DP")
	)
	(segment
		(start 241.311176 -155.88107)
		(end 240.549938 -155.499816)
		(width 0.127)
		(layer "In7.Cu")
		(net "PCIE_COMP_A_TO_SCC_A_5_DP")
	)
	(segment
		(start 292.33368 -235.17733)
		(end 292.41623 -234.805474)
		(width 0.127)
		(layer "In7.Cu")
		(net "PCIE_COMP_A_TO_SCC_A_5_DP")
	)
	(segment
		(start 292.447472 -235.356146)
		(end 292.33368 -235.17733)
		(width 0.127)
		(layer "In7.Cu")
		(net "PCIE_COMP_A_TO_SCC_A_5_DP")
	)
	(segment
		(start 291.16655 -219.902278)
		(end 257.222752 -166.618412)
		(width 0.127)
		(layer "In7.Cu")
		(net "PCIE_COMP_A_TO_SCC_A_5_DP")
	)
	(segment
		(start 286.276288 -254.82931)
		(end 286.276288 -255.303274)
		(width 0.127)
		(layer "In7.Cu")
		(net "PCIE_COMP_A_TO_SCC_A_5_DP")
	)
	(segment
		(start 292.217602 -236.39272)
		(end 292.10381 -236.213904)
		(width 0.127)
		(layer "In7.Cu")
		(net "PCIE_COMP_A_TO_SCC_A_5_DP")
	)
	(segment
		(start 241.325908 -156.134562)
		(end 241.326162 -156.134562)
		(width 0.127)
		(layer "In7.Cu")
		(net "PCIE_COMP_A_TO_SCC_A_5_DP")
	)
	(segment
		(start 293.520114 -230.51897)
		(end 291.16655 -219.902278)
		(width 0.127)
		(layer "In7.Cu")
		(net "PCIE_COMP_A_TO_SCC_A_5_DP")
	)
	(segment
		(start 290.102036 -245.241572)
		(end 290.280852 -245.12778)
		(width 0.127)
		(layer "In7.Cu")
		(net "PCIE_COMP_A_TO_SCC_A_5_DP")
	)
	(segment
		(start 291.04082 -252.757432)
		(end 291.40277 -251.58065)
		(width 0.127)
		(layer "In7.Cu")
		(net "PCIE_COMP_A_TO_SCC_A_5_DP")
	)
	(segment
		(start 292.41623 -234.805474)
		(end 292.594792 -234.691682)
		(width 0.127)
		(layer "In7.Cu")
		(net "PCIE_COMP_A_TO_SCC_A_5_DP")
	)
	(segment
		(start 288.467292 -255.462532)
		(end 290.67887 -253.934468)
		(width 0.127)
		(layer "In7.Cu")
		(net "PCIE_COMP_A_TO_SCC_A_5_DP")
	)
	(segment
		(start 286.836612 -254.70231)
		(end 286.403288 -254.70231)
		(width 0.127)
		(layer "In7.Cu")
		(net "PCIE_COMP_A_TO_SCC_A_5_DP")
	)
	(segment
		(start 243.128546 -157.639512)
		(end 241.94135 -157.639512)
		(width 0.127)
		(layer "In7.Cu")
		(net "PCIE_COMP_A_TO_SCC_A_5_DP")
	)
	(segment
		(start 290.363402 -244.755924)
		(end 290.249356 -244.577108)
		(width 0.127)
		(layer "In7.Cu")
		(net "PCIE_COMP_A_TO_SCC_A_5_DP")
	)
	(segment
		(start 257.222752 -166.618412)
		(end 250.17603 -162.129216)
		(width 0.127)
		(layer "In7.Cu")
		(net "PCIE_COMP_A_TO_SCC_A_5_DP")
	)
	(segment
		(start 292.10381 -236.213904)
		(end 292.18636 -235.842048)
		(width 0.127)
		(layer "In7.Cu")
		(net "PCIE_COMP_A_TO_SCC_A_5_DP")
	)
	(segment
		(start 290.510722 -244.091206)
		(end 290.593018 -243.71935)
		(width 0.127)
		(layer "In7.Cu")
		(net "PCIE_COMP_A_TO_SCC_A_5_DP")
	)
	(segment
		(start 290.593018 -243.71935)
		(end 290.479226 -243.540534)
		(width 0.127)
		(layer "In7.Cu")
		(net "PCIE_COMP_A_TO_SCC_A_5_DP")
	)
	(segment
		(start 290.019486 -245.613682)
		(end 290.102036 -245.241572)
		(width 0.127)
		(layer "In7.Cu")
		(net "PCIE_COMP_A_TO_SCC_A_5_DP")
	)
	(segment
		(start 241.94135 -157.639512)
		(end 241.23269 -156.930852)
		(width 0.127)
		(layer "In7.Cu")
		(net "PCIE_COMP_A_TO_SCC_A_5_DP")
	)
	(segment
		(start 241.326162 -156.134562)
		(end 241.367818 -156.051504)
		(width 0.127)
		(layer "In7.Cu")
		(net "PCIE_COMP_A_TO_SCC_A_5_DP")
	)
	(segment
		(start 290.561776 -243.168678)
		(end 290.740592 -243.054632)
		(width 0.127)
		(layer "In7.Cu")
		(net "PCIE_COMP_A_TO_SCC_A_5_DP")
	)
	(segment
		(start 286.435546 -255.462532)
		(end 288.467292 -255.462532)
		(width 0.127)
		(layer "In7.Cu")
		(net "PCIE_COMP_A_TO_SCC_A_5_DP")
	)
	(segment
		(start 290.740592 -243.054632)
		(end 292.217602 -236.39272)
		(width 0.127)
		(layer "In7.Cu")
		(net "PCIE_COMP_A_TO_SCC_A_5_DP")
	)
	(segment
		(start 290.859464 -253.346458)
		(end 290.859718 -253.346458)
		(width 0.127)
		(layer "In7.Cu")
		(net "PCIE_COMP_A_TO_SCC_A_5_DP")
	)
	(segment
		(start 292.594792 -234.691682)
		(end 292.677342 -234.319572)
		(width 0.127)
		(layer "In7.Cu")
		(net "PCIE_COMP_A_TO_SCC_A_5_DP")
	)
	(segment
		(start 290.67887 -253.934468)
		(end 290.859464 -253.346458)
		(width 0.127)
		(layer "In7.Cu")
		(net "PCIE_COMP_A_TO_SCC_A_5_DP")
	)
	(segment
		(start 290.479226 -243.540534)
		(end 290.561776 -243.168678)
		(width 0.127)
		(layer "In7.Cu")
		(net "PCIE_COMP_A_TO_SCC_A_5_DP")
	)
	(segment
		(start 292.6461 -233.7689)
		(end 292.824662 -233.655108)
		(width 0.127)
		(layer "In7.Cu")
		(net "PCIE_COMP_A_TO_SCC_A_5_DP")
	)
	(segment
		(start 291.40277 -251.58065)
		(end 290.050982 -246.164354)
		(width 0.127)
		(layer "In7.Cu")
		(net "PCIE_COMP_A_TO_SCC_A_5_DP")
	)
	(segment
		(start 290.133532 -245.792498)
		(end 290.019486 -245.613682)
		(width 0.127)
		(layer "In7.Cu")
		(net "PCIE_COMP_A_TO_SCC_A_5_DP")
	)
	(segment
		(start 292.365176 -235.728256)
		(end 292.447472 -235.356146)
		(width 0.127)
		(layer "In7.Cu")
		(net "PCIE_COMP_A_TO_SCC_A_5_DP")
	)
	(segment
		(start 290.331906 -244.205252)
		(end 290.510722 -244.091206)
		(width 0.127)
		(layer "In7.Cu")
		(net "PCIE_COMP_A_TO_SCC_A_5_DP")
	)
	(segment
		(start 292.677342 -234.319572)
		(end 292.56355 -234.14101)
		(width 0.127)
		(layer "In7.Cu")
		(net "PCIE_COMP_A_TO_SCC_A_5_DP")
	)
	(segment
		(start 292.824662 -233.655108)
		(end 293.520114 -230.51897)
		(width 0.127)
		(layer "In7.Cu")
		(net "PCIE_COMP_A_TO_SCC_A_5_DP")
	)
	(segment
		(start 290.249356 -244.577108)
		(end 290.331906 -244.205252)
		(width 0.127)
		(layer "In7.Cu")
		(net "PCIE_COMP_A_TO_SCC_A_5_DP")
	)
	(segment
		(start 290.280852 -245.12778)
		(end 290.363402 -244.755924)
		(width 0.127)
		(layer "In7.Cu")
		(net "PCIE_COMP_A_TO_SCC_A_5_DP")
	)
	(segment
		(start 292.18636 -235.842048)
		(end 292.365176 -235.728256)
		(width 0.127)
		(layer "In7.Cu")
		(net "PCIE_COMP_A_TO_SCC_A_5_DP")
	)
	(segment
		(start 250.17603 -162.129216)
		(end 243.128546 -157.639512)
		(width 0.127)
		(layer "In7.Cu")
		(net "PCIE_COMP_A_TO_SCC_A_5_DP")
	)
	(arc
		(start 241.367818 -156.051504)
		(mid 241.374795 -155.954556)
		(end 241.311176 -155.88107)
		(width 0.127)
		(layer "In7.Cu")
		(net "PCIE_COMP_A_TO_SCC_A_5_DP")
	)
	(arc
		(start 286.403288 -254.70231)
		(mid 286.313485 -254.739507)
		(end 286.276288 -254.82931)
		(width 0.127)
		(layer "In7.Cu")
		(net "PCIE_COMP_A_TO_SCC_A_5_DP")
	)
	(arc
		(start 286.276288 -255.303274)
		(mid 286.322934 -255.415886)
		(end 286.435546 -255.462532)
		(width 0.127)
		(layer "In7.Cu")
		(net "PCIE_COMP_A_TO_SCC_A_5_DP")
	)
	(arc
		(start 241.23269 -156.930852)
		(mid 241.113698 -156.670195)
		(end 241.194844 -156.39542)
		(width 0.127)
		(layer "In7.Cu")
		(net "PCIE_COMP_A_TO_SCC_A_5_DP")
	)
	(segment
		(start 241.800634 -156.124656)
		(end 242.549934 -156.499814)
		(width 0.127)
		(layer "In7.Cu")
		(net "PCIE_COMP_A_TO_SCC_A_5_DN")
	)
	(segment
		(start 286.435546 -255.741932)
		(end 288.554668 -255.741932)
		(width 0.127)
		(layer "In7.Cu")
		(net "PCIE_COMP_A_TO_SCC_A_5_DN")
	)
	(segment
		(start 241.589052 -156.233622)
		(end 241.61242 -156.187648)
		(width 0.127)
		(layer "In7.Cu")
		(net "PCIE_COMP_A_TO_SCC_A_5_DN")
	)
	(segment
		(start 241.430302 -156.549852)
		(end 241.576098 -156.259784)
		(width 0.127)
		(layer "In7.Cu")
		(net "PCIE_COMP_A_TO_SCC_A_5_DN")
	)
	(segment
		(start 242.057174 -157.360112)
		(end 241.430302 -156.73324)
		(width 0.127)
		(layer "In7.Cu")
		(net "PCIE_COMP_A_TO_SCC_A_5_DN")
	)
	(segment
		(start 285.436564 -254.70231)
		(end 285.869888 -254.70231)
		(width 0.127)
		(layer "In7.Cu")
		(net "PCIE_COMP_A_TO_SCC_A_5_DN")
	)
	(segment
		(start 243.210334 -157.360112)
		(end 242.057174 -157.360112)
		(width 0.127)
		(layer "In7.Cu")
		(net "PCIE_COMP_A_TO_SCC_A_5_DN")
	)
	(segment
		(start 291.308028 -252.839728)
		(end 291.692838 -251.588524)
		(width 0.127)
		(layer "In7.Cu")
		(net "PCIE_COMP_A_TO_SCC_A_5_DN")
	)
	(segment
		(start 290.91763 -254.109474)
		(end 291.308028 -252.839728)
		(width 0.127)
		(layer "In7.Cu")
		(net "PCIE_COMP_A_TO_SCC_A_5_DN")
	)
	(segment
		(start 293.806372 -230.51897)
		(end 291.428932 -219.793566)
		(width 0.127)
		(layer "In7.Cu")
		(net "PCIE_COMP_A_TO_SCC_A_5_DN")
	)
	(segment
		(start 257.42519 -166.415974)
		(end 243.210334 -157.360112)
		(width 0.127)
		(layer "In7.Cu")
		(net "PCIE_COMP_A_TO_SCC_A_5_DN")
	)
	(segment
		(start 291.428932 -219.793566)
		(end 257.42519 -166.415974)
		(width 0.127)
		(layer "In7.Cu")
		(net "PCIE_COMP_A_TO_SCC_A_5_DN")
	)
	(segment
		(start 291.692838 -251.588524)
		(end 290.338256 -246.160544)
		(width 0.127)
		(layer "In7.Cu")
		(net "PCIE_COMP_A_TO_SCC_A_5_DN")
	)
	(segment
		(start 290.338256 -246.160544)
		(end 293.806372 -230.51897)
		(width 0.127)
		(layer "In7.Cu")
		(net "PCIE_COMP_A_TO_SCC_A_5_DN")
	)
	(segment
		(start 288.554668 -255.741932)
		(end 290.91763 -254.109474)
		(width 0.127)
		(layer "In7.Cu")
		(net "PCIE_COMP_A_TO_SCC_A_5_DN")
	)
	(segment
		(start 241.576098 -156.259784)
		(end 241.589052 -156.233622)
		(width 0.127)
		(layer "In7.Cu")
		(net "PCIE_COMP_A_TO_SCC_A_5_DN")
	)
	(segment
		(start 285.996888 -254.82931)
		(end 285.996888 -255.303274)
		(width 0.127)
		(layer "In7.Cu")
		(net "PCIE_COMP_A_TO_SCC_A_5_DN")
	)
	(arc
		(start 241.430302 -156.73324)
		(mid 241.392321 -156.641546)
		(end 241.430302 -156.549852)
		(width 0.127)
		(layer "In7.Cu")
		(net "PCIE_COMP_A_TO_SCC_A_5_DN")
	)
	(arc
		(start 241.61242 -156.187648)
		(mid 241.693444 -156.117059)
		(end 241.800634 -156.124656)
		(width 0.127)
		(layer "In7.Cu")
		(net "PCIE_COMP_A_TO_SCC_A_5_DN")
	)
	(arc
		(start 285.869888 -254.70231)
		(mid 285.959691 -254.739507)
		(end 285.996888 -254.82931)
		(width 0.127)
		(layer "In7.Cu")
		(net "PCIE_COMP_A_TO_SCC_A_5_DN")
	)
	(arc
		(start 285.996888 -255.303274)
		(mid 286.125368 -255.613452)
		(end 286.435546 -255.741932)
		(width 0.127)
		(layer "In7.Cu")
		(net "PCIE_COMP_A_TO_SCC_A_5_DN")
	)
	(segment
		(start 241.325908 -152.13457)
		(end 241.326162 -152.13457)
		(width 0.127)
		(layer "In7.Cu")
		(net "PCIE_COMP_A_TO_SCC_A_4_DP")
	)
	(segment
		(start 255.875536 -161.777172)
		(end 243.101876 -153.63952)
		(width 0.127)
		(layer "In7.Cu")
		(net "PCIE_COMP_A_TO_SCC_A_4_DP")
	)
	(segment
		(start 291.277548 -246.113046)
		(end 291.360098 -245.74119)
		(width 0.127)
		(layer "In7.Cu")
		(net "PCIE_COMP_A_TO_SCC_A_4_DP")
	)
	(segment
		(start 294.104314 -232.670096)
		(end 294.28313 -232.55605)
		(width 0.127)
		(layer "In7.Cu")
		(net "PCIE_COMP_A_TO_SCC_A_4_DP")
	)
	(segment
		(start 293.67607 -235.293916)
		(end 293.562278 -235.1151)
		(width 0.127)
		(layer "In7.Cu")
		(net "PCIE_COMP_A_TO_SCC_A_4_DP")
	)
	(segment
		(start 241.194844 -152.395428)
		(end 241.325908 -152.134824)
		(width 0.127)
		(layer "In7.Cu")
		(net "PCIE_COMP_A_TO_SCC_A_4_DP")
	)
	(segment
		(start 291.558472 -244.15369)
		(end 291.737288 -244.039898)
		(width 0.127)
		(layer "In7.Cu")
		(net "PCIE_COMP_A_TO_SCC_A_4_DP")
	)
	(segment
		(start 241.325908 -152.134824)
		(end 241.325908 -152.13457)
		(width 0.127)
		(layer "In7.Cu")
		(net "PCIE_COMP_A_TO_SCC_A_4_DP")
	)
	(segment
		(start 241.326162 -152.13457)
		(end 241.367818 -152.051512)
		(width 0.127)
		(layer "In7.Cu")
		(net "PCIE_COMP_A_TO_SCC_A_4_DP")
	)
	(segment
		(start 291.475922 -244.5258)
		(end 291.558472 -244.15369)
		(width 0.127)
		(layer "In7.Cu")
		(net "PCIE_COMP_A_TO_SCC_A_4_DP")
	)
	(segment
		(start 294.022018 -233.041952)
		(end 294.104314 -232.670096)
		(width 0.127)
		(layer "In7.Cu")
		(net "PCIE_COMP_A_TO_SCC_A_4_DP")
	)
	(segment
		(start 291.360098 -245.74119)
		(end 291.246052 -245.562374)
		(width 0.127)
		(layer "In7.Cu")
		(net "PCIE_COMP_A_TO_SCC_A_4_DP")
	)
	(segment
		(start 293.562278 -235.1151)
		(end 293.644828 -234.74299)
		(width 0.127)
		(layer "In7.Cu")
		(net "PCIE_COMP_A_TO_SCC_A_4_DP")
	)
	(segment
		(start 291.85616 -255.277874)
		(end 292.799262 -252.210824)
		(width 0.127)
		(layer "In7.Cu")
		(net "PCIE_COMP_A_TO_SCC_A_4_DP")
	)
	(segment
		(start 292.439852 -219.168726)
		(end 255.875536 -161.777172)
		(width 0.127)
		(layer "In7.Cu")
		(net "PCIE_COMP_A_TO_SCC_A_4_DP")
	)
	(segment
		(start 291.246052 -245.562374)
		(end 291.328602 -245.190264)
		(width 0.127)
		(layer "In7.Cu")
		(net "PCIE_COMP_A_TO_SCC_A_4_DP")
	)
	(segment
		(start 292.799262 -252.210824)
		(end 291.277548 -246.113046)
		(width 0.127)
		(layer "In7.Cu")
		(net "PCIE_COMP_A_TO_SCC_A_4_DP")
	)
	(segment
		(start 294.13581 -233.220768)
		(end 294.022018 -233.041952)
		(width 0.127)
		(layer "In7.Cu")
		(net "PCIE_COMP_A_TO_SCC_A_4_DP")
	)
	(segment
		(start 241.311176 -151.881078)
		(end 240.549938 -151.499824)
		(width 0.127)
		(layer "In7.Cu")
		(net "PCIE_COMP_A_TO_SCC_A_4_DP")
	)
	(segment
		(start 287.276286 -256.629408)
		(end 287.276286 -257.103372)
		(width 0.127)
		(layer "In7.Cu")
		(net "PCIE_COMP_A_TO_SCC_A_4_DP")
	)
	(segment
		(start 293.823644 -234.629198)
		(end 293.90594 -234.257342)
		(width 0.127)
		(layer "In7.Cu")
		(net "PCIE_COMP_A_TO_SCC_A_4_DP")
	)
	(segment
		(start 294.845486 -230.01986)
		(end 292.439852 -219.168726)
		(width 0.127)
		(layer "In7.Cu")
		(net "PCIE_COMP_A_TO_SCC_A_4_DP")
	)
	(segment
		(start 291.507418 -245.076472)
		(end 291.589714 -244.704616)
		(width 0.127)
		(layer "In7.Cu")
		(net "PCIE_COMP_A_TO_SCC_A_4_DP")
	)
	(segment
		(start 287.435544 -257.26263)
		(end 288.986722 -257.26263)
		(width 0.127)
		(layer "In7.Cu")
		(net "PCIE_COMP_A_TO_SCC_A_4_DP")
	)
	(segment
		(start 291.819584 -243.668042)
		(end 291.705792 -243.489226)
		(width 0.127)
		(layer "In7.Cu")
		(net "PCIE_COMP_A_TO_SCC_A_4_DP")
	)
	(segment
		(start 241.94135 -153.63952)
		(end 241.23269 -152.93086)
		(width 0.127)
		(layer "In7.Cu")
		(net "PCIE_COMP_A_TO_SCC_A_4_DP")
	)
	(segment
		(start 293.644828 -234.74299)
		(end 293.823644 -234.629198)
		(width 0.127)
		(layer "In7.Cu")
		(net "PCIE_COMP_A_TO_SCC_A_4_DP")
	)
	(segment
		(start 287.83661 -256.502408)
		(end 287.403286 -256.502408)
		(width 0.127)
		(layer "In7.Cu")
		(net "PCIE_COMP_A_TO_SCC_A_4_DP")
	)
	(segment
		(start 293.874698 -233.706416)
		(end 294.05326 -233.592624)
		(width 0.127)
		(layer "In7.Cu")
		(net "PCIE_COMP_A_TO_SCC_A_4_DP")
	)
	(segment
		(start 293.90594 -234.257342)
		(end 293.792148 -234.078526)
		(width 0.127)
		(layer "In7.Cu")
		(net "PCIE_COMP_A_TO_SCC_A_4_DP")
	)
	(segment
		(start 293.792148 -234.078526)
		(end 293.874698 -233.706416)
		(width 0.127)
		(layer "In7.Cu")
		(net "PCIE_COMP_A_TO_SCC_A_4_DP")
	)
	(segment
		(start 291.589714 -244.704616)
		(end 291.475922 -244.5258)
		(width 0.127)
		(layer "In7.Cu")
		(net "PCIE_COMP_A_TO_SCC_A_4_DP")
	)
	(segment
		(start 291.737288 -244.039898)
		(end 291.819584 -243.668042)
		(width 0.127)
		(layer "In7.Cu")
		(net "PCIE_COMP_A_TO_SCC_A_4_DP")
	)
	(segment
		(start 291.328602 -245.190264)
		(end 291.507418 -245.076472)
		(width 0.127)
		(layer "In7.Cu")
		(net "PCIE_COMP_A_TO_SCC_A_4_DP")
	)
	(segment
		(start 291.966904 -243.003324)
		(end 293.67607 -235.293916)
		(width 0.127)
		(layer "In7.Cu")
		(net "PCIE_COMP_A_TO_SCC_A_4_DP")
	)
	(segment
		(start 294.05326 -233.592624)
		(end 294.13581 -233.220768)
		(width 0.127)
		(layer "In7.Cu")
		(net "PCIE_COMP_A_TO_SCC_A_4_DP")
	)
	(segment
		(start 291.788342 -243.11737)
		(end 291.966904 -243.003324)
		(width 0.127)
		(layer "In7.Cu")
		(net "PCIE_COMP_A_TO_SCC_A_4_DP")
	)
	(segment
		(start 243.101876 -153.63952)
		(end 241.94135 -153.63952)
		(width 0.127)
		(layer "In7.Cu")
		(net "PCIE_COMP_A_TO_SCC_A_4_DP")
	)
	(segment
		(start 288.986722 -257.26263)
		(end 291.85616 -255.277874)
		(width 0.127)
		(layer "In7.Cu")
		(net "PCIE_COMP_A_TO_SCC_A_4_DP")
	)
	(segment
		(start 294.28313 -232.55605)
		(end 294.845486 -230.01986)
		(width 0.127)
		(layer "In7.Cu")
		(net "PCIE_COMP_A_TO_SCC_A_4_DP")
	)
	(segment
		(start 291.705792 -243.489226)
		(end 291.788342 -243.11737)
		(width 0.127)
		(layer "In7.Cu")
		(net "PCIE_COMP_A_TO_SCC_A_4_DP")
	)
	(arc
		(start 241.23269 -152.93086)
		(mid 241.113698 -152.670203)
		(end 241.194844 -152.395428)
		(width 0.127)
		(layer "In7.Cu")
		(net "PCIE_COMP_A_TO_SCC_A_4_DP")
	)
	(arc
		(start 241.367818 -152.051512)
		(mid 241.374795 -151.954564)
		(end 241.311176 -151.881078)
		(width 0.127)
		(layer "In7.Cu")
		(net "PCIE_COMP_A_TO_SCC_A_4_DP")
	)
	(arc
		(start 287.276286 -257.103372)
		(mid 287.322932 -257.215984)
		(end 287.435544 -257.26263)
		(width 0.127)
		(layer "In7.Cu")
		(net "PCIE_COMP_A_TO_SCC_A_4_DP")
	)
	(arc
		(start 287.403286 -256.502408)
		(mid 287.313483 -256.539605)
		(end 287.276286 -256.629408)
		(width 0.127)
		(layer "In7.Cu")
		(net "PCIE_COMP_A_TO_SCC_A_4_DP")
	)
	(segment
		(start 241.589052 -152.23363)
		(end 241.61242 -152.187656)
		(width 0.127)
		(layer "In7.Cu")
		(net "PCIE_COMP_A_TO_SCC_A_4_DN")
	)
	(segment
		(start 290.580318 -256.500122)
		(end 292.09492 -255.452626)
		(width 0.127)
		(layer "In7.Cu")
		(net "PCIE_COMP_A_TO_SCC_A_4_DN")
	)
	(segment
		(start 291.564822 -246.109236)
		(end 295.131744 -230.01986)
		(width 0.127)
		(layer "In7.Cu")
		(net "PCIE_COMP_A_TO_SCC_A_4_DN")
	)
	(segment
		(start 292.702234 -219.060014)
		(end 256.077974 -161.574734)
		(width 0.127)
		(layer "In7.Cu")
		(net "PCIE_COMP_A_TO_SCC_A_4_DN")
	)
	(segment
		(start 289.074098 -257.54203)
		(end 290.580318 -256.500122)
		(width 0.127)
		(layer "In7.Cu")
		(net "PCIE_COMP_A_TO_SCC_A_4_DN")
	)
	(segment
		(start 241.800634 -152.124664)
		(end 242.549934 -152.499822)
		(width 0.127)
		(layer "In7.Cu")
		(net "PCIE_COMP_A_TO_SCC_A_4_DN")
	)
	(segment
		(start 243.18341 -153.36012)
		(end 242.057174 -153.36012)
		(width 0.127)
		(layer "In7.Cu")
		(net "PCIE_COMP_A_TO_SCC_A_4_DN")
	)
	(segment
		(start 286.996886 -256.629408)
		(end 286.996886 -257.103372)
		(width 0.127)
		(layer "In7.Cu")
		(net "PCIE_COMP_A_TO_SCC_A_4_DN")
	)
	(segment
		(start 242.057174 -153.36012)
		(end 241.430302 -152.733248)
		(width 0.127)
		(layer "In7.Cu")
		(net "PCIE_COMP_A_TO_SCC_A_4_DN")
	)
	(segment
		(start 241.576098 -152.259792)
		(end 241.589052 -152.23363)
		(width 0.127)
		(layer "In7.Cu")
		(net "PCIE_COMP_A_TO_SCC_A_4_DN")
	)
	(segment
		(start 293.08933 -252.218698)
		(end 291.564822 -246.109236)
		(width 0.127)
		(layer "In7.Cu")
		(net "PCIE_COMP_A_TO_SCC_A_4_DN")
	)
	(segment
		(start 256.077974 -161.574734)
		(end 243.18341 -153.36012)
		(width 0.127)
		(layer "In7.Cu")
		(net "PCIE_COMP_A_TO_SCC_A_4_DN")
	)
	(segment
		(start 295.131744 -230.01986)
		(end 292.702234 -219.060014)
		(width 0.127)
		(layer "In7.Cu")
		(net "PCIE_COMP_A_TO_SCC_A_4_DN")
	)
	(segment
		(start 292.09492 -255.452626)
		(end 293.08933 -252.218698)
		(width 0.127)
		(layer "In7.Cu")
		(net "PCIE_COMP_A_TO_SCC_A_4_DN")
	)
	(segment
		(start 287.435544 -257.54203)
		(end 289.074098 -257.54203)
		(width 0.127)
		(layer "In7.Cu")
		(net "PCIE_COMP_A_TO_SCC_A_4_DN")
	)
	(segment
		(start 286.436562 -256.502408)
		(end 286.869886 -256.502408)
		(width 0.127)
		(layer "In7.Cu")
		(net "PCIE_COMP_A_TO_SCC_A_4_DN")
	)
	(segment
		(start 241.430302 -152.54986)
		(end 241.576098 -152.259792)
		(width 0.127)
		(layer "In7.Cu")
		(net "PCIE_COMP_A_TO_SCC_A_4_DN")
	)
	(arc
		(start 286.996886 -257.103372)
		(mid 287.125366 -257.41355)
		(end 287.435544 -257.54203)
		(width 0.127)
		(layer "In7.Cu")
		(net "PCIE_COMP_A_TO_SCC_A_4_DN")
	)
	(arc
		(start 286.869886 -256.502408)
		(mid 286.959689 -256.539605)
		(end 286.996886 -256.629408)
		(width 0.127)
		(layer "In7.Cu")
		(net "PCIE_COMP_A_TO_SCC_A_4_DN")
	)
	(arc
		(start 241.61242 -152.187656)
		(mid 241.693444 -152.117067)
		(end 241.800634 -152.124664)
		(width 0.127)
		(layer "In7.Cu")
		(net "PCIE_COMP_A_TO_SCC_A_4_DN")
	)
	(arc
		(start 241.430302 -152.733248)
		(mid 241.392321 -152.641554)
		(end 241.430302 -152.54986)
		(width 0.127)
		(layer "In7.Cu")
		(net "PCIE_COMP_A_TO_SCC_A_4_DN")
	)
	(segment
		(start 292.565074 -215.801956)
		(end 292.357556 -215.482424)
		(width 0.127)
		(layer "In7.Cu")
		(net "PCIE_COMP_A_TO_SCC_A_3_DP")
	)
	(segment
		(start 286.276288 -258.429252)
		(end 286.276288 -258.903216)
		(width 0.127)
		(layer "In7.Cu")
		(net "PCIE_COMP_A_TO_SCC_A_3_DP")
	)
	(segment
		(start 305.38166 -235.537502)
		(end 305.174142 -235.21797)
		(width 0.127)
		(layer "In7.Cu")
		(net "PCIE_COMP_A_TO_SCC_A_3_DP")
	)
	(segment
		(start 305.588924 -235.581698)
		(end 305.38166 -235.537502)
		(width 0.127)
		(layer "In7.Cu")
		(net "PCIE_COMP_A_TO_SCC_A_3_DP")
	)
	(segment
		(start 293.721536 -217.583004)
		(end 293.514018 -217.263472)
		(width 0.127)
		(layer "In7.Cu")
		(net "PCIE_COMP_A_TO_SCC_A_3_DP")
	)
	(segment
		(start 293.929054 -217.626946)
		(end 293.721536 -217.583004)
		(width 0.127)
		(layer "In7.Cu")
		(net "PCIE_COMP_A_TO_SCC_A_3_DP")
	)
	(segment
		(start 241.367818 -128.05156)
		(end 241.367818 -128.051306)
		(width 0.127)
		(layer "In7.Cu")
		(net "PCIE_COMP_A_TO_SCC_A_3_DP")
	)
	(segment
		(start 286.435546 -259.062474)
		(end 290.257738 -259.062474)
		(width 0.127)
		(layer "In7.Cu")
		(net "PCIE_COMP_A_TO_SCC_A_3_DP")
	)
	(segment
		(start 307.454554 -238.454438)
		(end 306.745386 -237.362492)
		(width 0.127)
		(layer "In7.Cu")
		(net "PCIE_COMP_A_TO_SCC_A_3_DP")
	)
	(segment
		(start 252.232922 -141.621002)
		(end 243.970302 -130.387852)
		(width 0.127)
		(layer "In7.Cu")
		(net "PCIE_COMP_A_TO_SCC_A_3_DP")
	)
	(segment
		(start 293.558214 -217.055954)
		(end 293.350696 -216.736422)
		(width 0.127)
		(layer "In7.Cu")
		(net "PCIE_COMP_A_TO_SCC_A_3_DP")
	)
	(segment
		(start 286.836612 -258.302252)
		(end 286.403288 -258.302252)
		(width 0.127)
		(layer "In7.Cu")
		(net "PCIE_COMP_A_TO_SCC_A_3_DP")
	)
	(segment
		(start 242.838986 -129.639568)
		(end 241.953796 -129.639568)
		(width 0.127)
		(layer "In7.Cu")
		(net "PCIE_COMP_A_TO_SCC_A_3_DP")
	)
	(segment
		(start 308.897528 -244.966236)
		(end 307.454554 -238.454438)
		(width 0.127)
		(layer "In7.Cu")
		(net "PCIE_COMP_A_TO_SCC_A_3_DP")
	)
	(segment
		(start 255.73482 -158.812484)
		(end 252.232922 -141.621002)
		(width 0.127)
		(layer "In7.Cu")
		(net "PCIE_COMP_A_TO_SCC_A_3_DP")
	)
	(segment
		(start 302.757078 -256.524506)
		(end 305.79822 -254.702564)
		(width 0.127)
		(layer "In7.Cu")
		(net "PCIE_COMP_A_TO_SCC_A_3_DP")
	)
	(segment
		(start 306.3748 -236.7915)
		(end 306.167282 -236.471968)
		(width 0.127)
		(layer "In7.Cu")
		(net "PCIE_COMP_A_TO_SCC_A_3_DP")
	)
	(segment
		(start 306.330604 -236.999018)
		(end 306.3748 -236.7915)
		(width 0.127)
		(layer "In7.Cu")
		(net "PCIE_COMP_A_TO_SCC_A_3_DP")
	)
	(segment
		(start 292.935914 -216.372948)
		(end 292.979856 -216.165684)
		(width 0.127)
		(layer "In7.Cu")
		(net "PCIE_COMP_A_TO_SCC_A_3_DP")
	)
	(segment
		(start 292.401752 -215.27516)
		(end 255.73482 -158.812484)
		(width 0.127)
		(layer "In7.Cu")
		(net "PCIE_COMP_A_TO_SCC_A_3_DP")
	)
	(segment
		(start 241.164364 -128.455166)
		(end 241.367818 -128.05156)
		(width 0.127)
		(layer "In7.Cu")
		(net "PCIE_COMP_A_TO_SCC_A_3_DP")
	)
	(segment
		(start 290.257738 -259.062474)
		(end 302.757078 -256.524506)
		(width 0.127)
		(layer "In7.Cu")
		(net "PCIE_COMP_A_TO_SCC_A_3_DP")
	)
	(segment
		(start 241.953796 -129.639568)
		(end 241.240056 -128.925828)
		(width 0.127)
		(layer "In7.Cu")
		(net "PCIE_COMP_A_TO_SCC_A_3_DP")
	)
	(segment
		(start 293.350696 -216.736422)
		(end 293.143432 -216.69248)
		(width 0.127)
		(layer "In7.Cu")
		(net "PCIE_COMP_A_TO_SCC_A_3_DP")
	)
	(segment
		(start 306.538122 -237.31855)
		(end 306.330604 -236.999018)
		(width 0.127)
		(layer "In7.Cu")
		(net "PCIE_COMP_A_TO_SCC_A_3_DP")
	)
	(segment
		(start 306.745386 -237.362492)
		(end 306.538122 -237.31855)
		(width 0.127)
		(layer "In7.Cu")
		(net "PCIE_COMP_A_TO_SCC_A_3_DP")
	)
	(segment
		(start 293.514018 -217.263472)
		(end 293.558214 -217.055954)
		(width 0.127)
		(layer "In7.Cu")
		(net "PCIE_COMP_A_TO_SCC_A_3_DP")
	)
	(segment
		(start 241.311176 -127.880872)
		(end 240.549938 -127.499872)
		(width 0.127)
		(layer "In7.Cu")
		(net "PCIE_COMP_A_TO_SCC_A_3_DP")
	)
	(segment
		(start 305.174142 -235.21797)
		(end 305.218084 -235.010706)
		(width 0.127)
		(layer "In7.Cu")
		(net "PCIE_COMP_A_TO_SCC_A_3_DP")
	)
	(segment
		(start 305.218084 -235.010706)
		(end 293.929054 -217.626946)
		(width 0.127)
		(layer "In7.Cu")
		(net "PCIE_COMP_A_TO_SCC_A_3_DP")
	)
	(segment
		(start 292.979856 -216.165684)
		(end 292.772338 -215.846152)
		(width 0.127)
		(layer "In7.Cu")
		(net "PCIE_COMP_A_TO_SCC_A_3_DP")
	)
	(segment
		(start 305.959764 -236.428026)
		(end 305.7525 -236.108494)
		(width 0.127)
		(layer "In7.Cu")
		(net "PCIE_COMP_A_TO_SCC_A_3_DP")
	)
	(segment
		(start 306.167282 -236.471968)
		(end 305.959764 -236.428026)
		(width 0.127)
		(layer "In7.Cu")
		(net "PCIE_COMP_A_TO_SCC_A_3_DP")
	)
	(segment
		(start 305.796442 -235.90123)
		(end 305.588924 -235.581698)
		(width 0.127)
		(layer "In7.Cu")
		(net "PCIE_COMP_A_TO_SCC_A_3_DP")
	)
	(segment
		(start 307.328062 -252.34646)
		(end 308.897528 -244.966236)
		(width 0.127)
		(layer "In7.Cu")
		(net "PCIE_COMP_A_TO_SCC_A_3_DP")
	)
	(segment
		(start 305.79822 -254.702564)
		(end 307.328062 -252.34646)
		(width 0.127)
		(layer "In7.Cu")
		(net "PCIE_COMP_A_TO_SCC_A_3_DP")
	)
	(segment
		(start 293.143432 -216.69248)
		(end 292.935914 -216.372948)
		(width 0.127)
		(layer "In7.Cu")
		(net "PCIE_COMP_A_TO_SCC_A_3_DP")
	)
	(segment
		(start 292.772338 -215.846152)
		(end 292.565074 -215.801956)
		(width 0.127)
		(layer "In7.Cu")
		(net "PCIE_COMP_A_TO_SCC_A_3_DP")
	)
	(segment
		(start 305.7525 -236.108494)
		(end 305.796442 -235.90123)
		(width 0.127)
		(layer "In7.Cu")
		(net "PCIE_COMP_A_TO_SCC_A_3_DP")
	)
	(segment
		(start 292.357556 -215.482424)
		(end 292.401752 -215.27516)
		(width 0.127)
		(layer "In7.Cu")
		(net "PCIE_COMP_A_TO_SCC_A_3_DP")
	)
	(segment
		(start 243.970302 -130.387852)
		(end 242.838986 -129.639568)
		(width 0.127)
		(layer "In7.Cu")
		(net "PCIE_COMP_A_TO_SCC_A_3_DP")
	)
	(arc
		(start 241.367818 -128.051306)
		(mid 241.374795 -127.954358)
		(end 241.311176 -127.880872)
		(width 0.127)
		(layer "In7.Cu")
		(net "PCIE_COMP_A_TO_SCC_A_3_DP")
	)
	(arc
		(start 286.403288 -258.302252)
		(mid 286.313485 -258.339449)
		(end 286.276288 -258.429252)
		(width 0.127)
		(layer "In7.Cu")
		(net "PCIE_COMP_A_TO_SCC_A_3_DP")
	)
	(arc
		(start 241.240056 -128.925828)
		(mid 241.126028 -128.702765)
		(end 241.164364 -128.455166)
		(width 0.127)
		(layer "In7.Cu")
		(net "PCIE_COMP_A_TO_SCC_A_3_DP")
	)
	(arc
		(start 286.276288 -258.903216)
		(mid 286.322934 -259.015828)
		(end 286.435546 -259.062474)
		(width 0.127)
		(layer "In7.Cu")
		(net "PCIE_COMP_A_TO_SCC_A_3_DP")
	)
	(segment
		(start 241.414046 -128.58115)
		(end 241.617754 -128.177036)
		(width 0.127)
		(layer "In7.Cu")
		(net "PCIE_COMP_A_TO_SCC_A_3_DN")
	)
	(segment
		(start 241.618262 -128.175766)
		(end 241.618262 -128.175512)
		(width 0.127)
		(layer "In7.Cu")
		(net "PCIE_COMP_A_TO_SCC_A_3_DN")
	)
	(segment
		(start 253.820168 -148.012658)
		(end 252.494542 -141.504924)
		(width 0.127)
		(layer "In7.Cu")
		(net "PCIE_COMP_A_TO_SCC_A_3_DN")
	)
	(segment
		(start 307.590698 -252.455172)
		(end 309.183532 -244.964966)
		(width 0.127)
		(layer "In7.Cu")
		(net "PCIE_COMP_A_TO_SCC_A_3_DN")
	)
	(segment
		(start 255.998218 -158.704788)
		(end 254.25781 -150.161244)
		(width 0.127)
		(layer "In7.Cu")
		(net "PCIE_COMP_A_TO_SCC_A_3_DN")
	)
	(segment
		(start 242.06962 -129.360168)
		(end 241.437668 -128.728216)
		(width 0.127)
		(layer "In7.Cu")
		(net "PCIE_COMP_A_TO_SCC_A_3_DN")
	)
	(segment
		(start 285.436564 -258.302252)
		(end 285.869888 -258.302252)
		(width 0.127)
		(layer "In7.Cu")
		(net "PCIE_COMP_A_TO_SCC_A_3_DN")
	)
	(segment
		(start 241.788696 -128.11887)
		(end 242.549934 -128.49987)
		(width 0.127)
		(layer "In7.Cu")
		(net "PCIE_COMP_A_TO_SCC_A_3_DN")
	)
	(segment
		(start 244.166136 -130.182112)
		(end 242.92306 -129.360168)
		(width 0.127)
		(layer "In7.Cu")
		(net "PCIE_COMP_A_TO_SCC_A_3_DN")
	)
	(segment
		(start 242.92306 -129.360168)
		(end 242.06962 -129.360168)
		(width 0.127)
		(layer "In7.Cu")
		(net "PCIE_COMP_A_TO_SCC_A_3_DN")
	)
	(segment
		(start 302.859694 -256.78892)
		(end 305.997356 -254.909066)
		(width 0.127)
		(layer "In7.Cu")
		(net "PCIE_COMP_A_TO_SCC_A_3_DN")
	)
	(segment
		(start 305.997356 -254.909066)
		(end 307.590698 -252.455172)
		(width 0.127)
		(layer "In7.Cu")
		(net "PCIE_COMP_A_TO_SCC_A_3_DN")
	)
	(segment
		(start 307.716682 -238.344456)
		(end 255.998218 -158.704788)
		(width 0.127)
		(layer "In7.Cu")
		(net "PCIE_COMP_A_TO_SCC_A_3_DN")
	)
	(segment
		(start 309.183532 -244.964966)
		(end 307.716682 -238.344456)
		(width 0.127)
		(layer "In7.Cu")
		(net "PCIE_COMP_A_TO_SCC_A_3_DN")
	)
	(segment
		(start 252.494542 -141.504924)
		(end 244.166136 -130.182112)
		(width 0.127)
		(layer "In7.Cu")
		(net "PCIE_COMP_A_TO_SCC_A_3_DN")
	)
	(segment
		(start 290.285932 -259.341874)
		(end 302.859694 -256.78892)
		(width 0.127)
		(layer "In7.Cu")
		(net "PCIE_COMP_A_TO_SCC_A_3_DN")
	)
	(segment
		(start 241.617754 -128.177036)
		(end 241.617754 -128.176782)
		(width 0.127)
		(layer "In7.Cu")
		(net "PCIE_COMP_A_TO_SCC_A_3_DN")
	)
	(segment
		(start 241.617754 -128.176782)
		(end 241.618262 -128.175766)
		(width 0.127)
		(layer "In7.Cu")
		(net "PCIE_COMP_A_TO_SCC_A_3_DN")
	)
	(segment
		(start 286.435546 -259.341874)
		(end 290.285932 -259.341874)
		(width 0.127)
		(layer "In7.Cu")
		(net "PCIE_COMP_A_TO_SCC_A_3_DN")
	)
	(segment
		(start 254.25781 -150.161244)
		(end 253.820168 -148.012658)
		(width 0.127)
		(layer "In7.Cu")
		(net "PCIE_COMP_A_TO_SCC_A_3_DN")
	)
	(segment
		(start 285.996888 -258.429252)
		(end 285.996888 -258.903216)
		(width 0.127)
		(layer "In7.Cu")
		(net "PCIE_COMP_A_TO_SCC_A_3_DN")
	)
	(arc
		(start 285.996888 -258.903216)
		(mid 286.125368 -259.213394)
		(end 286.435546 -259.341874)
		(width 0.127)
		(layer "In7.Cu")
		(net "PCIE_COMP_A_TO_SCC_A_3_DN")
	)
	(arc
		(start 241.618262 -128.175512)
		(mid 241.691748 -128.111893)
		(end 241.788696 -128.11887)
		(width 0.127)
		(layer "In7.Cu")
		(net "PCIE_COMP_A_TO_SCC_A_3_DN")
	)
	(arc
		(start 285.869888 -258.302252)
		(mid 285.959691 -258.339449)
		(end 285.996888 -258.429252)
		(width 0.127)
		(layer "In7.Cu")
		(net "PCIE_COMP_A_TO_SCC_A_3_DN")
	)
	(arc
		(start 241.437668 -128.728216)
		(mid 241.402038 -128.658501)
		(end 241.414046 -128.58115)
		(width 0.127)
		(layer "In7.Cu")
		(net "PCIE_COMP_A_TO_SCC_A_3_DN")
	)
	(segment
		(start 308.559454 -237.448598)
		(end 257.259582 -158.442914)
		(width 0.127)
		(layer "In7.Cu")
		(net "PCIE_COMP_A_TO_SCC_A_2_DP")
	)
	(segment
		(start 309.268114 -249.644408)
		(end 309.152798 -249.466608)
		(width 0.127)
		(layer "In7.Cu")
		(net "PCIE_COMP_A_TO_SCC_A_2_DP")
	)
	(segment
		(start 309.851298 -246.901462)
		(end 310.244744 -245.052088)
		(width 0.127)
		(layer "In7.Cu")
		(net "PCIE_COMP_A_TO_SCC_A_2_DP")
	)
	(segment
		(start 302.569118 -258.315968)
		(end 306.92725 -255.70434)
		(width 0.127)
		(layer "In7.Cu")
		(net "PCIE_COMP_A_TO_SCC_A_2_DP")
	)
	(segment
		(start 242.82781 -125.639576)
		(end 241.94135 -125.639576)
		(width 0.127)
		(layer "In7.Cu")
		(net "PCIE_COMP_A_TO_SCC_A_2_DP")
	)
	(segment
		(start 310.244744 -245.052088)
		(end 308.559454 -237.448598)
		(width 0.127)
		(layer "In7.Cu")
		(net "PCIE_COMP_A_TO_SCC_A_2_DP")
	)
	(segment
		(start 309.452772 -248.055384)
		(end 309.630572 -247.940068)
		(width 0.127)
		(layer "In7.Cu")
		(net "PCIE_COMP_A_TO_SCC_A_2_DP")
	)
	(segment
		(start 243.69141 -126.153672)
		(end 242.82781 -125.639576)
		(width 0.127)
		(layer "In7.Cu")
		(net "PCIE_COMP_A_TO_SCC_A_2_DP")
	)
	(segment
		(start 296.790364 -259.489194)
		(end 297.163744 -259.413248)
		(width 0.127)
		(layer "In7.Cu")
		(net "PCIE_COMP_A_TO_SCC_A_2_DP")
	)
	(segment
		(start 287.276286 -260.22935)
		(end 287.276286 -260.703314)
		(width 0.127)
		(layer "In7.Cu")
		(net "PCIE_COMP_A_TO_SCC_A_2_DP")
	)
	(segment
		(start 241.325908 -124.13488)
		(end 241.325908 -124.134626)
		(width 0.127)
		(layer "In7.Cu")
		(net "PCIE_COMP_A_TO_SCC_A_2_DP")
	)
	(segment
		(start 309.48884 -248.605802)
		(end 309.373524 -248.428256)
		(width 0.127)
		(layer "In7.Cu")
		(net "PCIE_COMP_A_TO_SCC_A_2_DP")
	)
	(segment
		(start 297.654218 -259.160772)
		(end 297.830748 -259.277866)
		(width 0.127)
		(layer "In7.Cu")
		(net "PCIE_COMP_A_TO_SCC_A_2_DP")
	)
	(segment
		(start 309.594504 -247.38965)
		(end 309.673752 -247.017032)
		(width 0.127)
		(layer "In7.Cu")
		(net "PCIE_COMP_A_TO_SCC_A_2_DP")
	)
	(segment
		(start 309.152798 -249.466608)
		(end 309.232046 -249.09399)
		(width 0.127)
		(layer "In7.Cu")
		(net "PCIE_COMP_A_TO_SCC_A_2_DP")
	)
	(segment
		(start 295.082722 -259.835904)
		(end 295.199816 -259.65912)
		(width 0.127)
		(layer "In7.Cu")
		(net "PCIE_COMP_A_TO_SCC_A_2_DP")
	)
	(segment
		(start 306.92725 -255.70434)
		(end 308.491636 -253.295658)
		(width 0.127)
		(layer "In7.Cu")
		(net "PCIE_COMP_A_TO_SCC_A_2_DP")
	)
	(segment
		(start 241.311176 -123.881134)
		(end 240.549938 -123.49988)
		(width 0.127)
		(layer "In7.Cu")
		(net "PCIE_COMP_A_TO_SCC_A_2_DP")
	)
	(segment
		(start 257.259582 -158.442914)
		(end 253.328678 -139.256008)
		(width 0.127)
		(layer "In7.Cu")
		(net "PCIE_COMP_A_TO_SCC_A_2_DP")
	)
	(segment
		(start 297.830748 -259.277866)
		(end 302.569118 -258.315968)
		(width 0.127)
		(layer "In7.Cu")
		(net "PCIE_COMP_A_TO_SCC_A_2_DP")
	)
	(segment
		(start 287.435544 -260.862572)
		(end 290.025328 -260.862572)
		(width 0.127)
		(layer "In7.Cu")
		(net "PCIE_COMP_A_TO_SCC_A_2_DP")
	)
	(segment
		(start 297.280838 -259.236718)
		(end 297.654218 -259.160772)
		(width 0.127)
		(layer "In7.Cu")
		(net "PCIE_COMP_A_TO_SCC_A_2_DP")
	)
	(segment
		(start 309.409592 -248.978674)
		(end 309.48884 -248.605802)
		(width 0.127)
		(layer "In7.Cu")
		(net "PCIE_COMP_A_TO_SCC_A_2_DP")
	)
	(segment
		(start 241.325908 -124.134626)
		(end 241.326162 -124.134626)
		(width 0.127)
		(layer "In7.Cu")
		(net "PCIE_COMP_A_TO_SCC_A_2_DP")
	)
	(segment
		(start 295.749726 -259.700268)
		(end 296.123106 -259.624576)
		(width 0.127)
		(layer "In7.Cu")
		(net "PCIE_COMP_A_TO_SCC_A_2_DP")
	)
	(segment
		(start 309.70982 -247.56745)
		(end 309.594504 -247.38965)
		(width 0.127)
		(layer "In7.Cu")
		(net "PCIE_COMP_A_TO_SCC_A_2_DP")
	)
	(segment
		(start 309.373524 -248.428256)
		(end 309.452772 -248.055384)
		(width 0.127)
		(layer "In7.Cu")
		(net "PCIE_COMP_A_TO_SCC_A_2_DP")
	)
	(segment
		(start 253.328678 -139.256008)
		(end 243.69141 -126.153672)
		(width 0.127)
		(layer "In7.Cu")
		(net "PCIE_COMP_A_TO_SCC_A_2_DP")
	)
	(segment
		(start 287.83661 -260.10235)
		(end 287.403286 -260.10235)
		(width 0.127)
		(layer "In7.Cu")
		(net "PCIE_COMP_A_TO_SCC_A_2_DP")
	)
	(segment
		(start 309.673752 -247.017032)
		(end 309.851298 -246.901462)
		(width 0.127)
		(layer "In7.Cu")
		(net "PCIE_COMP_A_TO_SCC_A_2_DP")
	)
	(segment
		(start 241.194844 -124.395484)
		(end 241.325908 -124.13488)
		(width 0.127)
		(layer "In7.Cu")
		(net "PCIE_COMP_A_TO_SCC_A_2_DP")
	)
	(segment
		(start 241.326162 -124.134626)
		(end 241.367818 -124.051568)
		(width 0.127)
		(layer "In7.Cu")
		(net "PCIE_COMP_A_TO_SCC_A_2_DP")
	)
	(segment
		(start 296.2402 -259.447792)
		(end 296.61358 -259.3721)
		(width 0.127)
		(layer "In7.Cu")
		(net "PCIE_COMP_A_TO_SCC_A_2_DP")
	)
	(segment
		(start 241.94135 -125.639576)
		(end 241.23269 -124.930916)
		(width 0.127)
		(layer "In7.Cu")
		(net "PCIE_COMP_A_TO_SCC_A_2_DP")
	)
	(segment
		(start 297.163744 -259.413248)
		(end 297.280838 -259.236718)
		(width 0.127)
		(layer "In7.Cu")
		(net "PCIE_COMP_A_TO_SCC_A_2_DP")
	)
	(segment
		(start 295.573196 -259.583428)
		(end 295.749726 -259.700268)
		(width 0.127)
		(layer "In7.Cu")
		(net "PCIE_COMP_A_TO_SCC_A_2_DP")
	)
	(segment
		(start 296.123106 -259.624576)
		(end 296.2402 -259.447792)
		(width 0.127)
		(layer "In7.Cu")
		(net "PCIE_COMP_A_TO_SCC_A_2_DP")
	)
	(segment
		(start 290.025328 -260.862572)
		(end 295.082722 -259.835904)
		(width 0.127)
		(layer "In7.Cu")
		(net "PCIE_COMP_A_TO_SCC_A_2_DP")
	)
	(segment
		(start 309.232046 -249.09399)
		(end 309.409592 -248.978674)
		(width 0.127)
		(layer "In7.Cu")
		(net "PCIE_COMP_A_TO_SCC_A_2_DP")
	)
	(segment
		(start 309.630572 -247.940068)
		(end 309.70982 -247.56745)
		(width 0.127)
		(layer "In7.Cu")
		(net "PCIE_COMP_A_TO_SCC_A_2_DP")
	)
	(segment
		(start 295.199816 -259.65912)
		(end 295.573196 -259.583428)
		(width 0.127)
		(layer "In7.Cu")
		(net "PCIE_COMP_A_TO_SCC_A_2_DP")
	)
	(segment
		(start 296.61358 -259.3721)
		(end 296.790364 -259.489194)
		(width 0.127)
		(layer "In7.Cu")
		(net "PCIE_COMP_A_TO_SCC_A_2_DP")
	)
	(segment
		(start 308.491636 -253.295658)
		(end 309.268114 -249.644408)
		(width 0.127)
		(layer "In7.Cu")
		(net "PCIE_COMP_A_TO_SCC_A_2_DP")
	)
	(arc
		(start 287.276286 -260.703314)
		(mid 287.322932 -260.815926)
		(end 287.435544 -260.862572)
		(width 0.127)
		(layer "In7.Cu")
		(net "PCIE_COMP_A_TO_SCC_A_2_DP")
	)
	(arc
		(start 241.23269 -124.930916)
		(mid 241.113698 -124.670259)
		(end 241.194844 -124.395484)
		(width 0.127)
		(layer "In7.Cu")
		(net "PCIE_COMP_A_TO_SCC_A_2_DP")
	)
	(arc
		(start 241.367818 -124.051568)
		(mid 241.374795 -123.95462)
		(end 241.311176 -123.881134)
		(width 0.127)
		(layer "In7.Cu")
		(net "PCIE_COMP_A_TO_SCC_A_2_DP")
	)
	(arc
		(start 287.403286 -260.10235)
		(mid 287.313483 -260.139547)
		(end 287.276286 -260.22935)
		(width 0.127)
		(layer "In7.Cu")
		(net "PCIE_COMP_A_TO_SCC_A_2_DP")
	)
	(segment
		(start 287.435544 -261.141972)
		(end 290.053522 -261.141972)
		(width 0.127)
		(layer "In7.Cu")
		(net "PCIE_COMP_A_TO_SCC_A_2_DN")
	)
	(segment
		(start 304.891694 -257.24993)
		(end 307.126386 -255.910842)
		(width 0.127)
		(layer "In7.Cu")
		(net "PCIE_COMP_A_TO_SCC_A_2_DN")
	)
	(segment
		(start 242.904772 -125.360176)
		(end 242.057174 -125.360176)
		(width 0.127)
		(layer "In7.Cu")
		(net "PCIE_COMP_A_TO_SCC_A_2_DN")
	)
	(segment
		(start 286.436562 -260.10235)
		(end 286.869886 -260.10235)
		(width 0.127)
		(layer "In7.Cu")
		(net "PCIE_COMP_A_TO_SCC_A_2_DN")
	)
	(segment
		(start 241.430302 -124.549916)
		(end 241.576098 -124.259848)
		(width 0.127)
		(layer "In7.Cu")
		(net "PCIE_COMP_A_TO_SCC_A_2_DN")
	)
	(segment
		(start 308.754272 -253.40437)
		(end 310.530748 -245.050818)
		(width 0.127)
		(layer "In7.Cu")
		(net "PCIE_COMP_A_TO_SCC_A_2_DN")
	)
	(segment
		(start 308.821582 -237.338616)
		(end 283.1719 -197.83679)
		(width 0.127)
		(layer "In7.Cu")
		(net "PCIE_COMP_A_TO_SCC_A_2_DN")
	)
	(segment
		(start 241.589052 -124.233686)
		(end 241.61242 -124.187712)
		(width 0.127)
		(layer "In7.Cu")
		(net "PCIE_COMP_A_TO_SCC_A_2_DN")
	)
	(segment
		(start 290.053522 -261.141972)
		(end 302.671734 -258.580382)
		(width 0.127)
		(layer "In7.Cu")
		(net "PCIE_COMP_A_TO_SCC_A_2_DN")
	)
	(segment
		(start 257.522726 -158.334964)
		(end 253.590298 -139.139676)
		(width 0.127)
		(layer "In7.Cu")
		(net "PCIE_COMP_A_TO_SCC_A_2_DN")
	)
	(segment
		(start 241.800634 -124.12472)
		(end 242.549934 -124.499878)
		(width 0.127)
		(layer "In7.Cu")
		(net "PCIE_COMP_A_TO_SCC_A_2_DN")
	)
	(segment
		(start 307.126386 -255.910842)
		(end 308.754272 -253.40437)
		(width 0.127)
		(layer "In7.Cu")
		(net "PCIE_COMP_A_TO_SCC_A_2_DN")
	)
	(segment
		(start 310.530748 -245.050818)
		(end 308.821582 -237.338616)
		(width 0.127)
		(layer "In7.Cu")
		(net "PCIE_COMP_A_TO_SCC_A_2_DN")
	)
	(segment
		(start 241.576098 -124.259848)
		(end 241.589052 -124.233686)
		(width 0.127)
		(layer "In7.Cu")
		(net "PCIE_COMP_A_TO_SCC_A_2_DN")
	)
	(segment
		(start 283.1719 -197.83679)
		(end 257.522726 -158.334964)
		(width 0.127)
		(layer "In7.Cu")
		(net "PCIE_COMP_A_TO_SCC_A_2_DN")
	)
	(segment
		(start 242.057174 -125.360176)
		(end 241.430302 -124.733304)
		(width 0.127)
		(layer "In7.Cu")
		(net "PCIE_COMP_A_TO_SCC_A_2_DN")
	)
	(segment
		(start 302.671734 -258.580382)
		(end 304.891694 -257.24993)
		(width 0.127)
		(layer "In7.Cu")
		(net "PCIE_COMP_A_TO_SCC_A_2_DN")
	)
	(segment
		(start 243.88318 -125.942344)
		(end 242.904772 -125.360176)
		(width 0.127)
		(layer "In7.Cu")
		(net "PCIE_COMP_A_TO_SCC_A_2_DN")
	)
	(segment
		(start 286.996886 -260.22935)
		(end 286.996886 -260.703314)
		(width 0.127)
		(layer "In7.Cu")
		(net "PCIE_COMP_A_TO_SCC_A_2_DN")
	)
	(segment
		(start 253.590298 -139.139676)
		(end 243.88318 -125.942344)
		(width 0.127)
		(layer "In7.Cu")
		(net "PCIE_COMP_A_TO_SCC_A_2_DN")
	)
	(arc
		(start 241.61242 -124.187712)
		(mid 241.693444 -124.117123)
		(end 241.800634 -124.12472)
		(width 0.127)
		(layer "In7.Cu")
		(net "PCIE_COMP_A_TO_SCC_A_2_DN")
	)
	(arc
		(start 286.996886 -260.703314)
		(mid 287.125366 -261.013492)
		(end 287.435544 -261.141972)
		(width 0.127)
		(layer "In7.Cu")
		(net "PCIE_COMP_A_TO_SCC_A_2_DN")
	)
	(arc
		(start 286.869886 -260.10235)
		(mid 286.959689 -260.139547)
		(end 286.996886 -260.22935)
		(width 0.127)
		(layer "In7.Cu")
		(net "PCIE_COMP_A_TO_SCC_A_2_DN")
	)
	(arc
		(start 241.430302 -124.733304)
		(mid 241.392321 -124.64161)
		(end 241.430302 -124.549916)
		(width 0.127)
		(layer "In7.Cu")
		(net "PCIE_COMP_A_TO_SCC_A_2_DN")
	)
	(segment
		(start 308.51729 -234.95254)
		(end 308.323996 -234.911392)
		(width 0.127)
		(layer "In7.Cu")
		(net "PCIE_COMP_A_TO_SCC_A_1_DP")
	)
	(segment
		(start 286.836612 -261.902194)
		(end 286.403288 -261.902194)
		(width 0.127)
		(layer "In7.Cu")
		(net "PCIE_COMP_A_TO_SCC_A_1_DP")
	)
	(segment
		(start 302.909478 -259.876544)
		(end 308.072536 -256.78257)
		(width 0.127)
		(layer "In7.Cu")
		(net "PCIE_COMP_A_TO_SCC_A_1_DP")
	)
	(segment
		(start 242.851686 -121.639584)
		(end 241.94135 -121.639584)
		(width 0.127)
		(layer "In7.Cu")
		(net "PCIE_COMP_A_TO_SCC_A_1_DP")
	)
	(segment
		(start 294.792908 -261.371334)
		(end 294.969692 -261.488428)
		(width 0.127)
		(layer "In7.Cu")
		(net "PCIE_COMP_A_TO_SCC_A_1_DP")
	)
	(segment
		(start 295.343072 -261.412736)
		(end 295.460166 -261.235952)
		(width 0.127)
		(layer "In7.Cu")
		(net "PCIE_COMP_A_TO_SCC_A_1_DP")
	)
	(segment
		(start 295.833546 -261.16026)
		(end 296.010076 -261.277354)
		(width 0.127)
		(layer "In7.Cu")
		(net "PCIE_COMP_A_TO_SCC_A_1_DP")
	)
	(segment
		(start 241.194844 -120.395492)
		(end 241.325908 -120.134888)
		(width 0.127)
		(layer "In7.Cu")
		(net "PCIE_COMP_A_TO_SCC_A_1_DP")
	)
	(segment
		(start 307.549296 -233.718608)
		(end 307.590444 -233.525314)
		(width 0.127)
		(layer "In7.Cu")
		(net "PCIE_COMP_A_TO_SCC_A_1_DP")
	)
	(segment
		(start 296.010076 -261.277354)
		(end 296.383456 -261.201408)
		(width 0.127)
		(layer "In7.Cu")
		(net "PCIE_COMP_A_TO_SCC_A_1_DP")
	)
	(segment
		(start 241.94135 -121.639584)
		(end 241.23269 -120.930924)
		(width 0.127)
		(layer "In7.Cu")
		(net "PCIE_COMP_A_TO_SCC_A_1_DP")
	)
	(segment
		(start 308.116478 -234.59186)
		(end 308.157626 -234.398566)
		(width 0.127)
		(layer "In7.Cu")
		(net "PCIE_COMP_A_TO_SCC_A_1_DP")
	)
	(segment
		(start 296.87393 -260.948932)
		(end 297.050714 -261.066026)
		(width 0.127)
		(layer "In7.Cu")
		(net "PCIE_COMP_A_TO_SCC_A_1_DP")
	)
	(segment
		(start 307.023262 -232.651808)
		(end 259.094732 -158.85668)
		(width 0.127)
		(layer "In7.Cu")
		(net "PCIE_COMP_A_TO_SCC_A_1_DP")
	)
	(segment
		(start 286.276288 -262.029194)
		(end 286.276288 -262.503158)
		(width 0.127)
		(layer "In7.Cu")
		(net "PCIE_COMP_A_TO_SCC_A_1_DP")
	)
	(segment
		(start 309.405782 -254.725932)
		(end 311.465976 -245.036848)
		(width 0.127)
		(layer "In7.Cu")
		(net "PCIE_COMP_A_TO_SCC_A_1_DP")
	)
	(segment
		(start 286.435546 -262.662416)
		(end 289.187128 -262.662416)
		(width 0.127)
		(layer "In7.Cu")
		(net "PCIE_COMP_A_TO_SCC_A_1_DP")
	)
	(segment
		(start 241.325908 -120.134634)
		(end 241.326162 -120.134634)
		(width 0.127)
		(layer "In7.Cu")
		(net "PCIE_COMP_A_TO_SCC_A_1_DP")
	)
	(segment
		(start 307.382926 -233.205782)
		(end 307.189632 -233.164634)
		(width 0.127)
		(layer "In7.Cu")
		(net "PCIE_COMP_A_TO_SCC_A_1_DP")
	)
	(segment
		(start 241.311176 -119.881142)
		(end 240.549938 -119.499888)
		(width 0.127)
		(layer "In7.Cu")
		(net "PCIE_COMP_A_TO_SCC_A_1_DP")
	)
	(segment
		(start 308.072536 -256.78257)
		(end 309.405782 -254.725932)
		(width 0.127)
		(layer "In7.Cu")
		(net "PCIE_COMP_A_TO_SCC_A_1_DP")
	)
	(segment
		(start 296.50055 -261.024624)
		(end 296.87393 -260.948932)
		(width 0.127)
		(layer "In7.Cu")
		(net "PCIE_COMP_A_TO_SCC_A_1_DP")
	)
	(segment
		(start 308.157626 -234.398566)
		(end 307.950108 -234.079034)
		(width 0.127)
		(layer "In7.Cu")
		(net "PCIE_COMP_A_TO_SCC_A_1_DP")
	)
	(segment
		(start 309.6006 -236.620304)
		(end 308.51729 -234.95254)
		(width 0.127)
		(layer "In7.Cu")
		(net "PCIE_COMP_A_TO_SCC_A_1_DP")
	)
	(segment
		(start 297.050714 -261.066026)
		(end 302.909478 -259.876544)
		(width 0.127)
		(layer "In7.Cu")
		(net "PCIE_COMP_A_TO_SCC_A_1_DP")
	)
	(segment
		(start 254.65786 -137.063226)
		(end 243.617242 -122.052588)
		(width 0.127)
		(layer "In7.Cu")
		(net "PCIE_COMP_A_TO_SCC_A_1_DP")
	)
	(segment
		(start 307.756814 -234.037886)
		(end 307.549296 -233.718608)
		(width 0.127)
		(layer "In7.Cu")
		(net "PCIE_COMP_A_TO_SCC_A_1_DP")
	)
	(segment
		(start 294.302434 -261.62381)
		(end 294.419528 -261.44728)
		(width 0.127)
		(layer "In7.Cu")
		(net "PCIE_COMP_A_TO_SCC_A_1_DP")
	)
	(segment
		(start 259.094732 -158.85668)
		(end 254.65786 -137.063226)
		(width 0.127)
		(layer "In7.Cu")
		(net "PCIE_COMP_A_TO_SCC_A_1_DP")
	)
	(segment
		(start 308.323996 -234.911392)
		(end 308.116478 -234.59186)
		(width 0.127)
		(layer "In7.Cu")
		(net "PCIE_COMP_A_TO_SCC_A_1_DP")
	)
	(segment
		(start 306.982114 -232.845102)
		(end 307.023262 -232.651808)
		(width 0.127)
		(layer "In7.Cu")
		(net "PCIE_COMP_A_TO_SCC_A_1_DP")
	)
	(segment
		(start 289.187128 -262.662416)
		(end 294.302434 -261.62381)
		(width 0.127)
		(layer "In7.Cu")
		(net "PCIE_COMP_A_TO_SCC_A_1_DP")
	)
	(segment
		(start 296.383456 -261.201408)
		(end 296.50055 -261.024624)
		(width 0.127)
		(layer "In7.Cu")
		(net "PCIE_COMP_A_TO_SCC_A_1_DP")
	)
	(segment
		(start 311.465976 -245.036848)
		(end 309.6006 -236.620304)
		(width 0.127)
		(layer "In7.Cu")
		(net "PCIE_COMP_A_TO_SCC_A_1_DP")
	)
	(segment
		(start 307.189632 -233.164634)
		(end 306.982114 -232.845102)
		(width 0.127)
		(layer "In7.Cu")
		(net "PCIE_COMP_A_TO_SCC_A_1_DP")
	)
	(segment
		(start 295.460166 -261.235952)
		(end 295.833546 -261.16026)
		(width 0.127)
		(layer "In7.Cu")
		(net "PCIE_COMP_A_TO_SCC_A_1_DP")
	)
	(segment
		(start 294.419528 -261.44728)
		(end 294.792908 -261.371334)
		(width 0.127)
		(layer "In7.Cu")
		(net "PCIE_COMP_A_TO_SCC_A_1_DP")
	)
	(segment
		(start 243.617242 -122.052588)
		(end 242.851686 -121.639584)
		(width 0.127)
		(layer "In7.Cu")
		(net "PCIE_COMP_A_TO_SCC_A_1_DP")
	)
	(segment
		(start 241.326162 -120.134634)
		(end 241.367818 -120.051576)
		(width 0.127)
		(layer "In7.Cu")
		(net "PCIE_COMP_A_TO_SCC_A_1_DP")
	)
	(segment
		(start 307.950108 -234.079034)
		(end 307.756814 -234.037886)
		(width 0.127)
		(layer "In7.Cu")
		(net "PCIE_COMP_A_TO_SCC_A_1_DP")
	)
	(segment
		(start 307.590444 -233.525314)
		(end 307.382926 -233.205782)
		(width 0.127)
		(layer "In7.Cu")
		(net "PCIE_COMP_A_TO_SCC_A_1_DP")
	)
	(segment
		(start 294.969692 -261.488428)
		(end 295.343072 -261.412736)
		(width 0.127)
		(layer "In7.Cu")
		(net "PCIE_COMP_A_TO_SCC_A_1_DP")
	)
	(segment
		(start 241.325908 -120.134888)
		(end 241.325908 -120.134634)
		(width 0.127)
		(layer "In7.Cu")
		(net "PCIE_COMP_A_TO_SCC_A_1_DP")
	)
	(arc
		(start 241.23269 -120.930924)
		(mid 241.113698 -120.670267)
		(end 241.194844 -120.395492)
		(width 0.127)
		(layer "In7.Cu")
		(net "PCIE_COMP_A_TO_SCC_A_1_DP")
	)
	(arc
		(start 286.276288 -262.503158)
		(mid 286.322934 -262.61577)
		(end 286.435546 -262.662416)
		(width 0.127)
		(layer "In7.Cu")
		(net "PCIE_COMP_A_TO_SCC_A_1_DP")
	)
	(arc
		(start 241.367818 -120.051576)
		(mid 241.374795 -119.954628)
		(end 241.311176 -119.881142)
		(width 0.127)
		(layer "In7.Cu")
		(net "PCIE_COMP_A_TO_SCC_A_1_DP")
	)
	(arc
		(start 286.403288 -261.902194)
		(mid 286.313485 -261.939391)
		(end 286.276288 -262.029194)
		(width 0.127)
		(layer "In7.Cu")
		(net "PCIE_COMP_A_TO_SCC_A_1_DP")
	)
	(segment
		(start 241.430302 -120.549924)
		(end 241.576098 -120.259856)
		(width 0.127)
		(layer "In7.Cu")
		(net "PCIE_COMP_A_TO_SCC_A_1_DN")
	)
	(segment
		(start 241.589052 -120.233694)
		(end 241.61242 -120.18772)
		(width 0.127)
		(layer "In7.Cu")
		(net "PCIE_COMP_A_TO_SCC_A_1_DN")
	)
	(segment
		(start 311.75198 -245.035832)
		(end 309.862982 -236.511084)
		(width 0.127)
		(layer "In7.Cu")
		(net "PCIE_COMP_A_TO_SCC_A_1_DN")
	)
	(segment
		(start 308.271926 -256.989072)
		(end 309.668418 -254.834644)
		(width 0.127)
		(layer "In7.Cu")
		(net "PCIE_COMP_A_TO_SCC_A_1_DN")
	)
	(segment
		(start 303.012094 -260.140958)
		(end 308.271926 -256.989072)
		(width 0.127)
		(layer "In7.Cu")
		(net "PCIE_COMP_A_TO_SCC_A_1_DN")
	)
	(segment
		(start 285.436564 -261.902194)
		(end 285.869888 -261.902194)
		(width 0.127)
		(layer "In7.Cu")
		(net "PCIE_COMP_A_TO_SCC_A_1_DN")
	)
	(segment
		(start 254.91948 -136.947148)
		(end 243.805202 -121.836434)
		(width 0.127)
		(layer "In7.Cu")
		(net "PCIE_COMP_A_TO_SCC_A_1_DN")
	)
	(segment
		(start 243.805202 -121.836434)
		(end 242.922298 -121.360184)
		(width 0.127)
		(layer "In7.Cu")
		(net "PCIE_COMP_A_TO_SCC_A_1_DN")
	)
	(segment
		(start 241.576098 -120.259856)
		(end 241.589052 -120.233694)
		(width 0.127)
		(layer "In7.Cu")
		(net "PCIE_COMP_A_TO_SCC_A_1_DN")
	)
	(segment
		(start 309.862982 -236.511084)
		(end 309.862728 -236.510322)
		(width 0.127)
		(layer "In7.Cu")
		(net "PCIE_COMP_A_TO_SCC_A_1_DN")
	)
	(segment
		(start 309.668418 -254.834644)
		(end 311.75198 -245.035832)
		(width 0.127)
		(layer "In7.Cu")
		(net "PCIE_COMP_A_TO_SCC_A_1_DN")
	)
	(segment
		(start 286.435546 -262.941816)
		(end 289.215322 -262.941816)
		(width 0.127)
		(layer "In7.Cu")
		(net "PCIE_COMP_A_TO_SCC_A_1_DN")
	)
	(segment
		(start 242.922298 -121.360184)
		(end 242.057174 -121.360184)
		(width 0.127)
		(layer "In7.Cu")
		(net "PCIE_COMP_A_TO_SCC_A_1_DN")
	)
	(segment
		(start 241.800634 -120.124728)
		(end 242.549934 -120.499886)
		(width 0.127)
		(layer "In7.Cu")
		(net "PCIE_COMP_A_TO_SCC_A_1_DN")
	)
	(segment
		(start 285.996888 -262.029194)
		(end 285.996888 -262.503158)
		(width 0.127)
		(layer "In7.Cu")
		(net "PCIE_COMP_A_TO_SCC_A_1_DN")
	)
	(segment
		(start 259.35813 -158.748984)
		(end 254.91948 -136.947148)
		(width 0.127)
		(layer "In7.Cu")
		(net "PCIE_COMP_A_TO_SCC_A_1_DN")
	)
	(segment
		(start 289.215322 -262.941816)
		(end 303.012094 -260.140958)
		(width 0.127)
		(layer "In7.Cu")
		(net "PCIE_COMP_A_TO_SCC_A_1_DN")
	)
	(segment
		(start 242.057174 -121.360184)
		(end 241.430302 -120.733312)
		(width 0.127)
		(layer "In7.Cu")
		(net "PCIE_COMP_A_TO_SCC_A_1_DN")
	)
	(segment
		(start 309.862728 -236.510322)
		(end 259.35813 -158.748984)
		(width 0.127)
		(layer "In7.Cu")
		(net "PCIE_COMP_A_TO_SCC_A_1_DN")
	)
	(arc
		(start 241.430302 -120.733312)
		(mid 241.392321 -120.641618)
		(end 241.430302 -120.549924)
		(width 0.127)
		(layer "In7.Cu")
		(net "PCIE_COMP_A_TO_SCC_A_1_DN")
	)
	(arc
		(start 241.61242 -120.18772)
		(mid 241.693444 -120.117131)
		(end 241.800634 -120.124728)
		(width 0.127)
		(layer "In7.Cu")
		(net "PCIE_COMP_A_TO_SCC_A_1_DN")
	)
	(arc
		(start 285.996888 -262.503158)
		(mid 286.125368 -262.813336)
		(end 286.435546 -262.941816)
		(width 0.127)
		(layer "In7.Cu")
		(net "PCIE_COMP_A_TO_SCC_A_1_DN")
	)
	(arc
		(start 285.869888 -261.902194)
		(mid 285.959691 -261.939391)
		(end 285.996888 -262.029194)
		(width 0.127)
		(layer "In7.Cu")
		(net "PCIE_COMP_A_TO_SCC_A_1_DN")
	)
	(segment
		(start 309.662322 -233.646726)
		(end 309.455058 -233.602784)
		(width 0.127)
		(layer "In7.Cu")
		(net "PCIE_COMP_A_TO_SCC_A_0_DP")
	)
	(segment
		(start 308.090824 -231.502204)
		(end 308.134766 -231.294686)
		(width 0.127)
		(layer "In7.Cu")
		(net "PCIE_COMP_A_TO_SCC_A_0_DP")
	)
	(segment
		(start 299.901102 -218.615768)
		(end 299.693584 -218.571572)
		(width 0.127)
		(layer "In7.Cu")
		(net "PCIE_COMP_A_TO_SCC_A_0_DP")
	)
	(segment
		(start 241.325908 -116.134642)
		(end 241.326162 -116.134642)
		(width 0.127)
		(layer "In7.Cu")
		(net "PCIE_COMP_A_TO_SCC_A_0_DP")
	)
	(segment
		(start 309.455058 -233.602784)
		(end 309.24754 -233.283252)
		(width 0.127)
		(layer "In7.Cu")
		(net "PCIE_COMP_A_TO_SCC_A_0_DP")
	)
	(segment
		(start 241.94135 -117.639592)
		(end 241.23269 -116.930932)
		(width 0.127)
		(layer "In7.Cu")
		(net "PCIE_COMP_A_TO_SCC_A_0_DP")
	)
	(segment
		(start 309.291482 -233.075734)
		(end 309.083964 -232.756202)
		(width 0.127)
		(layer "In7.Cu")
		(net "PCIE_COMP_A_TO_SCC_A_0_DP")
	)
	(segment
		(start 242.79987 -117.639592)
		(end 241.94135 -117.639592)
		(width 0.127)
		(layer "In7.Cu")
		(net "PCIE_COMP_A_TO_SCC_A_0_DP")
	)
	(segment
		(start 308.713124 -232.18521)
		(end 308.505606 -231.865678)
		(width 0.127)
		(layer "In7.Cu")
		(net "PCIE_COMP_A_TO_SCC_A_0_DP")
	)
	(segment
		(start 308.8767 -232.71226)
		(end 308.669182 -232.392728)
		(width 0.127)
		(layer "In7.Cu")
		(net "PCIE_COMP_A_TO_SCC_A_0_DP")
	)
	(segment
		(start 287.83661 -263.702292)
		(end 287.403286 -263.702292)
		(width 0.127)
		(layer "In7.Cu")
		(net "PCIE_COMP_A_TO_SCC_A_0_DP")
	)
	(segment
		(start 310.84647 -255.198626)
		(end 312.725816 -246.35714)
		(width 0.127)
		(layer "In7.Cu")
		(net "PCIE_COMP_A_TO_SCC_A_0_DP")
	)
	(segment
		(start 287.276286 -263.829292)
		(end 287.276286 -264.303256)
		(width 0.127)
		(layer "In7.Cu")
		(net "PCIE_COMP_A_TO_SCC_A_0_DP")
	)
	(segment
		(start 300.064424 -219.142564)
		(end 300.10862 -218.9353)
		(width 0.127)
		(layer "In7.Cu")
		(net "PCIE_COMP_A_TO_SCC_A_0_DP")
	)
	(segment
		(start 300.271942 -219.462096)
		(end 300.064424 -219.142564)
		(width 0.127)
		(layer "In7.Cu")
		(net "PCIE_COMP_A_TO_SCC_A_0_DP")
	)
	(segment
		(start 300.479206 -219.506038)
		(end 300.271942 -219.462096)
		(width 0.127)
		(layer "In7.Cu")
		(net "PCIE_COMP_A_TO_SCC_A_0_DP")
	)
	(segment
		(start 290.53155 -264.462514)
		(end 302.05553 -262.123682)
		(width 0.127)
		(layer "In7.Cu")
		(net "PCIE_COMP_A_TO_SCC_A_0_DP")
	)
	(segment
		(start 299.530262 -218.044776)
		(end 299.322744 -217.725244)
		(width 0.127)
		(layer "In7.Cu")
		(net "PCIE_COMP_A_TO_SCC_A_0_DP")
	)
	(segment
		(start 298.951904 -217.153998)
		(end 260.765036 -158.35122)
		(width 0.127)
		(layer "In7.Cu")
		(net "PCIE_COMP_A_TO_SCC_A_0_DP")
	)
	(segment
		(start 299.11548 -217.681048)
		(end 298.907962 -217.361516)
		(width 0.127)
		(layer "In7.Cu")
		(net "PCIE_COMP_A_TO_SCC_A_0_DP")
	)
	(segment
		(start 312.725816 -246.35714)
		(end 310.03621 -234.222544)
		(width 0.127)
		(layer "In7.Cu")
		(net "PCIE_COMP_A_TO_SCC_A_0_DP")
	)
	(segment
		(start 298.951904 -217.154252)
		(end 298.951904 -217.153998)
		(width 0.127)
		(layer "In7.Cu")
		(net "PCIE_COMP_A_TO_SCC_A_0_DP")
	)
	(segment
		(start 309.24754 -233.283252)
		(end 309.291482 -233.075734)
		(width 0.127)
		(layer "In7.Cu")
		(net "PCIE_COMP_A_TO_SCC_A_0_DP")
	)
	(segment
		(start 308.298342 -231.821736)
		(end 308.090824 -231.502204)
		(width 0.127)
		(layer "In7.Cu")
		(net "PCIE_COMP_A_TO_SCC_A_0_DP")
	)
	(segment
		(start 241.194844 -116.3955)
		(end 241.325908 -116.134896)
		(width 0.127)
		(layer "In7.Cu")
		(net "PCIE_COMP_A_TO_SCC_A_0_DP")
	)
	(segment
		(start 309.084726 -257.911346)
		(end 310.84647 -255.198626)
		(width 0.127)
		(layer "In7.Cu")
		(net "PCIE_COMP_A_TO_SCC_A_0_DP")
	)
	(segment
		(start 299.322744 -217.725244)
		(end 299.11548 -217.681048)
		(width 0.127)
		(layer "In7.Cu")
		(net "PCIE_COMP_A_TO_SCC_A_0_DP")
	)
	(segment
		(start 241.311176 -115.88115)
		(end 240.549938 -115.499896)
		(width 0.127)
		(layer "In7.Cu")
		(net "PCIE_COMP_A_TO_SCC_A_0_DP")
	)
	(segment
		(start 241.325908 -116.134896)
		(end 241.325908 -116.134642)
		(width 0.127)
		(layer "In7.Cu")
		(net "PCIE_COMP_A_TO_SCC_A_0_DP")
	)
	(segment
		(start 308.134766 -231.294686)
		(end 300.479206 -219.506038)
		(width 0.127)
		(layer "In7.Cu")
		(net "PCIE_COMP_A_TO_SCC_A_0_DP")
	)
	(segment
		(start 310.03621 -234.222544)
		(end 309.662322 -233.646726)
		(width 0.127)
		(layer "In7.Cu")
		(net "PCIE_COMP_A_TO_SCC_A_0_DP")
	)
	(segment
		(start 255.980692 -134.861808)
		(end 243.637308 -118.080282)
		(width 0.127)
		(layer "In7.Cu")
		(net "PCIE_COMP_A_TO_SCC_A_0_DP")
	)
	(segment
		(start 243.637308 -118.080282)
		(end 242.79987 -117.639592)
		(width 0.127)
		(layer "In7.Cu")
		(net "PCIE_COMP_A_TO_SCC_A_0_DP")
	)
	(segment
		(start 300.10862 -218.9353)
		(end 299.901102 -218.615768)
		(width 0.127)
		(layer "In7.Cu")
		(net "PCIE_COMP_A_TO_SCC_A_0_DP")
	)
	(segment
		(start 299.486066 -218.25204)
		(end 299.530262 -218.044776)
		(width 0.127)
		(layer "In7.Cu")
		(net "PCIE_COMP_A_TO_SCC_A_0_DP")
	)
	(segment
		(start 287.435544 -264.462514)
		(end 290.53155 -264.462514)
		(width 0.127)
		(layer "In7.Cu")
		(net "PCIE_COMP_A_TO_SCC_A_0_DP")
	)
	(segment
		(start 298.907962 -217.361516)
		(end 298.951904 -217.154252)
		(width 0.127)
		(layer "In7.Cu")
		(net "PCIE_COMP_A_TO_SCC_A_0_DP")
	)
	(segment
		(start 299.693584 -218.571572)
		(end 299.486066 -218.25204)
		(width 0.127)
		(layer "In7.Cu")
		(net "PCIE_COMP_A_TO_SCC_A_0_DP")
	)
	(segment
		(start 308.669182 -232.392728)
		(end 308.713124 -232.18521)
		(width 0.127)
		(layer "In7.Cu")
		(net "PCIE_COMP_A_TO_SCC_A_0_DP")
	)
	(segment
		(start 309.083964 -232.756202)
		(end 308.8767 -232.71226)
		(width 0.127)
		(layer "In7.Cu")
		(net "PCIE_COMP_A_TO_SCC_A_0_DP")
	)
	(segment
		(start 308.505606 -231.865678)
		(end 308.298342 -231.821736)
		(width 0.127)
		(layer "In7.Cu")
		(net "PCIE_COMP_A_TO_SCC_A_0_DP")
	)
	(segment
		(start 260.765036 -158.35122)
		(end 255.980692 -134.861808)
		(width 0.127)
		(layer "In7.Cu")
		(net "PCIE_COMP_A_TO_SCC_A_0_DP")
	)
	(segment
		(start 241.326162 -116.134642)
		(end 241.367818 -116.051584)
		(width 0.127)
		(layer "In7.Cu")
		(net "PCIE_COMP_A_TO_SCC_A_0_DP")
	)
	(segment
		(start 302.05553 -262.123682)
		(end 309.084726 -257.911346)
		(width 0.127)
		(layer "In7.Cu")
		(net "PCIE_COMP_A_TO_SCC_A_0_DP")
	)
	(arc
		(start 241.367818 -116.051584)
		(mid 241.374795 -115.954636)
		(end 241.311176 -115.88115)
		(width 0.127)
		(layer "In7.Cu")
		(net "PCIE_COMP_A_TO_SCC_A_0_DP")
	)
	(arc
		(start 287.276286 -264.303256)
		(mid 287.322932 -264.415868)
		(end 287.435544 -264.462514)
		(width 0.127)
		(layer "In7.Cu")
		(net "PCIE_COMP_A_TO_SCC_A_0_DP")
	)
	(arc
		(start 287.403286 -263.702292)
		(mid 287.313483 -263.739489)
		(end 287.276286 -263.829292)
		(width 0.127)
		(layer "In7.Cu")
		(net "PCIE_COMP_A_TO_SCC_A_0_DP")
	)
	(arc
		(start 241.23269 -116.930932)
		(mid 241.113698 -116.670275)
		(end 241.194844 -116.3955)
		(width 0.127)
		(layer "In7.Cu")
		(net "PCIE_COMP_A_TO_SCC_A_0_DP")
	)
	(segment
		(start 302.158146 -262.388096)
		(end 309.283862 -258.117848)
		(width 0.127)
		(layer "In7.Cu")
		(net "PCIE_COMP_A_TO_SCC_A_0_DN")
	)
	(segment
		(start 290.559744 -264.741914)
		(end 302.158146 -262.388096)
		(width 0.127)
		(layer "In7.Cu")
		(net "PCIE_COMP_A_TO_SCC_A_0_DN")
	)
	(segment
		(start 241.430302 -116.549932)
		(end 241.576098 -116.259864)
		(width 0.127)
		(layer "In7.Cu")
		(net "PCIE_COMP_A_TO_SCC_A_0_DN")
	)
	(segment
		(start 286.436562 -263.702292)
		(end 286.869886 -263.702292)
		(width 0.127)
		(layer "In7.Cu")
		(net "PCIE_COMP_A_TO_SCC_A_0_DN")
	)
	(segment
		(start 313.01182 -246.356378)
		(end 313.01182 -246.35587)
		(width 0.127)
		(layer "In7.Cu")
		(net "PCIE_COMP_A_TO_SCC_A_0_DN")
	)
	(segment
		(start 310.298338 -234.112308)
		(end 310.298338 -234.112562)
		(width 0.127)
		(layer "In7.Cu")
		(net "PCIE_COMP_A_TO_SCC_A_0_DN")
	)
	(segment
		(start 286.996886 -263.829292)
		(end 286.996886 -264.303256)
		(width 0.127)
		(layer "In7.Cu")
		(net "PCIE_COMP_A_TO_SCC_A_0_DN")
	)
	(segment
		(start 311.109106 -255.307338)
		(end 313.01182 -246.356378)
		(width 0.127)
		(layer "In7.Cu")
		(net "PCIE_COMP_A_TO_SCC_A_0_DN")
	)
	(segment
		(start 241.800634 -116.124736)
		(end 242.549934 -116.499894)
		(width 0.127)
		(layer "In7.Cu")
		(net "PCIE_COMP_A_TO_SCC_A_0_DN")
	)
	(segment
		(start 241.589052 -116.233702)
		(end 241.61242 -116.187728)
		(width 0.127)
		(layer "In7.Cu")
		(net "PCIE_COMP_A_TO_SCC_A_0_DN")
	)
	(segment
		(start 242.868958 -117.360192)
		(end 242.057174 -117.360192)
		(width 0.127)
		(layer "In7.Cu")
		(net "PCIE_COMP_A_TO_SCC_A_0_DN")
	)
	(segment
		(start 287.435544 -264.741914)
		(end 290.559744 -264.741914)
		(width 0.127)
		(layer "In7.Cu")
		(net "PCIE_COMP_A_TO_SCC_A_0_DN")
	)
	(segment
		(start 309.283862 -258.117848)
		(end 311.109106 -255.307338)
		(width 0.127)
		(layer "In7.Cu")
		(net "PCIE_COMP_A_TO_SCC_A_0_DN")
	)
	(segment
		(start 310.298338 -234.112562)
		(end 261.028434 -158.243524)
		(width 0.127)
		(layer "In7.Cu")
		(net "PCIE_COMP_A_TO_SCC_A_0_DN")
	)
	(segment
		(start 242.057174 -117.360192)
		(end 241.430302 -116.73332)
		(width 0.127)
		(layer "In7.Cu")
		(net "PCIE_COMP_A_TO_SCC_A_0_DN")
	)
	(segment
		(start 259.837682 -152.39746)
		(end 256.242312 -134.74573)
		(width 0.127)
		(layer "In7.Cu")
		(net "PCIE_COMP_A_TO_SCC_A_0_DN")
	)
	(segment
		(start 241.576098 -116.259864)
		(end 241.589052 -116.233702)
		(width 0.127)
		(layer "In7.Cu")
		(net "PCIE_COMP_A_TO_SCC_A_0_DN")
	)
	(segment
		(start 256.242312 -134.74573)
		(end 243.824252 -117.862858)
		(width 0.127)
		(layer "In7.Cu")
		(net "PCIE_COMP_A_TO_SCC_A_0_DN")
	)
	(segment
		(start 313.01182 -246.35587)
		(end 310.298338 -234.112308)
		(width 0.127)
		(layer "In7.Cu")
		(net "PCIE_COMP_A_TO_SCC_A_0_DN")
	)
	(segment
		(start 261.028434 -158.243524)
		(end 259.837682 -152.39746)
		(width 0.127)
		(layer "In7.Cu")
		(net "PCIE_COMP_A_TO_SCC_A_0_DN")
	)
	(segment
		(start 243.824252 -117.862858)
		(end 242.868958 -117.360192)
		(width 0.127)
		(layer "In7.Cu")
		(net "PCIE_COMP_A_TO_SCC_A_0_DN")
	)
	(arc
		(start 286.869886 -263.702292)
		(mid 286.959689 -263.739489)
		(end 286.996886 -263.829292)
		(width 0.127)
		(layer "In7.Cu")
		(net "PCIE_COMP_A_TO_SCC_A_0_DN")
	)
	(arc
		(start 241.430302 -116.73332)
		(mid 241.392321 -116.641626)
		(end 241.430302 -116.549932)
		(width 0.127)
		(layer "In7.Cu")
		(net "PCIE_COMP_A_TO_SCC_A_0_DN")
	)
	(arc
		(start 241.61242 -116.187728)
		(mid 241.693444 -116.117139)
		(end 241.800634 -116.124736)
		(width 0.127)
		(layer "In7.Cu")
		(net "PCIE_COMP_A_TO_SCC_A_0_DN")
	)
	(arc
		(start 286.996886 -264.303256)
		(mid 287.125366 -264.613434)
		(end 287.435544 -264.741914)
		(width 0.127)
		(layer "In7.Cu")
		(net "PCIE_COMP_A_TO_SCC_A_0_DN")
	)
	(segment
		(start 256.7051 -16.1544)
		(end 256.7051 -17.1831)
		(width 0.17145)
		(layer "F.Cu")
		(net "PCIE_COMP_A_TO_IOM_A_RST_4")
	)
	(segment
		(start 255.9812 -16.1544)
		(end 256.7051 -16.1544)
		(width 0.17145)
		(layer "F.Cu")
		(net "PCIE_COMP_A_TO_IOM_A_RST_4")
	)
	(segment
		(start 255.93548 -16.20012)
		(end 255.9812 -16.1544)
		(width 0.17145)
		(layer "F.Cu")
		(net "PCIE_COMP_A_TO_IOM_A_RST_4")
	)
	(segment
		(start 242.549934 -16.20012)
		(end 255.3716 -16.20012)
		(width 0.17145)
		(layer "F.Cu")
		(net "PCIE_COMP_A_TO_IOM_A_RST_4")
	)
	(segment
		(start 255.3716 -16.20012)
		(end 255.93548 -16.20012)
		(width 0.17145)
		(layer "F.Cu")
		(net "PCIE_COMP_A_TO_IOM_A_RST_4")
	)
	(via
		(at 256.7051 -17.1831)
		(size 0.5588)
		(drill 0.3048)
		(layers "F.Cu" "B.Cu")
		(net "PCIE_COMP_A_TO_IOM_A_RST_4")
	)
	(via
		(at 255.3716 -16.20012)
		(size 0.6604)
		(drill 0.3302)
		(layers "F.Cu" "B.Cu")
		(net "PCIE_COMP_A_TO_IOM_A_RST_4")
	)
	(segment
		(start 124.293884 -24.024844)
		(end 128.544574 -24.024844)
		(width 0.12065)
		(layer "In7.Cu")
		(net "PCIE_COMP_A_TO_IOM_A_RST_4")
	)
	(segment
		(start 167.969692 -19.99615)
		(end 180.33746 -7.628382)
		(width 0.12065)
		(layer "In7.Cu")
		(net "PCIE_COMP_A_TO_IOM_A_RST_4")
	)
	(segment
		(start 132.559044 -32.534098)
		(end 134.31774 -32.534098)
		(width 0.12065)
		(layer "In7.Cu")
		(net "PCIE_COMP_A_TO_IOM_A_RST_4")
	)
	(segment
		(start 122.768614 -25.550114)
		(end 124.293884 -24.024844)
		(width 0.12065)
		(layer "In7.Cu")
		(net "PCIE_COMP_A_TO_IOM_A_RST_4")
	)
	(segment
		(start 256.7051 -16.360394)
		(end 256.7051 -17.1831)
		(width 0.12065)
		(layer "In7.Cu")
		(net "PCIE_COMP_A_TO_IOM_A_RST_4")
	)
	(segment
		(start 130.819144 -31.78302)
		(end 131.807966 -31.78302)
		(width 0.12065)
		(layer "In7.Cu")
		(net "PCIE_COMP_A_TO_IOM_A_RST_4")
	)
	(segment
		(start 130.102102 -25.582372)
		(end 130.102102 -31.065978)
		(width 0.12065)
		(layer "In7.Cu")
		(net "PCIE_COMP_A_TO_IOM_A_RST_4")
	)
	(segment
		(start 234.493054 -1.363218)
		(end 241.707924 -1.363218)
		(width 0.12065)
		(layer "In7.Cu")
		(net "PCIE_COMP_A_TO_IOM_A_RST_4")
	)
	(segment
		(start 121.750074 -25.550114)
		(end 122.768614 -25.550114)
		(width 0.12065)
		(layer "In7.Cu")
		(net "PCIE_COMP_A_TO_IOM_A_RST_4")
	)
	(segment
		(start 180.33746 -7.628382)
		(end 228.22789 -7.628382)
		(width 0.12065)
		(layer "In7.Cu")
		(net "PCIE_COMP_A_TO_IOM_A_RST_4")
	)
	(segment
		(start 131.807966 -31.78302)
		(end 132.559044 -32.534098)
		(width 0.12065)
		(layer "In7.Cu")
		(net "PCIE_COMP_A_TO_IOM_A_RST_4")
	)
	(segment
		(start 137.397998 -33.98393)
		(end 139.29106 -35.876992)
		(width 0.12065)
		(layer "In7.Cu")
		(net "PCIE_COMP_A_TO_IOM_A_RST_4")
	)
	(segment
		(start 135.767572 -33.98393)
		(end 137.397998 -33.98393)
		(width 0.12065)
		(layer "In7.Cu")
		(net "PCIE_COMP_A_TO_IOM_A_RST_4")
	)
	(segment
		(start 134.31774 -32.534098)
		(end 135.767572 -33.98393)
		(width 0.12065)
		(layer "In7.Cu")
		(net "PCIE_COMP_A_TO_IOM_A_RST_4")
	)
	(segment
		(start 151.15667 -29.946092)
		(end 154.88793 -29.946092)
		(width 0.12065)
		(layer "In7.Cu")
		(net "PCIE_COMP_A_TO_IOM_A_RST_4")
	)
	(segment
		(start 130.102102 -31.065978)
		(end 130.819144 -31.78302)
		(width 0.12065)
		(layer "In7.Cu")
		(net "PCIE_COMP_A_TO_IOM_A_RST_4")
	)
	(segment
		(start 241.707924 -1.363218)
		(end 256.7051 -16.360394)
		(width 0.12065)
		(layer "In7.Cu")
		(net "PCIE_COMP_A_TO_IOM_A_RST_4")
	)
	(segment
		(start 154.88793 -29.946092)
		(end 164.837872 -19.99615)
		(width 0.12065)
		(layer "In7.Cu")
		(net "PCIE_COMP_A_TO_IOM_A_RST_4")
	)
	(segment
		(start 139.29106 -35.876992)
		(end 145.22577 -35.876992)
		(width 0.12065)
		(layer "In7.Cu")
		(net "PCIE_COMP_A_TO_IOM_A_RST_4")
	)
	(segment
		(start 228.22789 -7.628382)
		(end 234.493054 -1.363218)
		(width 0.12065)
		(layer "In7.Cu")
		(net "PCIE_COMP_A_TO_IOM_A_RST_4")
	)
	(segment
		(start 128.544574 -24.024844)
		(end 130.102102 -25.582372)
		(width 0.12065)
		(layer "In7.Cu")
		(net "PCIE_COMP_A_TO_IOM_A_RST_4")
	)
	(segment
		(start 145.22577 -35.876992)
		(end 151.15667 -29.946092)
		(width 0.12065)
		(layer "In7.Cu")
		(net "PCIE_COMP_A_TO_IOM_A_RST_4")
	)
	(segment
		(start 164.837872 -19.99615)
		(end 167.969692 -19.99615)
		(width 0.12065)
		(layer "In7.Cu")
		(net "PCIE_COMP_A_TO_IOM_A_RST_4")
	)
	(segment
		(start 256.6543 -13.8176)
		(end 256.7051 -13.7668)
		(width 0.17145)
		(layer "F.Cu")
		(net "PCIE_COMP_A_TO_IOM_A_RST_3")
	)
	(segment
		(start 241.167412 -13.8176)
		(end 255.016 -13.8176)
		(width 0.17145)
		(layer "F.Cu")
		(net "PCIE_COMP_A_TO_IOM_A_RST_3")
	)
	(segment
		(start 255.016 -13.8176)
		(end 256.6543 -13.8176)
		(width 0.17145)
		(layer "F.Cu")
		(net "PCIE_COMP_A_TO_IOM_A_RST_3")
	)
	(segment
		(start 240.549938 -13.200126)
		(end 241.167412 -13.8176)
		(width 0.17145)
		(layer "F.Cu")
		(net "PCIE_COMP_A_TO_IOM_A_RST_3")
	)
	(segment
		(start 256.7051 -13.7668)
		(end 256.7051 -12.6873)
		(width 0.17145)
		(layer "F.Cu")
		(net "PCIE_COMP_A_TO_IOM_A_RST_3")
	)
	(via
		(at 256.7051 -12.6873)
		(size 0.5588)
		(drill 0.3048)
		(layers "F.Cu" "B.Cu")
		(net "PCIE_COMP_A_TO_IOM_A_RST_3")
	)
	(via
		(at 255.016 -13.8176)
		(size 0.6604)
		(drill 0.3302)
		(layers "F.Cu" "B.Cu")
		(net "PCIE_COMP_A_TO_IOM_A_RST_3")
	)
	(segment
		(start 227.922836 -6.9342)
		(end 234.122468 -0.734568)
		(width 0.12065)
		(layer "In7.Cu")
		(net "PCIE_COMP_A_TO_IOM_A_RST_3")
	)
	(segment
		(start 134.9756 -32.302704)
		(end 136.028176 -33.35528)
		(width 0.12065)
		(layer "In7.Cu")
		(net "PCIE_COMP_A_TO_IOM_A_RST_3")
	)
	(segment
		(start 241.968528 -0.734568)
		(end 253.92126 -12.6873)
		(width 0.12065)
		(layer "In7.Cu")
		(net "PCIE_COMP_A_TO_IOM_A_RST_3")
	)
	(segment
		(start 154.44216 -29.317442)
		(end 154.599132 -29.16047)
		(width 0.12065)
		(layer "In7.Cu")
		(net "PCIE_COMP_A_TO_IOM_A_RST_3")
	)
	(segment
		(start 150.896066 -29.317442)
		(end 154.44216 -29.317442)
		(width 0.12065)
		(layer "In7.Cu")
		(net "PCIE_COMP_A_TO_IOM_A_RST_3")
	)
	(segment
		(start 136.028176 -33.35528)
		(end 137.658602 -33.35528)
		(width 0.12065)
		(layer "In7.Cu")
		(net "PCIE_COMP_A_TO_IOM_A_RST_3")
	)
	(segment
		(start 253.92126 -12.6873)
		(end 256.7051 -12.6873)
		(width 0.12065)
		(layer "In7.Cu")
		(net "PCIE_COMP_A_TO_IOM_A_RST_3")
	)
	(segment
		(start 139.551664 -35.248342)
		(end 144.965166 -35.248342)
		(width 0.12065)
		(layer "In7.Cu")
		(net "PCIE_COMP_A_TO_IOM_A_RST_3")
	)
	(segment
		(start 234.122468 -0.734568)
		(end 241.968528 -0.734568)
		(width 0.12065)
		(layer "In7.Cu")
		(net "PCIE_COMP_A_TO_IOM_A_RST_3")
	)
	(segment
		(start 167.709088 -19.3675)
		(end 180.142388 -6.9342)
		(width 0.12065)
		(layer "In7.Cu")
		(net "PCIE_COMP_A_TO_IOM_A_RST_3")
	)
	(segment
		(start 136.150096 -25.550114)
		(end 134.9756 -26.72461)
		(width 0.12065)
		(layer "In7.Cu")
		(net "PCIE_COMP_A_TO_IOM_A_RST_3")
	)
	(segment
		(start 180.142388 -6.9342)
		(end 227.922836 -6.9342)
		(width 0.12065)
		(layer "In7.Cu")
		(net "PCIE_COMP_A_TO_IOM_A_RST_3")
	)
	(segment
		(start 134.9756 -26.72461)
		(end 134.9756 -32.302704)
		(width 0.12065)
		(layer "In7.Cu")
		(net "PCIE_COMP_A_TO_IOM_A_RST_3")
	)
	(segment
		(start 154.599132 -29.16047)
		(end 154.674316 -29.16047)
		(width 0.12065)
		(layer "In7.Cu")
		(net "PCIE_COMP_A_TO_IOM_A_RST_3")
	)
	(segment
		(start 164.467286 -19.3675)
		(end 167.709088 -19.3675)
		(width 0.12065)
		(layer "In7.Cu")
		(net "PCIE_COMP_A_TO_IOM_A_RST_3")
	)
	(segment
		(start 144.965166 -35.248342)
		(end 150.896066 -29.317442)
		(width 0.12065)
		(layer "In7.Cu")
		(net "PCIE_COMP_A_TO_IOM_A_RST_3")
	)
	(segment
		(start 154.674316 -29.16047)
		(end 164.467286 -19.3675)
		(width 0.12065)
		(layer "In7.Cu")
		(net "PCIE_COMP_A_TO_IOM_A_RST_3")
	)
	(segment
		(start 137.658602 -33.35528)
		(end 139.551664 -35.248342)
		(width 0.12065)
		(layer "In7.Cu")
		(net "PCIE_COMP_A_TO_IOM_A_RST_3")
	)
	(segment
		(start 168.124886 -25.550114)
		(end 168.529 -25.146)
		(width 0.17145)
		(layer "F.Cu")
		(net "PCIE_COMP_A_TO_IOM_A_RST_2")
	)
	(segment
		(start 223.116648 -11.814302)
		(end 223.116648 -9.196832)
		(width 0.17145)
		(layer "F.Cu")
		(net "PCIE_COMP_A_TO_IOM_A_RST_2")
	)
	(segment
		(start 208.110328 -25.146)
		(end 212.471 -20.785328)
		(width 0.17145)
		(layer "F.Cu")
		(net "PCIE_COMP_A_TO_IOM_A_RST_2")
	)
	(segment
		(start 223.116648 -9.196832)
		(end 223.870012 -8.443468)
		(width 0.17145)
		(layer "F.Cu")
		(net "PCIE_COMP_A_TO_IOM_A_RST_2")
	)
	(segment
		(start 222.57766 -12.35329)
		(end 223.116648 -11.814302)
		(width 0.17145)
		(layer "F.Cu")
		(net "PCIE_COMP_A_TO_IOM_A_RST_2")
	)
	(segment
		(start 256.901188 -138.482578)
		(end 255.73101 -138.482578)
		(width 0.17145)
		(layer "F.Cu")
		(net "PCIE_COMP_A_TO_IOM_A_RST_2")
	)
	(segment
		(start 237.292642 -1.093216)
		(end 255.692656 -1.093216)
		(width 0.17145)
		(layer "F.Cu")
		(net "PCIE_COMP_A_TO_IOM_A_RST_2")
	)
	(segment
		(start 245.40464 -31.48076)
		(end 245.40464 -82.786728)
		(width 0.17145)
		(layer "F.Cu")
		(net "PCIE_COMP_A_TO_IOM_A_RST_2")
	)
	(segment
		(start 258.988052 -17.897348)
		(end 245.40464 -31.48076)
		(width 0.17145)
		(layer "F.Cu")
		(net "PCIE_COMP_A_TO_IOM_A_RST_2")
	)
	(segment
		(start 223.870012 -8.443468)
		(end 229.94239 -8.443468)
		(width 0.17145)
		(layer "F.Cu")
		(net "PCIE_COMP_A_TO_IOM_A_RST_2")
	)
	(segment
		(start 242.549934 -140.499846)
		(end 244.567202 -138.482578)
		(width 0.17145)
		(layer "F.Cu")
		(net "PCIE_COMP_A_TO_IOM_A_RST_2")
	)
	(segment
		(start 143.34998 -25.550114)
		(end 168.124886 -25.550114)
		(width 0.17145)
		(layer "F.Cu")
		(net "PCIE_COMP_A_TO_IOM_A_RST_2")
	)
	(segment
		(start 212.471 -20.785328)
		(end 212.471 -14.478)
		(width 0.17145)
		(layer "F.Cu")
		(net "PCIE_COMP_A_TO_IOM_A_RST_2")
	)
	(segment
		(start 255.692656 -1.093216)
		(end 258.988052 -4.388612)
		(width 0.17145)
		(layer "F.Cu")
		(net "PCIE_COMP_A_TO_IOM_A_RST_2")
	)
	(segment
		(start 229.94239 -8.443468)
		(end 237.292642 -1.093216)
		(width 0.17145)
		(layer "F.Cu")
		(net "PCIE_COMP_A_TO_IOM_A_RST_2")
	)
	(segment
		(start 214.59571 -12.35329)
		(end 222.57766 -12.35329)
		(width 0.17145)
		(layer "F.Cu")
		(net "PCIE_COMP_A_TO_IOM_A_RST_2")
	)
	(segment
		(start 258.988052 -4.388612)
		(end 258.988052 -17.897348)
		(width 0.17145)
		(layer "F.Cu")
		(net "PCIE_COMP_A_TO_IOM_A_RST_2")
	)
	(segment
		(start 244.567202 -138.482578)
		(end 255.73101 -138.482578)
		(width 0.17145)
		(layer "F.Cu")
		(net "PCIE_COMP_A_TO_IOM_A_RST_2")
	)
	(segment
		(start 245.40464 -82.786728)
		(end 256.901188 -94.283276)
		(width 0.17145)
		(layer "F.Cu")
		(net "PCIE_COMP_A_TO_IOM_A_RST_2")
	)
	(segment
		(start 256.901188 -94.283276)
		(end 256.901188 -138.482578)
		(width 0.17145)
		(layer "F.Cu")
		(net "PCIE_COMP_A_TO_IOM_A_RST_2")
	)
	(segment
		(start 168.529 -25.146)
		(end 208.110328 -25.146)
		(width 0.17145)
		(layer "F.Cu")
		(net "PCIE_COMP_A_TO_IOM_A_RST_2")
	)
	(segment
		(start 212.471 -14.478)
		(end 214.59571 -12.35329)
		(width 0.17145)
		(layer "F.Cu")
		(net "PCIE_COMP_A_TO_IOM_A_RST_2")
	)
	(via
		(at 255.73101 -138.482578)
		(size 0.6604)
		(drill 0.3302)
		(layers "F.Cu" "B.Cu")
		(net "PCIE_COMP_A_TO_IOM_A_RST_2")
	)
	(segment
		(start 195.130674 -21.020024)
		(end 195.130674 -21.01977)
		(width 0.127)
		(layer "In7.Cu")
		(net "PCIE_COMP_A_TO_IOM_A_CLK_4_DP")
	)
	(segment
		(start 222.069914 -19.084036)
		(end 233.910378 -11.394948)
		(width 0.127)
		(layer "In7.Cu")
		(net "PCIE_COMP_A_TO_IOM_A_CLK_4_DP")
	)
	(segment
		(start 149.677628 -35.925252)
		(end 167.579548 -24.299926)
		(width 0.127)
		(layer "In7.Cu")
		(net "PCIE_COMP_A_TO_IOM_A_CLK_4_DP")
	)
	(segment
		(start 123.5202 -31.04642)
		(end 129.221738 -34.82213)
		(width 0.127)
		(layer "In7.Cu")
		(net "PCIE_COMP_A_TO_IOM_A_CLK_4_DP")
	)
	(segment
		(start 237.324138 -11.563604)
		(end 238.05007 -11.20013)
		(width 0.127)
		(layer "In7.Cu")
		(net "PCIE_COMP_A_TO_IOM_A_CLK_4_DP")
	)
	(segment
		(start 233.910378 -11.394948)
		(end 235.476288 -11.061954)
		(width 0.127)
		(layer "In7.Cu")
		(net "PCIE_COMP_A_TO_IOM_A_CLK_4_DP")
	)
	(segment
		(start 121.750074 -29.59608)
		(end 121.877328 -29.723334)
		(width 0.127)
		(layer "In7.Cu")
		(net "PCIE_COMP_A_TO_IOM_A_CLK_4_DP")
	)
	(segment
		(start 121.750074 -29.150056)
		(end 121.750074 -29.59608)
		(width 0.127)
		(layer "In7.Cu")
		(net "PCIE_COMP_A_TO_IOM_A_CLK_4_DP")
	)
	(segment
		(start 167.579548 -24.299926)
		(end 186.08929 -19.09826)
		(width 0.127)
		(layer "In7.Cu")
		(net "PCIE_COMP_A_TO_IOM_A_CLK_4_DP")
	)
	(segment
		(start 235.476288 -11.061954)
		(end 236.471714 -11.061954)
		(width 0.127)
		(layer "In7.Cu")
		(net "PCIE_COMP_A_TO_IOM_A_CLK_4_DP")
	)
	(segment
		(start 121.877328 -29.723334)
		(end 122.525536 -29.723334)
		(width 0.127)
		(layer "In7.Cu")
		(net "PCIE_COMP_A_TO_IOM_A_CLK_4_DP")
	)
	(segment
		(start 195.130674 -21.01977)
		(end 204.046582 -22.915118)
		(width 0.127)
		(layer "In7.Cu")
		(net "PCIE_COMP_A_TO_IOM_A_CLK_4_DP")
	)
	(segment
		(start 129.221738 -34.82213)
		(end 142.04569 -37.547296)
		(width 0.127)
		(layer "In7.Cu")
		(net "PCIE_COMP_A_TO_IOM_A_CLK_4_DP")
	)
	(segment
		(start 236.818678 -11.205718)
		(end 237.148116 -11.535156)
		(width 0.127)
		(layer "In7.Cu")
		(net "PCIE_COMP_A_TO_IOM_A_CLK_4_DP")
	)
	(segment
		(start 142.04569 -37.547296)
		(end 149.677628 -35.925252)
		(width 0.127)
		(layer "In7.Cu")
		(net "PCIE_COMP_A_TO_IOM_A_CLK_4_DP")
	)
	(segment
		(start 122.525536 -29.723334)
		(end 122.876818 -30.074616)
		(width 0.127)
		(layer "In7.Cu")
		(net "PCIE_COMP_A_TO_IOM_A_CLK_4_DP")
	)
	(segment
		(start 186.08929 -19.09826)
		(end 195.130674 -21.020024)
		(width 0.127)
		(layer "In7.Cu")
		(net "PCIE_COMP_A_TO_IOM_A_CLK_4_DP")
	)
	(segment
		(start 122.876818 -30.074616)
		(end 123.5202 -31.04642)
		(width 0.127)
		(layer "In7.Cu")
		(net "PCIE_COMP_A_TO_IOM_A_CLK_4_DP")
	)
	(segment
		(start 204.046582 -22.915118)
		(end 222.069914 -19.084036)
		(width 0.127)
		(layer "In7.Cu")
		(net "PCIE_COMP_A_TO_IOM_A_CLK_4_DP")
	)
	(arc
		(start 236.471714 -11.061954)
		(mid 236.659507 -11.099308)
		(end 236.818678 -11.205718)
		(width 0.127)
		(layer "In7.Cu")
		(net "PCIE_COMP_A_TO_IOM_A_CLK_4_DP")
	)
	(arc
		(start 237.148116 -11.535156)
		(mid 237.231528 -11.577817)
		(end 237.324138 -11.563604)
		(width 0.127)
		(layer "In7.Cu")
		(net "PCIE_COMP_A_TO_IOM_A_CLK_4_DP")
	)
	(segment
		(start 122.659394 -30.252416)
		(end 123.318524 -31.248096)
		(width 0.127)
		(layer "In7.Cu")
		(net "PCIE_COMP_A_TO_IOM_A_CLK_4_DN")
	)
	(segment
		(start 231.87279 -13.217906)
		(end 232.192322 -13.010642)
		(width 0.127)
		(layer "In7.Cu")
		(net "PCIE_COMP_A_TO_IOM_A_CLK_4_DN")
	)
	(segment
		(start 232.23347 -12.817348)
		(end 232.553002 -12.60983)
		(width 0.127)
		(layer "In7.Cu")
		(net "PCIE_COMP_A_TO_IOM_A_CLK_4_DN")
	)
	(segment
		(start 232.746296 -12.650978)
		(end 233.065828 -12.44346)
		(width 0.127)
		(layer "In7.Cu")
		(net "PCIE_COMP_A_TO_IOM_A_CLK_4_DN")
	)
	(segment
		(start 142.04569 -37.833046)
		(end 149.78634 -36.187888)
		(width 0.127)
		(layer "In7.Cu")
		(net "PCIE_COMP_A_TO_IOM_A_CLK_4_DN")
	)
	(segment
		(start 121.750074 -30.129734)
		(end 121.877074 -30.002734)
		(width 0.127)
		(layer "In7.Cu")
		(net "PCIE_COMP_A_TO_IOM_A_CLK_4_DN")
	)
	(segment
		(start 236.803946 -11.82243)
		(end 236.79404 -11.82751)
		(width 0.127)
		(layer "In7.Cu")
		(net "PCIE_COMP_A_TO_IOM_A_CLK_4_DN")
	)
	(segment
		(start 233.106722 -12.250166)
		(end 234.01909 -11.657584)
		(width 0.127)
		(layer "In7.Cu")
		(net "PCIE_COMP_A_TO_IOM_A_CLK_4_DN")
	)
	(segment
		(start 234.01909 -11.657584)
		(end 235.505752 -11.341354)
		(width 0.127)
		(layer "In7.Cu")
		(net "PCIE_COMP_A_TO_IOM_A_CLK_4_DN")
	)
	(segment
		(start 167.696134 -24.557482)
		(end 186.098688 -19.386042)
		(width 0.127)
		(layer "In7.Cu")
		(net "PCIE_COMP_A_TO_IOM_A_CLK_4_DN")
	)
	(segment
		(start 235.505752 -11.341354)
		(end 236.47146 -11.341354)
		(width 0.127)
		(layer "In7.Cu")
		(net "PCIE_COMP_A_TO_IOM_A_CLK_4_DN")
	)
	(segment
		(start 121.750074 -30.550104)
		(end 121.750074 -30.129734)
		(width 0.127)
		(layer "In7.Cu")
		(net "PCIE_COMP_A_TO_IOM_A_CLK_4_DN")
	)
	(segment
		(start 232.192322 -13.010642)
		(end 232.23347 -12.817348)
		(width 0.127)
		(layer "In7.Cu")
		(net "PCIE_COMP_A_TO_IOM_A_CLK_4_DN")
	)
	(segment
		(start 233.065828 -12.44346)
		(end 233.106722 -12.250166)
		(width 0.127)
		(layer "In7.Cu")
		(net "PCIE_COMP_A_TO_IOM_A_CLK_4_DN")
	)
	(segment
		(start 231.679496 -13.177012)
		(end 231.87279 -13.217906)
		(width 0.127)
		(layer "In7.Cu")
		(net "PCIE_COMP_A_TO_IOM_A_CLK_4_DN")
	)
	(segment
		(start 123.318524 -31.248096)
		(end 129.111756 -35.084512)
		(width 0.127)
		(layer "In7.Cu")
		(net "PCIE_COMP_A_TO_IOM_A_CLK_4_DN")
	)
	(segment
		(start 186.098688 -19.386042)
		(end 204.046582 -23.200868)
		(width 0.127)
		(layer "In7.Cu")
		(net "PCIE_COMP_A_TO_IOM_A_CLK_4_DN")
	)
	(segment
		(start 230.999284 -13.785088)
		(end 231.318816 -13.577824)
		(width 0.127)
		(layer "In7.Cu")
		(net "PCIE_COMP_A_TO_IOM_A_CLK_4_DN")
	)
	(segment
		(start 129.111756 -35.084512)
		(end 142.04569 -37.833046)
		(width 0.127)
		(layer "In7.Cu")
		(net "PCIE_COMP_A_TO_IOM_A_CLK_4_DN")
	)
	(segment
		(start 231.359964 -13.38453)
		(end 231.679496 -13.177012)
		(width 0.127)
		(layer "In7.Cu")
		(net "PCIE_COMP_A_TO_IOM_A_CLK_4_DN")
	)
	(segment
		(start 204.046582 -23.200868)
		(end 222.178626 -19.346672)
		(width 0.127)
		(layer "In7.Cu")
		(net "PCIE_COMP_A_TO_IOM_A_CLK_4_DN")
	)
	(segment
		(start 236.79404 -11.82751)
		(end 236.050074 -12.200128)
		(width 0.127)
		(layer "In7.Cu")
		(net "PCIE_COMP_A_TO_IOM_A_CLK_4_DN")
	)
	(segment
		(start 149.78634 -36.187888)
		(end 167.696134 -24.557482)
		(width 0.127)
		(layer "In7.Cu")
		(net "PCIE_COMP_A_TO_IOM_A_CLK_4_DN")
	)
	(segment
		(start 222.178626 -19.346672)
		(end 230.806244 -13.744194)
		(width 0.127)
		(layer "In7.Cu")
		(net "PCIE_COMP_A_TO_IOM_A_CLK_4_DN")
	)
	(segment
		(start 230.806244 -13.744194)
		(end 230.999284 -13.785088)
		(width 0.127)
		(layer "In7.Cu")
		(net "PCIE_COMP_A_TO_IOM_A_CLK_4_DN")
	)
	(segment
		(start 231.318816 -13.577824)
		(end 231.359964 -13.38453)
		(width 0.127)
		(layer "In7.Cu")
		(net "PCIE_COMP_A_TO_IOM_A_CLK_4_DN")
	)
	(segment
		(start 122.409712 -30.002734)
		(end 122.659394 -30.252416)
		(width 0.127)
		(layer "In7.Cu")
		(net "PCIE_COMP_A_TO_IOM_A_CLK_4_DN")
	)
	(segment
		(start 121.877074 -30.002734)
		(end 122.409712 -30.002734)
		(width 0.127)
		(layer "In7.Cu")
		(net "PCIE_COMP_A_TO_IOM_A_CLK_4_DN")
	)
	(segment
		(start 236.621066 -11.40333)
		(end 236.836966 -11.61923)
		(width 0.127)
		(layer "In7.Cu")
		(net "PCIE_COMP_A_TO_IOM_A_CLK_4_DN")
	)
	(segment
		(start 232.553002 -12.60983)
		(end 232.746296 -12.650978)
		(width 0.127)
		(layer "In7.Cu")
		(net "PCIE_COMP_A_TO_IOM_A_CLK_4_DN")
	)
	(arc
		(start 236.47146 -11.341354)
		(mid 236.552415 -11.357475)
		(end 236.621066 -11.40333)
		(width 0.127)
		(layer "In7.Cu")
		(net "PCIE_COMP_A_TO_IOM_A_CLK_4_DN")
	)
	(arc
		(start 236.836966 -11.61923)
		(mid 236.872386 -11.729265)
		(end 236.803946 -11.82243)
		(width 0.127)
		(layer "In7.Cu")
		(net "PCIE_COMP_A_TO_IOM_A_CLK_4_DN")
	)
	(segment
		(start 137.992866 -34.179764)
		(end 143.0274 -35.211766)
		(width 0.1397)
		(layer "In2.Cu")
		(net "PCIE_COMP_A_TO_IOM_A_CLK_3_DP")
	)
	(segment
		(start 220.61551 -30.282134)
		(end 235.575094 -33.346136)
		(width 0.1397)
		(layer "In2.Cu")
		(net "PCIE_COMP_A_TO_IOM_A_CLK_3_DP")
	)
	(segment
		(start 135.09117 -31.56839)
		(end 135.588248 -32.588962)
		(width 0.1397)
		(layer "In2.Cu")
		(net "PCIE_COMP_A_TO_IOM_A_CLK_3_DP")
	)
	(segment
		(start 135.588248 -32.588962)
		(end 137.992866 -34.179764)
		(width 0.1397)
		(layer "In2.Cu")
		(net "PCIE_COMP_A_TO_IOM_A_CLK_3_DP")
	)
	(segment
		(start 143.0274 -35.211766)
		(end 158.92145 -31.746444)
		(width 0.1397)
		(layer "In2.Cu")
		(net "PCIE_COMP_A_TO_IOM_A_CLK_3_DP")
	)
	(segment
		(start 136.010142 -29.70403)
		(end 135.335264 -29.70403)
		(width 0.1397)
		(layer "In2.Cu")
		(net "PCIE_COMP_A_TO_IOM_A_CLK_3_DP")
	)
	(segment
		(start 179.9844 -33.295082)
		(end 186.79668 -31.809944)
		(width 0.1397)
		(layer "In2.Cu")
		(net "PCIE_COMP_A_TO_IOM_A_CLK_3_DP")
	)
	(segment
		(start 193.98996 -33.283652)
		(end 200.458832 -31.872936)
		(width 0.1397)
		(layer "In2.Cu")
		(net "PCIE_COMP_A_TO_IOM_A_CLK_3_DP")
	)
	(segment
		(start 235.575094 -33.346136)
		(end 236.575092 -33.346136)
		(width 0.1397)
		(layer "In2.Cu")
		(net "PCIE_COMP_A_TO_IOM_A_CLK_3_DP")
	)
	(segment
		(start 136.150096 -29.150056)
		(end 136.150096 -29.564076)
		(width 0.1397)
		(layer "In2.Cu")
		(net "PCIE_COMP_A_TO_IOM_A_CLK_3_DP")
	)
	(segment
		(start 241.481864 -35.509962)
		(end 241.294666 -35.5727)
		(width 0.1397)
		(layer "In2.Cu")
		(net "PCIE_COMP_A_TO_IOM_A_CLK_3_DP")
	)
	(segment
		(start 241.544348 -35.384994)
		(end 241.481864 -35.509962)
		(width 0.1397)
		(layer "In2.Cu")
		(net "PCIE_COMP_A_TO_IOM_A_CLK_3_DP")
	)
	(segment
		(start 174.635922 -32.199072)
		(end 179.9844 -33.295082)
		(width 0.1397)
		(layer "In2.Cu")
		(net "PCIE_COMP_A_TO_IOM_A_CLK_3_DP")
	)
	(segment
		(start 236.575092 -33.346136)
		(end 237.57509 -34.346134)
		(width 0.1397)
		(layer "In2.Cu")
		(net "PCIE_COMP_A_TO_IOM_A_CLK_3_DP")
	)
	(segment
		(start 135.335264 -29.70403)
		(end 135.09117 -29.948124)
		(width 0.1397)
		(layer "In2.Cu")
		(net "PCIE_COMP_A_TO_IOM_A_CLK_3_DP")
	)
	(segment
		(start 207.088994 -33.231074)
		(end 220.61551 -30.282134)
		(width 0.1397)
		(layer "In2.Cu")
		(net "PCIE_COMP_A_TO_IOM_A_CLK_3_DP")
	)
	(segment
		(start 241.544348 -34.815526)
		(end 241.544348 -35.384994)
		(width 0.1397)
		(layer "In2.Cu")
		(net "PCIE_COMP_A_TO_IOM_A_CLK_3_DP")
	)
	(segment
		(start 241.294666 -35.5727)
		(end 240.549938 -35.200082)
		(width 0.1397)
		(layer "In2.Cu")
		(net "PCIE_COMP_A_TO_IOM_A_CLK_3_DP")
	)
	(segment
		(start 237.57509 -34.346134)
		(end 241.074956 -34.346134)
		(width 0.1397)
		(layer "In2.Cu")
		(net "PCIE_COMP_A_TO_IOM_A_CLK_3_DP")
	)
	(segment
		(start 241.074956 -34.346134)
		(end 241.544348 -34.815526)
		(width 0.1397)
		(layer "In2.Cu")
		(net "PCIE_COMP_A_TO_IOM_A_CLK_3_DP")
	)
	(segment
		(start 158.92145 -31.746444)
		(end 168.092882 -33.625536)
		(width 0.1397)
		(layer "In2.Cu")
		(net "PCIE_COMP_A_TO_IOM_A_CLK_3_DP")
	)
	(segment
		(start 136.150096 -29.564076)
		(end 136.010142 -29.70403)
		(width 0.1397)
		(layer "In2.Cu")
		(net "PCIE_COMP_A_TO_IOM_A_CLK_3_DP")
	)
	(segment
		(start 200.458832 -31.872936)
		(end 207.088994 -33.231074)
		(width 0.1397)
		(layer "In2.Cu")
		(net "PCIE_COMP_A_TO_IOM_A_CLK_3_DP")
	)
	(segment
		(start 135.09117 -29.948124)
		(end 135.09117 -31.56839)
		(width 0.1397)
		(layer "In2.Cu")
		(net "PCIE_COMP_A_TO_IOM_A_CLK_3_DP")
	)
	(segment
		(start 168.092882 -33.625536)
		(end 174.635922 -32.199072)
		(width 0.1397)
		(layer "In2.Cu")
		(net "PCIE_COMP_A_TO_IOM_A_CLK_3_DP")
	)
	(segment
		(start 186.79668 -31.809944)
		(end 193.98996 -33.283652)
		(width 0.1397)
		(layer "In2.Cu")
		(net "PCIE_COMP_A_TO_IOM_A_CLK_3_DP")
	)
	(segment
		(start 234.674918 -32.721042)
		(end 235.085382 -32.805116)
		(width 0.1397)
		(layer "In2.Cu")
		(net "PCIE_COMP_A_TO_IOM_A_CLK_3_DN")
	)
	(segment
		(start 220.613732 -29.98343)
		(end 232.320084 -32.38119)
		(width 0.1397)
		(layer "In2.Cu")
		(net "PCIE_COMP_A_TO_IOM_A_CLK_3_DN")
	)
	(segment
		(start 158.919672 -31.44774)
		(end 168.091104 -33.326832)
		(width 0.1397)
		(layer "In2.Cu")
		(net "PCIE_COMP_A_TO_IOM_A_CLK_3_DN")
	)
	(segment
		(start 233.004614 -32.521398)
		(end 233.415078 -32.605472)
		(width 0.1397)
		(layer "In2.Cu")
		(net "PCIE_COMP_A_TO_IOM_A_CLK_3_DN")
	)
	(segment
		(start 136.150096 -30.550104)
		(end 136.150096 -30.14472)
		(width 0.1397)
		(layer "In2.Cu")
		(net "PCIE_COMP_A_TO_IOM_A_CLK_3_DN")
	)
	(segment
		(start 232.895648 -32.356552)
		(end 233.004614 -32.521398)
		(width 0.1397)
		(layer "In2.Cu")
		(net "PCIE_COMP_A_TO_IOM_A_CLK_3_DN")
	)
	(segment
		(start 135.816086 -32.389064)
		(end 138.106912 -33.904936)
		(width 0.1397)
		(layer "In2.Cu")
		(net "PCIE_COMP_A_TO_IOM_A_CLK_3_DN")
	)
	(segment
		(start 200.457054 -31.574232)
		(end 207.087216 -32.93237)
		(width 0.1397)
		(layer "In2.Cu")
		(net "PCIE_COMP_A_TO_IOM_A_CLK_3_DN")
	)
	(segment
		(start 233.579924 -32.49676)
		(end 233.990642 -32.580834)
		(width 0.1397)
		(layer "In2.Cu")
		(net "PCIE_COMP_A_TO_IOM_A_CLK_3_DN")
	)
	(segment
		(start 241.836448 -35.454082)
		(end 241.74323 -35.640518)
		(width 0.1397)
		(layer "In2.Cu")
		(net "PCIE_COMP_A_TO_IOM_A_CLK_3_DN")
	)
	(segment
		(start 136.001506 -29.99613)
		(end 135.456422 -29.99613)
		(width 0.1397)
		(layer "In2.Cu")
		(net "PCIE_COMP_A_TO_IOM_A_CLK_3_DN")
	)
	(segment
		(start 168.091104 -33.326832)
		(end 174.634144 -31.900368)
		(width 0.1397)
		(layer "In2.Cu")
		(net "PCIE_COMP_A_TO_IOM_A_CLK_3_DN")
	)
	(segment
		(start 233.415078 -32.605472)
		(end 233.579924 -32.49676)
		(width 0.1397)
		(layer "In2.Cu")
		(net "PCIE_COMP_A_TO_IOM_A_CLK_3_DN")
	)
	(segment
		(start 241.74323 -35.640518)
		(end 241.80546 -35.827716)
		(width 0.1397)
		(layer "In2.Cu")
		(net "PCIE_COMP_A_TO_IOM_A_CLK_3_DN")
	)
	(segment
		(start 232.485184 -32.272478)
		(end 232.895648 -32.356552)
		(width 0.1397)
		(layer "In2.Cu")
		(net "PCIE_COMP_A_TO_IOM_A_CLK_3_DN")
	)
	(segment
		(start 237.696248 -34.054034)
		(end 241.196114 -34.054034)
		(width 0.1397)
		(layer "In2.Cu")
		(net "PCIE_COMP_A_TO_IOM_A_CLK_3_DN")
	)
	(segment
		(start 235.194348 -32.969962)
		(end 235.604812 -33.054036)
		(width 0.1397)
		(layer "In2.Cu")
		(net "PCIE_COMP_A_TO_IOM_A_CLK_3_DN")
	)
	(segment
		(start 232.320084 -32.38119)
		(end 232.485184 -32.272478)
		(width 0.1397)
		(layer "In2.Cu")
		(net "PCIE_COMP_A_TO_IOM_A_CLK_3_DN")
	)
	(segment
		(start 241.836448 -34.694368)
		(end 241.836448 -35.454082)
		(width 0.1397)
		(layer "In2.Cu")
		(net "PCIE_COMP_A_TO_IOM_A_CLK_3_DN")
	)
	(segment
		(start 213.237064 -31.591758)
		(end 220.613732 -29.98343)
		(width 0.1397)
		(layer "In2.Cu")
		(net "PCIE_COMP_A_TO_IOM_A_CLK_3_DN")
	)
	(segment
		(start 234.099354 -32.74568)
		(end 234.509818 -32.829754)
		(width 0.1397)
		(layer "In2.Cu")
		(net "PCIE_COMP_A_TO_IOM_A_CLK_3_DN")
	)
	(segment
		(start 135.456422 -29.99613)
		(end 135.38327 -30.069282)
		(width 0.1397)
		(layer "In2.Cu")
		(net "PCIE_COMP_A_TO_IOM_A_CLK_3_DN")
	)
	(segment
		(start 235.085382 -32.805116)
		(end 235.194348 -32.969962)
		(width 0.1397)
		(layer "In2.Cu")
		(net "PCIE_COMP_A_TO_IOM_A_CLK_3_DN")
	)
	(segment
		(start 179.982622 -32.996378)
		(end 186.794902 -31.51124)
		(width 0.1397)
		(layer "In2.Cu")
		(net "PCIE_COMP_A_TO_IOM_A_CLK_3_DN")
	)
	(segment
		(start 241.196114 -34.054034)
		(end 241.836448 -34.694368)
		(width 0.1397)
		(layer "In2.Cu")
		(net "PCIE_COMP_A_TO_IOM_A_CLK_3_DN")
	)
	(segment
		(start 236.69625 -33.054036)
		(end 237.696248 -34.054034)
		(width 0.1397)
		(layer "In2.Cu")
		(net "PCIE_COMP_A_TO_IOM_A_CLK_3_DN")
	)
	(segment
		(start 186.794902 -31.51124)
		(end 193.987674 -32.984694)
		(width 0.1397)
		(layer "In2.Cu")
		(net "PCIE_COMP_A_TO_IOM_A_CLK_3_DN")
	)
	(segment
		(start 207.087216 -32.93237)
		(end 213.237064 -31.591758)
		(width 0.1397)
		(layer "In2.Cu")
		(net "PCIE_COMP_A_TO_IOM_A_CLK_3_DN")
	)
	(segment
		(start 138.106912 -33.904936)
		(end 143.025622 -34.913062)
		(width 0.1397)
		(layer "In2.Cu")
		(net "PCIE_COMP_A_TO_IOM_A_CLK_3_DN")
	)
	(segment
		(start 143.025622 -34.913062)
		(end 158.919672 -31.44774)
		(width 0.1397)
		(layer "In2.Cu")
		(net "PCIE_COMP_A_TO_IOM_A_CLK_3_DN")
	)
	(segment
		(start 233.990642 -32.580834)
		(end 234.099354 -32.74568)
		(width 0.1397)
		(layer "In2.Cu")
		(net "PCIE_COMP_A_TO_IOM_A_CLK_3_DN")
	)
	(segment
		(start 235.604812 -33.054036)
		(end 236.69625 -33.054036)
		(width 0.1397)
		(layer "In2.Cu")
		(net "PCIE_COMP_A_TO_IOM_A_CLK_3_DN")
	)
	(segment
		(start 241.80546 -35.827716)
		(end 242.549934 -36.20008)
		(width 0.1397)
		(layer "In2.Cu")
		(net "PCIE_COMP_A_TO_IOM_A_CLK_3_DN")
	)
	(segment
		(start 135.38327 -30.069282)
		(end 135.38327 -31.500826)
		(width 0.1397)
		(layer "In2.Cu")
		(net "PCIE_COMP_A_TO_IOM_A_CLK_3_DN")
	)
	(segment
		(start 174.634144 -31.900368)
		(end 179.982622 -32.996378)
		(width 0.1397)
		(layer "In2.Cu")
		(net "PCIE_COMP_A_TO_IOM_A_CLK_3_DN")
	)
	(segment
		(start 234.509818 -32.829754)
		(end 234.674918 -32.721042)
		(width 0.1397)
		(layer "In2.Cu")
		(net "PCIE_COMP_A_TO_IOM_A_CLK_3_DN")
	)
	(segment
		(start 193.987674 -32.984694)
		(end 200.457054 -31.574232)
		(width 0.1397)
		(layer "In2.Cu")
		(net "PCIE_COMP_A_TO_IOM_A_CLK_3_DN")
	)
	(segment
		(start 135.38327 -31.500826)
		(end 135.816086 -32.389064)
		(width 0.1397)
		(layer "In2.Cu")
		(net "PCIE_COMP_A_TO_IOM_A_CLK_3_DN")
	)
	(segment
		(start 136.150096 -30.14472)
		(end 136.001506 -29.99613)
		(width 0.1397)
		(layer "In2.Cu")
		(net "PCIE_COMP_A_TO_IOM_A_CLK_3_DN")
	)
	(segment
		(start 247.330722 -95.671894)
		(end 245.877334 -94.488508)
		(width 0.1651)
		(layer "F.Cu")
		(net "PCIE_COMP_A_TO_IOM_A_CLK_2_DP")
	)
	(segment
		(start 244.882924 -131.727702)
		(end 244.992906 -131.244848)
		(width 0.1651)
		(layer "F.Cu")
		(net "PCIE_COMP_A_TO_IOM_A_CLK_2_DP")
	)
	(segment
		(start 182.197502 -29.938218)
		(end 168.982136 -32.633412)
		(width 0.1651)
		(layer "F.Cu")
		(net "PCIE_COMP_A_TO_IOM_A_CLK_2_DP")
	)
	(segment
		(start 142.927578 -32.639762)
		(end 142.303754 -31.776924)
		(width 0.1651)
		(layer "F.Cu")
		(net "PCIE_COMP_A_TO_IOM_A_CLK_2_DP")
	)
	(segment
		(start 187.665106 -31.01467)
		(end 182.197502 -29.938218)
		(width 0.1651)
		(layer "F.Cu")
		(net "PCIE_COMP_A_TO_IOM_A_CLK_2_DP")
	)
	(segment
		(start 240.938304 -138.3538)
		(end 241.938302 -137.353802)
		(width 0.1651)
		(layer "F.Cu")
		(net "PCIE_COMP_A_TO_IOM_A_CLK_2_DP")
	)
	(segment
		(start 245.417086 -129.94259)
		(end 250.64593 -106.973624)
		(width 0.1651)
		(layer "F.Cu")
		(net "PCIE_COMP_A_TO_IOM_A_CLK_2_DP")
	)
	(segment
		(start 244.992906 -131.244848)
		(end 245.142004 -131.151122)
		(width 0.1651)
		(layer "F.Cu")
		(net "PCIE_COMP_A_TO_IOM_A_CLK_2_DP")
	)
	(segment
		(start 245.142004 -131.151122)
		(end 245.251986 -130.668268)
		(width 0.1651)
		(layer "F.Cu")
		(net "PCIE_COMP_A_TO_IOM_A_CLK_2_DP")
	)
	(segment
		(start 187.902596 -31.061406)
		(end 187.665106 -31.014924)
		(width 0.1651)
		(layer "F.Cu")
		(net "PCIE_COMP_A_TO_IOM_A_CLK_2_DP")
	)
	(segment
		(start 245.251986 -130.668268)
		(end 245.15826 -130.51917)
		(width 0.1651)
		(layer "F.Cu")
		(net "PCIE_COMP_A_TO_IOM_A_CLK_2_DP")
	)
	(segment
		(start 245.267988 -130.036316)
		(end 245.417086 -129.94259)
		(width 0.1651)
		(layer "F.Cu")
		(net "PCIE_COMP_A_TO_IOM_A_CLK_2_DP")
	)
	(segment
		(start 143.879316 -32.827214)
		(end 142.927578 -32.639762)
		(width 0.1651)
		(layer "F.Cu")
		(net "PCIE_COMP_A_TO_IOM_A_CLK_2_DP")
	)
	(segment
		(start 244.607842 -132.936488)
		(end 244.717824 -132.45338)
		(width 0.1651)
		(layer "F.Cu")
		(net "PCIE_COMP_A_TO_IOM_A_CLK_2_DP")
	)
	(segment
		(start 244.97665 -131.8768)
		(end 244.882924 -131.727702)
		(width 0.1651)
		(layer "F.Cu")
		(net "PCIE_COMP_A_TO_IOM_A_CLK_2_DP")
	)
	(segment
		(start 237.516416 -138.3538)
		(end 240.938304 -138.3538)
		(width 0.1651)
		(layer "F.Cu")
		(net "PCIE_COMP_A_TO_IOM_A_CLK_2_DP")
	)
	(segment
		(start 243.264944 -137.353802)
		(end 243.866924 -136.751822)
		(width 0.1651)
		(layer "F.Cu")
		(net "PCIE_COMP_A_TO_IOM_A_CLK_2_DP")
	)
	(segment
		(start 244.717824 -132.45338)
		(end 244.866922 -132.359654)
		(width 0.1651)
		(layer "F.Cu")
		(net "PCIE_COMP_A_TO_IOM_A_CLK_2_DP")
	)
	(segment
		(start 187.665106 -31.014924)
		(end 187.665106 -31.01467)
		(width 0.1651)
		(layer "F.Cu")
		(net "PCIE_COMP_A_TO_IOM_A_CLK_2_DP")
	)
	(segment
		(start 244.866922 -132.359654)
		(end 244.97665 -131.8768)
		(width 0.1651)
		(layer "F.Cu")
		(net "PCIE_COMP_A_TO_IOM_A_CLK_2_DP")
	)
	(segment
		(start 238.05007 -137.499852)
		(end 237.328202 -137.86104)
		(width 0.1651)
		(layer "F.Cu")
		(net "PCIE_COMP_A_TO_IOM_A_CLK_2_DP")
	)
	(segment
		(start 233.80573 -89.723468)
		(end 233.767376 -89.63533)
		(width 0.1651)
		(layer "F.Cu")
		(net "PCIE_COMP_A_TO_IOM_A_CLK_2_DP")
	)
	(segment
		(start 233.767376 -89.63533)
		(end 201.61377 -39.966392)
		(width 0.1651)
		(layer "F.Cu")
		(net "PCIE_COMP_A_TO_IOM_A_CLK_2_DP")
	)
	(segment
		(start 245.15826 -130.51917)
		(end 245.267988 -130.036316)
		(width 0.1651)
		(layer "F.Cu")
		(net "PCIE_COMP_A_TO_IOM_A_CLK_2_DP")
	)
	(segment
		(start 237.254542 -138.082528)
		(end 237.254542 -138.082782)
		(width 0.1651)
		(layer "F.Cu")
		(net "PCIE_COMP_A_TO_IOM_A_CLK_2_DP")
	)
	(segment
		(start 143.34998 -29.57703)
		(end 143.34998 -29.150056)
		(width 0.1651)
		(layer "F.Cu")
		(net "PCIE_COMP_A_TO_IOM_A_CLK_2_DP")
	)
	(segment
		(start 156.68625 -30.214824)
		(end 143.879316 -32.827214)
		(width 0.1651)
		(layer "F.Cu")
		(net "PCIE_COMP_A_TO_IOM_A_CLK_2_DP")
	)
	(segment
		(start 250.64593 -106.973624)
		(end 247.330722 -95.671894)
		(width 0.1651)
		(layer "F.Cu")
		(net "PCIE_COMP_A_TO_IOM_A_CLK_2_DP")
	)
	(segment
		(start 237.254542 -138.082782)
		(end 237.413546 -138.301476)
		(width 0.1651)
		(layer "F.Cu")
		(net "PCIE_COMP_A_TO_IOM_A_CLK_2_DP")
	)
	(segment
		(start 245.877334 -94.488508)
		(end 233.80573 -89.723468)
		(width 0.1651)
		(layer "F.Cu")
		(net "PCIE_COMP_A_TO_IOM_A_CLK_2_DP")
	)
	(segment
		(start 241.938302 -137.353802)
		(end 243.264944 -137.353802)
		(width 0.1651)
		(layer "F.Cu")
		(net "PCIE_COMP_A_TO_IOM_A_CLK_2_DP")
	)
	(segment
		(start 244.701568 -133.085332)
		(end 244.607842 -132.936488)
		(width 0.1651)
		(layer "F.Cu")
		(net "PCIE_COMP_A_TO_IOM_A_CLK_2_DP")
	)
	(segment
		(start 142.967202 -29.70403)
		(end 143.22298 -29.70403)
		(width 0.1651)
		(layer "F.Cu")
		(net "PCIE_COMP_A_TO_IOM_A_CLK_2_DP")
	)
	(segment
		(start 168.982136 -32.633412)
		(end 156.68625 -30.214824)
		(width 0.1651)
		(layer "F.Cu")
		(net "PCIE_COMP_A_TO_IOM_A_CLK_2_DP")
	)
	(segment
		(start 201.61377 -39.966392)
		(end 187.902596 -31.061406)
		(width 0.1651)
		(layer "F.Cu")
		(net "PCIE_COMP_A_TO_IOM_A_CLK_2_DP")
	)
	(segment
		(start 243.866924 -136.751822)
		(end 244.701568 -133.085332)
		(width 0.1651)
		(layer "F.Cu")
		(net "PCIE_COMP_A_TO_IOM_A_CLK_2_DP")
	)
	(segment
		(start 142.303754 -31.776924)
		(end 142.303754 -30.367478)
		(width 0.1651)
		(layer "F.Cu")
		(net "PCIE_COMP_A_TO_IOM_A_CLK_2_DP")
	)
	(arc
		(start 143.22298 -29.70403)
		(mid 143.312783 -29.666833)
		(end 143.34998 -29.57703)
		(width 0.1651)
		(layer "F.Cu")
		(net "PCIE_COMP_A_TO_IOM_A_CLK_2_DP")
	)
	(arc
		(start 142.303754 -30.367478)
		(mid 142.498073 -29.898349)
		(end 142.967202 -29.70403)
		(width 0.1651)
		(layer "F.Cu")
		(net "PCIE_COMP_A_TO_IOM_A_CLK_2_DP")
	)
	(arc
		(start 237.328202 -137.86104)
		(mid 237.2455 -137.956529)
		(end 237.254542 -138.082528)
		(width 0.1651)
		(layer "F.Cu")
		(net "PCIE_COMP_A_TO_IOM_A_CLK_2_DP")
	)
	(arc
		(start 237.413546 -138.301476)
		(mid 237.458702 -138.339959)
		(end 237.516416 -138.3538)
		(width 0.1651)
		(layer "F.Cu")
		(net "PCIE_COMP_A_TO_IOM_A_CLK_2_DP")
	)
	(segment
		(start 236.962442 -138.170412)
		(end 236.962442 -138.177778)
		(width 0.1651)
		(layer "F.Cu")
		(net "PCIE_COMP_A_TO_IOM_A_CLK_2_DN")
	)
	(segment
		(start 236.962442 -138.177778)
		(end 237.177072 -138.473434)
		(width 0.1651)
		(layer "F.Cu")
		(net "PCIE_COMP_A_TO_IOM_A_CLK_2_DN")
	)
	(segment
		(start 188.014356 -30.785562)
		(end 182.196486 -29.640276)
		(width 0.1651)
		(layer "F.Cu")
		(net "PCIE_COMP_A_TO_IOM_A_CLK_2_DN")
	)
	(segment
		(start 234.025694 -89.496138)
		(end 201.825098 -39.755318)
		(width 0.1651)
		(layer "F.Cu")
		(net "PCIE_COMP_A_TO_IOM_A_CLK_2_DN")
	)
	(segment
		(start 241.059462 -138.6459)
		(end 242.05946 -137.645902)
		(width 0.1651)
		(layer "F.Cu")
		(net "PCIE_COMP_A_TO_IOM_A_CLK_2_DN")
	)
	(segment
		(start 143.096996 -32.375348)
		(end 142.595854 -31.682182)
		(width 0.1651)
		(layer "F.Cu")
		(net "PCIE_COMP_A_TO_IOM_A_CLK_2_DN")
	)
	(segment
		(start 156.685234 -29.916882)
		(end 143.8783 -32.529272)
		(width 0.1651)
		(layer "F.Cu")
		(net "PCIE_COMP_A_TO_IOM_A_CLK_2_DN")
	)
	(segment
		(start 237.516416 -138.6459)
		(end 241.059462 -138.6459)
		(width 0.1651)
		(layer "F.Cu")
		(net "PCIE_COMP_A_TO_IOM_A_CLK_2_DN")
	)
	(segment
		(start 247.585738 -95.502476)
		(end 246.026686 -94.233238)
		(width 0.1651)
		(layer "F.Cu")
		(net "PCIE_COMP_A_TO_IOM_A_CLK_2_DN")
	)
	(segment
		(start 236.050074 -138.49985)
		(end 236.771434 -138.138916)
		(width 0.1651)
		(layer "F.Cu")
		(net "PCIE_COMP_A_TO_IOM_A_CLK_2_DN")
	)
	(segment
		(start 242.05946 -137.645902)
		(end 243.386102 -137.645902)
		(width 0.1651)
		(layer "F.Cu")
		(net "PCIE_COMP_A_TO_IOM_A_CLK_2_DN")
	)
	(segment
		(start 142.595854 -31.682182)
		(end 142.595854 -30.367478)
		(width 0.1651)
		(layer "F.Cu")
		(net "PCIE_COMP_A_TO_IOM_A_CLK_2_DN")
	)
	(segment
		(start 143.8783 -32.529272)
		(end 143.096996 -32.375348)
		(width 0.1651)
		(layer "F.Cu")
		(net "PCIE_COMP_A_TO_IOM_A_CLK_2_DN")
	)
	(segment
		(start 246.026686 -94.233238)
		(end 234.025694 -89.496138)
		(width 0.1651)
		(layer "F.Cu")
		(net "PCIE_COMP_A_TO_IOM_A_CLK_2_DN")
	)
	(segment
		(start 143.34998 -30.12313)
		(end 143.34998 -30.550104)
		(width 0.1651)
		(layer "F.Cu")
		(net "PCIE_COMP_A_TO_IOM_A_CLK_2_DN")
	)
	(segment
		(start 243.386102 -137.645902)
		(end 244.133116 -136.898888)
		(width 0.1651)
		(layer "F.Cu")
		(net "PCIE_COMP_A_TO_IOM_A_CLK_2_DN")
	)
	(segment
		(start 168.98112 -32.33547)
		(end 156.685234 -29.916882)
		(width 0.1651)
		(layer "F.Cu")
		(net "PCIE_COMP_A_TO_IOM_A_CLK_2_DN")
	)
	(segment
		(start 201.825098 -39.755318)
		(end 188.014356 -30.785562)
		(width 0.1651)
		(layer "F.Cu")
		(net "PCIE_COMP_A_TO_IOM_A_CLK_2_DN")
	)
	(segment
		(start 182.196486 -29.640276)
		(end 168.98112 -32.33547)
		(width 0.1651)
		(layer "F.Cu")
		(net "PCIE_COMP_A_TO_IOM_A_CLK_2_DN")
	)
	(segment
		(start 142.967202 -29.99613)
		(end 143.22298 -29.99613)
		(width 0.1651)
		(layer "F.Cu")
		(net "PCIE_COMP_A_TO_IOM_A_CLK_2_DN")
	)
	(segment
		(start 244.133116 -136.898888)
		(end 250.947682 -106.964226)
		(width 0.1651)
		(layer "F.Cu")
		(net "PCIE_COMP_A_TO_IOM_A_CLK_2_DN")
	)
	(segment
		(start 250.947682 -106.964226)
		(end 247.585738 -95.502476)
		(width 0.1651)
		(layer "F.Cu")
		(net "PCIE_COMP_A_TO_IOM_A_CLK_2_DN")
	)
	(arc
		(start 143.22298 -29.99613)
		(mid 143.312783 -30.033327)
		(end 143.34998 -30.12313)
		(width 0.1651)
		(layer "F.Cu")
		(net "PCIE_COMP_A_TO_IOM_A_CLK_2_DN")
	)
	(arc
		(start 236.771434 -138.138916)
		(mid 236.872013 -138.123765)
		(end 236.962442 -138.170412)
		(width 0.1651)
		(layer "F.Cu")
		(net "PCIE_COMP_A_TO_IOM_A_CLK_2_DN")
	)
	(arc
		(start 237.177072 -138.473434)
		(mid 237.326035 -138.600412)
		(end 237.516416 -138.6459)
		(width 0.1651)
		(layer "F.Cu")
		(net "PCIE_COMP_A_TO_IOM_A_CLK_2_DN")
	)
	(arc
		(start 142.595854 -30.367478)
		(mid 142.704619 -30.104895)
		(end 142.967202 -29.99613)
		(width 0.1651)
		(layer "F.Cu")
		(net "PCIE_COMP_A_TO_IOM_A_CLK_2_DN")
	)
	(segment
		(start 142.822676 -31.976822)
		(end 143.101822 -32.164528)
		(width 0.1397)
		(layer "In9.Cu")
		(net "PCIE_COMP_A_TO_IOM_A_9_DP")
	)
	(segment
		(start 234.411012 -169.95775)
		(end 235.030264 -170.907456)
		(width 0.1397)
		(layer "In9.Cu")
		(net "PCIE_COMP_A_TO_IOM_A_9_DP")
	)
	(segment
		(start 234.451906 -169.764456)
		(end 234.411012 -169.95775)
		(width 0.1397)
		(layer "In9.Cu")
		(net "PCIE_COMP_A_TO_IOM_A_9_DP")
	)
	(segment
		(start 235.60913 -171.353734)
		(end 236.599984 -171.353734)
		(width 0.1397)
		(layer "In9.Cu")
		(net "PCIE_COMP_A_TO_IOM_A_9_DP")
	)
	(segment
		(start 233.190288 -168.085516)
		(end 233.419142 -168.436544)
		(width 0.1397)
		(layer "In9.Cu")
		(net "PCIE_COMP_A_TO_IOM_A_9_DP")
	)
	(segment
		(start 234.029504 -169.372534)
		(end 234.223052 -169.413428)
		(width 0.1397)
		(layer "In9.Cu")
		(net "PCIE_COMP_A_TO_IOM_A_9_DP")
	)
	(segment
		(start 243.497862 -29.054044)
		(end 244.935248 -30.49143)
		(width 0.1397)
		(layer "In9.Cu")
		(net "PCIE_COMP_A_TO_IOM_A_9_DP")
	)
	(segment
		(start 159.22371 -35.365182)
		(end 217.636852 -23.921212)
		(width 0.1397)
		(layer "In9.Cu")
		(net "PCIE_COMP_A_TO_IOM_A_9_DP")
	)
	(segment
		(start 233.403902 -27.054048)
		(end 236.525054 -27.054048)
		(width 0.1397)
		(layer "In9.Cu")
		(net "PCIE_COMP_A_TO_IOM_A_9_DP")
	)
	(segment
		(start 235.030264 -170.907456)
		(end 235.60913 -171.353734)
		(width 0.1397)
		(layer "In9.Cu")
		(net "PCIE_COMP_A_TO_IOM_A_9_DP")
	)
	(segment
		(start 246.973344 -86.492334)
		(end 244.402356 -90.303858)
		(width 0.1397)
		(layer "In9.Cu")
		(net "PCIE_COMP_A_TO_IOM_A_9_DP")
	)
	(segment
		(start 142.595854 -31.632144)
		(end 142.822676 -31.976822)
		(width 0.1397)
		(layer "In9.Cu")
		(net "PCIE_COMP_A_TO_IOM_A_9_DP")
	)
	(segment
		(start 241.024918 -28.054046)
		(end 242.024916 -29.054044)
		(width 0.1397)
		(layer "In9.Cu")
		(net "PCIE_COMP_A_TO_IOM_A_9_DP")
	)
	(segment
		(start 232.80878 -167.5003)
		(end 233.002074 -167.541194)
		(width 0.1397)
		(layer "In9.Cu")
		(net "PCIE_COMP_A_TO_IOM_A_9_DP")
	)
	(segment
		(start 223.275398 -145.13179)
		(end 225.962464 -156.999178)
		(width 0.1397)
		(layer "In9.Cu")
		(net "PCIE_COMP_A_TO_IOM_A_9_DP")
	)
	(segment
		(start 241.294412 -171.872148)
		(end 240.549938 -171.499784)
		(width 0.1397)
		(layer "In9.Cu")
		(net "PCIE_COMP_A_TO_IOM_A_9_DP")
	)
	(segment
		(start 233.002074 -167.541194)
		(end 233.230928 -167.892222)
		(width 0.1397)
		(layer "In9.Cu")
		(net "PCIE_COMP_A_TO_IOM_A_9_DP")
	)
	(segment
		(start 233.80065 -169.021506)
		(end 234.029504 -169.372534)
		(width 0.1397)
		(layer "In9.Cu")
		(net "PCIE_COMP_A_TO_IOM_A_9_DP")
	)
	(segment
		(start 234.223052 -169.413428)
		(end 234.451906 -169.764456)
		(width 0.1397)
		(layer "In9.Cu")
		(net "PCIE_COMP_A_TO_IOM_A_9_DP")
	)
	(segment
		(start 233.419142 -168.436544)
		(end 233.612436 -168.477184)
		(width 0.1397)
		(layer "In9.Cu")
		(net "PCIE_COMP_A_TO_IOM_A_9_DP")
	)
	(segment
		(start 233.21391 -100.959666)
		(end 223.275398 -145.13179)
		(width 0.1397)
		(layer "In9.Cu")
		(net "PCIE_COMP_A_TO_IOM_A_9_DP")
	)
	(segment
		(start 142.595854 -18.390108)
		(end 142.595854 -31.632144)
		(width 0.1397)
		(layer "In9.Cu")
		(net "PCIE_COMP_A_TO_IOM_A_9_DP")
	)
	(segment
		(start 142.40637 -18.026634)
		(end 142.473426 -18.093944)
		(width 0.1397)
		(layer "In9.Cu")
		(net "PCIE_COMP_A_TO_IOM_A_9_DP")
	)
	(segment
		(start 141.549882 -17.349978)
		(end 141.549882 -17.761458)
		(width 0.1397)
		(layer "In9.Cu")
		(net "PCIE_COMP_A_TO_IOM_A_9_DP")
	)
	(segment
		(start 237.599982 -172.353732)
		(end 240.88598 -172.353732)
		(width 0.1397)
		(layer "In9.Cu")
		(net "PCIE_COMP_A_TO_IOM_A_9_DP")
	)
	(segment
		(start 237.525052 -28.054046)
		(end 241.024918 -28.054046)
		(width 0.1397)
		(layer "In9.Cu")
		(net "PCIE_COMP_A_TO_IOM_A_9_DP")
	)
	(segment
		(start 233.230928 -167.892222)
		(end 233.190288 -168.085516)
		(width 0.1397)
		(layer "In9.Cu")
		(net "PCIE_COMP_A_TO_IOM_A_9_DP")
	)
	(segment
		(start 235.46943 -97.486978)
		(end 234.604306 -98.8187)
		(width 0.1397)
		(layer "In9.Cu")
		(net "PCIE_COMP_A_TO_IOM_A_9_DP")
	)
	(segment
		(start 234.604306 -98.8187)
		(end 233.21391 -100.959666)
		(width 0.1397)
		(layer "In9.Cu")
		(net "PCIE_COMP_A_TO_IOM_A_9_DP")
	)
	(segment
		(start 143.101822 -32.164528)
		(end 143.101822 -32.164782)
		(width 0.1397)
		(layer "In9.Cu")
		(net "PCIE_COMP_A_TO_IOM_A_9_DP")
	)
	(segment
		(start 244.402356 -90.303858)
		(end 235.46943 -97.486978)
		(width 0.1397)
		(layer "In9.Cu")
		(net "PCIE_COMP_A_TO_IOM_A_9_DP")
	)
	(segment
		(start 236.525054 -27.054048)
		(end 237.525052 -28.054046)
		(width 0.1397)
		(layer "In9.Cu")
		(net "PCIE_COMP_A_TO_IOM_A_9_DP")
	)
	(segment
		(start 252.653038 -57.26557)
		(end 246.973344 -86.492334)
		(width 0.1397)
		(layer "In9.Cu")
		(net "PCIE_COMP_A_TO_IOM_A_9_DP")
	)
	(segment
		(start 242.024916 -29.054044)
		(end 243.497862 -29.054044)
		(width 0.1397)
		(layer "In9.Cu")
		(net "PCIE_COMP_A_TO_IOM_A_9_DP")
	)
	(segment
		(start 248.468388 -35.730434)
		(end 252.653038 -57.26557)
		(width 0.1397)
		(layer "In9.Cu")
		(net "PCIE_COMP_A_TO_IOM_A_9_DP")
	)
	(segment
		(start 141.692376 -17.903952)
		(end 141.69263 -17.904206)
		(width 0.1397)
		(layer "In9.Cu")
		(net "PCIE_COMP_A_TO_IOM_A_9_DP")
	)
	(segment
		(start 217.636852 -23.921212)
		(end 233.403902 -27.054048)
		(width 0.1397)
		(layer "In9.Cu")
		(net "PCIE_COMP_A_TO_IOM_A_9_DP")
	)
	(segment
		(start 233.612436 -168.477184)
		(end 233.841544 -168.828212)
		(width 0.1397)
		(layer "In9.Cu")
		(net "PCIE_COMP_A_TO_IOM_A_9_DP")
	)
	(segment
		(start 236.599984 -171.353734)
		(end 237.599982 -172.353732)
		(width 0.1397)
		(layer "In9.Cu")
		(net "PCIE_COMP_A_TO_IOM_A_9_DP")
	)
	(segment
		(start 225.962464 -156.999178)
		(end 232.80878 -167.5003)
		(width 0.1397)
		(layer "In9.Cu")
		(net "PCIE_COMP_A_TO_IOM_A_9_DP")
	)
	(segment
		(start 141.586966 -17.85112)
		(end 141.602714 -17.866868)
		(width 0.1397)
		(layer "In9.Cu")
		(net "PCIE_COMP_A_TO_IOM_A_9_DP")
	)
	(segment
		(start 244.935248 -30.49143)
		(end 248.468388 -35.730434)
		(width 0.1397)
		(layer "In9.Cu")
		(net "PCIE_COMP_A_TO_IOM_A_9_DP")
	)
	(segment
		(start 241.294412 -172.184568)
		(end 241.356896 -172.0596)
		(width 0.1397)
		(layer "In9.Cu")
		(net "PCIE_COMP_A_TO_IOM_A_9_DP")
	)
	(segment
		(start 141.69263 -17.904206)
		(end 142.109952 -17.904206)
		(width 0.1397)
		(layer "In9.Cu")
		(net "PCIE_COMP_A_TO_IOM_A_9_DP")
	)
	(segment
		(start 233.841544 -168.828212)
		(end 233.80065 -169.021506)
		(width 0.1397)
		(layer "In9.Cu")
		(net "PCIE_COMP_A_TO_IOM_A_9_DP")
	)
	(segment
		(start 143.101822 -32.164782)
		(end 159.22371 -35.365182)
		(width 0.1397)
		(layer "In9.Cu")
		(net "PCIE_COMP_A_TO_IOM_A_9_DP")
	)
	(arc
		(start 240.88598 -172.353732)
		(mid 241.107016 -172.309765)
		(end 241.294412 -172.184568)
		(width 0.1397)
		(layer "In9.Cu")
		(net "PCIE_COMP_A_TO_IOM_A_9_DP")
	)
	(arc
		(start 142.109952 -17.904206)
		(mid 142.270305 -17.935991)
		(end 142.40637 -18.026634)
		(width 0.1397)
		(layer "In9.Cu")
		(net "PCIE_COMP_A_TO_IOM_A_9_DP")
	)
	(arc
		(start 141.602714 -17.866868)
		(mid 141.643865 -17.894301)
		(end 141.692376 -17.903952)
		(width 0.1397)
		(layer "In9.Cu")
		(net "PCIE_COMP_A_TO_IOM_A_9_DP")
	)
	(arc
		(start 241.356896 -172.0596)
		(mid 241.364477 -171.952933)
		(end 241.294412 -171.872148)
		(width 0.1397)
		(layer "In9.Cu")
		(net "PCIE_COMP_A_TO_IOM_A_9_DP")
	)
	(arc
		(start 142.473426 -18.093944)
		(mid 142.564029 -18.229869)
		(end 142.595854 -18.390108)
		(width 0.1397)
		(layer "In9.Cu")
		(net "PCIE_COMP_A_TO_IOM_A_9_DP")
	)
	(arc
		(start 141.549882 -17.761458)
		(mid 141.559515 -17.809976)
		(end 141.586966 -17.85112)
		(width 0.1397)
		(layer "In9.Cu")
		(net "PCIE_COMP_A_TO_IOM_A_9_DP")
	)
	(segment
		(start 241.536728 -172.353224)
		(end 241.618262 -172.190156)
		(width 0.1397)
		(layer "In9.Cu")
		(net "PCIE_COMP_A_TO_IOM_A_9_DN")
	)
	(segment
		(start 232.940352 -100.84435)
		(end 227.959412 -122.981466)
		(width 0.1397)
		(layer "In9.Cu")
		(net "PCIE_COMP_A_TO_IOM_A_9_DN")
	)
	(segment
		(start 244.184678 -90.103706)
		(end 235.249974 -97.288604)
		(width 0.1397)
		(layer "In9.Cu")
		(net "PCIE_COMP_A_TO_IOM_A_9_DN")
	)
	(segment
		(start 248.192798 -35.84448)
		(end 252.35535 -57.26557)
		(width 0.1397)
		(layer "In9.Cu")
		(net "PCIE_COMP_A_TO_IOM_A_9_DN")
	)
	(segment
		(start 159.223456 -35.663124)
		(end 217.636344 -24.219154)
		(width 0.1397)
		(layer "In9.Cu")
		(net "PCIE_COMP_A_TO_IOM_A_9_DN")
	)
	(segment
		(start 141.586966 -18.249138)
		(end 141.602714 -18.23339)
		(width 0.1397)
		(layer "In9.Cu")
		(net "PCIE_COMP_A_TO_IOM_A_9_DN")
	)
	(segment
		(start 142.987268 -32.439864)
		(end 159.223456 -35.663124)
		(width 0.1397)
		(layer "In9.Cu")
		(net "PCIE_COMP_A_TO_IOM_A_9_DN")
	)
	(segment
		(start 244.70868 -30.67812)
		(end 248.192798 -35.84448)
		(width 0.1397)
		(layer "In9.Cu")
		(net "PCIE_COMP_A_TO_IOM_A_9_DN")
	)
	(segment
		(start 241.903758 -29.346144)
		(end 243.376704 -29.346144)
		(width 0.1397)
		(layer "In9.Cu")
		(net "PCIE_COMP_A_TO_IOM_A_9_DN")
	)
	(segment
		(start 142.61084 -32.186372)
		(end 142.799308 -32.313372)
		(width 0.1397)
		(layer "In9.Cu")
		(net "PCIE_COMP_A_TO_IOM_A_9_DN")
	)
	(segment
		(start 141.692376 -18.196306)
		(end 142.109952 -18.196306)
		(width 0.1397)
		(layer "In9.Cu")
		(net "PCIE_COMP_A_TO_IOM_A_9_DN")
	)
	(segment
		(start 235.509562 -171.645834)
		(end 236.478826 -171.645834)
		(width 0.1397)
		(layer "In9.Cu")
		(net "PCIE_COMP_A_TO_IOM_A_9_DN")
	)
	(segment
		(start 227.959412 -122.981466)
		(end 222.975932 -145.132044)
		(width 0.1397)
		(layer "In9.Cu")
		(net "PCIE_COMP_A_TO_IOM_A_9_DN")
	)
	(segment
		(start 141.549882 -18.750026)
		(end 141.549882 -18.3388)
		(width 0.1397)
		(layer "In9.Cu")
		(net "PCIE_COMP_A_TO_IOM_A_9_DN")
	)
	(segment
		(start 246.697754 -86.378288)
		(end 244.184678 -90.103706)
		(width 0.1397)
		(layer "In9.Cu")
		(net "PCIE_COMP_A_TO_IOM_A_9_DN")
	)
	(segment
		(start 240.90376 -28.346146)
		(end 241.903758 -29.346144)
		(width 0.1397)
		(layer "In9.Cu")
		(net "PCIE_COMP_A_TO_IOM_A_9_DN")
	)
	(segment
		(start 236.403896 -27.346148)
		(end 237.403894 -28.346146)
		(width 0.1397)
		(layer "In9.Cu")
		(net "PCIE_COMP_A_TO_IOM_A_9_DN")
	)
	(segment
		(start 222.975932 -145.132044)
		(end 225.688906 -157.115002)
		(width 0.1397)
		(layer "In9.Cu")
		(net "PCIE_COMP_A_TO_IOM_A_9_DN")
	)
	(segment
		(start 235.249974 -97.288604)
		(end 234.359196 -98.659442)
		(width 0.1397)
		(layer "In9.Cu")
		(net "PCIE_COMP_A_TO_IOM_A_9_DN")
	)
	(segment
		(start 234.812586 -171.108624)
		(end 235.509562 -171.645834)
		(width 0.1397)
		(layer "In9.Cu")
		(net "PCIE_COMP_A_TO_IOM_A_9_DN")
	)
	(segment
		(start 217.636344 -24.219154)
		(end 233.374946 -27.346148)
		(width 0.1397)
		(layer "In9.Cu")
		(net "PCIE_COMP_A_TO_IOM_A_9_DN")
	)
	(segment
		(start 142.799308 -32.313372)
		(end 142.987268 -32.439864)
		(width 0.1397)
		(layer "In9.Cu")
		(net "PCIE_COMP_A_TO_IOM_A_9_DN")
	)
	(segment
		(start 243.376704 -29.346144)
		(end 244.70868 -30.67812)
		(width 0.1397)
		(layer "In9.Cu")
		(net "PCIE_COMP_A_TO_IOM_A_9_DN")
	)
	(segment
		(start 237.403894 -28.346146)
		(end 240.90376 -28.346146)
		(width 0.1397)
		(layer "In9.Cu")
		(net "PCIE_COMP_A_TO_IOM_A_9_DN")
	)
	(segment
		(start 142.303754 -18.390108)
		(end 142.303754 -31.719774)
		(width 0.1397)
		(layer "In9.Cu")
		(net "PCIE_COMP_A_TO_IOM_A_9_DN")
	)
	(segment
		(start 233.374946 -27.346148)
		(end 236.403896 -27.346148)
		(width 0.1397)
		(layer "In9.Cu")
		(net "PCIE_COMP_A_TO_IOM_A_9_DN")
	)
	(segment
		(start 252.35535 -57.26557)
		(end 246.697754 -86.378288)
		(width 0.1397)
		(layer "In9.Cu")
		(net "PCIE_COMP_A_TO_IOM_A_9_DN")
	)
	(segment
		(start 142.303754 -31.719774)
		(end 142.61084 -32.186372)
		(width 0.1397)
		(layer "In9.Cu")
		(net "PCIE_COMP_A_TO_IOM_A_9_DN")
	)
	(segment
		(start 225.688906 -157.115002)
		(end 234.812586 -171.108624)
		(width 0.1397)
		(layer "In9.Cu")
		(net "PCIE_COMP_A_TO_IOM_A_9_DN")
	)
	(segment
		(start 237.478824 -172.645832)
		(end 240.885726 -172.645832)
		(width 0.1397)
		(layer "In9.Cu")
		(net "PCIE_COMP_A_TO_IOM_A_9_DN")
	)
	(segment
		(start 236.478826 -171.645834)
		(end 237.478824 -172.645832)
		(width 0.1397)
		(layer "In9.Cu")
		(net "PCIE_COMP_A_TO_IOM_A_9_DN")
	)
	(segment
		(start 142.199614 -18.23339)
		(end 142.26667 -18.300446)
		(width 0.1397)
		(layer "In9.Cu")
		(net "PCIE_COMP_A_TO_IOM_A_9_DN")
	)
	(segment
		(start 234.359196 -98.659442)
		(end 232.940352 -100.84435)
		(width 0.1397)
		(layer "In9.Cu")
		(net "PCIE_COMP_A_TO_IOM_A_9_DN")
	)
	(segment
		(start 241.805714 -172.127672)
		(end 242.549934 -172.499782)
		(width 0.1397)
		(layer "In9.Cu")
		(net "PCIE_COMP_A_TO_IOM_A_9_DN")
	)
	(arc
		(start 240.885726 -172.645832)
		(mid 241.242602 -172.569352)
		(end 241.536728 -172.353224)
		(width 0.1397)
		(layer "In9.Cu")
		(net "PCIE_COMP_A_TO_IOM_A_9_DN")
	)
	(arc
		(start 141.602714 -18.23339)
		(mid 141.643865 -18.205957)
		(end 141.692376 -18.196306)
		(width 0.1397)
		(layer "In9.Cu")
		(net "PCIE_COMP_A_TO_IOM_A_9_DN")
	)
	(arc
		(start 142.26667 -18.300446)
		(mid 142.294103 -18.341597)
		(end 142.303754 -18.390108)
		(width 0.1397)
		(layer "In9.Cu")
		(net "PCIE_COMP_A_TO_IOM_A_9_DN")
	)
	(arc
		(start 241.618262 -172.190156)
		(mid 241.699047 -172.120091)
		(end 241.805714 -172.127672)
		(width 0.1397)
		(layer "In9.Cu")
		(net "PCIE_COMP_A_TO_IOM_A_9_DN")
	)
	(arc
		(start 142.109952 -18.196306)
		(mid 142.15847 -18.205939)
		(end 142.199614 -18.23339)
		(width 0.1397)
		(layer "In9.Cu")
		(net "PCIE_COMP_A_TO_IOM_A_9_DN")
	)
	(arc
		(start 141.549882 -18.3388)
		(mid 141.559515 -18.290282)
		(end 141.586966 -18.249138)
		(width 0.1397)
		(layer "In9.Cu")
		(net "PCIE_COMP_A_TO_IOM_A_9_DN")
	)
	(segment
		(start 241.294412 -168.184576)
		(end 241.356896 -168.059608)
		(width 0.1397)
		(layer "In9.Cu")
		(net "PCIE_COMP_A_TO_IOM_A_8_DP")
	)
	(segment
		(start 234.795568 -166.727378)
		(end 234.897168 -166.805864)
		(width 0.1397)
		(layer "In9.Cu")
		(net "PCIE_COMP_A_TO_IOM_A_8_DP")
	)
	(segment
		(start 233.80573 -165.20287)
		(end 234.033822 -165.554406)
		(width 0.1397)
		(layer "In9.Cu")
		(net "PCIE_COMP_A_TO_IOM_A_8_DP")
	)
	(segment
		(start 214.61476 -21.367496)
		(end 233.171492 -25.054052)
		(width 0.1397)
		(layer "In9.Cu")
		(net "PCIE_COMP_A_TO_IOM_A_8_DP")
	)
	(segment
		(start 237.600998 -168.35374)
		(end 240.88598 -168.35374)
		(width 0.1397)
		(layer "In9.Cu")
		(net "PCIE_COMP_A_TO_IOM_A_8_DP")
	)
	(segment
		(start 233.23804 -164.072316)
		(end 233.197146 -164.26561)
		(width 0.1397)
		(layer "In9.Cu")
		(net "PCIE_COMP_A_TO_IOM_A_8_DP")
	)
	(segment
		(start 235.608876 -167.353742)
		(end 236.601 -167.353742)
		(width 0.1397)
		(layer "In9.Cu")
		(net "PCIE_COMP_A_TO_IOM_A_8_DP")
	)
	(segment
		(start 144.645888 -18.90395)
		(end 144.646396 -18.904458)
		(width 0.1397)
		(layer "In9.Cu")
		(net "PCIE_COMP_A_TO_IOM_A_8_DP")
	)
	(segment
		(start 234.033822 -165.554406)
		(end 234.220512 -165.59403)
		(width 0.1397)
		(layer "In9.Cu")
		(net "PCIE_COMP_A_TO_IOM_A_8_DP")
	)
	(segment
		(start 245.035324 -91.525344)
		(end 235.792518 -98.958146)
		(width 0.1397)
		(layer "In9.Cu")
		(net "PCIE_COMP_A_TO_IOM_A_8_DP")
	)
	(segment
		(start 234.897168 -166.805864)
		(end 235.608876 -167.353742)
		(width 0.1397)
		(layer "In9.Cu")
		(net "PCIE_COMP_A_TO_IOM_A_8_DP")
	)
	(segment
		(start 237.525052 -26.05405)
		(end 241.024918 -26.05405)
		(width 0.1397)
		(layer "In9.Cu")
		(net "PCIE_COMP_A_TO_IOM_A_8_DP")
	)
	(segment
		(start 233.846878 -165.00983)
		(end 233.80573 -165.20287)
		(width 0.1397)
		(layer "In9.Cu")
		(net "PCIE_COMP_A_TO_IOM_A_8_DP")
	)
	(segment
		(start 143.543782 -18.90395)
		(end 144.645888 -18.90395)
		(width 0.1397)
		(layer "In9.Cu")
		(net "PCIE_COMP_A_TO_IOM_A_8_DP")
	)
	(segment
		(start 234.220512 -165.59403)
		(end 234.453938 -165.953694)
		(width 0.1397)
		(layer "In9.Cu")
		(net "PCIE_COMP_A_TO_IOM_A_8_DP")
	)
	(segment
		(start 225.081338 -145.1229)
		(end 227.390452 -155.32354)
		(width 0.1397)
		(layer "In9.Cu")
		(net "PCIE_COMP_A_TO_IOM_A_8_DP")
	)
	(segment
		(start 144.646396 -18.904458)
		(end 186.589162 -27.23769)
		(width 0.1397)
		(layer "In9.Cu")
		(net "PCIE_COMP_A_TO_IOM_A_8_DP")
	)
	(segment
		(start 243.940584 -27.054048)
		(end 246.633492 -29.746956)
		(width 0.1397)
		(layer "In9.Cu")
		(net "PCIE_COMP_A_TO_IOM_A_8_DP")
	)
	(segment
		(start 143.34998 -18.35023)
		(end 143.34998 -18.710148)
		(width 0.1397)
		(layer "In9.Cu")
		(net "PCIE_COMP_A_TO_IOM_A_8_DP")
	)
	(segment
		(start 233.618532 -164.658294)
		(end 233.846878 -165.00983)
		(width 0.1397)
		(layer "In9.Cu")
		(net "PCIE_COMP_A_TO_IOM_A_8_DP")
	)
	(segment
		(start 241.294412 -167.872156)
		(end 240.549938 -167.499792)
		(width 0.1397)
		(layer "In9.Cu")
		(net "PCIE_COMP_A_TO_IOM_A_8_DP")
	)
	(segment
		(start 241.024918 -26.05405)
		(end 242.024916 -27.054048)
		(width 0.1397)
		(layer "In9.Cu")
		(net "PCIE_COMP_A_TO_IOM_A_8_DP")
	)
	(segment
		(start 233.197146 -164.26561)
		(end 233.425238 -164.617146)
		(width 0.1397)
		(layer "In9.Cu")
		(net "PCIE_COMP_A_TO_IOM_A_8_DP")
	)
	(segment
		(start 249.81408 -34.463736)
		(end 254.254762 -57.318402)
		(width 0.1397)
		(layer "In9.Cu")
		(net "PCIE_COMP_A_TO_IOM_A_8_DP")
	)
	(segment
		(start 234.414314 -166.140384)
		(end 234.795568 -166.727378)
		(width 0.1397)
		(layer "In9.Cu")
		(net "PCIE_COMP_A_TO_IOM_A_8_DP")
	)
	(segment
		(start 242.024916 -27.054048)
		(end 243.940584 -27.054048)
		(width 0.1397)
		(layer "In9.Cu")
		(net "PCIE_COMP_A_TO_IOM_A_8_DP")
	)
	(segment
		(start 254.254762 -57.318402)
		(end 248.66473 -86.080854)
		(width 0.1397)
		(layer "In9.Cu")
		(net "PCIE_COMP_A_TO_IOM_A_8_DP")
	)
	(segment
		(start 233.425238 -164.617146)
		(end 233.618532 -164.658294)
		(width 0.1397)
		(layer "In9.Cu")
		(net "PCIE_COMP_A_TO_IOM_A_8_DP")
	)
	(segment
		(start 232.816654 -163.679886)
		(end 233.009948 -163.721034)
		(width 0.1397)
		(layer "In9.Cu")
		(net "PCIE_COMP_A_TO_IOM_A_8_DP")
	)
	(segment
		(start 235.792518 -98.958146)
		(end 235.060744 -100.084636)
		(width 0.1397)
		(layer "In9.Cu")
		(net "PCIE_COMP_A_TO_IOM_A_8_DP")
	)
	(segment
		(start 235.060744 -100.084636)
		(end 225.081338 -145.1229)
		(width 0.1397)
		(layer "In9.Cu")
		(net "PCIE_COMP_A_TO_IOM_A_8_DP")
	)
	(segment
		(start 246.633492 -29.746956)
		(end 249.81408 -34.463736)
		(width 0.1397)
		(layer "In9.Cu")
		(net "PCIE_COMP_A_TO_IOM_A_8_DP")
	)
	(segment
		(start 186.589162 -27.23769)
		(end 214.61476 -21.367496)
		(width 0.1397)
		(layer "In9.Cu")
		(net "PCIE_COMP_A_TO_IOM_A_8_DP")
	)
	(segment
		(start 227.390452 -155.32354)
		(end 232.816654 -163.679886)
		(width 0.1397)
		(layer "In9.Cu")
		(net "PCIE_COMP_A_TO_IOM_A_8_DP")
	)
	(segment
		(start 236.525054 -25.054052)
		(end 237.525052 -26.05405)
		(width 0.1397)
		(layer "In9.Cu")
		(net "PCIE_COMP_A_TO_IOM_A_8_DP")
	)
	(segment
		(start 236.601 -167.353742)
		(end 237.600998 -168.35374)
		(width 0.1397)
		(layer "In9.Cu")
		(net "PCIE_COMP_A_TO_IOM_A_8_DP")
	)
	(segment
		(start 248.66473 -86.080854)
		(end 245.035324 -91.525344)
		(width 0.1397)
		(layer "In9.Cu")
		(net "PCIE_COMP_A_TO_IOM_A_8_DP")
	)
	(segment
		(start 233.009948 -163.721034)
		(end 233.23804 -164.072316)
		(width 0.1397)
		(layer "In9.Cu")
		(net "PCIE_COMP_A_TO_IOM_A_8_DP")
	)
	(segment
		(start 233.171492 -25.054052)
		(end 236.525054 -25.054052)
		(width 0.1397)
		(layer "In9.Cu")
		(net "PCIE_COMP_A_TO_IOM_A_8_DP")
	)
	(segment
		(start 234.453938 -165.953694)
		(end 234.414314 -166.140384)
		(width 0.1397)
		(layer "In9.Cu")
		(net "PCIE_COMP_A_TO_IOM_A_8_DP")
	)
	(arc
		(start 240.88598 -168.35374)
		(mid 241.107016 -168.309773)
		(end 241.294412 -168.184576)
		(width 0.1397)
		(layer "In9.Cu")
		(net "PCIE_COMP_A_TO_IOM_A_8_DP")
	)
	(arc
		(start 241.356896 -168.059608)
		(mid 241.364477 -167.952941)
		(end 241.294412 -167.872156)
		(width 0.1397)
		(layer "In9.Cu")
		(net "PCIE_COMP_A_TO_IOM_A_8_DP")
	)
	(arc
		(start 143.34998 -18.710148)
		(mid 143.406743 -18.847187)
		(end 143.543782 -18.90395)
		(width 0.1397)
		(layer "In9.Cu")
		(net "PCIE_COMP_A_TO_IOM_A_8_DP")
	)
	(segment
		(start 235.696252 -167.645842)
		(end 236.479842 -167.645842)
		(width 0.1397)
		(layer "In9.Cu")
		(net "PCIE_COMP_A_TO_IOM_A_8_DN")
	)
	(segment
		(start 253.957074 -57.318402)
		(end 248.38914 -85.96757)
		(width 0.1397)
		(layer "In9.Cu")
		(net "PCIE_COMP_A_TO_IOM_A_8_DN")
	)
	(segment
		(start 246.406924 -29.933646)
		(end 249.53849 -34.577782)
		(width 0.1397)
		(layer "In9.Cu")
		(net "PCIE_COMP_A_TO_IOM_A_8_DN")
	)
	(segment
		(start 224.781872 -145.123662)
		(end 227.116894 -155.43911)
		(width 0.1397)
		(layer "In9.Cu")
		(net "PCIE_COMP_A_TO_IOM_A_8_DN")
	)
	(segment
		(start 234.577636 -166.928546)
		(end 235.510578 -167.646858)
		(width 0.1397)
		(layer "In9.Cu")
		(net "PCIE_COMP_A_TO_IOM_A_8_DN")
	)
	(segment
		(start 241.903758 -27.346148)
		(end 243.819426 -27.346148)
		(width 0.1397)
		(layer "In9.Cu")
		(net "PCIE_COMP_A_TO_IOM_A_8_DN")
	)
	(segment
		(start 143.543782 -19.19605)
		(end 144.6149 -19.19605)
		(width 0.1397)
		(layer "In9.Cu")
		(net "PCIE_COMP_A_TO_IOM_A_8_DN")
	)
	(segment
		(start 240.90376 -26.34615)
		(end 241.903758 -27.346148)
		(width 0.1397)
		(layer "In9.Cu")
		(net "PCIE_COMP_A_TO_IOM_A_8_DN")
	)
	(segment
		(start 144.6149 -19.19605)
		(end 186.590686 -27.535886)
		(width 0.1397)
		(layer "In9.Cu")
		(net "PCIE_COMP_A_TO_IOM_A_8_DN")
	)
	(segment
		(start 235.510578 -167.646858)
		(end 235.695236 -167.646858)
		(width 0.1397)
		(layer "In9.Cu")
		(net "PCIE_COMP_A_TO_IOM_A_8_DN")
	)
	(segment
		(start 241.536728 -168.353232)
		(end 241.618262 -168.190164)
		(width 0.1397)
		(layer "In9.Cu")
		(net "PCIE_COMP_A_TO_IOM_A_8_DN")
	)
	(segment
		(start 143.34998 -19.750024)
		(end 143.34998 -19.389852)
		(width 0.1397)
		(layer "In9.Cu")
		(net "PCIE_COMP_A_TO_IOM_A_8_DN")
	)
	(segment
		(start 234.577382 -166.928292)
		(end 234.577636 -166.928546)
		(width 0.1397)
		(layer "In9.Cu")
		(net "PCIE_COMP_A_TO_IOM_A_8_DN")
	)
	(segment
		(start 237.47984 -168.64584)
		(end 240.885726 -168.64584)
		(width 0.1397)
		(layer "In9.Cu")
		(net "PCIE_COMP_A_TO_IOM_A_8_DN")
	)
	(segment
		(start 227.116894 -155.43911)
		(end 234.577382 -166.928292)
		(width 0.1397)
		(layer "In9.Cu")
		(net "PCIE_COMP_A_TO_IOM_A_8_DN")
	)
	(segment
		(start 249.53849 -34.577782)
		(end 253.957074 -57.318402)
		(width 0.1397)
		(layer "In9.Cu")
		(net "PCIE_COMP_A_TO_IOM_A_8_DN")
	)
	(segment
		(start 236.403896 -25.346152)
		(end 237.403894 -26.34615)
		(width 0.1397)
		(layer "In9.Cu")
		(net "PCIE_COMP_A_TO_IOM_A_8_DN")
	)
	(segment
		(start 243.819426 -27.346148)
		(end 246.406924 -29.933646)
		(width 0.1397)
		(layer "In9.Cu")
		(net "PCIE_COMP_A_TO_IOM_A_8_DN")
	)
	(segment
		(start 248.38914 -85.96757)
		(end 244.817138 -91.325954)
		(width 0.1397)
		(layer "In9.Cu")
		(net "PCIE_COMP_A_TO_IOM_A_8_DN")
	)
	(segment
		(start 186.590686 -27.535886)
		(end 214.616284 -21.665692)
		(width 0.1397)
		(layer "In9.Cu")
		(net "PCIE_COMP_A_TO_IOM_A_8_DN")
	)
	(segment
		(start 236.479842 -167.645842)
		(end 237.47984 -168.64584)
		(width 0.1397)
		(layer "In9.Cu")
		(net "PCIE_COMP_A_TO_IOM_A_8_DN")
	)
	(segment
		(start 214.616284 -21.665692)
		(end 233.142536 -25.346152)
		(width 0.1397)
		(layer "In9.Cu")
		(net "PCIE_COMP_A_TO_IOM_A_8_DN")
	)
	(segment
		(start 237.403894 -26.34615)
		(end 240.90376 -26.34615)
		(width 0.1397)
		(layer "In9.Cu")
		(net "PCIE_COMP_A_TO_IOM_A_8_DN")
	)
	(segment
		(start 244.817138 -91.325954)
		(end 235.572808 -98.759772)
		(width 0.1397)
		(layer "In9.Cu")
		(net "PCIE_COMP_A_TO_IOM_A_8_DN")
	)
	(segment
		(start 233.142536 -25.346152)
		(end 236.403896 -25.346152)
		(width 0.1397)
		(layer "In9.Cu")
		(net "PCIE_COMP_A_TO_IOM_A_8_DN")
	)
	(segment
		(start 235.572808 -98.759772)
		(end 234.786932 -99.969828)
		(width 0.1397)
		(layer "In9.Cu")
		(net "PCIE_COMP_A_TO_IOM_A_8_DN")
	)
	(segment
		(start 234.786932 -99.969828)
		(end 224.781872 -145.123662)
		(width 0.1397)
		(layer "In9.Cu")
		(net "PCIE_COMP_A_TO_IOM_A_8_DN")
	)
	(segment
		(start 241.805714 -168.12768)
		(end 242.549934 -168.49979)
		(width 0.1397)
		(layer "In9.Cu")
		(net "PCIE_COMP_A_TO_IOM_A_8_DN")
	)
	(segment
		(start 235.695236 -167.646858)
		(end 235.696252 -167.645842)
		(width 0.1397)
		(layer "In9.Cu")
		(net "PCIE_COMP_A_TO_IOM_A_8_DN")
	)
	(arc
		(start 241.618262 -168.190164)
		(mid 241.699047 -168.120099)
		(end 241.805714 -168.12768)
		(width 0.1397)
		(layer "In9.Cu")
		(net "PCIE_COMP_A_TO_IOM_A_8_DN")
	)
	(arc
		(start 240.885726 -168.64584)
		(mid 241.242602 -168.56936)
		(end 241.536728 -168.353232)
		(width 0.1397)
		(layer "In9.Cu")
		(net "PCIE_COMP_A_TO_IOM_A_8_DN")
	)
	(arc
		(start 143.34998 -19.389852)
		(mid 143.406743 -19.252813)
		(end 143.543782 -19.19605)
		(width 0.1397)
		(layer "In9.Cu")
		(net "PCIE_COMP_A_TO_IOM_A_8_DN")
	)
	(segment
		(start 237.696248 -84.053934)
		(end 240.88598 -84.053934)
		(width 0.1397)
		(layer "In9.Cu")
		(net "PCIE_COMP_A_TO_IOM_A_23_DP")
	)
	(segment
		(start 231.081072 -83.718146)
		(end 231.491282 -83.632294)
		(width 0.1397)
		(layer "In9.Cu")
		(net "PCIE_COMP_A_TO_IOM_A_23_DP")
	)
	(segment
		(start 109.29239 -17.903952)
		(end 109.292644 -17.904206)
		(width 0.1397)
		(layer "In9.Cu")
		(net "PCIE_COMP_A_TO_IOM_A_23_DP")
	)
	(segment
		(start 215.54313 -87.116412)
		(end 223.960944 -85.352382)
		(width 0.1397)
		(layer "In9.Cu")
		(net "PCIE_COMP_A_TO_IOM_A_23_DP")
	)
	(segment
		(start 109.18698 -17.85112)
		(end 109.202728 -17.866868)
		(width 0.1397)
		(layer "In9.Cu")
		(net "PCIE_COMP_A_TO_IOM_A_23_DP")
	)
	(segment
		(start 241.294412 -83.57235)
		(end 240.549938 -83.199986)
		(width 0.1397)
		(layer "In9.Cu")
		(net "PCIE_COMP_A_TO_IOM_A_23_DP")
	)
	(segment
		(start 223.960944 -85.352382)
		(end 229.879144 -84.112608)
		(width 0.1397)
		(layer "In9.Cu")
		(net "PCIE_COMP_A_TO_IOM_A_23_DP")
	)
	(segment
		(start 230.397558 -83.861402)
		(end 230.562912 -83.969352)
		(width 0.1397)
		(layer "In9.Cu")
		(net "PCIE_COMP_A_TO_IOM_A_23_DP")
	)
	(segment
		(start 157.180534 -75.524106)
		(end 215.54313 -87.116412)
		(width 0.1397)
		(layer "In9.Cu")
		(net "PCIE_COMP_A_TO_IOM_A_23_DP")
	)
	(segment
		(start 230.973122 -83.8835)
		(end 231.081072 -83.718146)
		(width 0.1397)
		(layer "In9.Cu")
		(net "PCIE_COMP_A_TO_IOM_A_23_DP")
	)
	(segment
		(start 232.17505 -83.489038)
		(end 232.58526 -83.402932)
		(width 0.1397)
		(layer "In9.Cu")
		(net "PCIE_COMP_A_TO_IOM_A_23_DP")
	)
	(segment
		(start 229.879144 -84.112608)
		(end 229.987348 -83.947254)
		(width 0.1397)
		(layer "In9.Cu")
		(net "PCIE_COMP_A_TO_IOM_A_23_DP")
	)
	(segment
		(start 230.562912 -83.969352)
		(end 230.973122 -83.8835)
		(width 0.1397)
		(layer "In9.Cu")
		(net "PCIE_COMP_A_TO_IOM_A_23_DP")
	)
	(segment
		(start 234.932728 -83.053936)
		(end 236.69625 -83.053936)
		(width 0.1397)
		(layer "In9.Cu")
		(net "PCIE_COMP_A_TO_IOM_A_23_DP")
	)
	(segment
		(start 110.195868 -18.390108)
		(end 110.195868 -35.502088)
		(width 0.1397)
		(layer "In9.Cu")
		(net "PCIE_COMP_A_TO_IOM_A_23_DP")
	)
	(segment
		(start 231.656636 -83.740244)
		(end 232.066846 -83.654392)
		(width 0.1397)
		(layer "In9.Cu")
		(net "PCIE_COMP_A_TO_IOM_A_23_DP")
	)
	(segment
		(start 236.69625 -83.053936)
		(end 237.696248 -84.053934)
		(width 0.1397)
		(layer "In9.Cu")
		(net "PCIE_COMP_A_TO_IOM_A_23_DP")
	)
	(segment
		(start 109.149896 -17.349978)
		(end 109.149896 -17.761458)
		(width 0.1397)
		(layer "In9.Cu")
		(net "PCIE_COMP_A_TO_IOM_A_23_DP")
	)
	(segment
		(start 232.066846 -83.654392)
		(end 232.17505 -83.489038)
		(width 0.1397)
		(layer "In9.Cu")
		(net "PCIE_COMP_A_TO_IOM_A_23_DP")
	)
	(segment
		(start 229.987348 -83.947254)
		(end 230.397558 -83.861402)
		(width 0.1397)
		(layer "In9.Cu")
		(net "PCIE_COMP_A_TO_IOM_A_23_DP")
	)
	(segment
		(start 110.006384 -18.026634)
		(end 110.07344 -18.093944)
		(width 0.1397)
		(layer "In9.Cu")
		(net "PCIE_COMP_A_TO_IOM_A_23_DP")
	)
	(segment
		(start 232.58526 -83.402932)
		(end 232.750614 -83.511136)
		(width 0.1397)
		(layer "In9.Cu")
		(net "PCIE_COMP_A_TO_IOM_A_23_DP")
	)
	(segment
		(start 109.292644 -17.904206)
		(end 109.709966 -17.904206)
		(width 0.1397)
		(layer "In9.Cu")
		(net "PCIE_COMP_A_TO_IOM_A_23_DP")
	)
	(segment
		(start 120.064276 -50.489358)
		(end 157.180534 -75.524106)
		(width 0.1397)
		(layer "In9.Cu")
		(net "PCIE_COMP_A_TO_IOM_A_23_DP")
	)
	(segment
		(start 231.491282 -83.632294)
		(end 231.656636 -83.740244)
		(width 0.1397)
		(layer "In9.Cu")
		(net "PCIE_COMP_A_TO_IOM_A_23_DP")
	)
	(segment
		(start 241.294412 -83.88477)
		(end 241.356896 -83.759802)
		(width 0.1397)
		(layer "In9.Cu")
		(net "PCIE_COMP_A_TO_IOM_A_23_DP")
	)
	(segment
		(start 232.750614 -83.511136)
		(end 234.932728 -83.053936)
		(width 0.1397)
		(layer "In9.Cu")
		(net "PCIE_COMP_A_TO_IOM_A_23_DP")
	)
	(segment
		(start 110.195868 -35.502088)
		(end 120.064276 -50.489358)
		(width 0.1397)
		(layer "In9.Cu")
		(net "PCIE_COMP_A_TO_IOM_A_23_DP")
	)
	(arc
		(start 110.07344 -18.093944)
		(mid 110.164043 -18.229869)
		(end 110.195868 -18.390108)
		(width 0.1397)
		(layer "In9.Cu")
		(net "PCIE_COMP_A_TO_IOM_A_23_DP")
	)
	(arc
		(start 240.88598 -84.053934)
		(mid 241.107016 -84.009967)
		(end 241.294412 -83.88477)
		(width 0.1397)
		(layer "In9.Cu")
		(net "PCIE_COMP_A_TO_IOM_A_23_DP")
	)
	(arc
		(start 109.709966 -17.904206)
		(mid 109.870319 -17.935991)
		(end 110.006384 -18.026634)
		(width 0.1397)
		(layer "In9.Cu")
		(net "PCIE_COMP_A_TO_IOM_A_23_DP")
	)
	(arc
		(start 109.149896 -17.761458)
		(mid 109.159529 -17.809976)
		(end 109.18698 -17.85112)
		(width 0.1397)
		(layer "In9.Cu")
		(net "PCIE_COMP_A_TO_IOM_A_23_DP")
	)
	(arc
		(start 109.202728 -17.866868)
		(mid 109.243879 -17.894301)
		(end 109.29239 -17.903952)
		(width 0.1397)
		(layer "In9.Cu")
		(net "PCIE_COMP_A_TO_IOM_A_23_DP")
	)
	(arc
		(start 241.356896 -83.759802)
		(mid 241.364477 -83.653135)
		(end 241.294412 -83.57235)
		(width 0.1397)
		(layer "In9.Cu")
		(net "PCIE_COMP_A_TO_IOM_A_23_DP")
	)
	(segment
		(start 215.544654 -87.414608)
		(end 234.963208 -83.346036)
		(width 0.1397)
		(layer "In9.Cu")
		(net "PCIE_COMP_A_TO_IOM_A_23_DN")
	)
	(segment
		(start 236.575092 -83.346036)
		(end 237.57509 -84.346034)
		(width 0.1397)
		(layer "In9.Cu")
		(net "PCIE_COMP_A_TO_IOM_A_23_DN")
	)
	(segment
		(start 109.903768 -18.390108)
		(end 109.903768 -35.547808)
		(width 0.1397)
		(layer "In9.Cu")
		(net "PCIE_COMP_A_TO_IOM_A_23_DN")
	)
	(segment
		(start 237.57509 -84.346034)
		(end 240.885726 -84.346034)
		(width 0.1397)
		(layer "In9.Cu")
		(net "PCIE_COMP_A_TO_IOM_A_23_DN")
	)
	(segment
		(start 109.18698 -18.249138)
		(end 109.202728 -18.23339)
		(width 0.1397)
		(layer "In9.Cu")
		(net "PCIE_COMP_A_TO_IOM_A_23_DN")
	)
	(segment
		(start 109.29239 -18.196306)
		(end 109.709966 -18.196306)
		(width 0.1397)
		(layer "In9.Cu")
		(net "PCIE_COMP_A_TO_IOM_A_23_DN")
	)
	(segment
		(start 109.926882 -35.62477)
		(end 119.836946 -50.67554)
		(width 0.1397)
		(layer "In9.Cu")
		(net "PCIE_COMP_A_TO_IOM_A_23_DN")
	)
	(segment
		(start 109.149896 -18.750026)
		(end 109.149896 -18.3388)
		(width 0.1397)
		(layer "In9.Cu")
		(net "PCIE_COMP_A_TO_IOM_A_23_DN")
	)
	(segment
		(start 119.875554 -50.714656)
		(end 157.06598 -75.799188)
		(width 0.1397)
		(layer "In9.Cu")
		(net "PCIE_COMP_A_TO_IOM_A_23_DN")
	)
	(segment
		(start 241.536728 -84.053426)
		(end 241.618262 -83.890358)
		(width 0.1397)
		(layer "In9.Cu")
		(net "PCIE_COMP_A_TO_IOM_A_23_DN")
	)
	(segment
		(start 234.963208 -83.346036)
		(end 236.575092 -83.346036)
		(width 0.1397)
		(layer "In9.Cu")
		(net "PCIE_COMP_A_TO_IOM_A_23_DN")
	)
	(segment
		(start 109.799628 -18.23339)
		(end 109.866684 -18.300446)
		(width 0.1397)
		(layer "In9.Cu")
		(net "PCIE_COMP_A_TO_IOM_A_23_DN")
	)
	(segment
		(start 241.805714 -83.827874)
		(end 242.549934 -84.199984)
		(width 0.1397)
		(layer "In9.Cu")
		(net "PCIE_COMP_A_TO_IOM_A_23_DN")
	)
	(segment
		(start 157.06598 -75.799188)
		(end 215.544654 -87.414608)
		(width 0.1397)
		(layer "In9.Cu")
		(net "PCIE_COMP_A_TO_IOM_A_23_DN")
	)
	(arc
		(start 240.885726 -84.346034)
		(mid 241.242602 -84.269554)
		(end 241.536728 -84.053426)
		(width 0.1397)
		(layer "In9.Cu")
		(net "PCIE_COMP_A_TO_IOM_A_23_DN")
	)
	(arc
		(start 119.836946 -50.67554)
		(mid 119.854308 -50.697015)
		(end 119.875554 -50.714656)
		(width 0.1397)
		(layer "In9.Cu")
		(net "PCIE_COMP_A_TO_IOM_A_23_DN")
	)
	(arc
		(start 109.149896 -18.3388)
		(mid 109.159529 -18.290282)
		(end 109.18698 -18.249138)
		(width 0.1397)
		(layer "In9.Cu")
		(net "PCIE_COMP_A_TO_IOM_A_23_DN")
	)
	(arc
		(start 109.202728 -18.23339)
		(mid 109.243879 -18.205957)
		(end 109.29239 -18.196306)
		(width 0.1397)
		(layer "In9.Cu")
		(net "PCIE_COMP_A_TO_IOM_A_23_DN")
	)
	(arc
		(start 109.709966 -18.196306)
		(mid 109.758484 -18.205939)
		(end 109.799628 -18.23339)
		(width 0.1397)
		(layer "In9.Cu")
		(net "PCIE_COMP_A_TO_IOM_A_23_DN")
	)
	(arc
		(start 109.866684 -18.300446)
		(mid 109.894117 -18.341597)
		(end 109.903768 -18.390108)
		(width 0.1397)
		(layer "In9.Cu")
		(net "PCIE_COMP_A_TO_IOM_A_23_DN")
	)
	(arc
		(start 241.618262 -83.890358)
		(mid 241.699047 -83.820293)
		(end 241.805714 -83.827874)
		(width 0.1397)
		(layer "In9.Cu")
		(net "PCIE_COMP_A_TO_IOM_A_23_DN")
	)
	(arc
		(start 109.903768 -35.547808)
		(mid 109.909671 -35.587987)
		(end 109.926882 -35.62477)
		(width 0.1397)
		(layer "In9.Cu")
		(net "PCIE_COMP_A_TO_IOM_A_23_DN")
	)
	(segment
		(start 234.03814 -79.395066)
		(end 234.14609 -79.229712)
		(width 0.1397)
		(layer "In9.Cu")
		(net "PCIE_COMP_A_TO_IOM_A_22_DP")
	)
	(segment
		(start 234.14609 -79.229712)
		(end 234.5563 -79.143606)
		(width 0.1397)
		(layer "In9.Cu")
		(net "PCIE_COMP_A_TO_IOM_A_22_DP")
	)
	(segment
		(start 111.995966 -19.390106)
		(end 111.995966 -31.990284)
		(width 0.1397)
		(layer "In9.Cu")
		(net "PCIE_COMP_A_TO_IOM_A_22_DP")
	)
	(segment
		(start 232.533952 -79.710026)
		(end 232.944162 -79.624174)
		(width 0.1397)
		(layer "In9.Cu")
		(net "PCIE_COMP_A_TO_IOM_A_22_DP")
	)
	(segment
		(start 232.368598 -79.602076)
		(end 232.533952 -79.710026)
		(width 0.1397)
		(layer "In9.Cu")
		(net "PCIE_COMP_A_TO_IOM_A_22_DP")
	)
	(segment
		(start 234.721654 -79.25181)
		(end 235.665772 -79.053944)
		(width 0.1397)
		(layer "In9.Cu")
		(net "PCIE_COMP_A_TO_IOM_A_22_DP")
	)
	(segment
		(start 231.850438 -79.853282)
		(end 231.958388 -79.687928)
		(width 0.1397)
		(layer "In9.Cu")
		(net "PCIE_COMP_A_TO_IOM_A_22_DP")
	)
	(segment
		(start 110.949994 -18.35023)
		(end 110.949994 -18.761456)
		(width 0.1397)
		(layer "In9.Cu")
		(net "PCIE_COMP_A_TO_IOM_A_22_DP")
	)
	(segment
		(start 233.62793 -79.480918)
		(end 234.03814 -79.395066)
		(width 0.1397)
		(layer "In9.Cu")
		(net "PCIE_COMP_A_TO_IOM_A_22_DP")
	)
	(segment
		(start 236.660944 -79.053944)
		(end 237.660942 -80.053942)
		(width 0.1397)
		(layer "In9.Cu")
		(net "PCIE_COMP_A_TO_IOM_A_22_DP")
	)
	(segment
		(start 237.660942 -80.053942)
		(end 240.88598 -80.053942)
		(width 0.1397)
		(layer "In9.Cu")
		(net "PCIE_COMP_A_TO_IOM_A_22_DP")
	)
	(segment
		(start 235.665772 -79.053944)
		(end 236.660944 -79.053944)
		(width 0.1397)
		(layer "In9.Cu")
		(net "PCIE_COMP_A_TO_IOM_A_22_DP")
	)
	(segment
		(start 111.995966 -31.990284)
		(end 125.637036 -52.706016)
		(width 0.1397)
		(layer "In9.Cu")
		(net "PCIE_COMP_A_TO_IOM_A_22_DP")
	)
	(segment
		(start 157.326838 -74.081894)
		(end 209.725514 -84.48929)
		(width 0.1397)
		(layer "In9.Cu")
		(net "PCIE_COMP_A_TO_IOM_A_22_DP")
	)
	(segment
		(start 111.092742 -18.904204)
		(end 111.510064 -18.904204)
		(width 0.1397)
		(layer "In9.Cu")
		(net "PCIE_COMP_A_TO_IOM_A_22_DP")
	)
	(segment
		(start 209.725514 -84.48929)
		(end 231.850184 -79.853536)
		(width 0.1397)
		(layer "In9.Cu")
		(net "PCIE_COMP_A_TO_IOM_A_22_DP")
	)
	(segment
		(start 125.637036 -52.706016)
		(end 157.326838 -74.081894)
		(width 0.1397)
		(layer "In9.Cu")
		(net "PCIE_COMP_A_TO_IOM_A_22_DP")
	)
	(segment
		(start 111.806482 -19.026632)
		(end 111.873538 -19.093942)
		(width 0.1397)
		(layer "In9.Cu")
		(net "PCIE_COMP_A_TO_IOM_A_22_DP")
	)
	(segment
		(start 232.944162 -79.624174)
		(end 233.052366 -79.45882)
		(width 0.1397)
		(layer "In9.Cu")
		(net "PCIE_COMP_A_TO_IOM_A_22_DP")
	)
	(segment
		(start 241.294412 -79.572358)
		(end 240.549938 -79.199994)
		(width 0.1397)
		(layer "In9.Cu")
		(net "PCIE_COMP_A_TO_IOM_A_22_DP")
	)
	(segment
		(start 231.958388 -79.687928)
		(end 232.368598 -79.602076)
		(width 0.1397)
		(layer "In9.Cu")
		(net "PCIE_COMP_A_TO_IOM_A_22_DP")
	)
	(segment
		(start 233.052366 -79.45882)
		(end 233.462576 -79.372968)
		(width 0.1397)
		(layer "In9.Cu")
		(net "PCIE_COMP_A_TO_IOM_A_22_DP")
	)
	(segment
		(start 241.294412 -79.884778)
		(end 241.356896 -79.75981)
		(width 0.1397)
		(layer "In9.Cu")
		(net "PCIE_COMP_A_TO_IOM_A_22_DP")
	)
	(segment
		(start 231.850184 -79.853536)
		(end 231.850438 -79.853282)
		(width 0.1397)
		(layer "In9.Cu")
		(net "PCIE_COMP_A_TO_IOM_A_22_DP")
	)
	(segment
		(start 234.5563 -79.143606)
		(end 234.721654 -79.25181)
		(width 0.1397)
		(layer "In9.Cu")
		(net "PCIE_COMP_A_TO_IOM_A_22_DP")
	)
	(segment
		(start 111.092488 -18.90395)
		(end 111.092742 -18.904204)
		(width 0.1397)
		(layer "In9.Cu")
		(net "PCIE_COMP_A_TO_IOM_A_22_DP")
	)
	(segment
		(start 233.462576 -79.372968)
		(end 233.62793 -79.480918)
		(width 0.1397)
		(layer "In9.Cu")
		(net "PCIE_COMP_A_TO_IOM_A_22_DP")
	)
	(segment
		(start 110.987078 -18.851118)
		(end 111.002826 -18.866866)
		(width 0.1397)
		(layer "In9.Cu")
		(net "PCIE_COMP_A_TO_IOM_A_22_DP")
	)
	(arc
		(start 111.002826 -18.866866)
		(mid 111.043977 -18.894299)
		(end 111.092488 -18.90395)
		(width 0.1397)
		(layer "In9.Cu")
		(net "PCIE_COMP_A_TO_IOM_A_22_DP")
	)
	(arc
		(start 241.356896 -79.75981)
		(mid 241.364477 -79.653143)
		(end 241.294412 -79.572358)
		(width 0.1397)
		(layer "In9.Cu")
		(net "PCIE_COMP_A_TO_IOM_A_22_DP")
	)
	(arc
		(start 110.949994 -18.761456)
		(mid 110.959627 -18.809974)
		(end 110.987078 -18.851118)
		(width 0.1397)
		(layer "In9.Cu")
		(net "PCIE_COMP_A_TO_IOM_A_22_DP")
	)
	(arc
		(start 111.510064 -18.904204)
		(mid 111.670417 -18.935989)
		(end 111.806482 -19.026632)
		(width 0.1397)
		(layer "In9.Cu")
		(net "PCIE_COMP_A_TO_IOM_A_22_DP")
	)
	(arc
		(start 240.88598 -80.053942)
		(mid 241.107016 -80.009975)
		(end 241.294412 -79.884778)
		(width 0.1397)
		(layer "In9.Cu")
		(net "PCIE_COMP_A_TO_IOM_A_22_DP")
	)
	(arc
		(start 111.873538 -19.093942)
		(mid 111.964141 -19.229867)
		(end 111.995966 -19.390106)
		(width 0.1397)
		(layer "In9.Cu")
		(net "PCIE_COMP_A_TO_IOM_A_22_DP")
	)
	(segment
		(start 231.406446 -80.245204)
		(end 231.910382 -80.13954)
		(width 0.1397)
		(layer "In9.Cu")
		(net "PCIE_COMP_A_TO_IOM_A_22_DN")
	)
	(segment
		(start 110.949994 -19.750024)
		(end 110.949994 -19.338798)
		(width 0.1397)
		(layer "In9.Cu")
		(net "PCIE_COMP_A_TO_IOM_A_22_DN")
	)
	(segment
		(start 157.212284 -74.356976)
		(end 209.727038 -84.787486)
		(width 0.1397)
		(layer "In9.Cu")
		(net "PCIE_COMP_A_TO_IOM_A_22_DN")
	)
	(segment
		(start 111.092488 -19.196304)
		(end 111.510064 -19.196304)
		(width 0.1397)
		(layer "In9.Cu")
		(net "PCIE_COMP_A_TO_IOM_A_22_DN")
	)
	(segment
		(start 111.703866 -32.077914)
		(end 125.4252 -52.915566)
		(width 0.1397)
		(layer "In9.Cu")
		(net "PCIE_COMP_A_TO_IOM_A_22_DN")
	)
	(segment
		(start 209.727038 -84.787486)
		(end 231.406446 -80.245204)
		(width 0.1397)
		(layer "In9.Cu")
		(net "PCIE_COMP_A_TO_IOM_A_22_DN")
	)
	(segment
		(start 241.536728 -80.053434)
		(end 241.618262 -79.890366)
		(width 0.1397)
		(layer "In9.Cu")
		(net "PCIE_COMP_A_TO_IOM_A_22_DN")
	)
	(segment
		(start 111.703866 -19.390106)
		(end 111.703866 -32.077914)
		(width 0.1397)
		(layer "In9.Cu")
		(net "PCIE_COMP_A_TO_IOM_A_22_DN")
	)
	(segment
		(start 111.599726 -19.233388)
		(end 111.666782 -19.300444)
		(width 0.1397)
		(layer "In9.Cu")
		(net "PCIE_COMP_A_TO_IOM_A_22_DN")
	)
	(segment
		(start 241.805714 -79.827882)
		(end 242.549934 -80.199992)
		(width 0.1397)
		(layer "In9.Cu")
		(net "PCIE_COMP_A_TO_IOM_A_22_DN")
	)
	(segment
		(start 237.539784 -80.346042)
		(end 240.885726 -80.346042)
		(width 0.1397)
		(layer "In9.Cu")
		(net "PCIE_COMP_A_TO_IOM_A_22_DN")
	)
	(segment
		(start 235.696252 -79.346044)
		(end 236.539786 -79.346044)
		(width 0.1397)
		(layer "In9.Cu")
		(net "PCIE_COMP_A_TO_IOM_A_22_DN")
	)
	(segment
		(start 110.987078 -19.249136)
		(end 111.002826 -19.233388)
		(width 0.1397)
		(layer "In9.Cu")
		(net "PCIE_COMP_A_TO_IOM_A_22_DN")
	)
	(segment
		(start 232.252012 -80.067658)
		(end 235.696252 -79.346044)
		(width 0.1397)
		(layer "In9.Cu")
		(net "PCIE_COMP_A_TO_IOM_A_22_DN")
	)
	(segment
		(start 125.4252 -52.915566)
		(end 157.212284 -74.356976)
		(width 0.1397)
		(layer "In9.Cu")
		(net "PCIE_COMP_A_TO_IOM_A_22_DN")
	)
	(segment
		(start 231.910382 -80.13954)
		(end 231.910382 -80.139286)
		(width 0.1397)
		(layer "In9.Cu")
		(net "PCIE_COMP_A_TO_IOM_A_22_DN")
	)
	(segment
		(start 236.539786 -79.346044)
		(end 237.539784 -80.346042)
		(width 0.1397)
		(layer "In9.Cu")
		(net "PCIE_COMP_A_TO_IOM_A_22_DN")
	)
	(segment
		(start 231.910382 -80.139286)
		(end 232.252012 -80.067658)
		(width 0.1397)
		(layer "In9.Cu")
		(net "PCIE_COMP_A_TO_IOM_A_22_DN")
	)
	(arc
		(start 241.618262 -79.890366)
		(mid 241.699047 -79.820301)
		(end 241.805714 -79.827882)
		(width 0.1397)
		(layer "In9.Cu")
		(net "PCIE_COMP_A_TO_IOM_A_22_DN")
	)
	(arc
		(start 240.885726 -80.346042)
		(mid 241.242602 -80.269562)
		(end 241.536728 -80.053434)
		(width 0.1397)
		(layer "In9.Cu")
		(net "PCIE_COMP_A_TO_IOM_A_22_DN")
	)
	(arc
		(start 111.666782 -19.300444)
		(mid 111.694215 -19.341595)
		(end 111.703866 -19.390106)
		(width 0.1397)
		(layer "In9.Cu")
		(net "PCIE_COMP_A_TO_IOM_A_22_DN")
	)
	(arc
		(start 111.002826 -19.233388)
		(mid 111.043977 -19.205955)
		(end 111.092488 -19.196304)
		(width 0.1397)
		(layer "In9.Cu")
		(net "PCIE_COMP_A_TO_IOM_A_22_DN")
	)
	(arc
		(start 111.510064 -19.196304)
		(mid 111.558582 -19.205937)
		(end 111.599726 -19.233388)
		(width 0.1397)
		(layer "In9.Cu")
		(net "PCIE_COMP_A_TO_IOM_A_22_DN")
	)
	(arc
		(start 110.949994 -19.338798)
		(mid 110.959627 -19.29028)
		(end 110.987078 -19.249136)
		(width 0.1397)
		(layer "In9.Cu")
		(net "PCIE_COMP_A_TO_IOM_A_22_DN")
	)
	(segment
		(start 241.294412 -75.884786)
		(end 241.356896 -75.759818)
		(width 0.1397)
		(layer "In9.Cu")
		(net "PCIE_COMP_A_TO_IOM_A_21_DP")
	)
	(segment
		(start 112.776508 -17.840452)
		(end 112.802924 -17.866868)
		(width 0.1397)
		(layer "In9.Cu")
		(net "PCIE_COMP_A_TO_IOM_A_21_DP")
	)
	(segment
		(start 229.694994 -76.13015)
		(end 230.105204 -76.044298)
		(width 0.1397)
		(layer "In9.Cu")
		(net "PCIE_COMP_A_TO_IOM_A_21_DP")
	)
	(segment
		(start 228.493066 -76.524612)
		(end 228.60127 -76.359258)
		(width 0.1397)
		(layer "In9.Cu")
		(net "PCIE_COMP_A_TO_IOM_A_21_DP")
	)
	(segment
		(start 230.788972 -75.901042)
		(end 231.199182 -75.814936)
		(width 0.1397)
		(layer "In9.Cu")
		(net "PCIE_COMP_A_TO_IOM_A_21_DP")
	)
	(segment
		(start 112.89284 -17.904206)
		(end 113.310162 -17.904206)
		(width 0.1397)
		(layer "In9.Cu")
		(net "PCIE_COMP_A_TO_IOM_A_21_DP")
	)
	(segment
		(start 229.01148 -76.273406)
		(end 229.176834 -76.381356)
		(width 0.1397)
		(layer "In9.Cu")
		(net "PCIE_COMP_A_TO_IOM_A_21_DP")
	)
	(segment
		(start 113.60658 -18.026634)
		(end 113.673636 -18.093944)
		(width 0.1397)
		(layer "In9.Cu")
		(net "PCIE_COMP_A_TO_IOM_A_21_DP")
	)
	(segment
		(start 228.60127 -76.359258)
		(end 229.01148 -76.273406)
		(width 0.1397)
		(layer "In9.Cu")
		(net "PCIE_COMP_A_TO_IOM_A_21_DP")
	)
	(segment
		(start 231.199182 -75.814936)
		(end 231.364536 -75.92314)
		(width 0.1397)
		(layer "In9.Cu")
		(net "PCIE_COMP_A_TO_IOM_A_21_DP")
	)
	(segment
		(start 113.796064 -18.390108)
		(end 113.796064 -31.836868)
		(width 0.1397)
		(layer "In9.Cu")
		(net "PCIE_COMP_A_TO_IOM_A_21_DP")
	)
	(segment
		(start 203.241148 -81.815178)
		(end 228.493066 -76.524612)
		(width 0.1397)
		(layer "In9.Cu")
		(net "PCIE_COMP_A_TO_IOM_A_21_DP")
	)
	(segment
		(start 112.892586 -17.903952)
		(end 112.89284 -17.904206)
		(width 0.1397)
		(layer "In9.Cu")
		(net "PCIE_COMP_A_TO_IOM_A_21_DP")
	)
	(segment
		(start 112.750092 -17.349978)
		(end 112.750092 -17.776698)
		(width 0.1397)
		(layer "In9.Cu")
		(net "PCIE_COMP_A_TO_IOM_A_21_DP")
	)
	(segment
		(start 241.294412 -75.572366)
		(end 240.549938 -75.200002)
		(width 0.1397)
		(layer "In9.Cu")
		(net "PCIE_COMP_A_TO_IOM_A_21_DP")
	)
	(segment
		(start 127.25273 -52.275232)
		(end 157.610048 -72.75195)
		(width 0.1397)
		(layer "In9.Cu")
		(net "PCIE_COMP_A_TO_IOM_A_21_DP")
	)
	(segment
		(start 231.364536 -75.92314)
		(end 235.513118 -75.053952)
		(width 0.1397)
		(layer "In9.Cu")
		(net "PCIE_COMP_A_TO_IOM_A_21_DP")
	)
	(segment
		(start 157.610048 -72.75195)
		(end 203.241148 -81.815178)
		(width 0.1397)
		(layer "In9.Cu")
		(net "PCIE_COMP_A_TO_IOM_A_21_DP")
	)
	(segment
		(start 237.696248 -76.05395)
		(end 240.88598 -76.05395)
		(width 0.1397)
		(layer "In9.Cu")
		(net "PCIE_COMP_A_TO_IOM_A_21_DP")
	)
	(segment
		(start 230.105204 -76.044298)
		(end 230.270812 -76.152248)
		(width 0.1397)
		(layer "In9.Cu")
		(net "PCIE_COMP_A_TO_IOM_A_21_DP")
	)
	(segment
		(start 113.796064 -31.836868)
		(end 127.25273 -52.275232)
		(width 0.1397)
		(layer "In9.Cu")
		(net "PCIE_COMP_A_TO_IOM_A_21_DP")
	)
	(segment
		(start 229.587044 -76.295504)
		(end 229.694994 -76.13015)
		(width 0.1397)
		(layer "In9.Cu")
		(net "PCIE_COMP_A_TO_IOM_A_21_DP")
	)
	(segment
		(start 236.69625 -75.053952)
		(end 237.696248 -76.05395)
		(width 0.1397)
		(layer "In9.Cu")
		(net "PCIE_COMP_A_TO_IOM_A_21_DP")
	)
	(segment
		(start 230.270812 -76.152248)
		(end 230.680768 -76.066396)
		(width 0.1397)
		(layer "In9.Cu")
		(net "PCIE_COMP_A_TO_IOM_A_21_DP")
	)
	(segment
		(start 230.680768 -76.066396)
		(end 230.788972 -75.901042)
		(width 0.1397)
		(layer "In9.Cu")
		(net "PCIE_COMP_A_TO_IOM_A_21_DP")
	)
	(segment
		(start 235.513118 -75.053952)
		(end 236.69625 -75.053952)
		(width 0.1397)
		(layer "In9.Cu")
		(net "PCIE_COMP_A_TO_IOM_A_21_DP")
	)
	(segment
		(start 229.176834 -76.381356)
		(end 229.587044 -76.295504)
		(width 0.1397)
		(layer "In9.Cu")
		(net "PCIE_COMP_A_TO_IOM_A_21_DP")
	)
	(arc
		(start 113.310162 -17.904206)
		(mid 113.470515 -17.935991)
		(end 113.60658 -18.026634)
		(width 0.1397)
		(layer "In9.Cu")
		(net "PCIE_COMP_A_TO_IOM_A_21_DP")
	)
	(arc
		(start 241.356896 -75.759818)
		(mid 241.364477 -75.653151)
		(end 241.294412 -75.572366)
		(width 0.1397)
		(layer "In9.Cu")
		(net "PCIE_COMP_A_TO_IOM_A_21_DP")
	)
	(arc
		(start 113.673636 -18.093944)
		(mid 113.764239 -18.229869)
		(end 113.796064 -18.390108)
		(width 0.1397)
		(layer "In9.Cu")
		(net "PCIE_COMP_A_TO_IOM_A_21_DP")
	)
	(arc
		(start 240.88598 -76.05395)
		(mid 241.107016 -76.009983)
		(end 241.294412 -75.884786)
		(width 0.1397)
		(layer "In9.Cu")
		(net "PCIE_COMP_A_TO_IOM_A_21_DP")
	)
	(arc
		(start 112.750092 -17.776698)
		(mid 112.756956 -17.811205)
		(end 112.776508 -17.840452)
		(width 0.1397)
		(layer "In9.Cu")
		(net "PCIE_COMP_A_TO_IOM_A_21_DP")
	)
	(arc
		(start 112.802924 -17.866868)
		(mid 112.844075 -17.894301)
		(end 112.892586 -17.903952)
		(width 0.1397)
		(layer "In9.Cu")
		(net "PCIE_COMP_A_TO_IOM_A_21_DP")
	)
	(segment
		(start 235.543598 -75.346052)
		(end 236.575092 -75.346052)
		(width 0.1397)
		(layer "In9.Cu")
		(net "PCIE_COMP_A_TO_IOM_A_21_DN")
	)
	(segment
		(start 241.805714 -75.82789)
		(end 242.549934 -76.2)
		(width 0.1397)
		(layer "In9.Cu")
		(net "PCIE_COMP_A_TO_IOM_A_21_DN")
	)
	(segment
		(start 142.267686 -62.755526)
		(end 157.495494 -73.027032)
		(width 0.1397)
		(layer "In9.Cu")
		(net "PCIE_COMP_A_TO_IOM_A_21_DN")
	)
	(segment
		(start 113.503964 -18.390108)
		(end 113.503964 -31.924498)
		(width 0.1397)
		(layer "In9.Cu")
		(net "PCIE_COMP_A_TO_IOM_A_21_DN")
	)
	(segment
		(start 203.242672 -82.113374)
		(end 235.543598 -75.346052)
		(width 0.1397)
		(layer "In9.Cu")
		(net "PCIE_COMP_A_TO_IOM_A_21_DN")
	)
	(segment
		(start 112.787176 -18.249138)
		(end 112.802924 -18.23339)
		(width 0.1397)
		(layer "In9.Cu")
		(net "PCIE_COMP_A_TO_IOM_A_21_DN")
	)
	(segment
		(start 157.495494 -73.027032)
		(end 203.242672 -82.113374)
		(width 0.1397)
		(layer "In9.Cu")
		(net "PCIE_COMP_A_TO_IOM_A_21_DN")
	)
	(segment
		(start 112.892586 -18.196306)
		(end 113.310162 -18.196306)
		(width 0.1397)
		(layer "In9.Cu")
		(net "PCIE_COMP_A_TO_IOM_A_21_DN")
	)
	(segment
		(start 237.57509 -76.34605)
		(end 240.885726 -76.34605)
		(width 0.1397)
		(layer "In9.Cu")
		(net "PCIE_COMP_A_TO_IOM_A_21_DN")
	)
	(segment
		(start 142.267686 -62.75578)
		(end 142.267686 -62.755526)
		(width 0.1397)
		(layer "In9.Cu")
		(net "PCIE_COMP_A_TO_IOM_A_21_DN")
	)
	(segment
		(start 112.750092 -18.750026)
		(end 112.750092 -18.3388)
		(width 0.1397)
		(layer "In9.Cu")
		(net "PCIE_COMP_A_TO_IOM_A_21_DN")
	)
	(segment
		(start 236.575092 -75.346052)
		(end 237.57509 -76.34605)
		(width 0.1397)
		(layer "In9.Cu")
		(net "PCIE_COMP_A_TO_IOM_A_21_DN")
	)
	(segment
		(start 241.536728 -76.053442)
		(end 241.618262 -75.890374)
		(width 0.1397)
		(layer "In9.Cu")
		(net "PCIE_COMP_A_TO_IOM_A_21_DN")
	)
	(segment
		(start 127.040894 -52.484782)
		(end 142.267686 -62.75578)
		(width 0.1397)
		(layer "In9.Cu")
		(net "PCIE_COMP_A_TO_IOM_A_21_DN")
	)
	(segment
		(start 113.399824 -18.23339)
		(end 113.46688 -18.300446)
		(width 0.1397)
		(layer "In9.Cu")
		(net "PCIE_COMP_A_TO_IOM_A_21_DN")
	)
	(segment
		(start 113.503964 -31.924498)
		(end 127.040894 -52.484782)
		(width 0.1397)
		(layer "In9.Cu")
		(net "PCIE_COMP_A_TO_IOM_A_21_DN")
	)
	(arc
		(start 113.310162 -18.196306)
		(mid 113.35868 -18.205939)
		(end 113.399824 -18.23339)
		(width 0.1397)
		(layer "In9.Cu")
		(net "PCIE_COMP_A_TO_IOM_A_21_DN")
	)
	(arc
		(start 112.802924 -18.23339)
		(mid 112.844075 -18.205957)
		(end 112.892586 -18.196306)
		(width 0.1397)
		(layer "In9.Cu")
		(net "PCIE_COMP_A_TO_IOM_A_21_DN")
	)
	(arc
		(start 112.750092 -18.3388)
		(mid 112.759725 -18.290282)
		(end 112.787176 -18.249138)
		(width 0.1397)
		(layer "In9.Cu")
		(net "PCIE_COMP_A_TO_IOM_A_21_DN")
	)
	(arc
		(start 241.618262 -75.890374)
		(mid 241.699047 -75.820309)
		(end 241.805714 -75.82789)
		(width 0.1397)
		(layer "In9.Cu")
		(net "PCIE_COMP_A_TO_IOM_A_21_DN")
	)
	(arc
		(start 240.885726 -76.34605)
		(mid 241.242602 -76.26957)
		(end 241.536728 -76.053442)
		(width 0.1397)
		(layer "In9.Cu")
		(net "PCIE_COMP_A_TO_IOM_A_21_DN")
	)
	(arc
		(start 113.46688 -18.300446)
		(mid 113.494313 -18.341597)
		(end 113.503964 -18.390108)
		(width 0.1397)
		(layer "In9.Cu")
		(net "PCIE_COMP_A_TO_IOM_A_21_DN")
	)
	(segment
		(start 155.457906 -68.566284)
		(end 203.783946 -78.169516)
		(width 0.1397)
		(layer "In9.Cu")
		(net "PCIE_COMP_A_TO_IOM_A_20_DP")
	)
	(segment
		(start 230.17353 -72.319896)
		(end 230.582724 -72.229218)
		(width 0.1397)
		(layer "In9.Cu")
		(net "PCIE_COMP_A_TO_IOM_A_20_DP")
	)
	(segment
		(start 231.673908 -71.987156)
		(end 231.78008 -71.820532)
		(width 0.1397)
		(layer "In9.Cu")
		(net "PCIE_COMP_A_TO_IOM_A_20_DP")
	)
	(segment
		(start 241.294412 -71.572374)
		(end 240.549938 -71.20001)
		(width 0.1397)
		(layer "In9.Cu")
		(net "PCIE_COMP_A_TO_IOM_A_20_DP")
	)
	(segment
		(start 230.582724 -72.229218)
		(end 230.688896 -72.062594)
		(width 0.1397)
		(layer "In9.Cu")
		(net "PCIE_COMP_A_TO_IOM_A_20_DP")
	)
	(segment
		(start 115.595908 -19.390106)
		(end 115.595908 -32.609028)
		(width 0.1397)
		(layer "In9.Cu")
		(net "PCIE_COMP_A_TO_IOM_A_20_DP")
	)
	(segment
		(start 241.294412 -71.884794)
		(end 241.356896 -71.759826)
		(width 0.1397)
		(layer "In9.Cu")
		(net "PCIE_COMP_A_TO_IOM_A_20_DP")
	)
	(segment
		(start 229.491794 -72.471026)
		(end 229.597966 -72.304402)
		(width 0.1397)
		(layer "In9.Cu")
		(net "PCIE_COMP_A_TO_IOM_A_20_DP")
	)
	(segment
		(start 126.8222 -49.666144)
		(end 155.457906 -68.566284)
		(width 0.1397)
		(layer "In9.Cu")
		(net "PCIE_COMP_A_TO_IOM_A_20_DP")
	)
	(segment
		(start 115.595908 -32.609028)
		(end 126.8222 -49.666144)
		(width 0.1397)
		(layer "In9.Cu")
		(net "PCIE_COMP_A_TO_IOM_A_20_DP")
	)
	(segment
		(start 231.78008 -71.820532)
		(end 232.189274 -71.729854)
		(width 0.1397)
		(layer "In9.Cu")
		(net "PCIE_COMP_A_TO_IOM_A_20_DP")
	)
	(segment
		(start 231.09809 -71.971916)
		(end 231.264714 -72.077834)
		(width 0.1397)
		(layer "In9.Cu")
		(net "PCIE_COMP_A_TO_IOM_A_20_DP")
	)
	(segment
		(start 229.597966 -72.304402)
		(end 230.006906 -72.213724)
		(width 0.1397)
		(layer "In9.Cu")
		(net "PCIE_COMP_A_TO_IOM_A_20_DP")
	)
	(segment
		(start 236.543342 -71.05396)
		(end 237.54334 -72.053958)
		(width 0.1397)
		(layer "In9.Cu")
		(net "PCIE_COMP_A_TO_IOM_A_20_DP")
	)
	(segment
		(start 230.006906 -72.213724)
		(end 230.17353 -72.319896)
		(width 0.1397)
		(layer "In9.Cu")
		(net "PCIE_COMP_A_TO_IOM_A_20_DP")
	)
	(segment
		(start 114.692684 -18.904204)
		(end 115.110006 -18.904204)
		(width 0.1397)
		(layer "In9.Cu")
		(net "PCIE_COMP_A_TO_IOM_A_20_DP")
	)
	(segment
		(start 230.688896 -72.062594)
		(end 231.09809 -71.971916)
		(width 0.1397)
		(layer "In9.Cu")
		(net "PCIE_COMP_A_TO_IOM_A_20_DP")
	)
	(segment
		(start 114.549936 -18.35023)
		(end 114.549936 -18.761456)
		(width 0.1397)
		(layer "In9.Cu")
		(net "PCIE_COMP_A_TO_IOM_A_20_DP")
	)
	(segment
		(start 237.54334 -72.053958)
		(end 240.88598 -72.053958)
		(width 0.1397)
		(layer "In9.Cu")
		(net "PCIE_COMP_A_TO_IOM_A_20_DP")
	)
	(segment
		(start 114.58702 -18.851118)
		(end 114.602768 -18.866866)
		(width 0.1397)
		(layer "In9.Cu")
		(net "PCIE_COMP_A_TO_IOM_A_20_DP")
	)
	(segment
		(start 115.406424 -19.026632)
		(end 115.47348 -19.093942)
		(width 0.1397)
		(layer "In9.Cu")
		(net "PCIE_COMP_A_TO_IOM_A_20_DP")
	)
	(segment
		(start 232.189274 -71.729854)
		(end 232.355898 -71.836026)
		(width 0.1397)
		(layer "In9.Cu")
		(net "PCIE_COMP_A_TO_IOM_A_20_DP")
	)
	(segment
		(start 114.69243 -18.90395)
		(end 114.692684 -18.904204)
		(width 0.1397)
		(layer "In9.Cu")
		(net "PCIE_COMP_A_TO_IOM_A_20_DP")
	)
	(segment
		(start 231.264714 -72.077834)
		(end 231.673908 -71.987156)
		(width 0.1397)
		(layer "In9.Cu")
		(net "PCIE_COMP_A_TO_IOM_A_20_DP")
	)
	(segment
		(start 217.509344 -75.12685)
		(end 229.491794 -72.471026)
		(width 0.1397)
		(layer "In9.Cu")
		(net "PCIE_COMP_A_TO_IOM_A_20_DP")
	)
	(segment
		(start 203.783946 -78.169516)
		(end 217.509344 -75.12685)
		(width 0.1397)
		(layer "In9.Cu")
		(net "PCIE_COMP_A_TO_IOM_A_20_DP")
	)
	(segment
		(start 232.355898 -71.836026)
		(end 235.884466 -71.05396)
		(width 0.1397)
		(layer "In9.Cu")
		(net "PCIE_COMP_A_TO_IOM_A_20_DP")
	)
	(segment
		(start 235.884466 -71.05396)
		(end 236.543342 -71.05396)
		(width 0.1397)
		(layer "In9.Cu")
		(net "PCIE_COMP_A_TO_IOM_A_20_DP")
	)
	(arc
		(start 240.88598 -72.053958)
		(mid 241.107016 -72.009991)
		(end 241.294412 -71.884794)
		(width 0.1397)
		(layer "In9.Cu")
		(net "PCIE_COMP_A_TO_IOM_A_20_DP")
	)
	(arc
		(start 114.602768 -18.866866)
		(mid 114.643919 -18.894299)
		(end 114.69243 -18.90395)
		(width 0.1397)
		(layer "In9.Cu")
		(net "PCIE_COMP_A_TO_IOM_A_20_DP")
	)
	(arc
		(start 115.110006 -18.904204)
		(mid 115.270359 -18.935989)
		(end 115.406424 -19.026632)
		(width 0.1397)
		(layer "In9.Cu")
		(net "PCIE_COMP_A_TO_IOM_A_20_DP")
	)
	(arc
		(start 241.356896 -71.759826)
		(mid 241.364477 -71.653159)
		(end 241.294412 -71.572374)
		(width 0.1397)
		(layer "In9.Cu")
		(net "PCIE_COMP_A_TO_IOM_A_20_DP")
	)
	(arc
		(start 114.549936 -18.761456)
		(mid 114.559569 -18.809974)
		(end 114.58702 -18.851118)
		(width 0.1397)
		(layer "In9.Cu")
		(net "PCIE_COMP_A_TO_IOM_A_20_DP")
	)
	(arc
		(start 115.47348 -19.093942)
		(mid 115.564083 -19.229867)
		(end 115.595908 -19.390106)
		(width 0.1397)
		(layer "In9.Cu")
		(net "PCIE_COMP_A_TO_IOM_A_20_DP")
	)
	(segment
		(start 235.91647 -71.34606)
		(end 236.422184 -71.34606)
		(width 0.1397)
		(layer "In9.Cu")
		(net "PCIE_COMP_A_TO_IOM_A_20_DN")
	)
	(segment
		(start 114.549936 -19.750024)
		(end 114.549936 -19.338798)
		(width 0.1397)
		(layer "In9.Cu")
		(net "PCIE_COMP_A_TO_IOM_A_20_DN")
	)
	(segment
		(start 115.303808 -19.390106)
		(end 115.303808 -32.696658)
		(width 0.1397)
		(layer "In9.Cu")
		(net "PCIE_COMP_A_TO_IOM_A_20_DN")
	)
	(segment
		(start 114.69243 -19.196304)
		(end 115.110006 -19.196304)
		(width 0.1397)
		(layer "In9.Cu")
		(net "PCIE_COMP_A_TO_IOM_A_20_DN")
	)
	(segment
		(start 114.58702 -19.249136)
		(end 114.602768 -19.233388)
		(width 0.1397)
		(layer "In9.Cu")
		(net "PCIE_COMP_A_TO_IOM_A_20_DN")
	)
	(segment
		(start 241.536728 -72.05345)
		(end 241.618262 -71.890382)
		(width 0.1397)
		(layer "In9.Cu")
		(net "PCIE_COMP_A_TO_IOM_A_20_DN")
	)
	(segment
		(start 115.303808 -32.696658)
		(end 126.611126 -49.876964)
		(width 0.1397)
		(layer "In9.Cu")
		(net "PCIE_COMP_A_TO_IOM_A_20_DN")
	)
	(segment
		(start 236.422184 -71.34606)
		(end 237.422182 -72.346058)
		(width 0.1397)
		(layer "In9.Cu")
		(net "PCIE_COMP_A_TO_IOM_A_20_DN")
	)
	(segment
		(start 241.805714 -71.827898)
		(end 242.549934 -72.200008)
		(width 0.1397)
		(layer "In9.Cu")
		(net "PCIE_COMP_A_TO_IOM_A_20_DN")
	)
	(segment
		(start 237.422182 -72.346058)
		(end 240.885726 -72.346058)
		(width 0.1397)
		(layer "In9.Cu")
		(net "PCIE_COMP_A_TO_IOM_A_20_DN")
	)
	(segment
		(start 203.787248 -78.46822)
		(end 235.91647 -71.34606)
		(width 0.1397)
		(layer "In9.Cu")
		(net "PCIE_COMP_A_TO_IOM_A_20_DN")
	)
	(segment
		(start 115.199668 -19.233388)
		(end 115.266724 -19.300444)
		(width 0.1397)
		(layer "In9.Cu")
		(net "PCIE_COMP_A_TO_IOM_A_20_DN")
	)
	(segment
		(start 126.611126 -49.876964)
		(end 155.344622 -68.841874)
		(width 0.1397)
		(layer "In9.Cu")
		(net "PCIE_COMP_A_TO_IOM_A_20_DN")
	)
	(segment
		(start 155.344622 -68.841874)
		(end 203.787248 -78.46822)
		(width 0.1397)
		(layer "In9.Cu")
		(net "PCIE_COMP_A_TO_IOM_A_20_DN")
	)
	(arc
		(start 115.110006 -19.196304)
		(mid 115.158524 -19.205937)
		(end 115.199668 -19.233388)
		(width 0.1397)
		(layer "In9.Cu")
		(net "PCIE_COMP_A_TO_IOM_A_20_DN")
	)
	(arc
		(start 114.549936 -19.338798)
		(mid 114.559569 -19.29028)
		(end 114.58702 -19.249136)
		(width 0.1397)
		(layer "In9.Cu")
		(net "PCIE_COMP_A_TO_IOM_A_20_DN")
	)
	(arc
		(start 115.266724 -19.300444)
		(mid 115.294157 -19.341595)
		(end 115.303808 -19.390106)
		(width 0.1397)
		(layer "In9.Cu")
		(net "PCIE_COMP_A_TO_IOM_A_20_DN")
	)
	(arc
		(start 241.618262 -71.890382)
		(mid 241.699047 -71.820317)
		(end 241.805714 -71.827898)
		(width 0.1397)
		(layer "In9.Cu")
		(net "PCIE_COMP_A_TO_IOM_A_20_DN")
	)
	(arc
		(start 240.885726 -72.346058)
		(mid 241.242602 -72.269578)
		(end 241.536728 -72.05345)
		(width 0.1397)
		(layer "In9.Cu")
		(net "PCIE_COMP_A_TO_IOM_A_20_DN")
	)
	(arc
		(start 114.602768 -19.233388)
		(mid 114.643919 -19.205955)
		(end 114.69243 -19.196304)
		(width 0.1397)
		(layer "In9.Cu")
		(net "PCIE_COMP_A_TO_IOM_A_20_DN")
	)
	(segment
		(start 226.613212 -60.078874)
		(end 229.111048 -62.002924)
		(width 0.1397)
		(layer "In9.Cu")
		(net "PCIE_COMP_A_TO_IOM_A_19_DP")
	)
	(segment
		(start 202.118214 -55.212742)
		(end 226.613212 -60.078874)
		(width 0.1397)
		(layer "In9.Cu")
		(net "PCIE_COMP_A_TO_IOM_A_19_DP")
	)
	(segment
		(start 235.66882 -67.053968)
		(end 236.543342 -67.053968)
		(width 0.1397)
		(layer "In9.Cu")
		(net "PCIE_COMP_A_TO_IOM_A_19_DP")
	)
	(segment
		(start 144.512792 -55.2196)
		(end 173.67504 -61.172852)
		(width 0.1397)
		(layer "In9.Cu")
		(net "PCIE_COMP_A_TO_IOM_A_19_DP")
	)
	(segment
		(start 116.492528 -17.903952)
		(end 116.492782 -17.904206)
		(width 0.1397)
		(layer "In9.Cu")
		(net "PCIE_COMP_A_TO_IOM_A_19_DP")
	)
	(segment
		(start 117.396006 -33.182052)
		(end 122.171968 -40.433244)
		(width 0.1397)
		(layer "In9.Cu")
		(net "PCIE_COMP_A_TO_IOM_A_19_DP")
	)
	(segment
		(start 116.350034 -17.349978)
		(end 116.350034 -17.776698)
		(width 0.1397)
		(layer "In9.Cu")
		(net "PCIE_COMP_A_TO_IOM_A_19_DP")
	)
	(segment
		(start 233.325162 -65.24879)
		(end 233.52125 -65.22339)
		(width 0.1397)
		(layer "In9.Cu")
		(net "PCIE_COMP_A_TO_IOM_A_19_DP")
	)
	(segment
		(start 173.67504 -61.172852)
		(end 202.118214 -55.212742)
		(width 0.1397)
		(layer "In9.Cu")
		(net "PCIE_COMP_A_TO_IOM_A_19_DP")
	)
	(segment
		(start 232.439718 -64.5668)
		(end 232.635806 -64.5414)
		(width 0.1397)
		(layer "In9.Cu")
		(net "PCIE_COMP_A_TO_IOM_A_19_DP")
	)
	(segment
		(start 231.750362 -63.85941)
		(end 232.08234 -64.115188)
		(width 0.1397)
		(layer "In9.Cu")
		(net "PCIE_COMP_A_TO_IOM_A_19_DP")
	)
	(segment
		(start 232.967784 -64.797178)
		(end 232.993184 -64.993012)
		(width 0.1397)
		(layer "In9.Cu")
		(net "PCIE_COMP_A_TO_IOM_A_19_DP")
	)
	(segment
		(start 241.294412 -67.572382)
		(end 240.549938 -67.200018)
		(width 0.1397)
		(layer "In9.Cu")
		(net "PCIE_COMP_A_TO_IOM_A_19_DP")
	)
	(segment
		(start 116.37645 -17.840452)
		(end 116.402866 -17.866868)
		(width 0.1397)
		(layer "In9.Cu")
		(net "PCIE_COMP_A_TO_IOM_A_19_DP")
	)
	(segment
		(start 241.294412 -67.884802)
		(end 241.356896 -67.759834)
		(width 0.1397)
		(layer "In9.Cu")
		(net "PCIE_COMP_A_TO_IOM_A_19_DP")
	)
	(segment
		(start 233.878628 -65.675002)
		(end 235.66882 -67.053968)
		(width 0.1397)
		(layer "In9.Cu")
		(net "PCIE_COMP_A_TO_IOM_A_19_DP")
	)
	(segment
		(start 232.635806 -64.5414)
		(end 232.967784 -64.797178)
		(width 0.1397)
		(layer "In9.Cu")
		(net "PCIE_COMP_A_TO_IOM_A_19_DP")
	)
	(segment
		(start 122.171968 -40.433244)
		(end 144.512792 -55.2196)
		(width 0.1397)
		(layer "In9.Cu")
		(net "PCIE_COMP_A_TO_IOM_A_19_DP")
	)
	(segment
		(start 237.54334 -68.053966)
		(end 240.88598 -68.053966)
		(width 0.1397)
		(layer "In9.Cu")
		(net "PCIE_COMP_A_TO_IOM_A_19_DP")
	)
	(segment
		(start 117.396006 -18.390108)
		(end 117.396006 -33.182052)
		(width 0.1397)
		(layer "In9.Cu")
		(net "PCIE_COMP_A_TO_IOM_A_19_DP")
	)
	(segment
		(start 233.853228 -65.479168)
		(end 233.878628 -65.675002)
		(width 0.1397)
		(layer "In9.Cu")
		(net "PCIE_COMP_A_TO_IOM_A_19_DP")
	)
	(segment
		(start 232.08234 -64.115188)
		(end 232.10774 -64.311022)
		(width 0.1397)
		(layer "In9.Cu")
		(net "PCIE_COMP_A_TO_IOM_A_19_DP")
	)
	(segment
		(start 117.206522 -18.026634)
		(end 117.273578 -18.093944)
		(width 0.1397)
		(layer "In9.Cu")
		(net "PCIE_COMP_A_TO_IOM_A_19_DP")
	)
	(segment
		(start 232.993184 -64.993012)
		(end 233.325162 -65.24879)
		(width 0.1397)
		(layer "In9.Cu")
		(net "PCIE_COMP_A_TO_IOM_A_19_DP")
	)
	(segment
		(start 236.543342 -67.053968)
		(end 237.54334 -68.053966)
		(width 0.1397)
		(layer "In9.Cu")
		(net "PCIE_COMP_A_TO_IOM_A_19_DP")
	)
	(segment
		(start 233.52125 -65.22339)
		(end 233.853228 -65.479168)
		(width 0.1397)
		(layer "In9.Cu")
		(net "PCIE_COMP_A_TO_IOM_A_19_DP")
	)
	(segment
		(start 229.111048 -62.002924)
		(end 231.554528 -63.88481)
		(width 0.1397)
		(layer "In9.Cu")
		(net "PCIE_COMP_A_TO_IOM_A_19_DP")
	)
	(segment
		(start 232.10774 -64.311022)
		(end 232.439718 -64.5668)
		(width 0.1397)
		(layer "In9.Cu")
		(net "PCIE_COMP_A_TO_IOM_A_19_DP")
	)
	(segment
		(start 116.492782 -17.904206)
		(end 116.910104 -17.904206)
		(width 0.1397)
		(layer "In9.Cu")
		(net "PCIE_COMP_A_TO_IOM_A_19_DP")
	)
	(segment
		(start 231.554528 -63.88481)
		(end 231.750362 -63.85941)
		(width 0.1397)
		(layer "In9.Cu")
		(net "PCIE_COMP_A_TO_IOM_A_19_DP")
	)
	(arc
		(start 117.273578 -18.093944)
		(mid 117.364181 -18.229869)
		(end 117.396006 -18.390108)
		(width 0.1397)
		(layer "In9.Cu")
		(net "PCIE_COMP_A_TO_IOM_A_19_DP")
	)
	(arc
		(start 116.402866 -17.866868)
		(mid 116.444017 -17.894301)
		(end 116.492528 -17.903952)
		(width 0.1397)
		(layer "In9.Cu")
		(net "PCIE_COMP_A_TO_IOM_A_19_DP")
	)
	(arc
		(start 240.88598 -68.053966)
		(mid 241.107016 -68.009999)
		(end 241.294412 -67.884802)
		(width 0.1397)
		(layer "In9.Cu")
		(net "PCIE_COMP_A_TO_IOM_A_19_DP")
	)
	(arc
		(start 116.350034 -17.776698)
		(mid 116.356898 -17.811205)
		(end 116.37645 -17.840452)
		(width 0.1397)
		(layer "In9.Cu")
		(net "PCIE_COMP_A_TO_IOM_A_19_DP")
	)
	(arc
		(start 241.356896 -67.759834)
		(mid 241.364477 -67.653167)
		(end 241.294412 -67.572382)
		(width 0.1397)
		(layer "In9.Cu")
		(net "PCIE_COMP_A_TO_IOM_A_19_DP")
	)
	(arc
		(start 116.910104 -17.904206)
		(mid 117.070457 -17.935991)
		(end 117.206522 -18.026634)
		(width 0.1397)
		(layer "In9.Cu")
		(net "PCIE_COMP_A_TO_IOM_A_19_DP")
	)
	(segment
		(start 241.536728 -68.053458)
		(end 241.618262 -67.89039)
		(width 0.1397)
		(layer "In9.Cu")
		(net "PCIE_COMP_A_TO_IOM_A_19_DN")
	)
	(segment
		(start 117.103906 -18.390108)
		(end 117.103906 -33.269682)
		(width 0.1397)
		(layer "In9.Cu")
		(net "PCIE_COMP_A_TO_IOM_A_19_DN")
	)
	(segment
		(start 116.350034 -18.750026)
		(end 116.350034 -18.3388)
		(width 0.1397)
		(layer "In9.Cu")
		(net "PCIE_COMP_A_TO_IOM_A_19_DN")
	)
	(segment
		(start 236.422184 -67.346068)
		(end 237.422182 -68.346066)
		(width 0.1397)
		(layer "In9.Cu")
		(net "PCIE_COMP_A_TO_IOM_A_19_DN")
	)
	(segment
		(start 116.492528 -18.196306)
		(end 116.910104 -18.196306)
		(width 0.1397)
		(layer "In9.Cu")
		(net "PCIE_COMP_A_TO_IOM_A_19_DN")
	)
	(segment
		(start 117.103906 -33.269682)
		(end 121.96064 -40.644064)
		(width 0.1397)
		(layer "In9.Cu")
		(net "PCIE_COMP_A_TO_IOM_A_19_DN")
	)
	(segment
		(start 173.675802 -61.471302)
		(end 202.119738 -55.510938)
		(width 0.1397)
		(layer "In9.Cu")
		(net "PCIE_COMP_A_TO_IOM_A_19_DN")
	)
	(segment
		(start 237.422182 -68.346066)
		(end 240.885726 -68.346066)
		(width 0.1397)
		(layer "In9.Cu")
		(net "PCIE_COMP_A_TO_IOM_A_19_DN")
	)
	(segment
		(start 116.999766 -18.23339)
		(end 117.066822 -18.300446)
		(width 0.1397)
		(layer "In9.Cu")
		(net "PCIE_COMP_A_TO_IOM_A_19_DN")
	)
	(segment
		(start 235.569252 -67.346068)
		(end 236.422184 -67.346068)
		(width 0.1397)
		(layer "In9.Cu")
		(net "PCIE_COMP_A_TO_IOM_A_19_DN")
	)
	(segment
		(start 226.489006 -60.352178)
		(end 235.569252 -67.346068)
		(width 0.1397)
		(layer "In9.Cu")
		(net "PCIE_COMP_A_TO_IOM_A_19_DN")
	)
	(segment
		(start 202.119738 -55.510938)
		(end 226.489006 -60.352178)
		(width 0.1397)
		(layer "In9.Cu")
		(net "PCIE_COMP_A_TO_IOM_A_19_DN")
	)
	(segment
		(start 130.489198 -46.288706)
		(end 138.967464 -51.900074)
		(width 0.1397)
		(layer "In9.Cu")
		(net "PCIE_COMP_A_TO_IOM_A_19_DN")
	)
	(segment
		(start 144.398746 -55.494682)
		(end 173.675802 -61.471302)
		(width 0.1397)
		(layer "In9.Cu")
		(net "PCIE_COMP_A_TO_IOM_A_19_DN")
	)
	(segment
		(start 138.967718 -51.900074)
		(end 144.398746 -55.494682)
		(width 0.1397)
		(layer "In9.Cu")
		(net "PCIE_COMP_A_TO_IOM_A_19_DN")
	)
	(segment
		(start 241.805714 -67.827906)
		(end 242.549934 -68.200016)
		(width 0.1397)
		(layer "In9.Cu")
		(net "PCIE_COMP_A_TO_IOM_A_19_DN")
	)
	(segment
		(start 116.387118 -18.249138)
		(end 116.402866 -18.23339)
		(width 0.1397)
		(layer "In9.Cu")
		(net "PCIE_COMP_A_TO_IOM_A_19_DN")
	)
	(segment
		(start 121.96064 -40.644064)
		(end 130.489198 -46.288452)
		(width 0.1397)
		(layer "In9.Cu")
		(net "PCIE_COMP_A_TO_IOM_A_19_DN")
	)
	(segment
		(start 138.967464 -51.900074)
		(end 138.967718 -51.900074)
		(width 0.1397)
		(layer "In9.Cu")
		(net "PCIE_COMP_A_TO_IOM_A_19_DN")
	)
	(segment
		(start 130.489198 -46.288452)
		(end 130.489198 -46.288706)
		(width 0.1397)
		(layer "In9.Cu")
		(net "PCIE_COMP_A_TO_IOM_A_19_DN")
	)
	(arc
		(start 241.618262 -67.89039)
		(mid 241.699047 -67.820325)
		(end 241.805714 -67.827906)
		(width 0.1397)
		(layer "In9.Cu")
		(net "PCIE_COMP_A_TO_IOM_A_19_DN")
	)
	(arc
		(start 116.402866 -18.23339)
		(mid 116.444017 -18.205957)
		(end 116.492528 -18.196306)
		(width 0.1397)
		(layer "In9.Cu")
		(net "PCIE_COMP_A_TO_IOM_A_19_DN")
	)
	(arc
		(start 117.066822 -18.300446)
		(mid 117.094255 -18.341597)
		(end 117.103906 -18.390108)
		(width 0.1397)
		(layer "In9.Cu")
		(net "PCIE_COMP_A_TO_IOM_A_19_DN")
	)
	(arc
		(start 116.350034 -18.3388)
		(mid 116.359667 -18.290282)
		(end 116.387118 -18.249138)
		(width 0.1397)
		(layer "In9.Cu")
		(net "PCIE_COMP_A_TO_IOM_A_19_DN")
	)
	(arc
		(start 116.910104 -18.196306)
		(mid 116.958622 -18.205939)
		(end 116.999766 -18.23339)
		(width 0.1397)
		(layer "In9.Cu")
		(net "PCIE_COMP_A_TO_IOM_A_19_DN")
	)
	(arc
		(start 240.885726 -68.346066)
		(mid 241.242602 -68.269586)
		(end 241.536728 -68.053458)
		(width 0.1397)
		(layer "In9.Cu")
		(net "PCIE_COMP_A_TO_IOM_A_19_DN")
	)
	(segment
		(start 201.71791 -53.693314)
		(end 228.813868 -59.11215)
		(width 0.1397)
		(layer "In9.Cu")
		(net "PCIE_COMP_A_TO_IOM_A_18_DP")
	)
	(segment
		(start 228.813868 -59.11215)
		(end 229.952804 -59.989212)
		(width 0.1397)
		(layer "In9.Cu")
		(net "PCIE_COMP_A_TO_IOM_A_18_DP")
	)
	(segment
		(start 232.808272 -62.188598)
		(end 233.004106 -62.163198)
		(width 0.1397)
		(layer "In9.Cu")
		(net "PCIE_COMP_A_TO_IOM_A_18_DP")
	)
	(segment
		(start 118.292626 -18.904204)
		(end 118.709948 -18.904204)
		(width 0.1397)
		(layer "In9.Cu")
		(net "PCIE_COMP_A_TO_IOM_A_18_DP")
	)
	(segment
		(start 126.70028 -41.965626)
		(end 140.681202 -51.398678)
		(width 0.1397)
		(layer "In9.Cu")
		(net "PCIE_COMP_A_TO_IOM_A_18_DP")
	)
	(segment
		(start 118.149878 -18.35023)
		(end 118.149878 -18.761456)
		(width 0.1397)
		(layer "In9.Cu")
		(net "PCIE_COMP_A_TO_IOM_A_18_DP")
	)
	(segment
		(start 233.336084 -62.418976)
		(end 233.361484 -62.61481)
		(width 0.1397)
		(layer "In9.Cu")
		(net "PCIE_COMP_A_TO_IOM_A_18_DP")
	)
	(segment
		(start 232.47604 -61.93282)
		(end 232.808272 -62.188598)
		(width 0.1397)
		(layer "In9.Cu")
		(net "PCIE_COMP_A_TO_IOM_A_18_DP")
	)
	(segment
		(start 119.19585 -30.568138)
		(end 126.70028 -41.965626)
		(width 0.1397)
		(layer "In9.Cu")
		(net "PCIE_COMP_A_TO_IOM_A_18_DP")
	)
	(segment
		(start 241.294412 -63.57239)
		(end 240.549938 -63.200026)
		(width 0.1397)
		(layer "In9.Cu")
		(net "PCIE_COMP_A_TO_IOM_A_18_DP")
	)
	(segment
		(start 118.292372 -18.90395)
		(end 118.292626 -18.904204)
		(width 0.1397)
		(layer "In9.Cu")
		(net "PCIE_COMP_A_TO_IOM_A_18_DP")
	)
	(segment
		(start 118.186962 -18.851118)
		(end 118.20271 -18.866866)
		(width 0.1397)
		(layer "In9.Cu")
		(net "PCIE_COMP_A_TO_IOM_A_18_DP")
	)
	(segment
		(start 233.931714 -63.053976)
		(end 236.543342 -63.053976)
		(width 0.1397)
		(layer "In9.Cu")
		(net "PCIE_COMP_A_TO_IOM_A_18_DP")
	)
	(segment
		(start 231.233218 -60.799218)
		(end 231.565196 -61.054996)
		(width 0.1397)
		(layer "In9.Cu")
		(net "PCIE_COMP_A_TO_IOM_A_18_DP")
	)
	(segment
		(start 231.037384 -60.824618)
		(end 231.233218 -60.799218)
		(width 0.1397)
		(layer "In9.Cu")
		(net "PCIE_COMP_A_TO_IOM_A_18_DP")
	)
	(segment
		(start 177.648362 -58.720228)
		(end 201.71791 -53.693314)
		(width 0.1397)
		(layer "In9.Cu")
		(net "PCIE_COMP_A_TO_IOM_A_18_DP")
	)
	(segment
		(start 231.922828 -61.506608)
		(end 232.118662 -61.481208)
		(width 0.1397)
		(layer "In9.Cu")
		(net "PCIE_COMP_A_TO_IOM_A_18_DP")
	)
	(segment
		(start 237.54334 -64.053974)
		(end 240.88598 -64.053974)
		(width 0.1397)
		(layer "In9.Cu")
		(net "PCIE_COMP_A_TO_IOM_A_18_DP")
	)
	(segment
		(start 119.006366 -19.026632)
		(end 119.073422 -19.093942)
		(width 0.1397)
		(layer "In9.Cu")
		(net "PCIE_COMP_A_TO_IOM_A_18_DP")
	)
	(segment
		(start 232.45064 -61.736986)
		(end 232.47604 -61.93282)
		(width 0.1397)
		(layer "In9.Cu")
		(net "PCIE_COMP_A_TO_IOM_A_18_DP")
	)
	(segment
		(start 233.004106 -62.163198)
		(end 233.336084 -62.418976)
		(width 0.1397)
		(layer "In9.Cu")
		(net "PCIE_COMP_A_TO_IOM_A_18_DP")
	)
	(segment
		(start 229.952804 -59.989212)
		(end 231.037384 -60.824618)
		(width 0.1397)
		(layer "In9.Cu")
		(net "PCIE_COMP_A_TO_IOM_A_18_DP")
	)
	(segment
		(start 140.681202 -51.398678)
		(end 177.648362 -58.720228)
		(width 0.1397)
		(layer "In9.Cu")
		(net "PCIE_COMP_A_TO_IOM_A_18_DP")
	)
	(segment
		(start 236.543342 -63.053976)
		(end 237.54334 -64.053974)
		(width 0.1397)
		(layer "In9.Cu")
		(net "PCIE_COMP_A_TO_IOM_A_18_DP")
	)
	(segment
		(start 231.565196 -61.054996)
		(end 231.590596 -61.25083)
		(width 0.1397)
		(layer "In9.Cu")
		(net "PCIE_COMP_A_TO_IOM_A_18_DP")
	)
	(segment
		(start 241.294412 -63.88481)
		(end 241.356896 -63.759842)
		(width 0.1397)
		(layer "In9.Cu")
		(net "PCIE_COMP_A_TO_IOM_A_18_DP")
	)
	(segment
		(start 233.361484 -62.61481)
		(end 233.931714 -63.053976)
		(width 0.1397)
		(layer "In9.Cu")
		(net "PCIE_COMP_A_TO_IOM_A_18_DP")
	)
	(segment
		(start 232.118662 -61.481208)
		(end 232.45064 -61.736986)
		(width 0.1397)
		(layer "In9.Cu")
		(net "PCIE_COMP_A_TO_IOM_A_18_DP")
	)
	(segment
		(start 119.19585 -19.390106)
		(end 119.19585 -30.568138)
		(width 0.1397)
		(layer "In9.Cu")
		(net "PCIE_COMP_A_TO_IOM_A_18_DP")
	)
	(segment
		(start 231.590596 -61.25083)
		(end 231.922828 -61.506608)
		(width 0.1397)
		(layer "In9.Cu")
		(net "PCIE_COMP_A_TO_IOM_A_18_DP")
	)
	(arc
		(start 118.709948 -18.904204)
		(mid 118.870301 -18.935989)
		(end 119.006366 -19.026632)
		(width 0.1397)
		(layer "In9.Cu")
		(net "PCIE_COMP_A_TO_IOM_A_18_DP")
	)
	(arc
		(start 119.073422 -19.093942)
		(mid 119.164025 -19.229867)
		(end 119.19585 -19.390106)
		(width 0.1397)
		(layer "In9.Cu")
		(net "PCIE_COMP_A_TO_IOM_A_18_DP")
	)
	(arc
		(start 240.88598 -64.053974)
		(mid 241.107016 -64.010007)
		(end 241.294412 -63.88481)
		(width 0.1397)
		(layer "In9.Cu")
		(net "PCIE_COMP_A_TO_IOM_A_18_DP")
	)
	(arc
		(start 241.356896 -63.759842)
		(mid 241.364477 -63.653175)
		(end 241.294412 -63.57239)
		(width 0.1397)
		(layer "In9.Cu")
		(net "PCIE_COMP_A_TO_IOM_A_18_DP")
	)
	(arc
		(start 118.20271 -18.866866)
		(mid 118.243861 -18.894299)
		(end 118.292372 -18.90395)
		(width 0.1397)
		(layer "In9.Cu")
		(net "PCIE_COMP_A_TO_IOM_A_18_DP")
	)
	(arc
		(start 118.149878 -18.761456)
		(mid 118.159511 -18.809974)
		(end 118.186962 -18.851118)
		(width 0.1397)
		(layer "In9.Cu")
		(net "PCIE_COMP_A_TO_IOM_A_18_DP")
	)
	(segment
		(start 140.566648 -51.674014)
		(end 177.649886 -59.018424)
		(width 0.1397)
		(layer "In9.Cu")
		(net "PCIE_COMP_A_TO_IOM_A_18_DN")
	)
	(segment
		(start 241.536728 -64.053466)
		(end 241.618262 -63.890398)
		(width 0.1397)
		(layer "In9.Cu")
		(net "PCIE_COMP_A_TO_IOM_A_18_DN")
	)
	(segment
		(start 126.488444 -42.175176)
		(end 133.527292 -46.924468)
		(width 0.1397)
		(layer "In9.Cu")
		(net "PCIE_COMP_A_TO_IOM_A_18_DN")
	)
	(segment
		(start 233.832146 -63.346076)
		(end 236.422184 -63.346076)
		(width 0.1397)
		(layer "In9.Cu")
		(net "PCIE_COMP_A_TO_IOM_A_18_DN")
	)
	(segment
		(start 241.805714 -63.827914)
		(end 242.549934 -64.200024)
		(width 0.1397)
		(layer "In9.Cu")
		(net "PCIE_COMP_A_TO_IOM_A_18_DN")
	)
	(segment
		(start 118.90375 -30.655768)
		(end 126.488444 -42.175176)
		(width 0.1397)
		(layer "In9.Cu")
		(net "PCIE_COMP_A_TO_IOM_A_18_DN")
	)
	(segment
		(start 118.149878 -19.750024)
		(end 118.149878 -19.338798)
		(width 0.1397)
		(layer "In9.Cu")
		(net "PCIE_COMP_A_TO_IOM_A_18_DN")
	)
	(segment
		(start 133.527546 -46.924722)
		(end 140.566648 -51.674014)
		(width 0.1397)
		(layer "In9.Cu")
		(net "PCIE_COMP_A_TO_IOM_A_18_DN")
	)
	(segment
		(start 236.422184 -63.346076)
		(end 237.422182 -64.346074)
		(width 0.1397)
		(layer "In9.Cu")
		(net "PCIE_COMP_A_TO_IOM_A_18_DN")
	)
	(segment
		(start 237.422182 -64.346074)
		(end 240.885726 -64.346074)
		(width 0.1397)
		(layer "In9.Cu")
		(net "PCIE_COMP_A_TO_IOM_A_18_DN")
	)
	(segment
		(start 118.90375 -19.390106)
		(end 118.90375 -30.655768)
		(width 0.1397)
		(layer "In9.Cu")
		(net "PCIE_COMP_A_TO_IOM_A_18_DN")
	)
	(segment
		(start 201.71918 -53.99151)
		(end 228.689662 -59.3852)
		(width 0.1397)
		(layer "In9.Cu")
		(net "PCIE_COMP_A_TO_IOM_A_18_DN")
	)
	(segment
		(start 118.292372 -19.196304)
		(end 118.709948 -19.196304)
		(width 0.1397)
		(layer "In9.Cu")
		(net "PCIE_COMP_A_TO_IOM_A_18_DN")
	)
	(segment
		(start 177.649886 -59.018424)
		(end 201.71918 -53.99151)
		(width 0.1397)
		(layer "In9.Cu")
		(net "PCIE_COMP_A_TO_IOM_A_18_DN")
	)
	(segment
		(start 118.186962 -19.249136)
		(end 118.20271 -19.233388)
		(width 0.1397)
		(layer "In9.Cu")
		(net "PCIE_COMP_A_TO_IOM_A_18_DN")
	)
	(segment
		(start 118.79961 -19.233388)
		(end 118.866666 -19.300444)
		(width 0.1397)
		(layer "In9.Cu")
		(net "PCIE_COMP_A_TO_IOM_A_18_DN")
	)
	(segment
		(start 133.527292 -46.924468)
		(end 133.527546 -46.924722)
		(width 0.1397)
		(layer "In9.Cu")
		(net "PCIE_COMP_A_TO_IOM_A_18_DN")
	)
	(segment
		(start 228.689662 -59.3852)
		(end 233.832146 -63.346076)
		(width 0.1397)
		(layer "In9.Cu")
		(net "PCIE_COMP_A_TO_IOM_A_18_DN")
	)
	(arc
		(start 118.149878 -19.338798)
		(mid 118.159511 -19.29028)
		(end 118.186962 -19.249136)
		(width 0.1397)
		(layer "In9.Cu")
		(net "PCIE_COMP_A_TO_IOM_A_18_DN")
	)
	(arc
		(start 118.709948 -19.196304)
		(mid 118.758466 -19.205937)
		(end 118.79961 -19.233388)
		(width 0.1397)
		(layer "In9.Cu")
		(net "PCIE_COMP_A_TO_IOM_A_18_DN")
	)
	(arc
		(start 118.866666 -19.300444)
		(mid 118.894099 -19.341595)
		(end 118.90375 -19.390106)
		(width 0.1397)
		(layer "In9.Cu")
		(net "PCIE_COMP_A_TO_IOM_A_18_DN")
	)
	(arc
		(start 241.618262 -63.890398)
		(mid 241.699047 -63.820333)
		(end 241.805714 -63.827914)
		(width 0.1397)
		(layer "In9.Cu")
		(net "PCIE_COMP_A_TO_IOM_A_18_DN")
	)
	(arc
		(start 118.20271 -19.233388)
		(mid 118.243861 -19.205955)
		(end 118.292372 -19.196304)
		(width 0.1397)
		(layer "In9.Cu")
		(net "PCIE_COMP_A_TO_IOM_A_18_DN")
	)
	(arc
		(start 240.885726 -64.346074)
		(mid 241.242602 -64.269594)
		(end 241.536728 -64.053466)
		(width 0.1397)
		(layer "In9.Cu")
		(net "PCIE_COMP_A_TO_IOM_A_18_DN")
	)
	(segment
		(start 228.124766 -57.402984)
		(end 228.235002 -57.567068)
		(width 0.1397)
		(layer "In9.Cu")
		(net "PCIE_COMP_A_TO_IOM_A_17_DP")
	)
	(segment
		(start 227.549456 -57.432448)
		(end 227.71354 -57.322212)
		(width 0.1397)
		(layer "In9.Cu")
		(net "PCIE_COMP_A_TO_IOM_A_17_DP")
	)
	(segment
		(start 236.543342 -59.053984)
		(end 237.54334 -60.053982)
		(width 0.1397)
		(layer "In9.Cu")
		(net "PCIE_COMP_A_TO_IOM_A_17_DP")
	)
	(segment
		(start 119.976392 -17.840452)
		(end 120.002808 -17.866868)
		(width 0.1397)
		(layer "In9.Cu")
		(net "PCIE_COMP_A_TO_IOM_A_17_DP")
	)
	(segment
		(start 228.646228 -57.647586)
		(end 228.810058 -57.537604)
		(width 0.1397)
		(layer "In9.Cu")
		(net "PCIE_COMP_A_TO_IOM_A_17_DP")
	)
	(segment
		(start 120.995948 -31.361888)
		(end 123.38304 -34.986468)
		(width 0.1397)
		(layer "In9.Cu")
		(net "PCIE_COMP_A_TO_IOM_A_17_DP")
	)
	(segment
		(start 230.318056 -57.833514)
		(end 230.428292 -57.997598)
		(width 0.1397)
		(layer "In9.Cu")
		(net "PCIE_COMP_A_TO_IOM_A_17_DP")
	)
	(segment
		(start 235.810044 -59.053984)
		(end 236.543342 -59.053984)
		(width 0.1397)
		(layer "In9.Cu")
		(net "PCIE_COMP_A_TO_IOM_A_17_DP")
	)
	(segment
		(start 237.54334 -60.053982)
		(end 240.88598 -60.053982)
		(width 0.1397)
		(layer "In9.Cu")
		(net "PCIE_COMP_A_TO_IOM_A_17_DP")
	)
	(segment
		(start 120.092724 -17.904206)
		(end 120.510046 -17.904206)
		(width 0.1397)
		(layer "In9.Cu")
		(net "PCIE_COMP_A_TO_IOM_A_17_DP")
	)
	(segment
		(start 229.90683 -57.752742)
		(end 230.318056 -57.833514)
		(width 0.1397)
		(layer "In9.Cu")
		(net "PCIE_COMP_A_TO_IOM_A_17_DP")
	)
	(segment
		(start 196.093334 -51.258216)
		(end 227.549456 -57.432448)
		(width 0.1397)
		(layer "In9.Cu")
		(net "PCIE_COMP_A_TO_IOM_A_17_DP")
	)
	(segment
		(start 241.294412 -59.572398)
		(end 240.549938 -59.200034)
		(width 0.1397)
		(layer "In9.Cu")
		(net "PCIE_COMP_A_TO_IOM_A_17_DP")
	)
	(segment
		(start 153.741628 -50.625756)
		(end 176.747424 -55.305452)
		(width 0.1397)
		(layer "In9.Cu")
		(net "PCIE_COMP_A_TO_IOM_A_17_DP")
	)
	(segment
		(start 120.806464 -18.026634)
		(end 120.87352 -18.093944)
		(width 0.1397)
		(layer "In9.Cu")
		(net "PCIE_COMP_A_TO_IOM_A_17_DP")
	)
	(segment
		(start 120.995948 -18.390108)
		(end 120.995948 -31.361888)
		(width 0.1397)
		(layer "In9.Cu")
		(net "PCIE_COMP_A_TO_IOM_A_17_DP")
	)
	(segment
		(start 230.428292 -57.997598)
		(end 235.810044 -59.053984)
		(width 0.1397)
		(layer "In9.Cu")
		(net "PCIE_COMP_A_TO_IOM_A_17_DP")
	)
	(segment
		(start 228.810058 -57.537604)
		(end 229.221284 -57.618122)
		(width 0.1397)
		(layer "In9.Cu")
		(net "PCIE_COMP_A_TO_IOM_A_17_DP")
	)
	(segment
		(start 241.294412 -59.884818)
		(end 241.356896 -59.75985)
		(width 0.1397)
		(layer "In9.Cu")
		(net "PCIE_COMP_A_TO_IOM_A_17_DP")
	)
	(segment
		(start 120.09247 -17.903952)
		(end 120.092724 -17.904206)
		(width 0.1397)
		(layer "In9.Cu")
		(net "PCIE_COMP_A_TO_IOM_A_17_DP")
	)
	(segment
		(start 229.221284 -57.618122)
		(end 229.33152 -57.782206)
		(width 0.1397)
		(layer "In9.Cu")
		(net "PCIE_COMP_A_TO_IOM_A_17_DP")
	)
	(segment
		(start 227.71354 -57.322212)
		(end 228.124766 -57.402984)
		(width 0.1397)
		(layer "In9.Cu")
		(net "PCIE_COMP_A_TO_IOM_A_17_DP")
	)
	(segment
		(start 229.742746 -57.862978)
		(end 229.90683 -57.752742)
		(width 0.1397)
		(layer "In9.Cu")
		(net "PCIE_COMP_A_TO_IOM_A_17_DP")
	)
	(segment
		(start 149.91842 -48.656494)
		(end 153.741628 -50.625756)
		(width 0.1397)
		(layer "In9.Cu")
		(net "PCIE_COMP_A_TO_IOM_A_17_DP")
	)
	(segment
		(start 119.949976 -17.349978)
		(end 119.949976 -17.776698)
		(width 0.1397)
		(layer "In9.Cu")
		(net "PCIE_COMP_A_TO_IOM_A_17_DP")
	)
	(segment
		(start 176.747424 -55.305452)
		(end 196.093334 -51.258216)
		(width 0.1397)
		(layer "In9.Cu")
		(net "PCIE_COMP_A_TO_IOM_A_17_DP")
	)
	(segment
		(start 228.235002 -57.567068)
		(end 228.646228 -57.647586)
		(width 0.1397)
		(layer "In9.Cu")
		(net "PCIE_COMP_A_TO_IOM_A_17_DP")
	)
	(segment
		(start 229.33152 -57.782206)
		(end 229.742746 -57.862978)
		(width 0.1397)
		(layer "In9.Cu")
		(net "PCIE_COMP_A_TO_IOM_A_17_DP")
	)
	(segment
		(start 123.38304 -34.986468)
		(end 149.91842 -48.656494)
		(width 0.1397)
		(layer "In9.Cu")
		(net "PCIE_COMP_A_TO_IOM_A_17_DP")
	)
	(arc
		(start 120.87352 -18.093944)
		(mid 120.964123 -18.229869)
		(end 120.995948 -18.390108)
		(width 0.1397)
		(layer "In9.Cu")
		(net "PCIE_COMP_A_TO_IOM_A_17_DP")
	)
	(arc
		(start 120.002808 -17.866868)
		(mid 120.043959 -17.894301)
		(end 120.09247 -17.903952)
		(width 0.1397)
		(layer "In9.Cu")
		(net "PCIE_COMP_A_TO_IOM_A_17_DP")
	)
	(arc
		(start 120.510046 -17.904206)
		(mid 120.670399 -17.935991)
		(end 120.806464 -18.026634)
		(width 0.1397)
		(layer "In9.Cu")
		(net "PCIE_COMP_A_TO_IOM_A_17_DP")
	)
	(arc
		(start 241.356896 -59.75985)
		(mid 241.364477 -59.653183)
		(end 241.294412 -59.572398)
		(width 0.1397)
		(layer "In9.Cu")
		(net "PCIE_COMP_A_TO_IOM_A_17_DP")
	)
	(arc
		(start 240.88598 -60.053982)
		(mid 241.107016 -60.010015)
		(end 241.294412 -59.884818)
		(width 0.1397)
		(layer "In9.Cu")
		(net "PCIE_COMP_A_TO_IOM_A_17_DP")
	)
	(arc
		(start 119.949976 -17.776698)
		(mid 119.95684 -17.811205)
		(end 119.976392 -17.840452)
		(width 0.1397)
		(layer "In9.Cu")
		(net "PCIE_COMP_A_TO_IOM_A_17_DP")
	)
	(segment
		(start 196.095112 -51.556412)
		(end 235.781596 -59.346084)
		(width 0.1397)
		(layer "In9.Cu")
		(net "PCIE_COMP_A_TO_IOM_A_17_DN")
	)
	(segment
		(start 123.18111 -35.211258)
		(end 153.643584 -50.90414)
		(width 0.1397)
		(layer "In9.Cu")
		(net "PCIE_COMP_A_TO_IOM_A_17_DN")
	)
	(segment
		(start 237.422182 -60.346082)
		(end 240.885726 -60.346082)
		(width 0.1397)
		(layer "In9.Cu")
		(net "PCIE_COMP_A_TO_IOM_A_17_DN")
	)
	(segment
		(start 120.599708 -18.23339)
		(end 120.666764 -18.300446)
		(width 0.1397)
		(layer "In9.Cu")
		(net "PCIE_COMP_A_TO_IOM_A_17_DN")
	)
	(segment
		(start 241.805714 -59.827922)
		(end 242.549934 -60.200032)
		(width 0.1397)
		(layer "In9.Cu")
		(net "PCIE_COMP_A_TO_IOM_A_17_DN")
	)
	(segment
		(start 119.949976 -18.750026)
		(end 119.949976 -18.3388)
		(width 0.1397)
		(layer "In9.Cu")
		(net "PCIE_COMP_A_TO_IOM_A_17_DN")
	)
	(segment
		(start 120.09247 -18.196306)
		(end 120.510046 -18.196306)
		(width 0.1397)
		(layer "In9.Cu")
		(net "PCIE_COMP_A_TO_IOM_A_17_DN")
	)
	(segment
		(start 120.703848 -18.390108)
		(end 120.703848 -31.449518)
		(width 0.1397)
		(layer "In9.Cu")
		(net "PCIE_COMP_A_TO_IOM_A_17_DN")
	)
	(segment
		(start 241.536728 -60.053474)
		(end 241.618262 -59.890406)
		(width 0.1397)
		(layer "In9.Cu")
		(net "PCIE_COMP_A_TO_IOM_A_17_DN")
	)
	(segment
		(start 235.781596 -59.346084)
		(end 236.422184 -59.346084)
		(width 0.1397)
		(layer "In9.Cu")
		(net "PCIE_COMP_A_TO_IOM_A_17_DN")
	)
	(segment
		(start 120.703848 -31.449518)
		(end 123.18111 -35.211258)
		(width 0.1397)
		(layer "In9.Cu")
		(net "PCIE_COMP_A_TO_IOM_A_17_DN")
	)
	(segment
		(start 176.748186 -55.603902)
		(end 196.095112 -51.556412)
		(width 0.1397)
		(layer "In9.Cu")
		(net "PCIE_COMP_A_TO_IOM_A_17_DN")
	)
	(segment
		(start 153.643584 -50.90414)
		(end 176.748186 -55.603902)
		(width 0.1397)
		(layer "In9.Cu")
		(net "PCIE_COMP_A_TO_IOM_A_17_DN")
	)
	(segment
		(start 236.422184 -59.346084)
		(end 237.422182 -60.346082)
		(width 0.1397)
		(layer "In9.Cu")
		(net "PCIE_COMP_A_TO_IOM_A_17_DN")
	)
	(segment
		(start 119.98706 -18.249138)
		(end 120.002808 -18.23339)
		(width 0.1397)
		(layer "In9.Cu")
		(net "PCIE_COMP_A_TO_IOM_A_17_DN")
	)
	(arc
		(start 120.666764 -18.300446)
		(mid 120.694197 -18.341597)
		(end 120.703848 -18.390108)
		(width 0.1397)
		(layer "In9.Cu")
		(net "PCIE_COMP_A_TO_IOM_A_17_DN")
	)
	(arc
		(start 120.002808 -18.23339)
		(mid 120.043959 -18.205957)
		(end 120.09247 -18.196306)
		(width 0.1397)
		(layer "In9.Cu")
		(net "PCIE_COMP_A_TO_IOM_A_17_DN")
	)
	(arc
		(start 241.618262 -59.890406)
		(mid 241.699047 -59.820341)
		(end 241.805714 -59.827922)
		(width 0.1397)
		(layer "In9.Cu")
		(net "PCIE_COMP_A_TO_IOM_A_17_DN")
	)
	(arc
		(start 240.885726 -60.346082)
		(mid 241.242602 -60.269602)
		(end 241.536728 -60.053474)
		(width 0.1397)
		(layer "In9.Cu")
		(net "PCIE_COMP_A_TO_IOM_A_17_DN")
	)
	(arc
		(start 120.510046 -18.196306)
		(mid 120.558564 -18.205939)
		(end 120.599708 -18.23339)
		(width 0.1397)
		(layer "In9.Cu")
		(net "PCIE_COMP_A_TO_IOM_A_17_DN")
	)
	(arc
		(start 119.949976 -18.3388)
		(mid 119.959609 -18.290282)
		(end 119.98706 -18.249138)
		(width 0.1397)
		(layer "In9.Cu")
		(net "PCIE_COMP_A_TO_IOM_A_17_DN")
	)
	(segment
		(start 241.294412 -55.884826)
		(end 241.356896 -55.759858)
		(width 0.1397)
		(layer "In9.Cu")
		(net "PCIE_COMP_A_TO_IOM_A_16_DP")
	)
	(segment
		(start 232.827068 -55.053992)
		(end 236.543342 -55.053992)
		(width 0.1397)
		(layer "In9.Cu")
		(net "PCIE_COMP_A_TO_IOM_A_16_DP")
	)
	(segment
		(start 176.637696 -53.597556)
		(end 200.688448 -48.704246)
		(width 0.1397)
		(layer "In9.Cu")
		(net "PCIE_COMP_A_TO_IOM_A_16_DP")
	)
	(segment
		(start 227.934774 -53.945028)
		(end 228.346 -54.026308)
		(width 0.1397)
		(layer "In9.Cu")
		(net "PCIE_COMP_A_TO_IOM_A_16_DP")
	)
	(segment
		(start 124.931424 -33.393888)
		(end 156.08554 -49.44364)
		(width 0.1397)
		(layer "In9.Cu")
		(net "PCIE_COMP_A_TO_IOM_A_16_DP")
	)
	(segment
		(start 121.892822 -18.904204)
		(end 122.310144 -18.904204)
		(width 0.1397)
		(layer "In9.Cu")
		(net "PCIE_COMP_A_TO_IOM_A_16_DP")
	)
	(segment
		(start 226.153218 -53.592984)
		(end 226.2632 -53.757068)
		(width 0.1397)
		(layer "In9.Cu")
		(net "PCIE_COMP_A_TO_IOM_A_16_DP")
	)
	(segment
		(start 121.892568 -18.90395)
		(end 121.892822 -18.904204)
		(width 0.1397)
		(layer "In9.Cu")
		(net "PCIE_COMP_A_TO_IOM_A_16_DP")
	)
	(segment
		(start 226.83851 -53.728366)
		(end 227.249482 -53.809646)
		(width 0.1397)
		(layer "In9.Cu")
		(net "PCIE_COMP_A_TO_IOM_A_16_DP")
	)
	(segment
		(start 225.577908 -53.621686)
		(end 225.741992 -53.511704)
		(width 0.1397)
		(layer "In9.Cu")
		(net "PCIE_COMP_A_TO_IOM_A_16_DP")
	)
	(segment
		(start 122.879358 -30.29331)
		(end 124.931424 -33.393888)
		(width 0.1397)
		(layer "In9.Cu")
		(net "PCIE_COMP_A_TO_IOM_A_16_DP")
	)
	(segment
		(start 122.606562 -19.026632)
		(end 122.673618 -19.093942)
		(width 0.1397)
		(layer "In9.Cu")
		(net "PCIE_COMP_A_TO_IOM_A_16_DP")
	)
	(segment
		(start 121.787158 -18.851118)
		(end 121.802906 -18.866866)
		(width 0.1397)
		(layer "In9.Cu")
		(net "PCIE_COMP_A_TO_IOM_A_16_DP")
	)
	(segment
		(start 227.249482 -53.809646)
		(end 227.359464 -53.97373)
		(width 0.1397)
		(layer "In9.Cu")
		(net "PCIE_COMP_A_TO_IOM_A_16_DP")
	)
	(segment
		(start 121.750074 -18.35023)
		(end 121.750074 -18.761456)
		(width 0.1397)
		(layer "In9.Cu")
		(net "PCIE_COMP_A_TO_IOM_A_16_DP")
	)
	(segment
		(start 226.674172 -53.838348)
		(end 226.83851 -53.728366)
		(width 0.1397)
		(layer "In9.Cu")
		(net "PCIE_COMP_A_TO_IOM_A_16_DP")
	)
	(segment
		(start 236.543342 -55.053992)
		(end 237.54334 -56.05399)
		(width 0.1397)
		(layer "In9.Cu")
		(net "PCIE_COMP_A_TO_IOM_A_16_DP")
	)
	(segment
		(start 122.796046 -19.390106)
		(end 122.796046 -29.884878)
		(width 0.1397)
		(layer "In9.Cu")
		(net "PCIE_COMP_A_TO_IOM_A_16_DP")
	)
	(segment
		(start 237.54334 -56.05399)
		(end 240.88598 -56.05399)
		(width 0.1397)
		(layer "In9.Cu")
		(net "PCIE_COMP_A_TO_IOM_A_16_DP")
	)
	(segment
		(start 228.346 -54.026308)
		(end 228.455982 -54.190392)
		(width 0.1397)
		(layer "In9.Cu")
		(net "PCIE_COMP_A_TO_IOM_A_16_DP")
	)
	(segment
		(start 227.359464 -53.97373)
		(end 227.77069 -54.05501)
		(width 0.1397)
		(layer "In9.Cu")
		(net "PCIE_COMP_A_TO_IOM_A_16_DP")
	)
	(segment
		(start 156.08554 -49.44364)
		(end 176.637696 -53.597556)
		(width 0.1397)
		(layer "In9.Cu")
		(net "PCIE_COMP_A_TO_IOM_A_16_DP")
	)
	(segment
		(start 241.294412 -55.572406)
		(end 240.549938 -55.200042)
		(width 0.1397)
		(layer "In9.Cu")
		(net "PCIE_COMP_A_TO_IOM_A_16_DP")
	)
	(segment
		(start 225.741992 -53.511704)
		(end 226.153218 -53.592984)
		(width 0.1397)
		(layer "In9.Cu")
		(net "PCIE_COMP_A_TO_IOM_A_16_DP")
	)
	(segment
		(start 122.796046 -29.884878)
		(end 122.879358 -30.29331)
		(width 0.1397)
		(layer "In9.Cu")
		(net "PCIE_COMP_A_TO_IOM_A_16_DP")
	)
	(segment
		(start 226.2632 -53.757068)
		(end 226.674172 -53.838348)
		(width 0.1397)
		(layer "In9.Cu")
		(net "PCIE_COMP_A_TO_IOM_A_16_DP")
	)
	(segment
		(start 227.77069 -54.05501)
		(end 227.934774 -53.945028)
		(width 0.1397)
		(layer "In9.Cu")
		(net "PCIE_COMP_A_TO_IOM_A_16_DP")
	)
	(segment
		(start 228.455982 -54.190392)
		(end 232.827068 -55.053992)
		(width 0.1397)
		(layer "In9.Cu")
		(net "PCIE_COMP_A_TO_IOM_A_16_DP")
	)
	(segment
		(start 200.688448 -48.704246)
		(end 225.577908 -53.621686)
		(width 0.1397)
		(layer "In9.Cu")
		(net "PCIE_COMP_A_TO_IOM_A_16_DP")
	)
	(arc
		(start 122.673618 -19.093942)
		(mid 122.764221 -19.229867)
		(end 122.796046 -19.390106)
		(width 0.1397)
		(layer "In9.Cu")
		(net "PCIE_COMP_A_TO_IOM_A_16_DP")
	)
	(arc
		(start 241.356896 -55.759858)
		(mid 241.364477 -55.653191)
		(end 241.294412 -55.572406)
		(width 0.1397)
		(layer "In9.Cu")
		(net "PCIE_COMP_A_TO_IOM_A_16_DP")
	)
	(arc
		(start 121.802906 -18.866866)
		(mid 121.844057 -18.894299)
		(end 121.892568 -18.90395)
		(width 0.1397)
		(layer "In9.Cu")
		(net "PCIE_COMP_A_TO_IOM_A_16_DP")
	)
	(arc
		(start 122.310144 -18.904204)
		(mid 122.470497 -18.935989)
		(end 122.606562 -19.026632)
		(width 0.1397)
		(layer "In9.Cu")
		(net "PCIE_COMP_A_TO_IOM_A_16_DP")
	)
	(arc
		(start 121.750074 -18.761456)
		(mid 121.759707 -18.809974)
		(end 121.787158 -18.851118)
		(width 0.1397)
		(layer "In9.Cu")
		(net "PCIE_COMP_A_TO_IOM_A_16_DP")
	)
	(arc
		(start 240.88598 -56.05399)
		(mid 241.107016 -56.010023)
		(end 241.294412 -55.884826)
		(width 0.1397)
		(layer "In9.Cu")
		(net "PCIE_COMP_A_TO_IOM_A_16_DP")
	)
	(segment
		(start 122.503946 -19.390106)
		(end 122.503946 -29.915104)
		(width 0.1397)
		(layer "In9.Cu")
		(net "PCIE_COMP_A_TO_IOM_A_16_DN")
	)
	(segment
		(start 176.63795 -53.895752)
		(end 200.68921 -49.002188)
		(width 0.1397)
		(layer "In9.Cu")
		(net "PCIE_COMP_A_TO_IOM_A_16_DN")
	)
	(segment
		(start 155.98775 -49.722024)
		(end 176.63795 -53.895752)
		(width 0.1397)
		(layer "In9.Cu")
		(net "PCIE_COMP_A_TO_IOM_A_16_DN")
	)
	(segment
		(start 121.750074 -19.750024)
		(end 121.750074 -19.338798)
		(width 0.1397)
		(layer "In9.Cu")
		(net "PCIE_COMP_A_TO_IOM_A_16_DN")
	)
	(segment
		(start 121.787158 -19.249136)
		(end 121.802906 -19.233388)
		(width 0.1397)
		(layer "In9.Cu")
		(net "PCIE_COMP_A_TO_IOM_A_16_DN")
	)
	(segment
		(start 232.798366 -55.346092)
		(end 236.422184 -55.346092)
		(width 0.1397)
		(layer "In9.Cu")
		(net "PCIE_COMP_A_TO_IOM_A_16_DN")
	)
	(segment
		(start 121.892568 -19.196304)
		(end 122.310144 -19.196304)
		(width 0.1397)
		(layer "In9.Cu")
		(net "PCIE_COMP_A_TO_IOM_A_16_DN")
	)
	(segment
		(start 237.422182 -56.34609)
		(end 240.885726 -56.34609)
		(width 0.1397)
		(layer "In9.Cu")
		(net "PCIE_COMP_A_TO_IOM_A_16_DN")
	)
	(segment
		(start 122.503946 -29.915104)
		(end 122.604276 -30.407356)
		(width 0.1397)
		(layer "In9.Cu")
		(net "PCIE_COMP_A_TO_IOM_A_16_DN")
	)
	(segment
		(start 241.536728 -56.053482)
		(end 241.618262 -55.890414)
		(width 0.1397)
		(layer "In9.Cu")
		(net "PCIE_COMP_A_TO_IOM_A_16_DN")
	)
	(segment
		(start 241.805714 -55.82793)
		(end 242.549934 -56.20004)
		(width 0.1397)
		(layer "In9.Cu")
		(net "PCIE_COMP_A_TO_IOM_A_16_DN")
	)
	(segment
		(start 200.68921 -49.002188)
		(end 232.798366 -55.346092)
		(width 0.1397)
		(layer "In9.Cu")
		(net "PCIE_COMP_A_TO_IOM_A_16_DN")
	)
	(segment
		(start 122.399806 -19.233388)
		(end 122.466862 -19.300444)
		(width 0.1397)
		(layer "In9.Cu")
		(net "PCIE_COMP_A_TO_IOM_A_16_DN")
	)
	(segment
		(start 236.422184 -55.346092)
		(end 237.422182 -56.34609)
		(width 0.1397)
		(layer "In9.Cu")
		(net "PCIE_COMP_A_TO_IOM_A_16_DN")
	)
	(segment
		(start 122.604276 -30.407356)
		(end 124.729748 -33.618932)
		(width 0.1397)
		(layer "In9.Cu")
		(net "PCIE_COMP_A_TO_IOM_A_16_DN")
	)
	(segment
		(start 124.729748 -33.618932)
		(end 155.98775 -49.722024)
		(width 0.1397)
		(layer "In9.Cu")
		(net "PCIE_COMP_A_TO_IOM_A_16_DN")
	)
	(arc
		(start 122.466862 -19.300444)
		(mid 122.494295 -19.341595)
		(end 122.503946 -19.390106)
		(width 0.1397)
		(layer "In9.Cu")
		(net "PCIE_COMP_A_TO_IOM_A_16_DN")
	)
	(arc
		(start 241.618262 -55.890414)
		(mid 241.699047 -55.820349)
		(end 241.805714 -55.82793)
		(width 0.1397)
		(layer "In9.Cu")
		(net "PCIE_COMP_A_TO_IOM_A_16_DN")
	)
	(arc
		(start 121.802906 -19.233388)
		(mid 121.844057 -19.205955)
		(end 121.892568 -19.196304)
		(width 0.1397)
		(layer "In9.Cu")
		(net "PCIE_COMP_A_TO_IOM_A_16_DN")
	)
	(arc
		(start 240.885726 -56.34609)
		(mid 241.242602 -56.26961)
		(end 241.536728 -56.053482)
		(width 0.1397)
		(layer "In9.Cu")
		(net "PCIE_COMP_A_TO_IOM_A_16_DN")
	)
	(arc
		(start 122.310144 -19.196304)
		(mid 122.358662 -19.205937)
		(end 122.399806 -19.233388)
		(width 0.1397)
		(layer "In9.Cu")
		(net "PCIE_COMP_A_TO_IOM_A_16_DN")
	)
	(arc
		(start 121.750074 -19.338798)
		(mid 121.759707 -19.29028)
		(end 121.787158 -19.249136)
		(width 0.1397)
		(layer "In9.Cu")
		(net "PCIE_COMP_A_TO_IOM_A_16_DN")
	)
	(segment
		(start 229.378256 -50.379884)
		(end 233.449622 -51.054)
		(width 0.1397)
		(layer "In9.Cu")
		(net "PCIE_COMP_A_TO_IOM_A_15_DP")
	)
	(segment
		(start 241.294412 -51.884834)
		(end 241.356896 -51.759866)
		(width 0.1397)
		(layer "In9.Cu")
		(net "PCIE_COMP_A_TO_IOM_A_15_DP")
	)
	(segment
		(start 228.16058 -50.03673)
		(end 228.275642 -50.197512)
		(width 0.1397)
		(layer "In9.Cu")
		(net "PCIE_COMP_A_TO_IOM_A_15_DP")
	)
	(segment
		(start 237.54334 -52.053998)
		(end 240.88598 -52.053998)
		(width 0.1397)
		(layer "In9.Cu")
		(net "PCIE_COMP_A_TO_IOM_A_15_DP")
	)
	(segment
		(start 228.689154 -50.265838)
		(end 228.849682 -50.150776)
		(width 0.1397)
		(layer "In9.Cu")
		(net "PCIE_COMP_A_TO_IOM_A_15_DP")
	)
	(segment
		(start 131.796028 -31.616142)
		(end 132.713476 -33.00857)
		(width 0.1397)
		(layer "In9.Cu")
		(net "PCIE_COMP_A_TO_IOM_A_15_DP")
	)
	(segment
		(start 131.606544 -18.026634)
		(end 131.6736 -18.093944)
		(width 0.1397)
		(layer "In9.Cu")
		(net "PCIE_COMP_A_TO_IOM_A_15_DP")
	)
	(segment
		(start 233.449622 -51.054)
		(end 236.543342 -51.054)
		(width 0.1397)
		(layer "In9.Cu")
		(net "PCIE_COMP_A_TO_IOM_A_15_DP")
	)
	(segment
		(start 132.713476 -33.008824)
		(end 133.63067 -34.401506)
		(width 0.1397)
		(layer "In9.Cu")
		(net "PCIE_COMP_A_TO_IOM_A_15_DP")
	)
	(segment
		(start 162.523424 -46.096428)
		(end 181.372764 -42.432986)
		(width 0.1397)
		(layer "In9.Cu")
		(net "PCIE_COMP_A_TO_IOM_A_15_DP")
	)
	(segment
		(start 130.89255 -17.903952)
		(end 130.892804 -17.904206)
		(width 0.1397)
		(layer "In9.Cu")
		(net "PCIE_COMP_A_TO_IOM_A_15_DP")
	)
	(segment
		(start 227.057966 -49.854358)
		(end 227.173028 -50.014886)
		(width 0.1397)
		(layer "In9.Cu")
		(net "PCIE_COMP_A_TO_IOM_A_15_DP")
	)
	(segment
		(start 130.892804 -17.904206)
		(end 131.310126 -17.904206)
		(width 0.1397)
		(layer "In9.Cu")
		(net "PCIE_COMP_A_TO_IOM_A_15_DP")
	)
	(segment
		(start 181.372764 -42.432986)
		(end 226.483926 -49.90084)
		(width 0.1397)
		(layer "In9.Cu")
		(net "PCIE_COMP_A_TO_IOM_A_15_DP")
	)
	(segment
		(start 241.294412 -51.572414)
		(end 240.549938 -51.20005)
		(width 0.1397)
		(layer "In9.Cu")
		(net "PCIE_COMP_A_TO_IOM_A_15_DP")
	)
	(segment
		(start 227.747068 -49.968404)
		(end 228.16058 -50.03673)
		(width 0.1397)
		(layer "In9.Cu")
		(net "PCIE_COMP_A_TO_IOM_A_15_DP")
	)
	(segment
		(start 130.750056 -17.349978)
		(end 130.750056 -17.776698)
		(width 0.1397)
		(layer "In9.Cu")
		(net "PCIE_COMP_A_TO_IOM_A_15_DP")
	)
	(segment
		(start 229.263194 -50.219356)
		(end 229.378256 -50.379884)
		(width 0.1397)
		(layer "In9.Cu")
		(net "PCIE_COMP_A_TO_IOM_A_15_DP")
	)
	(segment
		(start 130.776472 -17.840452)
		(end 130.802888 -17.866868)
		(width 0.1397)
		(layer "In9.Cu")
		(net "PCIE_COMP_A_TO_IOM_A_15_DP")
	)
	(segment
		(start 131.796028 -18.390108)
		(end 131.796028 -31.616142)
		(width 0.1397)
		(layer "In9.Cu")
		(net "PCIE_COMP_A_TO_IOM_A_15_DP")
	)
	(segment
		(start 226.644454 -49.785778)
		(end 227.057966 -49.854358)
		(width 0.1397)
		(layer "In9.Cu")
		(net "PCIE_COMP_A_TO_IOM_A_15_DP")
	)
	(segment
		(start 228.849682 -50.150776)
		(end 229.263194 -50.219356)
		(width 0.1397)
		(layer "In9.Cu")
		(net "PCIE_COMP_A_TO_IOM_A_15_DP")
	)
	(segment
		(start 227.58654 -50.083466)
		(end 227.747068 -49.968404)
		(width 0.1397)
		(layer "In9.Cu")
		(net "PCIE_COMP_A_TO_IOM_A_15_DP")
	)
	(segment
		(start 132.713476 -33.00857)
		(end 132.713476 -33.008824)
		(width 0.1397)
		(layer "In9.Cu")
		(net "PCIE_COMP_A_TO_IOM_A_15_DP")
	)
	(segment
		(start 228.275642 -50.197512)
		(end 228.689154 -50.265838)
		(width 0.1397)
		(layer "In9.Cu")
		(net "PCIE_COMP_A_TO_IOM_A_15_DP")
	)
	(segment
		(start 226.483926 -49.90084)
		(end 226.644454 -49.785778)
		(width 0.1397)
		(layer "In9.Cu")
		(net "PCIE_COMP_A_TO_IOM_A_15_DP")
	)
	(segment
		(start 133.63067 -34.401506)
		(end 146.150076 -42.851832)
		(width 0.1397)
		(layer "In9.Cu")
		(net "PCIE_COMP_A_TO_IOM_A_15_DP")
	)
	(segment
		(start 227.173028 -50.014886)
		(end 227.58654 -50.083466)
		(width 0.1397)
		(layer "In9.Cu")
		(net "PCIE_COMP_A_TO_IOM_A_15_DP")
	)
	(segment
		(start 146.150076 -42.851832)
		(end 162.523424 -46.096428)
		(width 0.1397)
		(layer "In9.Cu")
		(net "PCIE_COMP_A_TO_IOM_A_15_DP")
	)
	(segment
		(start 236.543342 -51.054)
		(end 237.54334 -52.053998)
		(width 0.1397)
		(layer "In9.Cu")
		(net "PCIE_COMP_A_TO_IOM_A_15_DP")
	)
	(arc
		(start 240.88598 -52.053998)
		(mid 241.107016 -52.010031)
		(end 241.294412 -51.884834)
		(width 0.1397)
		(layer "In9.Cu")
		(net "PCIE_COMP_A_TO_IOM_A_15_DP")
	)
	(arc
		(start 241.356896 -51.759866)
		(mid 241.364477 -51.653199)
		(end 241.294412 -51.572414)
		(width 0.1397)
		(layer "In9.Cu")
		(net "PCIE_COMP_A_TO_IOM_A_15_DP")
	)
	(arc
		(start 131.310126 -17.904206)
		(mid 131.470479 -17.935991)
		(end 131.606544 -18.026634)
		(width 0.1397)
		(layer "In9.Cu")
		(net "PCIE_COMP_A_TO_IOM_A_15_DP")
	)
	(arc
		(start 130.802888 -17.866868)
		(mid 130.844039 -17.894301)
		(end 130.89255 -17.903952)
		(width 0.1397)
		(layer "In9.Cu")
		(net "PCIE_COMP_A_TO_IOM_A_15_DP")
	)
	(arc
		(start 131.6736 -18.093944)
		(mid 131.764203 -18.229869)
		(end 131.796028 -18.390108)
		(width 0.1397)
		(layer "In9.Cu")
		(net "PCIE_COMP_A_TO_IOM_A_15_DP")
	)
	(arc
		(start 130.750056 -17.776698)
		(mid 130.75692 -17.811205)
		(end 130.776472 -17.840452)
		(width 0.1397)
		(layer "In9.Cu")
		(net "PCIE_COMP_A_TO_IOM_A_15_DP")
	)
	(segment
		(start 133.418834 -34.611056)
		(end 139.72667 -38.868858)
		(width 0.1397)
		(layer "In9.Cu")
		(net "PCIE_COMP_A_TO_IOM_A_15_DN")
	)
	(segment
		(start 131.399788 -18.23339)
		(end 131.466844 -18.300446)
		(width 0.1397)
		(layer "In9.Cu")
		(net "PCIE_COMP_A_TO_IOM_A_15_DN")
	)
	(segment
		(start 233.425492 -51.3461)
		(end 236.422184 -51.3461)
		(width 0.1397)
		(layer "In9.Cu")
		(net "PCIE_COMP_A_TO_IOM_A_15_DN")
	)
	(segment
		(start 241.805714 -51.827938)
		(end 242.549934 -52.200048)
		(width 0.1397)
		(layer "In9.Cu")
		(net "PCIE_COMP_A_TO_IOM_A_15_DN")
	)
	(segment
		(start 146.035522 -43.127168)
		(end 162.522916 -46.394116)
		(width 0.1397)
		(layer "In9.Cu")
		(net "PCIE_COMP_A_TO_IOM_A_15_DN")
	)
	(segment
		(start 131.503928 -18.390108)
		(end 131.503928 -31.703772)
		(width 0.1397)
		(layer "In9.Cu")
		(net "PCIE_COMP_A_TO_IOM_A_15_DN")
	)
	(segment
		(start 139.72667 -38.868858)
		(end 139.72667 -38.868604)
		(width 0.1397)
		(layer "In9.Cu")
		(net "PCIE_COMP_A_TO_IOM_A_15_DN")
	)
	(segment
		(start 130.750056 -18.750026)
		(end 130.750056 -18.3388)
		(width 0.1397)
		(layer "In9.Cu")
		(net "PCIE_COMP_A_TO_IOM_A_15_DN")
	)
	(segment
		(start 181.376828 -42.729912)
		(end 233.425492 -51.3461)
		(width 0.1397)
		(layer "In9.Cu")
		(net "PCIE_COMP_A_TO_IOM_A_15_DN")
	)
	(segment
		(start 236.422184 -51.3461)
		(end 237.422182 -52.346098)
		(width 0.1397)
		(layer "In9.Cu")
		(net "PCIE_COMP_A_TO_IOM_A_15_DN")
	)
	(segment
		(start 237.422182 -52.346098)
		(end 240.885726 -52.346098)
		(width 0.1397)
		(layer "In9.Cu")
		(net "PCIE_COMP_A_TO_IOM_A_15_DN")
	)
	(segment
		(start 162.522916 -46.394116)
		(end 181.376828 -42.729912)
		(width 0.1397)
		(layer "In9.Cu")
		(net "PCIE_COMP_A_TO_IOM_A_15_DN")
	)
	(segment
		(start 139.72667 -38.868604)
		(end 146.035522 -43.127168)
		(width 0.1397)
		(layer "In9.Cu")
		(net "PCIE_COMP_A_TO_IOM_A_15_DN")
	)
	(segment
		(start 131.503928 -31.703772)
		(end 133.418834 -34.611056)
		(width 0.1397)
		(layer "In9.Cu")
		(net "PCIE_COMP_A_TO_IOM_A_15_DN")
	)
	(segment
		(start 130.78714 -18.249138)
		(end 130.802888 -18.23339)
		(width 0.1397)
		(layer "In9.Cu")
		(net "PCIE_COMP_A_TO_IOM_A_15_DN")
	)
	(segment
		(start 130.89255 -18.196306)
		(end 131.310126 -18.196306)
		(width 0.1397)
		(layer "In9.Cu")
		(net "PCIE_COMP_A_TO_IOM_A_15_DN")
	)
	(segment
		(start 241.536728 -52.05349)
		(end 241.618262 -51.890422)
		(width 0.1397)
		(layer "In9.Cu")
		(net "PCIE_COMP_A_TO_IOM_A_15_DN")
	)
	(arc
		(start 131.466844 -18.300446)
		(mid 131.494277 -18.341597)
		(end 131.503928 -18.390108)
		(width 0.1397)
		(layer "In9.Cu")
		(net "PCIE_COMP_A_TO_IOM_A_15_DN")
	)
	(arc
		(start 130.750056 -18.3388)
		(mid 130.759689 -18.290282)
		(end 130.78714 -18.249138)
		(width 0.1397)
		(layer "In9.Cu")
		(net "PCIE_COMP_A_TO_IOM_A_15_DN")
	)
	(arc
		(start 240.885726 -52.346098)
		(mid 241.242602 -52.269618)
		(end 241.536728 -52.05349)
		(width 0.1397)
		(layer "In9.Cu")
		(net "PCIE_COMP_A_TO_IOM_A_15_DN")
	)
	(arc
		(start 131.310126 -18.196306)
		(mid 131.358644 -18.205939)
		(end 131.399788 -18.23339)
		(width 0.1397)
		(layer "In9.Cu")
		(net "PCIE_COMP_A_TO_IOM_A_15_DN")
	)
	(arc
		(start 241.618262 -51.890422)
		(mid 241.699047 -51.820357)
		(end 241.805714 -51.827938)
		(width 0.1397)
		(layer "In9.Cu")
		(net "PCIE_COMP_A_TO_IOM_A_15_DN")
	)
	(arc
		(start 130.802888 -18.23339)
		(mid 130.844039 -18.205957)
		(end 130.89255 -18.196306)
		(width 0.1397)
		(layer "In9.Cu")
		(net "PCIE_COMP_A_TO_IOM_A_15_DN")
	)
	(segment
		(start 223.668082 -44.903644)
		(end 223.831912 -44.793408)
		(width 0.1397)
		(layer "In9.Cu")
		(net "PCIE_COMP_A_TO_IOM_A_14_DP")
	)
	(segment
		(start 226.436936 -45.302678)
		(end 226.547172 -45.466762)
		(width 0.1397)
		(layer "In9.Cu")
		(net "PCIE_COMP_A_TO_IOM_A_14_DP")
	)
	(segment
		(start 241.294412 -47.572422)
		(end 240.549938 -47.200058)
		(width 0.1397)
		(layer "In9.Cu")
		(net "PCIE_COMP_A_TO_IOM_A_14_DP")
	)
	(segment
		(start 133.406388 -19.026632)
		(end 133.473444 -19.093942)
		(width 0.1397)
		(layer "In9.Cu")
		(net "PCIE_COMP_A_TO_IOM_A_14_DP")
	)
	(segment
		(start 226.547172 -45.466762)
		(end 234.664758 -47.054008)
		(width 0.1397)
		(layer "In9.Cu")
		(net "PCIE_COMP_A_TO_IOM_A_14_DP")
	)
	(segment
		(start 225.86188 -45.33265)
		(end 226.02571 -45.222414)
		(width 0.1397)
		(layer "In9.Cu")
		(net "PCIE_COMP_A_TO_IOM_A_14_DP")
	)
	(segment
		(start 147.235926 -41.97223)
		(end 162.453066 -44.987718)
		(width 0.1397)
		(layer "In9.Cu")
		(net "PCIE_COMP_A_TO_IOM_A_14_DP")
	)
	(segment
		(start 224.353628 -45.037756)
		(end 224.764854 -45.118274)
		(width 0.1397)
		(layer "In9.Cu")
		(net "PCIE_COMP_A_TO_IOM_A_14_DP")
	)
	(segment
		(start 132.692648 -18.904204)
		(end 133.10997 -18.904204)
		(width 0.1397)
		(layer "In9.Cu")
		(net "PCIE_COMP_A_TO_IOM_A_14_DP")
	)
	(segment
		(start 223.831912 -44.793408)
		(end 224.243392 -44.873926)
		(width 0.1397)
		(layer "In9.Cu")
		(net "PCIE_COMP_A_TO_IOM_A_14_DP")
	)
	(segment
		(start 241.294412 -47.884842)
		(end 241.356896 -47.759874)
		(width 0.1397)
		(layer "In9.Cu")
		(net "PCIE_COMP_A_TO_IOM_A_14_DP")
	)
	(segment
		(start 234.664758 -47.054008)
		(end 236.69625 -47.054008)
		(width 0.1397)
		(layer "In9.Cu")
		(net "PCIE_COMP_A_TO_IOM_A_14_DP")
	)
	(segment
		(start 133.595872 -30.99181)
		(end 135.706612 -34.19602)
		(width 0.1397)
		(layer "In9.Cu")
		(net "PCIE_COMP_A_TO_IOM_A_14_DP")
	)
	(segment
		(start 193.36512 -38.978586)
		(end 223.668082 -44.903644)
		(width 0.1397)
		(layer "In9.Cu")
		(net "PCIE_COMP_A_TO_IOM_A_14_DP")
	)
	(segment
		(start 237.696248 -48.054006)
		(end 240.88598 -48.054006)
		(width 0.1397)
		(layer "In9.Cu")
		(net "PCIE_COMP_A_TO_IOM_A_14_DP")
	)
	(segment
		(start 132.692394 -18.90395)
		(end 132.692648 -18.904204)
		(width 0.1397)
		(layer "In9.Cu")
		(net "PCIE_COMP_A_TO_IOM_A_14_DP")
	)
	(segment
		(start 162.453066 -44.987718)
		(end 193.36512 -38.978586)
		(width 0.1397)
		(layer "In9.Cu")
		(net "PCIE_COMP_A_TO_IOM_A_14_DP")
	)
	(segment
		(start 226.02571 -45.222414)
		(end 226.436936 -45.302678)
		(width 0.1397)
		(layer "In9.Cu")
		(net "PCIE_COMP_A_TO_IOM_A_14_DP")
	)
	(segment
		(start 132.5499 -18.35023)
		(end 132.5499 -18.761456)
		(width 0.1397)
		(layer "In9.Cu")
		(net "PCIE_COMP_A_TO_IOM_A_14_DP")
	)
	(segment
		(start 225.340164 -45.088302)
		(end 225.4504 -45.252132)
		(width 0.1397)
		(layer "In9.Cu")
		(net "PCIE_COMP_A_TO_IOM_A_14_DP")
	)
	(segment
		(start 135.706612 -34.19602)
		(end 147.235926 -41.97223)
		(width 0.1397)
		(layer "In9.Cu")
		(net "PCIE_COMP_A_TO_IOM_A_14_DP")
	)
	(segment
		(start 224.243392 -44.873926)
		(end 224.353628 -45.037756)
		(width 0.1397)
		(layer "In9.Cu")
		(net "PCIE_COMP_A_TO_IOM_A_14_DP")
	)
	(segment
		(start 224.928938 -45.007784)
		(end 225.340164 -45.088302)
		(width 0.1397)
		(layer "In9.Cu")
		(net "PCIE_COMP_A_TO_IOM_A_14_DP")
	)
	(segment
		(start 133.595872 -19.390106)
		(end 133.595872 -30.99181)
		(width 0.1397)
		(layer "In9.Cu")
		(net "PCIE_COMP_A_TO_IOM_A_14_DP")
	)
	(segment
		(start 236.69625 -47.054008)
		(end 237.696248 -48.054006)
		(width 0.1397)
		(layer "In9.Cu")
		(net "PCIE_COMP_A_TO_IOM_A_14_DP")
	)
	(segment
		(start 132.586984 -18.851118)
		(end 132.602732 -18.866866)
		(width 0.1397)
		(layer "In9.Cu")
		(net "PCIE_COMP_A_TO_IOM_A_14_DP")
	)
	(segment
		(start 224.764854 -45.118274)
		(end 224.928938 -45.007784)
		(width 0.1397)
		(layer "In9.Cu")
		(net "PCIE_COMP_A_TO_IOM_A_14_DP")
	)
	(segment
		(start 225.4504 -45.252132)
		(end 225.86188 -45.33265)
		(width 0.1397)
		(layer "In9.Cu")
		(net "PCIE_COMP_A_TO_IOM_A_14_DP")
	)
	(arc
		(start 240.88598 -48.054006)
		(mid 241.107016 -48.010039)
		(end 241.294412 -47.884842)
		(width 0.1397)
		(layer "In9.Cu")
		(net "PCIE_COMP_A_TO_IOM_A_14_DP")
	)
	(arc
		(start 132.5499 -18.761456)
		(mid 132.559533 -18.809974)
		(end 132.586984 -18.851118)
		(width 0.1397)
		(layer "In9.Cu")
		(net "PCIE_COMP_A_TO_IOM_A_14_DP")
	)
	(arc
		(start 132.602732 -18.866866)
		(mid 132.643883 -18.894299)
		(end 132.692394 -18.90395)
		(width 0.1397)
		(layer "In9.Cu")
		(net "PCIE_COMP_A_TO_IOM_A_14_DP")
	)
	(arc
		(start 133.473444 -19.093942)
		(mid 133.564047 -19.229867)
		(end 133.595872 -19.390106)
		(width 0.1397)
		(layer "In9.Cu")
		(net "PCIE_COMP_A_TO_IOM_A_14_DP")
	)
	(arc
		(start 133.10997 -18.904204)
		(mid 133.270323 -18.935989)
		(end 133.406388 -19.026632)
		(width 0.1397)
		(layer "In9.Cu")
		(net "PCIE_COMP_A_TO_IOM_A_14_DP")
	)
	(arc
		(start 241.356896 -47.759874)
		(mid 241.364477 -47.653207)
		(end 241.294412 -47.572422)
		(width 0.1397)
		(layer "In9.Cu")
		(net "PCIE_COMP_A_TO_IOM_A_14_DP")
	)
	(segment
		(start 241.805714 -47.827946)
		(end 242.549934 -48.200056)
		(width 0.1397)
		(layer "In9.Cu")
		(net "PCIE_COMP_A_TO_IOM_A_14_DN")
	)
	(segment
		(start 135.494268 -34.405062)
		(end 135.494268 -34.405316)
		(width 0.1397)
		(layer "In9.Cu")
		(net "PCIE_COMP_A_TO_IOM_A_14_DN")
	)
	(segment
		(start 135.494268 -34.405316)
		(end 147.121372 -42.247312)
		(width 0.1397)
		(layer "In9.Cu")
		(net "PCIE_COMP_A_TO_IOM_A_14_DN")
	)
	(segment
		(start 135.462264 -34.356548)
		(end 135.462518 -34.356802)
		(width 0.1397)
		(layer "In9.Cu")
		(net "PCIE_COMP_A_TO_IOM_A_14_DN")
	)
	(segment
		(start 132.692394 -19.196304)
		(end 133.10997 -19.196304)
		(width 0.1397)
		(layer "In9.Cu")
		(net "PCIE_COMP_A_TO_IOM_A_14_DN")
	)
	(segment
		(start 193.364866 -39.276274)
		(end 234.63631 -47.346108)
		(width 0.1397)
		(layer "In9.Cu")
		(net "PCIE_COMP_A_TO_IOM_A_14_DN")
	)
	(segment
		(start 135.462518 -34.356802)
		(end 135.494268 -34.405062)
		(width 0.1397)
		(layer "In9.Cu")
		(net "PCIE_COMP_A_TO_IOM_A_14_DN")
	)
	(segment
		(start 135.462518 -34.356548)
		(end 135.462264 -34.356548)
		(width 0.1397)
		(layer "In9.Cu")
		(net "PCIE_COMP_A_TO_IOM_A_14_DN")
	)
	(segment
		(start 241.536728 -48.053498)
		(end 241.618262 -47.89043)
		(width 0.1397)
		(layer "In9.Cu")
		(net "PCIE_COMP_A_TO_IOM_A_14_DN")
	)
	(segment
		(start 132.5499 -19.750024)
		(end 132.5499 -19.338798)
		(width 0.1397)
		(layer "In9.Cu")
		(net "PCIE_COMP_A_TO_IOM_A_14_DN")
	)
	(segment
		(start 234.63631 -47.346108)
		(end 236.575092 -47.346108)
		(width 0.1397)
		(layer "In9.Cu")
		(net "PCIE_COMP_A_TO_IOM_A_14_DN")
	)
	(segment
		(start 132.586984 -19.249136)
		(end 132.602732 -19.233388)
		(width 0.1397)
		(layer "In9.Cu")
		(net "PCIE_COMP_A_TO_IOM_A_14_DN")
	)
	(segment
		(start 133.199632 -19.233388)
		(end 133.266688 -19.300444)
		(width 0.1397)
		(layer "In9.Cu")
		(net "PCIE_COMP_A_TO_IOM_A_14_DN")
	)
	(segment
		(start 147.121372 -42.247312)
		(end 162.452558 -45.285406)
		(width 0.1397)
		(layer "In9.Cu")
		(net "PCIE_COMP_A_TO_IOM_A_14_DN")
	)
	(segment
		(start 237.57509 -48.346106)
		(end 240.885726 -48.346106)
		(width 0.1397)
		(layer "In9.Cu")
		(net "PCIE_COMP_A_TO_IOM_A_14_DN")
	)
	(segment
		(start 236.575092 -47.346108)
		(end 237.57509 -48.346106)
		(width 0.1397)
		(layer "In9.Cu")
		(net "PCIE_COMP_A_TO_IOM_A_14_DN")
	)
	(segment
		(start 133.303772 -19.390106)
		(end 133.303772 -31.07944)
		(width 0.1397)
		(layer "In9.Cu")
		(net "PCIE_COMP_A_TO_IOM_A_14_DN")
	)
	(segment
		(start 133.303772 -31.07944)
		(end 135.462518 -34.356548)
		(width 0.1397)
		(layer "In9.Cu")
		(net "PCIE_COMP_A_TO_IOM_A_14_DN")
	)
	(segment
		(start 162.452558 -45.285406)
		(end 193.364866 -39.276274)
		(width 0.1397)
		(layer "In9.Cu")
		(net "PCIE_COMP_A_TO_IOM_A_14_DN")
	)
	(arc
		(start 132.602732 -19.233388)
		(mid 132.643883 -19.205955)
		(end 132.692394 -19.196304)
		(width 0.1397)
		(layer "In9.Cu")
		(net "PCIE_COMP_A_TO_IOM_A_14_DN")
	)
	(arc
		(start 133.10997 -19.196304)
		(mid 133.158488 -19.205937)
		(end 133.199632 -19.233388)
		(width 0.1397)
		(layer "In9.Cu")
		(net "PCIE_COMP_A_TO_IOM_A_14_DN")
	)
	(arc
		(start 241.618262 -47.89043)
		(mid 241.699047 -47.820365)
		(end 241.805714 -47.827946)
		(width 0.1397)
		(layer "In9.Cu")
		(net "PCIE_COMP_A_TO_IOM_A_14_DN")
	)
	(arc
		(start 240.885726 -48.346106)
		(mid 241.242602 -48.269626)
		(end 241.536728 -48.053498)
		(width 0.1397)
		(layer "In9.Cu")
		(net "PCIE_COMP_A_TO_IOM_A_14_DN")
	)
	(arc
		(start 133.266688 -19.300444)
		(mid 133.294121 -19.341595)
		(end 133.303772 -19.390106)
		(width 0.1397)
		(layer "In9.Cu")
		(net "PCIE_COMP_A_TO_IOM_A_14_DN")
	)
	(arc
		(start 132.5499 -19.338798)
		(mid 132.559533 -19.29028)
		(end 132.586984 -19.249136)
		(width 0.1397)
		(layer "In9.Cu")
		(net "PCIE_COMP_A_TO_IOM_A_14_DN")
	)
	(segment
		(start 231.210358 -42.436288)
		(end 234.318048 -43.054016)
		(width 0.1397)
		(layer "In9.Cu")
		(net "PCIE_COMP_A_TO_IOM_A_13_DP")
	)
	(segment
		(start 134.492492 -17.903952)
		(end 134.492746 -17.904206)
		(width 0.1397)
		(layer "In9.Cu")
		(net "PCIE_COMP_A_TO_IOM_A_13_DP")
	)
	(segment
		(start 136.645396 -33.478724)
		(end 146.717766 -40.272462)
		(width 0.1397)
		(layer "In9.Cu")
		(net "PCIE_COMP_A_TO_IOM_A_13_DP")
	)
	(segment
		(start 134.387082 -17.85112)
		(end 134.40283 -17.866868)
		(width 0.1397)
		(layer "In9.Cu")
		(net "PCIE_COMP_A_TO_IOM_A_13_DP")
	)
	(segment
		(start 135.206486 -18.026634)
		(end 135.273542 -18.093944)
		(width 0.1397)
		(layer "In9.Cu")
		(net "PCIE_COMP_A_TO_IOM_A_13_DP")
	)
	(segment
		(start 234.318048 -43.054016)
		(end 236.60227 -43.054016)
		(width 0.1397)
		(layer "In9.Cu")
		(net "PCIE_COMP_A_TO_IOM_A_13_DP")
	)
	(segment
		(start 241.294412 -43.88485)
		(end 241.356896 -43.759882)
		(width 0.1397)
		(layer "In9.Cu")
		(net "PCIE_COMP_A_TO_IOM_A_13_DP")
	)
	(segment
		(start 157.659578 -42.49801)
		(end 195.000372 -35.238944)
		(width 0.1397)
		(layer "In9.Cu")
		(net "PCIE_COMP_A_TO_IOM_A_13_DP")
	)
	(segment
		(start 228.332792 -41.86428)
		(end 228.49713 -41.754552)
		(width 0.1397)
		(layer "In9.Cu")
		(net "PCIE_COMP_A_TO_IOM_A_13_DP")
	)
	(segment
		(start 135.39597 -18.390108)
		(end 135.39597 -31.581344)
		(width 0.1397)
		(layer "In9.Cu")
		(net "PCIE_COMP_A_TO_IOM_A_13_DP")
	)
	(segment
		(start 241.294412 -43.57243)
		(end 240.549938 -43.200066)
		(width 0.1397)
		(layer "In9.Cu")
		(net "PCIE_COMP_A_TO_IOM_A_13_DP")
	)
	(segment
		(start 229.429056 -42.082212)
		(end 229.59314 -41.972484)
		(width 0.1397)
		(layer "In9.Cu")
		(net "PCIE_COMP_A_TO_IOM_A_13_DP")
	)
	(segment
		(start 236.60227 -43.054016)
		(end 237.602268 -44.054014)
		(width 0.1397)
		(layer "In9.Cu")
		(net "PCIE_COMP_A_TO_IOM_A_13_DP")
	)
	(segment
		(start 231.100376 -42.27195)
		(end 231.210358 -42.436288)
		(width 0.1397)
		(layer "In9.Cu")
		(net "PCIE_COMP_A_TO_IOM_A_13_DP")
	)
	(segment
		(start 195.000372 -35.238944)
		(end 228.332792 -41.86428)
		(width 0.1397)
		(layer "In9.Cu")
		(net "PCIE_COMP_A_TO_IOM_A_13_DP")
	)
	(segment
		(start 228.908102 -41.83634)
		(end 229.01783 -42.000424)
		(width 0.1397)
		(layer "In9.Cu")
		(net "PCIE_COMP_A_TO_IOM_A_13_DP")
	)
	(segment
		(start 135.39597 -31.581344)
		(end 136.645396 -33.478724)
		(width 0.1397)
		(layer "In9.Cu")
		(net "PCIE_COMP_A_TO_IOM_A_13_DP")
	)
	(segment
		(start 228.49713 -41.754552)
		(end 228.908102 -41.83634)
		(width 0.1397)
		(layer "In9.Cu")
		(net "PCIE_COMP_A_TO_IOM_A_13_DP")
	)
	(segment
		(start 230.525066 -42.300144)
		(end 230.689404 -42.190416)
		(width 0.1397)
		(layer "In9.Cu")
		(net "PCIE_COMP_A_TO_IOM_A_13_DP")
	)
	(segment
		(start 230.689404 -42.190416)
		(end 231.100376 -42.27195)
		(width 0.1397)
		(layer "In9.Cu")
		(net "PCIE_COMP_A_TO_IOM_A_13_DP")
	)
	(segment
		(start 229.59314 -41.972484)
		(end 230.004366 -42.054272)
		(width 0.1397)
		(layer "In9.Cu")
		(net "PCIE_COMP_A_TO_IOM_A_13_DP")
	)
	(segment
		(start 230.114094 -42.218356)
		(end 230.525066 -42.300144)
		(width 0.1397)
		(layer "In9.Cu")
		(net "PCIE_COMP_A_TO_IOM_A_13_DP")
	)
	(segment
		(start 230.004366 -42.054272)
		(end 230.114094 -42.218356)
		(width 0.1397)
		(layer "In9.Cu")
		(net "PCIE_COMP_A_TO_IOM_A_13_DP")
	)
	(segment
		(start 134.492746 -17.904206)
		(end 134.910068 -17.904206)
		(width 0.1397)
		(layer "In9.Cu")
		(net "PCIE_COMP_A_TO_IOM_A_13_DP")
	)
	(segment
		(start 134.349998 -17.349978)
		(end 134.349998 -17.761458)
		(width 0.1397)
		(layer "In9.Cu")
		(net "PCIE_COMP_A_TO_IOM_A_13_DP")
	)
	(segment
		(start 146.717766 -40.272462)
		(end 157.659578 -42.49801)
		(width 0.1397)
		(layer "In9.Cu")
		(net "PCIE_COMP_A_TO_IOM_A_13_DP")
	)
	(segment
		(start 229.01783 -42.000424)
		(end 229.429056 -42.082212)
		(width 0.1397)
		(layer "In9.Cu")
		(net "PCIE_COMP_A_TO_IOM_A_13_DP")
	)
	(segment
		(start 237.602268 -44.054014)
		(end 240.88598 -44.054014)
		(width 0.1397)
		(layer "In9.Cu")
		(net "PCIE_COMP_A_TO_IOM_A_13_DP")
	)
	(arc
		(start 134.40283 -17.866868)
		(mid 134.443981 -17.894301)
		(end 134.492492 -17.903952)
		(width 0.1397)
		(layer "In9.Cu")
		(net "PCIE_COMP_A_TO_IOM_A_13_DP")
	)
	(arc
		(start 134.910068 -17.904206)
		(mid 135.070421 -17.935991)
		(end 135.206486 -18.026634)
		(width 0.1397)
		(layer "In9.Cu")
		(net "PCIE_COMP_A_TO_IOM_A_13_DP")
	)
	(arc
		(start 134.349998 -17.761458)
		(mid 134.359631 -17.809976)
		(end 134.387082 -17.85112)
		(width 0.1397)
		(layer "In9.Cu")
		(net "PCIE_COMP_A_TO_IOM_A_13_DP")
	)
	(arc
		(start 240.88598 -44.054014)
		(mid 241.107016 -44.010047)
		(end 241.294412 -43.88485)
		(width 0.1397)
		(layer "In9.Cu")
		(net "PCIE_COMP_A_TO_IOM_A_13_DP")
	)
	(arc
		(start 241.356896 -43.759882)
		(mid 241.364477 -43.653215)
		(end 241.294412 -43.57243)
		(width 0.1397)
		(layer "In9.Cu")
		(net "PCIE_COMP_A_TO_IOM_A_13_DP")
	)
	(arc
		(start 135.273542 -18.093944)
		(mid 135.364145 -18.229869)
		(end 135.39597 -18.390108)
		(width 0.1397)
		(layer "In9.Cu")
		(net "PCIE_COMP_A_TO_IOM_A_13_DP")
	)
	(segment
		(start 228.275642 -42.150792)
		(end 228.275896 -42.150792)
		(width 0.1397)
		(layer "In9.Cu")
		(net "PCIE_COMP_A_TO_IOM_A_13_DN")
	)
	(segment
		(start 134.492492 -18.196306)
		(end 134.910068 -18.196306)
		(width 0.1397)
		(layer "In9.Cu")
		(net "PCIE_COMP_A_TO_IOM_A_13_DN")
	)
	(segment
		(start 194.999864 -35.536886)
		(end 228.275642 -42.150792)
		(width 0.1397)
		(layer "In9.Cu")
		(net "PCIE_COMP_A_TO_IOM_A_13_DN")
	)
	(segment
		(start 135.10387 -18.390108)
		(end 135.10387 -31.668974)
		(width 0.1397)
		(layer "In9.Cu")
		(net "PCIE_COMP_A_TO_IOM_A_13_DN")
	)
	(segment
		(start 135.10387 -31.668974)
		(end 136.43356 -33.688274)
		(width 0.1397)
		(layer "In9.Cu")
		(net "PCIE_COMP_A_TO_IOM_A_13_DN")
	)
	(segment
		(start 134.349998 -18.750026)
		(end 134.349998 -18.3388)
		(width 0.1397)
		(layer "In9.Cu")
		(net "PCIE_COMP_A_TO_IOM_A_13_DN")
	)
	(segment
		(start 237.48111 -44.346114)
		(end 240.885726 -44.346114)
		(width 0.1397)
		(layer "In9.Cu")
		(net "PCIE_COMP_A_TO_IOM_A_13_DN")
	)
	(segment
		(start 134.387082 -18.249138)
		(end 134.40283 -18.23339)
		(width 0.1397)
		(layer "In9.Cu")
		(net "PCIE_COMP_A_TO_IOM_A_13_DN")
	)
	(segment
		(start 234.289092 -43.346116)
		(end 236.481112 -43.346116)
		(width 0.1397)
		(layer "In9.Cu")
		(net "PCIE_COMP_A_TO_IOM_A_13_DN")
	)
	(segment
		(start 241.536728 -44.053506)
		(end 241.618262 -43.890438)
		(width 0.1397)
		(layer "In9.Cu")
		(net "PCIE_COMP_A_TO_IOM_A_13_DN")
	)
	(segment
		(start 136.43356 -33.688274)
		(end 146.60245 -40.54729)
		(width 0.1397)
		(layer "In9.Cu")
		(net "PCIE_COMP_A_TO_IOM_A_13_DN")
	)
	(segment
		(start 228.275896 -42.150792)
		(end 234.289092 -43.346116)
		(width 0.1397)
		(layer "In9.Cu")
		(net "PCIE_COMP_A_TO_IOM_A_13_DN")
	)
	(segment
		(start 146.60245 -40.54729)
		(end 157.658308 -42.795952)
		(width 0.1397)
		(layer "In9.Cu")
		(net "PCIE_COMP_A_TO_IOM_A_13_DN")
	)
	(segment
		(start 134.99973 -18.23339)
		(end 135.066786 -18.300446)
		(width 0.1397)
		(layer "In9.Cu")
		(net "PCIE_COMP_A_TO_IOM_A_13_DN")
	)
	(segment
		(start 157.658308 -42.795952)
		(end 194.999864 -35.536886)
		(width 0.1397)
		(layer "In9.Cu")
		(net "PCIE_COMP_A_TO_IOM_A_13_DN")
	)
	(segment
		(start 236.481112 -43.346116)
		(end 237.48111 -44.346114)
		(width 0.1397)
		(layer "In9.Cu")
		(net "PCIE_COMP_A_TO_IOM_A_13_DN")
	)
	(segment
		(start 241.805714 -43.827954)
		(end 242.549934 -44.200064)
		(width 0.1397)
		(layer "In9.Cu")
		(net "PCIE_COMP_A_TO_IOM_A_13_DN")
	)
	(arc
		(start 135.066786 -18.300446)
		(mid 135.094219 -18.341597)
		(end 135.10387 -18.390108)
		(width 0.1397)
		(layer "In9.Cu")
		(net "PCIE_COMP_A_TO_IOM_A_13_DN")
	)
	(arc
		(start 241.618262 -43.890438)
		(mid 241.699047 -43.820373)
		(end 241.805714 -43.827954)
		(width 0.1397)
		(layer "In9.Cu")
		(net "PCIE_COMP_A_TO_IOM_A_13_DN")
	)
	(arc
		(start 240.885726 -44.346114)
		(mid 241.242602 -44.269634)
		(end 241.536728 -44.053506)
		(width 0.1397)
		(layer "In9.Cu")
		(net "PCIE_COMP_A_TO_IOM_A_13_DN")
	)
	(arc
		(start 134.349998 -18.3388)
		(mid 134.359631 -18.290282)
		(end 134.387082 -18.249138)
		(width 0.1397)
		(layer "In9.Cu")
		(net "PCIE_COMP_A_TO_IOM_A_13_DN")
	)
	(arc
		(start 134.40283 -18.23339)
		(mid 134.443981 -18.205957)
		(end 134.492492 -18.196306)
		(width 0.1397)
		(layer "In9.Cu")
		(net "PCIE_COMP_A_TO_IOM_A_13_DN")
	)
	(arc
		(start 134.910068 -18.196306)
		(mid 134.958586 -18.205939)
		(end 134.99973 -18.23339)
		(width 0.1397)
		(layer "In9.Cu")
		(net "PCIE_COMP_A_TO_IOM_A_13_DN")
	)
	(segment
		(start 136.150096 -18.35023)
		(end 136.150096 -18.761456)
		(width 0.1397)
		(layer "In9.Cu")
		(net "PCIE_COMP_A_TO_IOM_A_12_DP")
	)
	(segment
		(start 230.326438 -38.33241)
		(end 230.737664 -38.413944)
		(width 0.1397)
		(layer "In9.Cu")
		(net "PCIE_COMP_A_TO_IOM_A_12_DP")
	)
	(segment
		(start 231.422702 -38.549834)
		(end 231.833928 -38.631368)
		(width 0.1397)
		(layer "In9.Cu")
		(net "PCIE_COMP_A_TO_IOM_A_12_DP")
	)
	(segment
		(start 136.292844 -18.904204)
		(end 136.710166 -18.904204)
		(width 0.1397)
		(layer "In9.Cu")
		(net "PCIE_COMP_A_TO_IOM_A_12_DP")
	)
	(segment
		(start 137.196068 -31.428436)
		(end 138.508232 -33.420812)
		(width 0.1397)
		(layer "In9.Cu")
		(net "PCIE_COMP_A_TO_IOM_A_12_DP")
	)
	(segment
		(start 136.18718 -18.851118)
		(end 136.202928 -18.866866)
		(width 0.1397)
		(layer "In9.Cu")
		(net "PCIE_COMP_A_TO_IOM_A_12_DP")
	)
	(segment
		(start 231.998012 -38.52164)
		(end 232.409238 -38.603174)
		(width 0.1397)
		(layer "In9.Cu")
		(net "PCIE_COMP_A_TO_IOM_A_12_DP")
	)
	(segment
		(start 146.892772 -39.076884)
		(end 157.714696 -41.225216)
		(width 0.1397)
		(layer "In9.Cu")
		(net "PCIE_COMP_A_TO_IOM_A_12_DP")
	)
	(segment
		(start 236.69625 -39.054024)
		(end 237.696248 -40.054022)
		(width 0.1397)
		(layer "In9.Cu")
		(net "PCIE_COMP_A_TO_IOM_A_12_DP")
	)
	(segment
		(start 241.294412 -39.884858)
		(end 241.356896 -39.75989)
		(width 0.1397)
		(layer "In9.Cu")
		(net "PCIE_COMP_A_TO_IOM_A_12_DP")
	)
	(segment
		(start 237.696248 -40.054022)
		(end 240.88598 -40.054022)
		(width 0.1397)
		(layer "In9.Cu")
		(net "PCIE_COMP_A_TO_IOM_A_12_DP")
	)
	(segment
		(start 229.6414 -38.196266)
		(end 229.805484 -38.086538)
		(width 0.1397)
		(layer "In9.Cu")
		(net "PCIE_COMP_A_TO_IOM_A_12_DP")
	)
	(segment
		(start 230.901748 -38.304216)
		(end 231.312974 -38.38575)
		(width 0.1397)
		(layer "In9.Cu")
		(net "PCIE_COMP_A_TO_IOM_A_12_DP")
	)
	(segment
		(start 231.312974 -38.38575)
		(end 231.422702 -38.549834)
		(width 0.1397)
		(layer "In9.Cu")
		(net "PCIE_COMP_A_TO_IOM_A_12_DP")
	)
	(segment
		(start 157.714696 -41.225216)
		(end 201.760836 -32.66313)
		(width 0.1397)
		(layer "In9.Cu")
		(net "PCIE_COMP_A_TO_IOM_A_12_DP")
	)
	(segment
		(start 241.294412 -39.572438)
		(end 240.549938 -39.200074)
		(width 0.1397)
		(layer "In9.Cu")
		(net "PCIE_COMP_A_TO_IOM_A_12_DP")
	)
	(segment
		(start 229.805484 -38.086538)
		(end 230.21671 -38.168072)
		(width 0.1397)
		(layer "In9.Cu")
		(net "PCIE_COMP_A_TO_IOM_A_12_DP")
	)
	(segment
		(start 232.518966 -38.767512)
		(end 233.962956 -39.054024)
		(width 0.1397)
		(layer "In9.Cu")
		(net "PCIE_COMP_A_TO_IOM_A_12_DP")
	)
	(segment
		(start 233.962956 -39.054024)
		(end 236.69625 -39.054024)
		(width 0.1397)
		(layer "In9.Cu")
		(net "PCIE_COMP_A_TO_IOM_A_12_DP")
	)
	(segment
		(start 231.833928 -38.631368)
		(end 231.998012 -38.52164)
		(width 0.1397)
		(layer "In9.Cu")
		(net "PCIE_COMP_A_TO_IOM_A_12_DP")
	)
	(segment
		(start 146.892518 -39.07663)
		(end 146.892772 -39.076884)
		(width 0.1397)
		(layer "In9.Cu")
		(net "PCIE_COMP_A_TO_IOM_A_12_DP")
	)
	(segment
		(start 201.760836 -32.66313)
		(end 229.6414 -38.196266)
		(width 0.1397)
		(layer "In9.Cu")
		(net "PCIE_COMP_A_TO_IOM_A_12_DP")
	)
	(segment
		(start 230.737664 -38.413944)
		(end 230.901748 -38.304216)
		(width 0.1397)
		(layer "In9.Cu")
		(net "PCIE_COMP_A_TO_IOM_A_12_DP")
	)
	(segment
		(start 136.29259 -18.90395)
		(end 136.292844 -18.904204)
		(width 0.1397)
		(layer "In9.Cu")
		(net "PCIE_COMP_A_TO_IOM_A_12_DP")
	)
	(segment
		(start 232.409238 -38.603174)
		(end 232.518966 -38.767512)
		(width 0.1397)
		(layer "In9.Cu")
		(net "PCIE_COMP_A_TO_IOM_A_12_DP")
	)
	(segment
		(start 230.21671 -38.168072)
		(end 230.326438 -38.33241)
		(width 0.1397)
		(layer "In9.Cu")
		(net "PCIE_COMP_A_TO_IOM_A_12_DP")
	)
	(segment
		(start 137.196068 -19.390106)
		(end 137.196068 -31.428436)
		(width 0.1397)
		(layer "In9.Cu")
		(net "PCIE_COMP_A_TO_IOM_A_12_DP")
	)
	(segment
		(start 138.508232 -33.420812)
		(end 146.892518 -39.07663)
		(width 0.1397)
		(layer "In9.Cu")
		(net "PCIE_COMP_A_TO_IOM_A_12_DP")
	)
	(segment
		(start 137.006584 -19.026632)
		(end 137.07364 -19.093942)
		(width 0.1397)
		(layer "In9.Cu")
		(net "PCIE_COMP_A_TO_IOM_A_12_DP")
	)
	(arc
		(start 136.710166 -18.904204)
		(mid 136.870519 -18.935989)
		(end 137.006584 -19.026632)
		(width 0.1397)
		(layer "In9.Cu")
		(net "PCIE_COMP_A_TO_IOM_A_12_DP")
	)
	(arc
		(start 136.150096 -18.761456)
		(mid 136.159729 -18.809974)
		(end 136.18718 -18.851118)
		(width 0.1397)
		(layer "In9.Cu")
		(net "PCIE_COMP_A_TO_IOM_A_12_DP")
	)
	(arc
		(start 136.202928 -18.866866)
		(mid 136.244079 -18.894299)
		(end 136.29259 -18.90395)
		(width 0.1397)
		(layer "In9.Cu")
		(net "PCIE_COMP_A_TO_IOM_A_12_DP")
	)
	(arc
		(start 137.07364 -19.093942)
		(mid 137.164243 -19.229867)
		(end 137.196068 -19.390106)
		(width 0.1397)
		(layer "In9.Cu")
		(net "PCIE_COMP_A_TO_IOM_A_12_DP")
	)
	(arc
		(start 241.356896 -39.75989)
		(mid 241.364477 -39.653223)
		(end 241.294412 -39.572438)
		(width 0.1397)
		(layer "In9.Cu")
		(net "PCIE_COMP_A_TO_IOM_A_12_DP")
	)
	(arc
		(start 240.88598 -40.054022)
		(mid 241.107016 -40.010055)
		(end 241.294412 -39.884858)
		(width 0.1397)
		(layer "In9.Cu")
		(net "PCIE_COMP_A_TO_IOM_A_12_DP")
	)
	(segment
		(start 157.714188 -41.523158)
		(end 201.760328 -32.961072)
		(width 0.1397)
		(layer "In9.Cu")
		(net "PCIE_COMP_A_TO_IOM_A_12_DN")
	)
	(segment
		(start 201.760328 -32.961072)
		(end 233.934 -39.346124)
		(width 0.1397)
		(layer "In9.Cu")
		(net "PCIE_COMP_A_TO_IOM_A_12_DN")
	)
	(segment
		(start 236.575092 -39.346124)
		(end 237.57509 -40.346122)
		(width 0.1397)
		(layer "In9.Cu")
		(net "PCIE_COMP_A_TO_IOM_A_12_DN")
	)
	(segment
		(start 146.778218 -39.351966)
		(end 157.714188 -41.523158)
		(width 0.1397)
		(layer "In9.Cu")
		(net "PCIE_COMP_A_TO_IOM_A_12_DN")
	)
	(segment
		(start 146.777964 -39.351966)
		(end 146.778218 -39.351966)
		(width 0.1397)
		(layer "In9.Cu")
		(net "PCIE_COMP_A_TO_IOM_A_12_DN")
	)
	(segment
		(start 136.799828 -19.233388)
		(end 136.866884 -19.300444)
		(width 0.1397)
		(layer "In9.Cu")
		(net "PCIE_COMP_A_TO_IOM_A_12_DN")
	)
	(segment
		(start 138.296396 -33.630362)
		(end 146.777964 -39.351966)
		(width 0.1397)
		(layer "In9.Cu")
		(net "PCIE_COMP_A_TO_IOM_A_12_DN")
	)
	(segment
		(start 136.903968 -19.390106)
		(end 136.903968 -31.516066)
		(width 0.1397)
		(layer "In9.Cu")
		(net "PCIE_COMP_A_TO_IOM_A_12_DN")
	)
	(segment
		(start 241.805714 -39.827962)
		(end 242.549934 -40.200072)
		(width 0.1397)
		(layer "In9.Cu")
		(net "PCIE_COMP_A_TO_IOM_A_12_DN")
	)
	(segment
		(start 136.18718 -19.249136)
		(end 136.202928 -19.233388)
		(width 0.1397)
		(layer "In9.Cu")
		(net "PCIE_COMP_A_TO_IOM_A_12_DN")
	)
	(segment
		(start 136.150096 -19.750024)
		(end 136.150096 -19.338798)
		(width 0.1397)
		(layer "In9.Cu")
		(net "PCIE_COMP_A_TO_IOM_A_12_DN")
	)
	(segment
		(start 136.903968 -31.516066)
		(end 138.296396 -33.630362)
		(width 0.1397)
		(layer "In9.Cu")
		(net "PCIE_COMP_A_TO_IOM_A_12_DN")
	)
	(segment
		(start 136.29259 -19.196304)
		(end 136.710166 -19.196304)
		(width 0.1397)
		(layer "In9.Cu")
		(net "PCIE_COMP_A_TO_IOM_A_12_DN")
	)
	(segment
		(start 237.57509 -40.346122)
		(end 240.885726 -40.346122)
		(width 0.1397)
		(layer "In9.Cu")
		(net "PCIE_COMP_A_TO_IOM_A_12_DN")
	)
	(segment
		(start 241.536728 -40.053514)
		(end 241.618262 -39.890446)
		(width 0.1397)
		(layer "In9.Cu")
		(net "PCIE_COMP_A_TO_IOM_A_12_DN")
	)
	(segment
		(start 233.934 -39.346124)
		(end 236.575092 -39.346124)
		(width 0.1397)
		(layer "In9.Cu")
		(net "PCIE_COMP_A_TO_IOM_A_12_DN")
	)
	(arc
		(start 240.885726 -40.346122)
		(mid 241.242602 -40.269642)
		(end 241.536728 -40.053514)
		(width 0.1397)
		(layer "In9.Cu")
		(net "PCIE_COMP_A_TO_IOM_A_12_DN")
	)
	(arc
		(start 136.150096 -19.338798)
		(mid 136.159729 -19.29028)
		(end 136.18718 -19.249136)
		(width 0.1397)
		(layer "In9.Cu")
		(net "PCIE_COMP_A_TO_IOM_A_12_DN")
	)
	(arc
		(start 241.618262 -39.890446)
		(mid 241.699047 -39.820381)
		(end 241.805714 -39.827962)
		(width 0.1397)
		(layer "In9.Cu")
		(net "PCIE_COMP_A_TO_IOM_A_12_DN")
	)
	(arc
		(start 136.710166 -19.196304)
		(mid 136.758684 -19.205937)
		(end 136.799828 -19.233388)
		(width 0.1397)
		(layer "In9.Cu")
		(net "PCIE_COMP_A_TO_IOM_A_12_DN")
	)
	(arc
		(start 136.866884 -19.300444)
		(mid 136.894317 -19.341595)
		(end 136.903968 -19.390106)
		(width 0.1397)
		(layer "In9.Cu")
		(net "PCIE_COMP_A_TO_IOM_A_12_DN")
	)
	(arc
		(start 136.202928 -19.233388)
		(mid 136.244079 -19.205955)
		(end 136.29259 -19.196304)
		(width 0.1397)
		(layer "In9.Cu")
		(net "PCIE_COMP_A_TO_IOM_A_12_DN")
	)
	(segment
		(start 233.824272 -176.775872)
		(end 233.783124 -176.969166)
		(width 0.1397)
		(layer "In9.Cu")
		(net "PCIE_COMP_A_TO_IOM_A_11_DP")
	)
	(segment
		(start 235.010198 -178.858672)
		(end 235.652564 -179.353718)
		(width 0.1397)
		(layer "In9.Cu")
		(net "PCIE_COMP_A_TO_IOM_A_11_DP")
	)
	(segment
		(start 243.679726 -86.908132)
		(end 242.533678 -88.472264)
		(width 0.1397)
		(layer "In9.Cu")
		(net "PCIE_COMP_A_TO_IOM_A_11_DP")
	)
	(segment
		(start 234.391708 -177.906426)
		(end 235.010198 -178.858672)
		(width 0.1397)
		(layer "In9.Cu")
		(net "PCIE_COMP_A_TO_IOM_A_11_DP")
	)
	(segment
		(start 241.294412 -180.184552)
		(end 241.356896 -180.059584)
		(width 0.1397)
		(layer "In9.Cu")
		(net "PCIE_COMP_A_TO_IOM_A_11_DP")
	)
	(segment
		(start 236.525054 -31.05404)
		(end 237.525052 -32.054038)
		(width 0.1397)
		(layer "In9.Cu")
		(net "PCIE_COMP_A_TO_IOM_A_11_DP")
	)
	(segment
		(start 241.294412 -179.872132)
		(end 240.549938 -179.499768)
		(width 0.1397)
		(layer "In9.Cu")
		(net "PCIE_COMP_A_TO_IOM_A_11_DP")
	)
	(segment
		(start 138.092688 -17.904206)
		(end 138.51001 -17.904206)
		(width 0.1397)
		(layer "In9.Cu")
		(net "PCIE_COMP_A_TO_IOM_A_11_DP")
	)
	(segment
		(start 221.803214 -153.42616)
		(end 221.803468 -153.42616)
		(width 0.1397)
		(layer "In9.Cu")
		(net "PCIE_COMP_A_TO_IOM_A_11_DP")
	)
	(segment
		(start 242.024916 -33.054036)
		(end 243.087652 -33.054036)
		(width 0.1397)
		(layer "In9.Cu")
		(net "PCIE_COMP_A_TO_IOM_A_11_DP")
	)
	(segment
		(start 137.987024 -17.85112)
		(end 138.002772 -17.866868)
		(width 0.1397)
		(layer "In9.Cu")
		(net "PCIE_COMP_A_TO_IOM_A_11_DP")
	)
	(segment
		(start 137.94994 -17.349978)
		(end 137.94994 -17.761458)
		(width 0.1397)
		(layer "In9.Cu")
		(net "PCIE_COMP_A_TO_IOM_A_11_DP")
	)
	(segment
		(start 221.803468 -153.42616)
		(end 223.57334 -161.249106)
		(width 0.1397)
		(layer "In9.Cu")
		(net "PCIE_COMP_A_TO_IOM_A_11_DP")
	)
	(segment
		(start 236.599984 -179.353718)
		(end 237.599982 -180.353716)
		(width 0.1397)
		(layer "In9.Cu")
		(net "PCIE_COMP_A_TO_IOM_A_11_DP")
	)
	(segment
		(start 220.032834 -145.601944)
		(end 221.803214 -153.42616)
		(width 0.1397)
		(layer "In9.Cu")
		(net "PCIE_COMP_A_TO_IOM_A_11_DP")
	)
	(segment
		(start 244.16512 -34.131504)
		(end 245.303294 -35.81908)
		(width 0.1397)
		(layer "In9.Cu")
		(net "PCIE_COMP_A_TO_IOM_A_11_DP")
	)
	(segment
		(start 235.652564 -179.353718)
		(end 236.599984 -179.353718)
		(width 0.1397)
		(layer "In9.Cu")
		(net "PCIE_COMP_A_TO_IOM_A_11_DP")
	)
	(segment
		(start 244.12448 -86.301834)
		(end 243.679726 -86.908132)
		(width 0.1397)
		(layer "In9.Cu")
		(net "PCIE_COMP_A_TO_IOM_A_11_DP")
	)
	(segment
		(start 232.342944 -96.668336)
		(end 230.114602 -100.10013)
		(width 0.1397)
		(layer "In9.Cu")
		(net "PCIE_COMP_A_TO_IOM_A_11_DP")
	)
	(segment
		(start 138.995912 -18.390108)
		(end 138.995912 -31.854902)
		(width 0.1397)
		(layer "In9.Cu")
		(net "PCIE_COMP_A_TO_IOM_A_11_DP")
	)
	(segment
		(start 241.024918 -32.054038)
		(end 242.024916 -33.054036)
		(width 0.1397)
		(layer "In9.Cu")
		(net "PCIE_COMP_A_TO_IOM_A_11_DP")
	)
	(segment
		(start 223.57334 -161.249106)
		(end 232.793794 -175.446182)
		(width 0.1397)
		(layer "In9.Cu")
		(net "PCIE_COMP_A_TO_IOM_A_11_DP")
	)
	(segment
		(start 138.092434 -17.903952)
		(end 138.092688 -17.904206)
		(width 0.1397)
		(layer "In9.Cu")
		(net "PCIE_COMP_A_TO_IOM_A_11_DP")
	)
	(segment
		(start 235.877354 -31.05404)
		(end 236.525054 -31.05404)
		(width 0.1397)
		(layer "In9.Cu")
		(net "PCIE_COMP_A_TO_IOM_A_11_DP")
	)
	(segment
		(start 142.422372 -34.396934)
		(end 161.185606 -38.143942)
		(width 0.1397)
		(layer "In9.Cu")
		(net "PCIE_COMP_A_TO_IOM_A_11_DP")
	)
	(segment
		(start 249.714258 -58.520838)
		(end 244.385592 -85.945218)
		(width 0.1397)
		(layer "In9.Cu")
		(net "PCIE_COMP_A_TO_IOM_A_11_DP")
	)
	(segment
		(start 233.783124 -176.969166)
		(end 234.01147 -177.320702)
		(width 0.1397)
		(layer "In9.Cu")
		(net "PCIE_COMP_A_TO_IOM_A_11_DP")
	)
	(segment
		(start 234.01147 -177.320702)
		(end 234.20451 -177.36185)
		(width 0.1397)
		(layer "In9.Cu")
		(net "PCIE_COMP_A_TO_IOM_A_11_DP")
	)
	(segment
		(start 234.432856 -177.713132)
		(end 234.391708 -177.906426)
		(width 0.1397)
		(layer "In9.Cu")
		(net "PCIE_COMP_A_TO_IOM_A_11_DP")
	)
	(segment
		(start 138.995912 -31.854902)
		(end 139.270232 -32.271716)
		(width 0.1397)
		(layer "In9.Cu")
		(net "PCIE_COMP_A_TO_IOM_A_11_DP")
	)
	(segment
		(start 232.987088 -175.48733)
		(end 233.215434 -175.838612)
		(width 0.1397)
		(layer "In9.Cu")
		(net "PCIE_COMP_A_TO_IOM_A_11_DP")
	)
	(segment
		(start 244.385592 -85.945218)
		(end 244.235732 -86.149942)
		(width 0.1397)
		(layer "In9.Cu")
		(net "PCIE_COMP_A_TO_IOM_A_11_DP")
	)
	(segment
		(start 244.235732 -86.149942)
		(end 244.12448 -86.301834)
		(width 0.1397)
		(layer "In9.Cu")
		(net "PCIE_COMP_A_TO_IOM_A_11_DP")
	)
	(segment
		(start 233.215434 -175.838612)
		(end 233.174286 -176.031906)
		(width 0.1397)
		(layer "In9.Cu")
		(net "PCIE_COMP_A_TO_IOM_A_11_DP")
	)
	(segment
		(start 161.185606 -38.143942)
		(end 216.981532 -27.298142)
		(width 0.1397)
		(layer "In9.Cu")
		(net "PCIE_COMP_A_TO_IOM_A_11_DP")
	)
	(segment
		(start 242.533678 -88.472264)
		(end 232.342944 -96.668336)
		(width 0.1397)
		(layer "In9.Cu")
		(net "PCIE_COMP_A_TO_IOM_A_11_DP")
	)
	(segment
		(start 237.525052 -32.054038)
		(end 241.024918 -32.054038)
		(width 0.1397)
		(layer "In9.Cu")
		(net "PCIE_COMP_A_TO_IOM_A_11_DP")
	)
	(segment
		(start 234.20451 -177.36185)
		(end 234.432856 -177.713132)
		(width 0.1397)
		(layer "In9.Cu")
		(net "PCIE_COMP_A_TO_IOM_A_11_DP")
	)
	(segment
		(start 139.270232 -32.271716)
		(end 142.422372 -34.396934)
		(width 0.1397)
		(layer "In9.Cu")
		(net "PCIE_COMP_A_TO_IOM_A_11_DP")
	)
	(segment
		(start 138.806428 -18.026634)
		(end 138.873484 -18.093944)
		(width 0.1397)
		(layer "In9.Cu")
		(net "PCIE_COMP_A_TO_IOM_A_11_DP")
	)
	(segment
		(start 230.114602 -100.10013)
		(end 220.032834 -145.601944)
		(width 0.1397)
		(layer "In9.Cu")
		(net "PCIE_COMP_A_TO_IOM_A_11_DP")
	)
	(segment
		(start 233.174286 -176.031906)
		(end 233.402632 -176.383442)
		(width 0.1397)
		(layer "In9.Cu")
		(net "PCIE_COMP_A_TO_IOM_A_11_DP")
	)
	(segment
		(start 232.793794 -175.446182)
		(end 232.987088 -175.48733)
		(width 0.1397)
		(layer "In9.Cu")
		(net "PCIE_COMP_A_TO_IOM_A_11_DP")
	)
	(segment
		(start 233.402632 -176.383442)
		(end 233.595926 -176.42459)
		(width 0.1397)
		(layer "In9.Cu")
		(net "PCIE_COMP_A_TO_IOM_A_11_DP")
	)
	(segment
		(start 245.303294 -35.81908)
		(end 249.714258 -58.520838)
		(width 0.1397)
		(layer "In9.Cu")
		(net "PCIE_COMP_A_TO_IOM_A_11_DP")
	)
	(segment
		(start 243.087652 -33.054036)
		(end 244.16512 -34.131504)
		(width 0.1397)
		(layer "In9.Cu")
		(net "PCIE_COMP_A_TO_IOM_A_11_DP")
	)
	(segment
		(start 237.599982 -180.353716)
		(end 240.88598 -180.353716)
		(width 0.1397)
		(layer "In9.Cu")
		(net "PCIE_COMP_A_TO_IOM_A_11_DP")
	)
	(segment
		(start 216.981532 -27.298142)
		(end 235.877354 -31.05404)
		(width 0.1397)
		(layer "In9.Cu")
		(net "PCIE_COMP_A_TO_IOM_A_11_DP")
	)
	(segment
		(start 233.595926 -176.42459)
		(end 233.824272 -176.775872)
		(width 0.1397)
		(layer "In9.Cu")
		(net "PCIE_COMP_A_TO_IOM_A_11_DP")
	)
	(arc
		(start 138.51001 -17.904206)
		(mid 138.670363 -17.935991)
		(end 138.806428 -18.026634)
		(width 0.1397)
		(layer "In9.Cu")
		(net "PCIE_COMP_A_TO_IOM_A_11_DP")
	)
	(arc
		(start 241.356896 -180.059584)
		(mid 241.364477 -179.952917)
		(end 241.294412 -179.872132)
		(width 0.1397)
		(layer "In9.Cu")
		(net "PCIE_COMP_A_TO_IOM_A_11_DP")
	)
	(arc
		(start 137.94994 -17.761458)
		(mid 137.959573 -17.809976)
		(end 137.987024 -17.85112)
		(width 0.1397)
		(layer "In9.Cu")
		(net "PCIE_COMP_A_TO_IOM_A_11_DP")
	)
	(arc
		(start 138.873484 -18.093944)
		(mid 138.964087 -18.229869)
		(end 138.995912 -18.390108)
		(width 0.1397)
		(layer "In9.Cu")
		(net "PCIE_COMP_A_TO_IOM_A_11_DP")
	)
	(arc
		(start 240.88598 -180.353716)
		(mid 241.107016 -180.309749)
		(end 241.294412 -180.184552)
		(width 0.1397)
		(layer "In9.Cu")
		(net "PCIE_COMP_A_TO_IOM_A_11_DP")
	)
	(arc
		(start 138.002772 -17.866868)
		(mid 138.043923 -17.894301)
		(end 138.092434 -17.903952)
		(width 0.1397)
		(layer "In9.Cu")
		(net "PCIE_COMP_A_TO_IOM_A_11_DP")
	)
	(segment
		(start 243.444014 -86.735412)
		(end 242.320572 -88.268556)
		(width 0.1397)
		(layer "In9.Cu")
		(net "PCIE_COMP_A_TO_IOM_A_11_DN")
	)
	(segment
		(start 244.111272 -85.82533)
		(end 243.888768 -86.12886)
		(width 0.1397)
		(layer "In9.Cu")
		(net "PCIE_COMP_A_TO_IOM_A_11_DN")
	)
	(segment
		(start 161.184844 -38.441884)
		(end 216.981024 -27.596084)
		(width 0.1397)
		(layer "In9.Cu")
		(net "PCIE_COMP_A_TO_IOM_A_11_DN")
	)
	(segment
		(start 243.938552 -34.318194)
		(end 245.027704 -35.933126)
		(width 0.1397)
		(layer "In9.Cu")
		(net "PCIE_COMP_A_TO_IOM_A_11_DN")
	)
	(segment
		(start 138.703812 -31.942532)
		(end 138.888978 -32.223964)
		(width 0.1397)
		(layer "In9.Cu")
		(net "PCIE_COMP_A_TO_IOM_A_11_DN")
	)
	(segment
		(start 240.90376 -32.346138)
		(end 241.903758 -33.346136)
		(width 0.1397)
		(layer "In9.Cu")
		(net "PCIE_COMP_A_TO_IOM_A_11_DN")
	)
	(segment
		(start 237.478824 -180.645816)
		(end 240.885726 -180.645816)
		(width 0.1397)
		(layer "In9.Cu")
		(net "PCIE_COMP_A_TO_IOM_A_11_DN")
	)
	(segment
		(start 229.84079 -99.985322)
		(end 219.733368 -145.602706)
		(width 0.1397)
		(layer "In9.Cu")
		(net "PCIE_COMP_A_TO_IOM_A_11_DN")
	)
	(segment
		(start 137.94994 -18.750026)
		(end 137.94994 -18.3388)
		(width 0.1397)
		(layer "In9.Cu")
		(net "PCIE_COMP_A_TO_IOM_A_11_DN")
	)
	(segment
		(start 249.41657 -58.520838)
		(end 244.111272 -85.82533)
		(width 0.1397)
		(layer "In9.Cu")
		(net "PCIE_COMP_A_TO_IOM_A_11_DN")
	)
	(segment
		(start 242.966494 -33.346136)
		(end 243.938552 -34.318194)
		(width 0.1397)
		(layer "In9.Cu")
		(net "PCIE_COMP_A_TO_IOM_A_11_DN")
	)
	(segment
		(start 138.703812 -18.390108)
		(end 138.703812 -31.942532)
		(width 0.1397)
		(layer "In9.Cu")
		(net "PCIE_COMP_A_TO_IOM_A_11_DN")
	)
	(segment
		(start 138.889232 -32.224218)
		(end 139.058396 -32.481266)
		(width 0.1397)
		(layer "In9.Cu")
		(net "PCIE_COMP_A_TO_IOM_A_11_DN")
	)
	(segment
		(start 241.903758 -33.346136)
		(end 242.966494 -33.346136)
		(width 0.1397)
		(layer "In9.Cu")
		(net "PCIE_COMP_A_TO_IOM_A_11_DN")
	)
	(segment
		(start 241.805714 -180.127656)
		(end 242.549934 -180.499766)
		(width 0.1397)
		(layer "In9.Cu")
		(net "PCIE_COMP_A_TO_IOM_A_11_DN")
	)
	(segment
		(start 142.307564 -34.672016)
		(end 161.184844 -38.441884)
		(width 0.1397)
		(layer "In9.Cu")
		(net "PCIE_COMP_A_TO_IOM_A_11_DN")
	)
	(segment
		(start 139.058396 -32.481266)
		(end 142.307564 -34.672016)
		(width 0.1397)
		(layer "In9.Cu")
		(net "PCIE_COMP_A_TO_IOM_A_11_DN")
	)
	(segment
		(start 235.552996 -179.645818)
		(end 236.478826 -179.645818)
		(width 0.1397)
		(layer "In9.Cu")
		(net "PCIE_COMP_A_TO_IOM_A_11_DN")
	)
	(segment
		(start 137.987024 -18.249138)
		(end 138.002772 -18.23339)
		(width 0.1397)
		(layer "In9.Cu")
		(net "PCIE_COMP_A_TO_IOM_A_11_DN")
	)
	(segment
		(start 243.888768 -86.12886)
		(end 243.444014 -86.735412)
		(width 0.1397)
		(layer "In9.Cu")
		(net "PCIE_COMP_A_TO_IOM_A_11_DN")
	)
	(segment
		(start 234.992672 -179.214018)
		(end 235.552996 -179.645818)
		(width 0.1397)
		(layer "In9.Cu")
		(net "PCIE_COMP_A_TO_IOM_A_11_DN")
	)
	(segment
		(start 223.299782 -161.364676)
		(end 234.792266 -179.059586)
		(width 0.1397)
		(layer "In9.Cu")
		(net "PCIE_COMP_A_TO_IOM_A_11_DN")
	)
	(segment
		(start 236.403896 -31.34614)
		(end 237.403894 -32.346138)
		(width 0.1397)
		(layer "In9.Cu")
		(net "PCIE_COMP_A_TO_IOM_A_11_DN")
	)
	(segment
		(start 245.027704 -35.933126)
		(end 249.41657 -58.520838)
		(width 0.1397)
		(layer "In9.Cu")
		(net "PCIE_COMP_A_TO_IOM_A_11_DN")
	)
	(segment
		(start 219.733368 -145.602706)
		(end 223.299782 -161.364676)
		(width 0.1397)
		(layer "In9.Cu")
		(net "PCIE_COMP_A_TO_IOM_A_11_DN")
	)
	(segment
		(start 236.478826 -179.645818)
		(end 237.478824 -180.645816)
		(width 0.1397)
		(layer "In9.Cu")
		(net "PCIE_COMP_A_TO_IOM_A_11_DN")
	)
	(segment
		(start 216.981024 -27.596084)
		(end 235.848398 -31.34614)
		(width 0.1397)
		(layer "In9.Cu")
		(net "PCIE_COMP_A_TO_IOM_A_11_DN")
	)
	(segment
		(start 138.599672 -18.23339)
		(end 138.666728 -18.300446)
		(width 0.1397)
		(layer "In9.Cu")
		(net "PCIE_COMP_A_TO_IOM_A_11_DN")
	)
	(segment
		(start 242.320572 -88.268556)
		(end 232.123234 -96.469962)
		(width 0.1397)
		(layer "In9.Cu")
		(net "PCIE_COMP_A_TO_IOM_A_11_DN")
	)
	(segment
		(start 232.123234 -96.469962)
		(end 229.84079 -99.985322)
		(width 0.1397)
		(layer "In9.Cu")
		(net "PCIE_COMP_A_TO_IOM_A_11_DN")
	)
	(segment
		(start 237.403894 -32.346138)
		(end 240.90376 -32.346138)
		(width 0.1397)
		(layer "In9.Cu")
		(net "PCIE_COMP_A_TO_IOM_A_11_DN")
	)
	(segment
		(start 138.092434 -18.196306)
		(end 138.51001 -18.196306)
		(width 0.1397)
		(layer "In9.Cu")
		(net "PCIE_COMP_A_TO_IOM_A_11_DN")
	)
	(segment
		(start 241.536728 -180.353208)
		(end 241.618262 -180.19014)
		(width 0.1397)
		(layer "In9.Cu")
		(net "PCIE_COMP_A_TO_IOM_A_11_DN")
	)
	(segment
		(start 234.792266 -179.059586)
		(end 234.992672 -179.214018)
		(width 0.1397)
		(layer "In9.Cu")
		(net "PCIE_COMP_A_TO_IOM_A_11_DN")
	)
	(segment
		(start 235.848398 -31.34614)
		(end 236.403896 -31.34614)
		(width 0.1397)
		(layer "In9.Cu")
		(net "PCIE_COMP_A_TO_IOM_A_11_DN")
	)
	(segment
		(start 138.888978 -32.223964)
		(end 138.889232 -32.224218)
		(width 0.1397)
		(layer "In9.Cu")
		(net "PCIE_COMP_A_TO_IOM_A_11_DN")
	)
	(arc
		(start 241.618262 -180.19014)
		(mid 241.699047 -180.120075)
		(end 241.805714 -180.127656)
		(width 0.1397)
		(layer "In9.Cu")
		(net "PCIE_COMP_A_TO_IOM_A_11_DN")
	)
	(arc
		(start 240.885726 -180.645816)
		(mid 241.242602 -180.569336)
		(end 241.536728 -180.353208)
		(width 0.1397)
		(layer "In9.Cu")
		(net "PCIE_COMP_A_TO_IOM_A_11_DN")
	)
	(arc
		(start 138.666728 -18.300446)
		(mid 138.694161 -18.341597)
		(end 138.703812 -18.390108)
		(width 0.1397)
		(layer "In9.Cu")
		(net "PCIE_COMP_A_TO_IOM_A_11_DN")
	)
	(arc
		(start 137.94994 -18.3388)
		(mid 137.959573 -18.290282)
		(end 137.987024 -18.249138)
		(width 0.1397)
		(layer "In9.Cu")
		(net "PCIE_COMP_A_TO_IOM_A_11_DN")
	)
	(arc
		(start 138.51001 -18.196306)
		(mid 138.558528 -18.205939)
		(end 138.599672 -18.23339)
		(width 0.1397)
		(layer "In9.Cu")
		(net "PCIE_COMP_A_TO_IOM_A_11_DN")
	)
	(arc
		(start 138.002772 -18.23339)
		(mid 138.043923 -18.205957)
		(end 138.092434 -18.196306)
		(width 0.1397)
		(layer "In9.Cu")
		(net "PCIE_COMP_A_TO_IOM_A_11_DN")
	)
	(segment
		(start 140.606526 -19.026632)
		(end 140.673582 -19.093942)
		(width 0.1397)
		(layer "In9.Cu")
		(net "PCIE_COMP_A_TO_IOM_A_10_DP")
	)
	(segment
		(start 251.07138 -57.311798)
		(end 245.349268 -86.750144)
		(width 0.1397)
		(layer "In9.Cu")
		(net "PCIE_COMP_A_TO_IOM_A_10_DP")
	)
	(segment
		(start 223.16186 -152.323546)
		(end 223.162114 -152.323546)
		(width 0.1397)
		(layer "In9.Cu")
		(net "PCIE_COMP_A_TO_IOM_A_10_DP")
	)
	(segment
		(start 223.162114 -152.323546)
		(end 224.733612 -159.268668)
		(width 0.1397)
		(layer "In9.Cu")
		(net "PCIE_COMP_A_TO_IOM_A_10_DP")
	)
	(segment
		(start 246.901462 -35.848544)
		(end 251.070872 -57.311798)
		(width 0.1397)
		(layer "In9.Cu")
		(net "PCIE_COMP_A_TO_IOM_A_10_DP")
	)
	(segment
		(start 232.83926 -171.749974)
		(end 233.0323 -171.791122)
		(width 0.1397)
		(layer "In9.Cu")
		(net "PCIE_COMP_A_TO_IOM_A_10_DP")
	)
	(segment
		(start 221.589854 -145.377154)
		(end 223.16186 -152.323546)
		(width 0.1397)
		(layer "In9.Cu")
		(net "PCIE_COMP_A_TO_IOM_A_10_DP")
	)
	(segment
		(start 241.294412 -176.18456)
		(end 241.356896 -176.059592)
		(width 0.1397)
		(layer "In9.Cu")
		(net "PCIE_COMP_A_TO_IOM_A_10_DP")
	)
	(segment
		(start 233.86923 -173.079664)
		(end 233.828336 -173.272958)
		(width 0.1397)
		(layer "In9.Cu")
		(net "PCIE_COMP_A_TO_IOM_A_10_DP")
	)
	(segment
		(start 235.608622 -175.353726)
		(end 236.599984 -175.353726)
		(width 0.1397)
		(layer "In9.Cu")
		(net "PCIE_COMP_A_TO_IOM_A_10_DP")
	)
	(segment
		(start 139.892786 -18.904204)
		(end 140.310108 -18.904204)
		(width 0.1397)
		(layer "In9.Cu")
		(net "PCIE_COMP_A_TO_IOM_A_10_DP")
	)
	(segment
		(start 233.828336 -173.272958)
		(end 234.056428 -173.624494)
		(width 0.1397)
		(layer "In9.Cu")
		(net "PCIE_COMP_A_TO_IOM_A_10_DP")
	)
	(segment
		(start 139.787122 -18.851118)
		(end 139.80287 -18.866866)
		(width 0.1397)
		(layer "In9.Cu")
		(net "PCIE_COMP_A_TO_IOM_A_10_DP")
	)
	(segment
		(start 236.525054 -29.054044)
		(end 237.525052 -30.054042)
		(width 0.1397)
		(layer "In9.Cu")
		(net "PCIE_COMP_A_TO_IOM_A_10_DP")
	)
	(segment
		(start 235.873544 -29.054044)
		(end 236.525054 -29.054044)
		(width 0.1397)
		(layer "In9.Cu")
		(net "PCIE_COMP_A_TO_IOM_A_10_DP")
	)
	(segment
		(start 234.43692 -174.210218)
		(end 234.749848 -174.692056)
		(width 0.1397)
		(layer "In9.Cu")
		(net "PCIE_COMP_A_TO_IOM_A_10_DP")
	)
	(segment
		(start 241.024918 -30.054042)
		(end 242.024916 -31.05404)
		(width 0.1397)
		(layer "In9.Cu")
		(net "PCIE_COMP_A_TO_IOM_A_10_DP")
	)
	(segment
		(start 139.892532 -18.90395)
		(end 139.892786 -18.904204)
		(width 0.1397)
		(layer "In9.Cu")
		(net "PCIE_COMP_A_TO_IOM_A_10_DP")
	)
	(segment
		(start 142.727934 -33.182052)
		(end 160.572196 -36.747958)
		(width 0.1397)
		(layer "In9.Cu")
		(net "PCIE_COMP_A_TO_IOM_A_10_DP")
	)
	(segment
		(start 233.447844 -172.687234)
		(end 233.641138 -172.728128)
		(width 0.1397)
		(layer "In9.Cu")
		(net "PCIE_COMP_A_TO_IOM_A_10_DP")
	)
	(segment
		(start 243.112798 -31.05404)
		(end 244.889274 -32.830516)
		(width 0.1397)
		(layer "In9.Cu")
		(net "PCIE_COMP_A_TO_IOM_A_10_DP")
	)
	(segment
		(start 236.599984 -175.353726)
		(end 237.599982 -176.353724)
		(width 0.1397)
		(layer "In9.Cu")
		(net "PCIE_COMP_A_TO_IOM_A_10_DP")
	)
	(segment
		(start 142.72768 -33.181798)
		(end 142.727934 -33.182052)
		(width 0.1397)
		(layer "In9.Cu")
		(net "PCIE_COMP_A_TO_IOM_A_10_DP")
	)
	(segment
		(start 251.070872 -57.311798)
		(end 251.07138 -57.311798)
		(width 0.1397)
		(layer "In9.Cu")
		(net "PCIE_COMP_A_TO_IOM_A_10_DP")
	)
	(segment
		(start 234.749848 -174.692056)
		(end 235.608622 -175.353726)
		(width 0.1397)
		(layer "In9.Cu")
		(net "PCIE_COMP_A_TO_IOM_A_10_DP")
	)
	(segment
		(start 242.024916 -31.05404)
		(end 243.112798 -31.05404)
		(width 0.1397)
		(layer "In9.Cu")
		(net "PCIE_COMP_A_TO_IOM_A_10_DP")
	)
	(segment
		(start 244.889274 -32.830516)
		(end 246.901462 -35.848544)
		(width 0.1397)
		(layer "In9.Cu")
		(net "PCIE_COMP_A_TO_IOM_A_10_DP")
	)
	(segment
		(start 233.0323 -171.791122)
		(end 233.260646 -172.142404)
		(width 0.1397)
		(layer "In9.Cu")
		(net "PCIE_COMP_A_TO_IOM_A_10_DP")
	)
	(segment
		(start 237.525052 -30.054042)
		(end 241.024918 -30.054042)
		(width 0.1397)
		(layer "In9.Cu")
		(net "PCIE_COMP_A_TO_IOM_A_10_DP")
	)
	(segment
		(start 139.750038 -18.35023)
		(end 139.750038 -18.761456)
		(width 0.1397)
		(layer "In9.Cu")
		(net "PCIE_COMP_A_TO_IOM_A_10_DP")
	)
	(segment
		(start 237.599982 -176.353724)
		(end 240.88598 -176.353724)
		(width 0.1397)
		(layer "In9.Cu")
		(net "PCIE_COMP_A_TO_IOM_A_10_DP")
	)
	(segment
		(start 234.249722 -173.665388)
		(end 234.478068 -174.016924)
		(width 0.1397)
		(layer "In9.Cu")
		(net "PCIE_COMP_A_TO_IOM_A_10_DP")
	)
	(segment
		(start 224.733612 -159.268668)
		(end 232.83926 -171.749974)
		(width 0.1397)
		(layer "In9.Cu")
		(net "PCIE_COMP_A_TO_IOM_A_10_DP")
	)
	(segment
		(start 241.294412 -175.87214)
		(end 240.549938 -175.499776)
		(width 0.1397)
		(layer "In9.Cu")
		(net "PCIE_COMP_A_TO_IOM_A_10_DP")
	)
	(segment
		(start 233.260646 -172.142404)
		(end 233.219498 -172.335698)
		(width 0.1397)
		(layer "In9.Cu")
		(net "PCIE_COMP_A_TO_IOM_A_10_DP")
	)
	(segment
		(start 245.349268 -86.750144)
		(end 245.31574 -86.799674)
		(width 0.1397)
		(layer "In9.Cu")
		(net "PCIE_COMP_A_TO_IOM_A_10_DP")
	)
	(segment
		(start 231.49433 -100.677726)
		(end 221.589854 -145.377154)
		(width 0.1397)
		(layer "In9.Cu")
		(net "PCIE_COMP_A_TO_IOM_A_10_DP")
	)
	(segment
		(start 233.709718 -97.265236)
		(end 231.49433 -100.677726)
		(width 0.1397)
		(layer "In9.Cu")
		(net "PCIE_COMP_A_TO_IOM_A_10_DP")
	)
	(segment
		(start 234.056428 -173.624494)
		(end 234.249722 -173.665388)
		(width 0.1397)
		(layer "In9.Cu")
		(net "PCIE_COMP_A_TO_IOM_A_10_DP")
	)
	(segment
		(start 140.79601 -19.390106)
		(end 140.79601 -31.584392)
		(width 0.1397)
		(layer "In9.Cu")
		(net "PCIE_COMP_A_TO_IOM_A_10_DP")
	)
	(segment
		(start 243.633244 -89.285064)
		(end 233.709718 -97.265236)
		(width 0.1397)
		(layer "In9.Cu")
		(net "PCIE_COMP_A_TO_IOM_A_10_DP")
	)
	(segment
		(start 218.290902 -25.53716)
		(end 235.873544 -29.054044)
		(width 0.1397)
		(layer "In9.Cu")
		(net "PCIE_COMP_A_TO_IOM_A_10_DP")
	)
	(segment
		(start 245.31574 -86.799674)
		(end 243.633244 -89.285064)
		(width 0.1397)
		(layer "In9.Cu")
		(net "PCIE_COMP_A_TO_IOM_A_10_DP")
	)
	(segment
		(start 234.478068 -174.016924)
		(end 234.43692 -174.210218)
		(width 0.1397)
		(layer "In9.Cu")
		(net "PCIE_COMP_A_TO_IOM_A_10_DP")
	)
	(segment
		(start 141.145768 -32.114744)
		(end 142.72768 -33.181798)
		(width 0.1397)
		(layer "In9.Cu")
		(net "PCIE_COMP_A_TO_IOM_A_10_DP")
	)
	(segment
		(start 233.219498 -172.335698)
		(end 233.447844 -172.687234)
		(width 0.1397)
		(layer "In9.Cu")
		(net "PCIE_COMP_A_TO_IOM_A_10_DP")
	)
	(segment
		(start 140.79601 -31.584392)
		(end 141.145768 -32.114744)
		(width 0.1397)
		(layer "In9.Cu")
		(net "PCIE_COMP_A_TO_IOM_A_10_DP")
	)
	(segment
		(start 233.641138 -172.728128)
		(end 233.86923 -173.079664)
		(width 0.1397)
		(layer "In9.Cu")
		(net "PCIE_COMP_A_TO_IOM_A_10_DP")
	)
	(segment
		(start 160.572196 -36.747958)
		(end 218.290902 -25.53716)
		(width 0.1397)
		(layer "In9.Cu")
		(net "PCIE_COMP_A_TO_IOM_A_10_DP")
	)
	(arc
		(start 139.80287 -18.866866)
		(mid 139.844021 -18.894299)
		(end 139.892532 -18.90395)
		(width 0.1397)
		(layer "In9.Cu")
		(net "PCIE_COMP_A_TO_IOM_A_10_DP")
	)
	(arc
		(start 140.673582 -19.093942)
		(mid 140.764185 -19.229867)
		(end 140.79601 -19.390106)
		(width 0.1397)
		(layer "In9.Cu")
		(net "PCIE_COMP_A_TO_IOM_A_10_DP")
	)
	(arc
		(start 240.88598 -176.353724)
		(mid 241.107016 -176.309757)
		(end 241.294412 -176.18456)
		(width 0.1397)
		(layer "In9.Cu")
		(net "PCIE_COMP_A_TO_IOM_A_10_DP")
	)
	(arc
		(start 140.310108 -18.904204)
		(mid 140.470461 -18.935989)
		(end 140.606526 -19.026632)
		(width 0.1397)
		(layer "In9.Cu")
		(net "PCIE_COMP_A_TO_IOM_A_10_DP")
	)
	(arc
		(start 241.356896 -176.059592)
		(mid 241.364477 -175.952925)
		(end 241.294412 -175.87214)
		(width 0.1397)
		(layer "In9.Cu")
		(net "PCIE_COMP_A_TO_IOM_A_10_DP")
	)
	(arc
		(start 139.750038 -18.761456)
		(mid 139.759671 -18.809974)
		(end 139.787122 -18.851118)
		(width 0.1397)
		(layer "In9.Cu")
		(net "PCIE_COMP_A_TO_IOM_A_10_DP")
	)
	(segment
		(start 240.90376 -30.346142)
		(end 241.903758 -31.34614)
		(width 0.1397)
		(layer "In9.Cu")
		(net "PCIE_COMP_A_TO_IOM_A_10_DN")
	)
	(segment
		(start 218.29014 -25.835102)
		(end 235.844588 -29.346144)
		(width 0.1397)
		(layer "In9.Cu")
		(net "PCIE_COMP_A_TO_IOM_A_10_DN")
	)
	(segment
		(start 224.460054 -159.384238)
		(end 234.531916 -174.893224)
		(width 0.1397)
		(layer "In9.Cu")
		(net "PCIE_COMP_A_TO_IOM_A_10_DN")
	)
	(segment
		(start 140.933932 -32.324294)
		(end 141.773148 -32.89046)
		(width 0.1397)
		(layer "In9.Cu")
		(net "PCIE_COMP_A_TO_IOM_A_10_DN")
	)
	(segment
		(start 142.613126 -33.457134)
		(end 160.571434 -37.0459)
		(width 0.1397)
		(layer "In9.Cu")
		(net "PCIE_COMP_A_TO_IOM_A_10_DN")
	)
	(segment
		(start 241.536728 -176.353216)
		(end 241.618262 -176.190148)
		(width 0.1397)
		(layer "In9.Cu")
		(net "PCIE_COMP_A_TO_IOM_A_10_DN")
	)
	(segment
		(start 139.787122 -19.249136)
		(end 139.80287 -19.233388)
		(width 0.1397)
		(layer "In9.Cu")
		(net "PCIE_COMP_A_TO_IOM_A_10_DN")
	)
	(segment
		(start 242.99164 -31.34614)
		(end 244.662198 -33.016698)
		(width 0.1397)
		(layer "In9.Cu")
		(net "PCIE_COMP_A_TO_IOM_A_10_DN")
	)
	(segment
		(start 244.662198 -33.016698)
		(end 246.625872 -35.961828)
		(width 0.1397)
		(layer "In9.Cu")
		(net "PCIE_COMP_A_TO_IOM_A_10_DN")
	)
	(segment
		(start 246.625872 -35.961828)
		(end 250.773184 -57.311798)
		(width 0.1397)
		(layer "In9.Cu")
		(net "PCIE_COMP_A_TO_IOM_A_10_DN")
	)
	(segment
		(start 140.50391 -31.672276)
		(end 140.933932 -32.324294)
		(width 0.1397)
		(layer "In9.Cu")
		(net "PCIE_COMP_A_TO_IOM_A_10_DN")
	)
	(segment
		(start 234.531916 -174.893224)
		(end 235.509054 -175.645826)
		(width 0.1397)
		(layer "In9.Cu")
		(net "PCIE_COMP_A_TO_IOM_A_10_DN")
	)
	(segment
		(start 221.290388 -145.377916)
		(end 224.460054 -159.384238)
		(width 0.1397)
		(layer "In9.Cu")
		(net "PCIE_COMP_A_TO_IOM_A_10_DN")
	)
	(segment
		(start 235.509054 -175.645826)
		(end 236.478826 -175.645826)
		(width 0.1397)
		(layer "In9.Cu")
		(net "PCIE_COMP_A_TO_IOM_A_10_DN")
	)
	(segment
		(start 236.403896 -29.346144)
		(end 237.403894 -30.346142)
		(width 0.1397)
		(layer "In9.Cu")
		(net "PCIE_COMP_A_TO_IOM_A_10_DN")
	)
	(segment
		(start 237.403894 -30.346142)
		(end 240.90376 -30.346142)
		(width 0.1397)
		(layer "In9.Cu")
		(net "PCIE_COMP_A_TO_IOM_A_10_DN")
	)
	(segment
		(start 241.805714 -176.127664)
		(end 242.549934 -176.499774)
		(width 0.1397)
		(layer "In9.Cu")
		(net "PCIE_COMP_A_TO_IOM_A_10_DN")
	)
	(segment
		(start 245.073678 -86.635844)
		(end 243.41582 -89.084658)
		(width 0.1397)
		(layer "In9.Cu")
		(net "PCIE_COMP_A_TO_IOM_A_10_DN")
	)
	(segment
		(start 160.571434 -37.0459)
		(end 218.29014 -25.835102)
		(width 0.1397)
		(layer "In9.Cu")
		(net "PCIE_COMP_A_TO_IOM_A_10_DN")
	)
	(segment
		(start 243.41582 -89.084658)
		(end 233.490008 -97.066862)
		(width 0.1397)
		(layer "In9.Cu")
		(net "PCIE_COMP_A_TO_IOM_A_10_DN")
	)
	(segment
		(start 140.50391 -19.390106)
		(end 140.50391 -31.672276)
		(width 0.1397)
		(layer "In9.Cu")
		(net "PCIE_COMP_A_TO_IOM_A_10_DN")
	)
	(segment
		(start 236.478826 -175.645826)
		(end 237.478824 -176.645824)
		(width 0.1397)
		(layer "In9.Cu")
		(net "PCIE_COMP_A_TO_IOM_A_10_DN")
	)
	(segment
		(start 241.903758 -31.34614)
		(end 242.99164 -31.34614)
		(width 0.1397)
		(layer "In9.Cu")
		(net "PCIE_COMP_A_TO_IOM_A_10_DN")
	)
	(segment
		(start 140.39977 -19.233388)
		(end 140.466826 -19.300444)
		(width 0.1397)
		(layer "In9.Cu")
		(net "PCIE_COMP_A_TO_IOM_A_10_DN")
	)
	(segment
		(start 245.073678 -86.63559)
		(end 245.073678 -86.635844)
		(width 0.1397)
		(layer "In9.Cu")
		(net "PCIE_COMP_A_TO_IOM_A_10_DN")
	)
	(segment
		(start 231.220518 -100.562918)
		(end 221.290388 -145.377916)
		(width 0.1397)
		(layer "In9.Cu")
		(net "PCIE_COMP_A_TO_IOM_A_10_DN")
	)
	(segment
		(start 141.773148 -32.89046)
		(end 142.613126 -33.457134)
		(width 0.1397)
		(layer "In9.Cu")
		(net "PCIE_COMP_A_TO_IOM_A_10_DN")
	)
	(segment
		(start 235.844588 -29.346144)
		(end 236.403896 -29.346144)
		(width 0.1397)
		(layer "In9.Cu")
		(net "PCIE_COMP_A_TO_IOM_A_10_DN")
	)
	(segment
		(start 250.773184 -57.311798)
		(end 250.773692 -57.311798)
		(width 0.1397)
		(layer "In9.Cu")
		(net "PCIE_COMP_A_TO_IOM_A_10_DN")
	)
	(segment
		(start 139.892532 -19.196304)
		(end 140.310108 -19.196304)
		(width 0.1397)
		(layer "In9.Cu")
		(net "PCIE_COMP_A_TO_IOM_A_10_DN")
	)
	(segment
		(start 139.750038 -19.750024)
		(end 139.750038 -19.338798)
		(width 0.1397)
		(layer "In9.Cu")
		(net "PCIE_COMP_A_TO_IOM_A_10_DN")
	)
	(segment
		(start 250.773692 -57.311798)
		(end 245.073678 -86.63559)
		(width 0.1397)
		(layer "In9.Cu")
		(net "PCIE_COMP_A_TO_IOM_A_10_DN")
	)
	(segment
		(start 233.490008 -97.066862)
		(end 231.220518 -100.562918)
		(width 0.1397)
		(layer "In9.Cu")
		(net "PCIE_COMP_A_TO_IOM_A_10_DN")
	)
	(segment
		(start 237.478824 -176.645824)
		(end 240.885726 -176.645824)
		(width 0.1397)
		(layer "In9.Cu")
		(net "PCIE_COMP_A_TO_IOM_A_10_DN")
	)
	(arc
		(start 140.466826 -19.300444)
		(mid 140.494259 -19.341595)
		(end 140.50391 -19.390106)
		(width 0.1397)
		(layer "In9.Cu")
		(net "PCIE_COMP_A_TO_IOM_A_10_DN")
	)
	(arc
		(start 139.80287 -19.233388)
		(mid 139.844021 -19.205955)
		(end 139.892532 -19.196304)
		(width 0.1397)
		(layer "In9.Cu")
		(net "PCIE_COMP_A_TO_IOM_A_10_DN")
	)
	(arc
		(start 139.750038 -19.338798)
		(mid 139.759671 -19.29028)
		(end 139.787122 -19.249136)
		(width 0.1397)
		(layer "In9.Cu")
		(net "PCIE_COMP_A_TO_IOM_A_10_DN")
	)
	(arc
		(start 140.310108 -19.196304)
		(mid 140.358626 -19.205937)
		(end 140.39977 -19.233388)
		(width 0.1397)
		(layer "In9.Cu")
		(net "PCIE_COMP_A_TO_IOM_A_10_DN")
	)
	(arc
		(start 241.618262 -176.190148)
		(mid 241.699047 -176.120083)
		(end 241.805714 -176.127664)
		(width 0.1397)
		(layer "In9.Cu")
		(net "PCIE_COMP_A_TO_IOM_A_10_DN")
	)
	(arc
		(start 240.885726 -176.645824)
		(mid 241.242602 -176.569344)
		(end 241.536728 -176.353216)
		(width 0.1397)
		(layer "In9.Cu")
		(net "PCIE_COMP_A_TO_IOM_A_10_DN")
	)
	(segment
		(start 255.519174 -14.961108)
		(end 256.704592 -14.961108)
		(width 0.17145)
		(layer "F.Cu")
		(net "PCIE_COMP_A_RST_5")
	)
	(segment
		(start 256.704592 -14.961108)
		(end 256.7051 -14.9606)
		(width 0.17145)
		(layer "F.Cu")
		(net "PCIE_COMP_A_RST_5")
	)
	(segment
		(start 240.549938 -16.396462)
		(end 241.985292 -14.961108)
		(width 0.17145)
		(layer "F.Cu")
		(net "PCIE_COMP_A_RST_5")
	)
	(segment
		(start 241.985292 -14.961108)
		(end 255.519174 -14.961108)
		(width 0.17145)
		(layer "F.Cu")
		(net "PCIE_COMP_A_RST_5")
	)
	(segment
		(start 240.549938 -17.200118)
		(end 240.549938 -16.396462)
		(width 0.17145)
		(layer "F.Cu")
		(net "PCIE_COMP_A_RST_5")
	)
	(via
		(at 255.519174 -14.961108)
		(size 0.6604)
		(drill 0.3302)
		(layers "F.Cu" "B.Cu")
		(net "PCIE_COMP_A_RST_5")
	)
	(segment
		(start 240.549938 -139.499848)
		(end 239.689386 -140.3604)
		(width 0.17145)
		(layer "F.Cu")
		(net "PCIE_COMP_A_PCIE_RST_1")
	)
	(segment
		(start 236.405166 -141.357096)
		(end 235.694982 -141.357096)
		(width 0.17145)
		(layer "F.Cu")
		(net "PCIE_COMP_A_PCIE_RST_1")
	)
	(segment
		(start 235.694982 -141.357096)
		(end 232.108756 -137.77087)
		(width 0.17145)
		(layer "F.Cu")
		(net "PCIE_COMP_A_PCIE_RST_1")
	)
	(segment
		(start 239.689386 -140.3604)
		(end 237.401862 -140.3604)
		(width 0.17145)
		(layer "F.Cu")
		(net "PCIE_COMP_A_PCIE_RST_1")
	)
	(segment
		(start 237.401862 -140.3604)
		(end 236.405166 -141.357096)
		(width 0.17145)
		(layer "F.Cu")
		(net "PCIE_COMP_A_PCIE_RST_1")
	)
	(segment
		(start 223.365822 -137.77087)
		(end 224.5106 -137.77087)
		(width 0.17145)
		(layer "F.Cu")
		(net "PCIE_COMP_A_PCIE_RST_1")
	)
	(segment
		(start 232.108756 -137.77087)
		(end 224.5106 -137.77087)
		(width 0.17145)
		(layer "F.Cu")
		(net "PCIE_COMP_A_PCIE_RST_1")
	)
	(via
		(at 224.5106 -137.77087)
		(size 0.6604)
		(drill 0.3302)
		(layers "F.Cu" "B.Cu")
		(net "PCIE_COMP_A_PCIE_RST_1")
	)
	(segment
		(start 31.900876 -245.38305)
		(end 32.068516 -245.55069)
		(width 0.508)
		(layer "F.Cu")
		(net "P5V_SNB")
	)
	(segment
		(start 32.068516 -245.55069)
		(end 33.417002 -245.55069)
		(width 0.508)
		(layer "F.Cu")
		(net "P5V_SNB")
	)
	(segment
		(start 33.417002 -245.55069)
		(end 35.173412 -245.55069)
		(width 0.508)
		(layer "F.Cu")
		(net "P5V_SNB")
	)
	(via
		(at 33.417002 -245.55069)
		(size 0.6604)
		(drill 0.3302)
		(layers "F.Cu" "B.Cu")
		(net "P5V_SNB")
	)
	(via
		(at 19.9898 -289.433)
		(size 0.6604)
		(drill 0.3302)
		(layers "F.Cu" "B.Cu")
		(net "P5V_HDD0")
	)
	(segment
		(start 475.53626 -237.938564)
		(end 479.611436 -237.938564)
		(width 0.254)
		(layer "F.Cu")
		(net "P5V_D_VREG")
	)
	(segment
		(start 479.611436 -237.938564)
		(end 483.616 -233.934)
		(width 0.254)
		(layer "F.Cu")
		(net "P5V_D_VREG")
	)
	(via
		(at 483.616 -233.934)
		(size 0.5588)
		(drill 0.3048)
		(layers "F.Cu" "B.Cu")
		(net "P5V_D_VREG")
	)
	(via
		(at 475.494096 -236.859572)
		(size 0.6096)
		(drill 0.3048)
		(layers "F.Cu" "B.Cu")
		(net "P5V_D_VREG")
	)
	(via
		(at 475.53626 -237.938564)
		(size 0.5588)
		(drill 0.3048)
		(layers "F.Cu" "B.Cu")
		(net "P5V_D_VREG")
	)
	(segment
		(start 475.04223 -236.407706)
		(end 475.494096 -236.859572)
		(width 0.254)
		(layer "B.Cu")
		(net "P5V_D_VREG")
	)
	(segment
		(start 475.916244 -237.281974)
		(end 476.572834 -237.938564)
		(width 0.254)
		(layer "B.Cu")
		(net "P5V_D_VREG")
	)
	(segment
		(start 482.6635 -233.934)
		(end 483.616 -233.934)
		(width 0.254)
		(layer "B.Cu")
		(net "P5V_D_VREG")
	)
	(segment
		(start 475.494096 -236.859572)
		(end 475.916244 -237.28172)
		(width 0.254)
		(layer "B.Cu")
		(net "P5V_D_VREG")
	)
	(segment
		(start 475.916244 -237.28172)
		(end 475.916244 -237.281974)
		(width 0.254)
		(layer "B.Cu")
		(net "P5V_D_VREG")
	)
	(segment
		(start 475.04223 -235.128308)
		(end 475.04223 -236.407706)
		(width 0.254)
		(layer "B.Cu")
		(net "P5V_D_VREG")
	)
	(segment
		(start 476.572834 -237.938564)
		(end 475.53626 -237.938564)
		(width 0.254)
		(layer "B.Cu")
		(net "P5V_D_VREG")
	)
	(via
		(at 481.966778 -230.0605)
		(size 0.6096)
		(drill 0.3048)
		(layers "F.Cu" "B.Cu")
		(net "P5V_D_VFB_R")
	)
	(segment
		(start 481.966778 -230.0605)
		(end 480.949 -230.0605)
		(width 0.254)
		(layer "B.Cu")
		(net "P5V_D_VFB_R")
	)
	(segment
		(start 480.949 -230.0605)
		(end 479.933 -230.0605)
		(width 0.254)
		(layer "B.Cu")
		(net "P5V_D_VFB_R")
	)
	(segment
		(start 483.097586 -230.0605)
		(end 481.966778 -230.0605)
		(width 0.254)
		(layer "B.Cu")
		(net "P5V_D_VFB_R")
	)
	(via
		(at 484.12654 -223.660462)
		(size 0.6096)
		(drill 0.3048)
		(layers "F.Cu" "B.Cu")
		(net "P5V_D_VFB")
	)
	(segment
		(start 484.12654 -223.660462)
		(end 484.856282 -223.660462)
		(width 0.254)
		(layer "B.Cu")
		(net "P5V_D_VFB")
	)
	(segment
		(start 485.640888 -231.548432)
		(end 482.900736 -231.548432)
		(width 0.254)
		(layer "B.Cu")
		(net "P5V_D_VFB")
	)
	(segment
		(start 478.663 -230.0605)
		(end 478.8535 -230.0605)
		(width 0.254)
		(layer "B.Cu")
		(net "P5V_D_VFB")
	)
	(segment
		(start 479.7425 -230.9495)
		(end 479.933 -230.9495)
		(width 0.254)
		(layer "B.Cu")
		(net "P5V_D_VFB")
	)
	(segment
		(start 478.8535 -230.0605)
		(end 479.7425 -230.9495)
		(width 0.254)
		(layer "B.Cu")
		(net "P5V_D_VFB")
	)
	(segment
		(start 479.933 -230.9495)
		(end 480.949 -230.9495)
		(width 0.254)
		(layer "B.Cu")
		(net "P5V_D_VFB")
	)
	(segment
		(start 478.663 -230.0605)
		(end 477.901 -230.0605)
		(width 0.254)
		(layer "B.Cu")
		(net "P5V_D_VFB")
	)
	(segment
		(start 486.466642 -230.722678)
		(end 485.640888 -231.548432)
		(width 0.254)
		(layer "B.Cu")
		(net "P5V_D_VFB")
	)
	(segment
		(start 484.856282 -223.660462)
		(end 486.466642 -225.270822)
		(width 0.254)
		(layer "B.Cu")
		(net "P5V_D_VFB")
	)
	(segment
		(start 477.901 -230.0605)
		(end 477.731836 -230.229664)
		(width 0.254)
		(layer "B.Cu")
		(net "P5V_D_VFB")
	)
	(segment
		(start 482.301804 -230.9495)
		(end 480.949 -230.9495)
		(width 0.254)
		(layer "B.Cu")
		(net "P5V_D_VFB")
	)
	(segment
		(start 482.900736 -231.548432)
		(end 482.301804 -230.9495)
		(width 0.254)
		(layer "B.Cu")
		(net "P5V_D_VFB")
	)
	(segment
		(start 486.466642 -225.270822)
		(end 486.466642 -230.722678)
		(width 0.254)
		(layer "B.Cu")
		(net "P5V_D_VFB")
	)
	(segment
		(start 480.536758 -223.660462)
		(end 484.12654 -223.660462)
		(width 0.254)
		(layer "B.Cu")
		(net "P5V_D_VFB")
	)
	(segment
		(start 477.731836 -230.229664)
		(end 477.042226 -230.229664)
		(width 0.254)
		(layer "B.Cu")
		(net "P5V_D_VFB")
	)
	(via
		(at 467.63051 -230.606346)
		(size 0.6096)
		(drill 0.3048)
		(layers "F.Cu" "B.Cu")
		(net "P5V_D_VBST_RC")
	)
	(segment
		(start 467.63051 -230.606346)
		(end 466.360764 -230.606346)
		(width 0.508)
		(layer "B.Cu")
		(net "P5V_D_VBST_RC")
	)
	(segment
		(start 469.2015 -229.616)
		(end 468.620856 -229.616)
		(width 0.508)
		(layer "B.Cu")
		(net "P5V_D_VBST_RC")
	)
	(segment
		(start 468.620856 -229.616)
		(end 467.63051 -230.606346)
		(width 0.508)
		(layer "B.Cu")
		(net "P5V_D_VBST_RC")
	)
	(segment
		(start 474.953838 -229.743)
		(end 475.742254 -228.954584)
		(width 0.508)
		(layer "F.Cu")
		(net "P5V_D_VBST")
	)
	(segment
		(start 463.435954 -229.743)
		(end 474.953838 -229.743)
		(width 0.508)
		(layer "F.Cu")
		(net "P5V_D_VBST")
	)
	(segment
		(start 462.572608 -230.606346)
		(end 463.435954 -229.743)
		(width 0.508)
		(layer "F.Cu")
		(net "P5V_D_VBST")
	)
	(via
		(at 475.742254 -228.954584)
		(size 0.5588)
		(drill 0.3048)
		(layers "F.Cu" "B.Cu")
		(net "P5V_D_VBST")
	)
	(via
		(at 463.758534 -230.606346)
		(size 0.6096)
		(drill 0.3048)
		(layers "F.Cu" "B.Cu")
		(net "P5V_D_VBST")
	)
	(via
		(at 462.572608 -230.606346)
		(size 0.5588)
		(drill 0.3048)
		(layers "F.Cu" "B.Cu")
		(net "P5V_D_VBST")
	)
	(segment
		(start 463.758534 -230.606346)
		(end 462.572608 -230.606346)
		(width 0.508)
		(layer "B.Cu")
		(net "P5V_D_VBST")
	)
	(segment
		(start 475.542102 -229.154736)
		(end 475.542102 -230.229664)
		(width 0.3048)
		(layer "B.Cu")
		(net "P5V_D_VBST")
	)
	(segment
		(start 464.836764 -230.606346)
		(end 463.758534 -230.606346)
		(width 0.508)
		(layer "B.Cu")
		(net "P5V_D_VBST")
	)
	(segment
		(start 475.742254 -228.954584)
		(end 475.542102 -229.154736)
		(width 0.3048)
		(layer "B.Cu")
		(net "P5V_D_VBST")
	)
	(via
		(at 479.250756 -235.966)
		(size 0.6096)
		(drill 0.3048)
		(layers "F.Cu" "B.Cu")
		(net "P5V_D_TRIP")
	)
	(segment
		(start 476.5421 -235.736892)
		(end 476.771208 -235.966)
		(width 0.254)
		(layer "B.Cu")
		(net "P5V_D_TRIP")
	)
	(segment
		(start 476.5421 -235.128308)
		(end 476.5421 -235.736892)
		(width 0.254)
		(layer "B.Cu")
		(net "P5V_D_TRIP")
	)
	(segment
		(start 479.250756 -235.966)
		(end 481.7745 -235.966)
		(width 0.254)
		(layer "B.Cu")
		(net "P5V_D_TRIP")
	)
	(segment
		(start 476.771208 -235.966)
		(end 479.250756 -235.966)
		(width 0.254)
		(layer "B.Cu")
		(net "P5V_D_TRIP")
	)
	(via
		(at 468.1728 -231.854502)
		(size 0.6096)
		(drill 0.3048)
		(layers "F.Cu" "B.Cu")
		(net "P5V_D_SNB")
	)
	(segment
		(start 468.1728 -233.299)
		(end 468.1728 -231.854502)
		(width 0.508)
		(layer "B.Cu")
		(net "P5V_D_SNB")
	)
	(segment
		(start 468.1728 -231.5337)
		(end 469.2015 -230.505)
		(width 0.508)
		(layer "B.Cu")
		(net "P5V_D_SNB")
	)
	(segment
		(start 468.1728 -231.854502)
		(end 468.1728 -231.5337)
		(width 0.508)
		(layer "B.Cu")
		(net "P5V_D_SNB")
	)
	(via
		(at 482.966268 -224.539048)
		(size 0.6096)
		(drill 0.3048)
		(layers "F.Cu" "B.Cu")
		(net "P5V_D_ROVP")
	)
	(segment
		(start 475.04223 -228.587808)
		(end 475.04223 -230.229664)
		(width 0.254)
		(layer "B.Cu")
		(net "P5V_D_ROVP")
	)
	(segment
		(start 482.966268 -224.539048)
		(end 483.555548 -224.539048)
		(width 0.254)
		(layer "B.Cu")
		(net "P5V_D_ROVP")
	)
	(segment
		(start 477.393 -225.171)
		(end 477.393 -227.711)
		(width 0.254)
		(layer "B.Cu")
		(net "P5V_D_ROVP")
	)
	(segment
		(start 476.796354 -228.307646)
		(end 475.322392 -228.307646)
		(width 0.254)
		(layer "B.Cu")
		(net "P5V_D_ROVP")
	)
	(segment
		(start 483.555548 -224.539048)
		(end 484.251 -225.2345)
		(width 0.254)
		(layer "B.Cu")
		(net "P5V_D_ROVP")
	)
	(segment
		(start 482.966268 -224.539048)
		(end 478.024952 -224.539048)
		(width 0.254)
		(layer "B.Cu")
		(net "P5V_D_ROVP")
	)
	(segment
		(start 478.024952 -224.539048)
		(end 477.393 -225.171)
		(width 0.254)
		(layer "B.Cu")
		(net "P5V_D_ROVP")
	)
	(segment
		(start 475.322392 -228.307646)
		(end 475.04223 -228.587808)
		(width 0.254)
		(layer "B.Cu")
		(net "P5V_D_ROVP")
	)
	(segment
		(start 477.393 -227.711)
		(end 476.796354 -228.307646)
		(width 0.254)
		(layer "B.Cu")
		(net "P5V_D_ROVP")
	)
	(via
		(at 480.470464 -235.128308)
		(size 0.6096)
		(drill 0.3048)
		(layers "F.Cu" "B.Cu")
		(net "P5V_D_RF")
	)
	(segment
		(start 481.080572 -235.128308)
		(end 481.25888 -234.95)
		(width 0.254)
		(layer "B.Cu")
		(net "P5V_D_RF")
	)
	(segment
		(start 481.7745 -233.934)
		(end 481.7745 -234.95)
		(width 0.254)
		(layer "B.Cu")
		(net "P5V_D_RF")
	)
	(segment
		(start 477.042226 -235.128308)
		(end 480.470464 -235.128308)
		(width 0.254)
		(layer "B.Cu")
		(net "P5V_D_RF")
	)
	(segment
		(start 481.25888 -234.95)
		(end 481.7745 -234.95)
		(width 0.254)
		(layer "B.Cu")
		(net "P5V_D_RF")
	)
	(segment
		(start 480.470464 -235.128308)
		(end 481.080572 -235.128308)
		(width 0.254)
		(layer "B.Cu")
		(net "P5V_D_RF")
	)
	(via
		(at 480.338892 -237.109)
		(size 0.6096)
		(drill 0.3048)
		(layers "F.Cu" "B.Cu")
		(net "P5V_D_MODE")
	)
	(segment
		(start 476.042228 -235.909358)
		(end 476.042228 -235.128308)
		(width 0.254)
		(layer "B.Cu")
		(net "P5V_D_MODE")
	)
	(segment
		(start 481.7745 -237.109)
		(end 480.338892 -237.109)
		(width 0.254)
		(layer "B.Cu")
		(net "P5V_D_MODE")
	)
	(segment
		(start 477.760284 -236.460284)
		(end 476.593154 -236.460284)
		(width 0.254)
		(layer "B.Cu")
		(net "P5V_D_MODE")
	)
	(segment
		(start 480.338892 -237.109)
		(end 478.409 -237.109)
		(width 0.254)
		(layer "B.Cu")
		(net "P5V_D_MODE")
	)
	(segment
		(start 476.593154 -236.460284)
		(end 476.042228 -235.909358)
		(width 0.254)
		(layer "B.Cu")
		(net "P5V_D_MODE")
	)
	(segment
		(start 481.7745 -238.252)
		(end 481.7745 -237.109)
		(width 0.254)
		(layer "B.Cu")
		(net "P5V_D_MODE")
	)
	(segment
		(start 478.409 -237.109)
		(end 477.760284 -236.460284)
		(width 0.254)
		(layer "B.Cu")
		(net "P5V_D_MODE")
	)
	(via
		(at 481.787454 -222.452184)
		(size 0.6096)
		(drill 0.3048)
		(layers "F.Cu" "B.Cu")
		(net "P5V_D_LL_R")
	)
	(segment
		(start 473.272358 -223.595184)
		(end 472.516454 -223.595184)
		(width 0.508)
		(layer "B.Cu")
		(net "P5V_D_LL")
	)
	(segment
		(start 472.516454 -223.595184)
		(end 471.722704 -224.388934)
		(width 0.508)
		(layer "B.Cu")
		(net "P5V_D_LL")
	)
	(segment
		(start 473.279216 -223.602042)
		(end 473.272358 -223.595184)
		(width 0.508)
		(layer "B.Cu")
		(net "P5V_D_LL")
	)
	(segment
		(start 478.282 -223.602042)
		(end 473.279216 -223.602042)
		(width 0.508)
		(layer "B.Cu")
		(net "P5V_D_LL")
	)
	(segment
		(start 471.722704 -224.388934)
		(end 471.722704 -226.96678)
		(width 0.508)
		(layer "B.Cu")
		(net "P5V_D_LL")
	)
	(via
		(at 482.966268 -228.854)
		(size 0.6096)
		(drill 0.3048)
		(layers "F.Cu" "B.Cu")
		(net "P5V_D_EN_R")
	)
	(segment
		(start 480.680522 -228.854)
		(end 481.823522 -228.854)
		(width 0.254)
		(layer "B.Cu")
		(net "P5V_D_EN_R")
	)
	(segment
		(start 479.552 -228.854)
		(end 478.79 -228.854)
		(width 0.254)
		(layer "B.Cu")
		(net "P5V_D_EN_R")
	)
	(segment
		(start 476.871538 -229.2985)
		(end 476.5421 -229.627938)
		(width 0.254)
		(layer "B.Cu")
		(net "P5V_D_EN_R")
	)
	(segment
		(start 479.552 -228.854)
		(end 480.680522 -228.854)
		(width 0.254)
		(layer "B.Cu")
		(net "P5V_D_EN_R")
	)
	(segment
		(start 478.3455 -229.2985)
		(end 476.871538 -229.2985)
		(width 0.254)
		(layer "B.Cu")
		(net "P5V_D_EN_R")
	)
	(segment
		(start 478.79 -228.854)
		(end 478.3455 -229.2985)
		(width 0.254)
		(layer "B.Cu")
		(net "P5V_D_EN_R")
	)
	(segment
		(start 482.966268 -228.854)
		(end 481.823522 -228.854)
		(width 0.254)
		(layer "B.Cu")
		(net "P5V_D_EN_R")
	)
	(segment
		(start 484.109522 -228.854)
		(end 482.966268 -228.854)
		(width 0.254)
		(layer "B.Cu")
		(net "P5V_D_EN_R")
	)
	(segment
		(start 476.5421 -229.627938)
		(end 476.5421 -230.229664)
		(width 0.254)
		(layer "B.Cu")
		(net "P5V_D_EN_R")
	)
	(segment
		(start 477.669098 -203.399898)
		(end 479.2853 -205.0161)
		(width 0.254)
		(layer "F.Cu")
		(net "P5V_D_CC")
	)
	(segment
		(start 483.87 -209.6008)
		(end 486.346754 -212.077554)
		(width 0.254)
		(layer "F.Cu")
		(net "P5V_D_CC")
	)
	(segment
		(start 479.2853 -205.0161)
		(end 479.2853 -205.922626)
		(width 0.254)
		(layer "F.Cu")
		(net "P5V_D_CC")
	)
	(segment
		(start 471.341704 -203.399898)
		(end 477.669098 -203.399898)
		(width 0.254)
		(layer "F.Cu")
		(net "P5V_D_CC")
	)
	(segment
		(start 482.963474 -209.6008)
		(end 483.87 -209.6008)
		(width 0.254)
		(layer "F.Cu")
		(net "P5V_D_CC")
	)
	(segment
		(start 486.346754 -212.077554)
		(end 486.346754 -226.160076)
		(width 0.254)
		(layer "F.Cu")
		(net "P5V_D_CC")
	)
	(segment
		(start 479.2853 -205.922626)
		(end 482.963474 -209.6008)
		(width 0.254)
		(layer "F.Cu")
		(net "P5V_D_CC")
	)
	(segment
		(start 486.346754 -226.160076)
		(end 485.565704 -226.941126)
		(width 0.254)
		(layer "F.Cu")
		(net "P5V_D_CC")
	)
	(via
		(at 471.341704 -203.399898)
		(size 0.5588)
		(drill 0.3048)
		(layers "F.Cu" "B.Cu")
		(net "P5V_D_CC")
	)
	(via
		(at 485.565704 -226.941126)
		(size 0.5588)
		(drill 0.3048)
		(layers "F.Cu" "B.Cu")
		(net "P5V_D_CC")
	)
	(via
		(at 485.565704 -228.808534)
		(size 0.6096)
		(drill 0.3048)
		(layers "F.Cu" "B.Cu")
		(net "P5V_D_CC")
	)
	(segment
		(start 485.565704 -228.808534)
		(end 485.565704 -229.737412)
		(width 0.254)
		(layer "B.Cu")
		(net "P5V_D_CC")
	)
	(segment
		(start 485.565704 -226.941126)
		(end 485.565704 -228.808534)
		(width 0.254)
		(layer "B.Cu")
		(net "P5V_D_CC")
	)
	(segment
		(start 485.565704 -229.737412)
		(end 485.242616 -230.0605)
		(width 0.254)
		(layer "B.Cu")
		(net "P5V_D_CC")
	)
	(segment
		(start 485.242616 -230.0605)
		(end 484.621586 -230.0605)
		(width 0.254)
		(layer "B.Cu")
		(net "P5V_D_CC")
	)
	(segment
		(start 471.964004 -203.399898)
		(end 471.341704 -203.399898)
		(width 0.254)
		(layer "B.Cu")
		(net "P5V_D_CC")
	)
	(segment
		(start 442.623702 -253.42215)
		(end 441.289186 -253.42215)
		(width 0.254)
		(layer "F.Cu")
		(net "P5V_C_VREG")
	)
	(segment
		(start 441.289186 -253.42215)
		(end 441.259214 -253.452122)
		(width 0.254)
		(layer "F.Cu")
		(net "P5V_C_VREG")
	)
	(via
		(at 441.259214 -253.452122)
		(size 0.6604)
		(drill 0.3048)
		(layers "F.Cu" "B.Cu")
		(net "P5V_C_VREG")
	)
	(segment
		(start 441.124594 -253.586742)
		(end 441.124594 -254.514096)
		(width 0.254)
		(layer "B.Cu")
		(net "P5V_C_VREG")
	)
	(segment
		(start 442.272928 -252.264926)
		(end 443.981078 -252.264926)
		(width 0.254)
		(layer "B.Cu")
		(net "P5V_C_VREG")
	)
	(segment
		(start 441.259214 -253.27864)
		(end 442.272928 -252.264926)
		(width 0.254)
		(layer "B.Cu")
		(net "P5V_C_VREG")
	)
	(segment
		(start 441.259214 -253.452122)
		(end 441.124594 -253.586742)
		(width 0.254)
		(layer "B.Cu")
		(net "P5V_C_VREG")
	)
	(segment
		(start 441.259214 -253.452122)
		(end 441.259214 -253.27864)
		(width 0.254)
		(layer "B.Cu")
		(net "P5V_C_VREG")
	)
	(via
		(at 451.069202 -257.86715)
		(size 0.6096)
		(drill 0.3048)
		(layers "F.Cu" "B.Cu")
		(net "P5V_C_VFB_R")
	)
	(segment
		(start 450.123814 -256.474214)
		(end 451.263004 -256.474214)
		(width 0.254)
		(layer "B.Cu")
		(net "P5V_C_VFB_R")
	)
	(segment
		(start 450.116702 -257.86715)
		(end 451.069202 -257.86715)
		(width 0.254)
		(layer "B.Cu")
		(net "P5V_C_VFB_R")
	)
	(segment
		(start 451.263004 -256.474214)
		(end 451.263004 -257.673348)
		(width 0.254)
		(layer "B.Cu")
		(net "P5V_C_VFB_R")
	)
	(segment
		(start 451.263004 -257.673348)
		(end 451.069202 -257.86715)
		(width 0.254)
		(layer "B.Cu")
		(net "P5V_C_VFB_R")
	)
	(segment
		(start 449.7959 -256.4638)
		(end 450.1134 -256.4638)
		(width 0.254)
		(layer "B.Cu")
		(net "P5V_C_VFB_R")
	)
	(segment
		(start 450.1134 -256.4638)
		(end 450.123814 -256.474214)
		(width 0.254)
		(layer "B.Cu")
		(net "P5V_C_VFB_R")
	)
	(segment
		(start 449.735702 -257.48615)
		(end 450.116702 -257.86715)
		(width 0.254)
		(layer "B.Cu")
		(net "P5V_C_VFB_R")
	)
	(via
		(at 453.126602 -258.65455)
		(size 0.6096)
		(drill 0.3048)
		(layers "F.Cu" "B.Cu")
		(net "P5V_C_VFB")
	)
	(segment
		(start 448.846702 -257.48615)
		(end 448.846702 -257.67665)
		(width 0.254)
		(layer "B.Cu")
		(net "P5V_C_VFB")
	)
	(segment
		(start 449.824602 -258.65455)
		(end 453.126602 -258.65455)
		(width 0.254)
		(layer "B.Cu")
		(net "P5V_C_VFB")
	)
	(segment
		(start 455.448924 -257.759454)
		(end 454.553828 -258.65455)
		(width 0.254)
		(layer "B.Cu")
		(net "P5V_C_VFB")
	)
	(segment
		(start 448.9069 -254.829056)
		(end 448.879722 -254.801878)
		(width 0.254)
		(layer "B.Cu")
		(net "P5V_C_VFB")
	)
	(segment
		(start 448.846702 -257.67665)
		(end 449.824602 -258.65455)
		(width 0.254)
		(layer "B.Cu")
		(net "P5V_C_VFB")
	)
	(segment
		(start 448.5386 -256.4638)
		(end 448.9069 -256.4638)
		(width 0.254)
		(layer "B.Cu")
		(net "P5V_C_VFB")
	)
	(segment
		(start 454.553828 -258.65455)
		(end 453.126602 -258.65455)
		(width 0.254)
		(layer "B.Cu")
		(net "P5V_C_VFB")
	)
	(segment
		(start 448.9069 -257.425952)
		(end 448.846702 -257.48615)
		(width 0.254)
		(layer "B.Cu")
		(net "P5V_C_VFB")
	)
	(segment
		(start 447.431414 -255.947164)
		(end 448.021964 -255.947164)
		(width 0.254)
		(layer "B.Cu")
		(net "P5V_C_VFB")
	)
	(segment
		(start 448.021964 -255.947164)
		(end 448.5386 -256.4638)
		(width 0.254)
		(layer "B.Cu")
		(net "P5V_C_VFB")
	)
	(segment
		(start 448.879722 -254.801878)
		(end 448.879722 -254.264922)
		(width 0.254)
		(layer "B.Cu")
		(net "P5V_C_VFB")
	)
	(segment
		(start 448.9069 -256.4638)
		(end 448.9069 -254.829056)
		(width 0.254)
		(layer "B.Cu")
		(net "P5V_C_VFB")
	)
	(segment
		(start 448.9069 -256.4638)
		(end 448.9069 -257.425952)
		(width 0.254)
		(layer "B.Cu")
		(net "P5V_C_VFB")
	)
	(segment
		(start 452.197724 -249.875548)
		(end 451.673722 -250.39955)
		(width 0.508)
		(layer "F.Cu")
		(net "P5V_C_VBST_RC")
	)
	(segment
		(start 451.673722 -250.39955)
		(end 451.094602 -250.39955)
		(width 0.508)
		(layer "F.Cu")
		(net "P5V_C_VBST_RC")
	)
	(segment
		(start 451.094602 -250.39955)
		(end 449.037202 -250.39955)
		(width 0.508)
		(layer "F.Cu")
		(net "P5V_C_VBST_RC")
	)
	(via
		(at 451.094602 -250.39955)
		(size 0.6604)
		(drill 0.3302)
		(layers "F.Cu" "B.Cu")
		(net "P5V_C_VBST_RC")
	)
	(segment
		(start 450.154802 -252.96495)
		(end 450.596 -252.523752)
		(width 0.508)
		(layer "F.Cu")
		(net "P5V_C_VBST")
	)
	(segment
		(start 450.596 -252.523752)
		(end 450.596 -251.92355)
		(width 0.508)
		(layer "F.Cu")
		(net "P5V_C_VBST")
	)
	(segment
		(start 450.596 -251.92355)
		(end 449.037202 -251.92355)
		(width 0.508)
		(layer "F.Cu")
		(net "P5V_C_VBST")
	)
	(via
		(at 450.596 -251.92355)
		(size 0.6604)
		(drill 0.3302)
		(layers "F.Cu" "B.Cu")
		(net "P5V_C_VBST")
	)
	(via
		(at 450.154802 -252.96495)
		(size 0.5588)
		(drill 0.3048)
		(layers "F.Cu" "B.Cu")
		(net "P5V_C_VBST")
	)
	(segment
		(start 449.95465 -252.764798)
		(end 448.879722 -252.764798)
		(width 0.3048)
		(layer "B.Cu")
		(net "P5V_C_VBST")
	)
	(segment
		(start 450.154802 -252.96495)
		(end 449.95465 -252.764798)
		(width 0.3048)
		(layer "B.Cu")
		(net "P5V_C_VBST")
	)
	(segment
		(start 443.49162 -255.069086)
		(end 443.49162 -255.551432)
		(width 0.254)
		(layer "F.Cu")
		(net "P5V_C_TRIP")
	)
	(segment
		(start 442.953902 -256.08915)
		(end 442.953902 -256.59715)
		(width 0.254)
		(layer "F.Cu")
		(net "P5V_C_TRIP")
	)
	(segment
		(start 443.49162 -255.551432)
		(end 442.953902 -256.08915)
		(width 0.254)
		(layer "F.Cu")
		(net "P5V_C_TRIP")
	)
	(segment
		(start 442.953902 -257.89255)
		(end 442.953902 -256.59715)
		(width 0.254)
		(layer "F.Cu")
		(net "P5V_C_TRIP")
	)
	(via
		(at 442.953902 -256.59715)
		(size 0.6604)
		(drill 0.3302)
		(layers "F.Cu" "B.Cu")
		(net "P5V_C_TRIP")
	)
	(via
		(at 443.49162 -255.069086)
		(size 0.5588)
		(drill 0.3048)
		(layers "F.Cu" "B.Cu")
		(net "P5V_C_TRIP")
	)
	(segment
		(start 443.372494 -253.764796)
		(end 443.981078 -253.764796)
		(width 0.254)
		(layer "B.Cu")
		(net "P5V_C_TRIP")
	)
	(segment
		(start 443.144402 -254.721868)
		(end 443.144402 -253.992888)
		(width 0.254)
		(layer "B.Cu")
		(net "P5V_C_TRIP")
	)
	(segment
		(start 443.144402 -253.992888)
		(end 443.372494 -253.764796)
		(width 0.254)
		(layer "B.Cu")
		(net "P5V_C_TRIP")
	)
	(segment
		(start 443.49162 -255.069086)
		(end 443.144402 -254.721868)
		(width 0.254)
		(layer "B.Cu")
		(net "P5V_C_TRIP")
	)
	(segment
		(start 448.918076 -248.43105)
		(end 449.085716 -248.59869)
		(width 0.508)
		(layer "F.Cu")
		(net "P5V_C_SNB")
	)
	(segment
		(start 451.069202 -248.59869)
		(end 452.190612 -248.59869)
		(width 0.508)
		(layer "F.Cu")
		(net "P5V_C_SNB")
	)
	(segment
		(start 449.085716 -248.59869)
		(end 451.069202 -248.59869)
		(width 0.508)
		(layer "F.Cu")
		(net "P5V_C_SNB")
	)
	(via
		(at 451.069202 -248.59869)
		(size 0.6604)
		(drill 0.3302)
		(layers "F.Cu" "B.Cu")
		(net "P5V_C_SNB")
	)
	(segment
		(start 445.5922 -255.91262)
		(end 445.5922 -255.565148)
		(width 0.254)
		(layer "F.Cu")
		(net "P5V_C_ROVP")
	)
	(segment
		(start 445.5922 -255.565148)
		(end 446.0494 -255.107948)
		(width 0.254)
		(layer "F.Cu")
		(net "P5V_C_ROVP")
	)
	(via
		(at 451.856602 -253.77775)
		(size 0.6604)
		(drill 0.3048)
		(layers "F.Cu" "B.Cu")
		(net "P5V_C_ROVP")
	)
	(via
		(at 446.0494 -255.107948)
		(size 0.5588)
		(drill 0.3048)
		(layers "F.Cu" "B.Cu")
		(net "P5V_C_ROVP")
	)
	(segment
		(start 450.343778 -252.264926)
		(end 448.879722 -252.264926)
		(width 0.254)
		(layer "B.Cu")
		(net "P5V_C_ROVP")
	)
	(segment
		(start 451.856602 -253.77775)
		(end 450.343778 -252.264926)
		(width 0.254)
		(layer "B.Cu")
		(net "P5V_C_ROVP")
	)
	(segment
		(start 449.358004 -255.107948)
		(end 446.0494 -255.107948)
		(width 0.254)
		(layer "In2.Cu")
		(net "P5V_C_ROVP")
	)
	(segment
		(start 451.856602 -253.77775)
		(end 450.688202 -253.77775)
		(width 0.254)
		(layer "In2.Cu")
		(net "P5V_C_ROVP")
	)
	(segment
		(start 450.688202 -253.77775)
		(end 449.358004 -255.107948)
		(width 0.254)
		(layer "In2.Cu")
		(net "P5V_C_ROVP")
	)
	(segment
		(start 444.541402 -255.89865)
		(end 444.541402 -255.07315)
		(width 0.254)
		(layer "F.Cu")
		(net "P5V_C_RF")
	)
	(segment
		(start 443.855602 -253.42215)
		(end 444.465202 -254.03175)
		(width 0.254)
		(layer "F.Cu")
		(net "P5V_C_RF")
	)
	(segment
		(start 444.541402 -255.07315)
		(end 444.465202 -254.99695)
		(width 0.254)
		(layer "F.Cu")
		(net "P5V_C_RF")
	)
	(segment
		(start 443.512702 -253.42215)
		(end 443.855602 -253.42215)
		(width 0.254)
		(layer "F.Cu")
		(net "P5V_C_RF")
	)
	(segment
		(start 444.465202 -254.99695)
		(end 444.465202 -254.03175)
		(width 0.254)
		(layer "F.Cu")
		(net "P5V_C_RF")
	)
	(via
		(at 444.465202 -254.03175)
		(size 0.6604)
		(drill 0.3302)
		(layers "F.Cu" "B.Cu")
		(net "P5V_C_RF")
	)
	(via
		(at 444.465202 -254.99695)
		(size 0.5588)
		(drill 0.3048)
		(layers "F.Cu" "B.Cu")
		(net "P5V_C_RF")
	)
	(segment
		(start 444.465202 -254.99695)
		(end 443.981078 -254.512826)
		(width 0.254)
		(layer "B.Cu")
		(net "P5V_C_RF")
	)
	(segment
		(start 443.981078 -254.512826)
		(end 443.981078 -254.264922)
		(width 0.254)
		(layer "B.Cu")
		(net "P5V_C_RF")
	)
	(segment
		(start 447.61023 -257.050286)
		(end 447.094356 -257.56616)
		(width 0.254)
		(layer "F.Cu")
		(net "P5V_C_MODE")
	)
	(segment
		(start 442.086746 -256.088642)
		(end 442.026802 -256.148586)
		(width 0.254)
		(layer "F.Cu")
		(net "P5V_C_MODE")
	)
	(segment
		(start 447.610738 -256.81051)
		(end 447.61023 -256.811018)
		(width 0.254)
		(layer "F.Cu")
		(net "P5V_C_MODE")
	)
	(segment
		(start 447.610738 -255.778254)
		(end 447.610738 -256.81051)
		(width 0.254)
		(layer "F.Cu")
		(net "P5V_C_MODE")
	)
	(segment
		(start 447.094356 -257.56616)
		(end 447.094356 -258.412996)
		(width 0.254)
		(layer "F.Cu")
		(net "P5V_C_MODE")
	)
	(segment
		(start 442.026802 -258.24815)
		(end 442.788802 -259.01015)
		(width 0.254)
		(layer "F.Cu")
		(net "P5V_C_MODE")
	)
	(segment
		(start 442.788802 -259.01015)
		(end 446.497202 -259.01015)
		(width 0.254)
		(layer "F.Cu")
		(net "P5V_C_MODE")
	)
	(segment
		(start 447.61023 -256.811018)
		(end 447.61023 -257.050286)
		(width 0.254)
		(layer "F.Cu")
		(net "P5V_C_MODE")
	)
	(segment
		(start 447.094356 -258.412996)
		(end 446.751202 -258.75615)
		(width 0.254)
		(layer "F.Cu")
		(net "P5V_C_MODE")
	)
	(segment
		(start 442.026802 -256.148586)
		(end 442.026802 -258.24815)
		(width 0.254)
		(layer "F.Cu")
		(net "P5V_C_MODE")
	)
	(segment
		(start 446.497202 -259.01015)
		(end 446.751202 -258.75615)
		(width 0.254)
		(layer "F.Cu")
		(net "P5V_C_MODE")
	)
	(via
		(at 442.086746 -256.088642)
		(size 0.5588)
		(drill 0.3048)
		(layers "F.Cu" "B.Cu")
		(net "P5V_C_MODE")
	)
	(via
		(at 446.751202 -258.75615)
		(size 0.6604)
		(drill 0.3302)
		(layers "F.Cu" "B.Cu")
		(net "P5V_C_MODE")
	)
	(segment
		(start 442.529722 -255.645666)
		(end 442.529722 -253.93523)
		(width 0.254)
		(layer "B.Cu")
		(net "P5V_C_MODE")
	)
	(segment
		(start 442.529722 -253.93523)
		(end 443.200028 -253.264924)
		(width 0.254)
		(layer "B.Cu")
		(net "P5V_C_MODE")
	)
	(segment
		(start 443.200028 -253.264924)
		(end 443.981078 -253.264924)
		(width 0.254)
		(layer "B.Cu")
		(net "P5V_C_MODE")
	)
	(segment
		(start 442.086746 -256.088642)
		(end 442.529722 -255.645666)
		(width 0.254)
		(layer "B.Cu")
		(net "P5V_C_MODE")
	)
	(via
		(at 456.9714 -258.6736)
		(size 0.6096)
		(drill 0.3048)
		(layers "F.Cu" "B.Cu")
		(net "P5V_C_LL_R")
	)
	(segment
		(start 453.086724 -249.875548)
		(end 453.086724 -251.324872)
		(width 0.6096)
		(layer "F.Cu")
		(net "P5V_C_LL")
	)
	(segment
		(start 453.079612 -248.59869)
		(end 453.079612 -247.490234)
		(width 0.508)
		(layer "F.Cu")
		(net "P5V_C_LL")
	)
	(segment
		(start 453.079612 -247.490234)
		(end 453.079612 -246.474234)
		(width 0.508)
		(layer "F.Cu")
		(net "P5V_C_LL")
	)
	(via
		(at 453.079612 -246.474234)
		(size 0.5588)
		(drill 0.3048)
		(layers "F.Cu" "B.Cu")
		(net "P5V_C_LL")
	)
	(via
		(at 453.079612 -247.490234)
		(size 0.6604)
		(drill 0.3302)
		(layers "F.Cu" "B.Cu")
		(net "P5V_C_LL")
	)
	(via
		(at 453.086724 -251.324872)
		(size 0.7112)
		(drill 0.4064)
		(layers "F.Cu" "B.Cu")
		(net "P5V_C_LL")
	)
	(segment
		(start 455.507344 -255.504696)
		(end 455.507344 -250.501912)
		(width 0.508)
		(layer "B.Cu")
		(net "P5V_C_LL")
	)
	(segment
		(start 454.720452 -248.9454)
		(end 452.142606 -248.9454)
		(width 0.508)
		(layer "B.Cu")
		(net "P5V_C_LL")
	)
	(segment
		(start 455.514202 -249.73915)
		(end 454.720452 -248.9454)
		(width 0.508)
		(layer "B.Cu")
		(net "P5V_C_LL")
	)
	(segment
		(start 455.514202 -250.495054)
		(end 455.514202 -249.73915)
		(width 0.508)
		(layer "B.Cu")
		(net "P5V_C_LL")
	)
	(segment
		(start 455.507344 -250.501912)
		(end 455.514202 -250.495054)
		(width 0.508)
		(layer "B.Cu")
		(net "P5V_C_LL")
	)
	(segment
		(start 449.545202 -258.75615)
		(end 449.545202 -258.05765)
		(width 0.254)
		(layer "F.Cu")
		(net "P5V_C_EN_R")
	)
	(segment
		(start 450.307202 -256.34315)
		(end 450.307202 -255.347216)
		(width 0.254)
		(layer "F.Cu")
		(net "P5V_C_EN_R")
	)
	(segment
		(start 449.735702 -256.91465)
		(end 450.307202 -256.34315)
		(width 0.254)
		(layer "F.Cu")
		(net "P5V_C_EN_R")
	)
	(segment
		(start 449.545202 -258.75615)
		(end 450.624702 -258.75615)
		(width 0.254)
		(layer "F.Cu")
		(net "P5V_C_EN_R")
	)
	(segment
		(start 449.735702 -257.48615)
		(end 449.735702 -256.91465)
		(width 0.254)
		(layer "F.Cu")
		(net "P5V_C_EN_R")
	)
	(segment
		(start 450.624702 -258.75615)
		(end 450.815202 -258.56565)
		(width 0.254)
		(layer "F.Cu")
		(net "P5V_C_EN_R")
	)
	(segment
		(start 449.735702 -257.86715)
		(end 449.735702 -257.48615)
		(width 0.254)
		(layer "F.Cu")
		(net "P5V_C_EN_R")
	)
	(segment
		(start 449.545202 -258.05765)
		(end 449.735702 -257.86715)
		(width 0.254)
		(layer "F.Cu")
		(net "P5V_C_EN_R")
	)
	(segment
		(start 450.815202 -258.56565)
		(end 451.755002 -258.56565)
		(width 0.254)
		(layer "F.Cu")
		(net "P5V_C_EN_R")
	)
	(segment
		(start 451.755002 -258.56565)
		(end 451.843902 -258.47675)
		(width 0.254)
		(layer "F.Cu")
		(net "P5V_C_EN_R")
	)
	(via
		(at 450.307202 -255.347216)
		(size 0.5588)
		(drill 0.3048)
		(layers "F.Cu" "B.Cu")
		(net "P5V_C_EN_R")
	)
	(via
		(at 449.545202 -258.75615)
		(size 0.6604)
		(drill 0.3302)
		(layers "F.Cu" "B.Cu")
		(net "P5V_C_EN_R")
	)
	(segment
		(start 449.481448 -253.764796)
		(end 448.879722 -253.764796)
		(width 0.254)
		(layer "B.Cu")
		(net "P5V_C_EN_R")
	)
	(segment
		(start 450.307202 -255.347216)
		(end 450.307202 -254.59055)
		(width 0.254)
		(layer "B.Cu")
		(net "P5V_C_EN_R")
	)
	(segment
		(start 450.307202 -254.59055)
		(end 449.481448 -253.764796)
		(width 0.254)
		(layer "B.Cu")
		(net "P5V_C_EN_R")
	)
	(via
		(at 474.462602 -253.09195)
		(size 0.5588)
		(drill 0.3048)
		(layers "F.Cu" "B.Cu")
		(net "P5V_C_CC")
	)
	(via
		(at 453.939402 -256.474214)
		(size 0.6604)
		(drill 0.3048)
		(layers "F.Cu" "B.Cu")
		(net "P5V_C_CC")
	)
	(segment
		(start 453.939402 -256.474214)
		(end 452.787004 -256.474214)
		(width 0.254)
		(layer "B.Cu")
		(net "P5V_C_CC")
	)
	(segment
		(start 474.462602 -252.46965)
		(end 474.462602 -253.09195)
		(width 0.254)
		(layer "B.Cu")
		(net "P5V_C_CC")
	)
	(segment
		(start 474.462602 -255.126998)
		(end 473.6592 -255.9304)
		(width 0.254)
		(layer "In2.Cu")
		(net "P5V_C_CC")
	)
	(segment
		(start 474.462602 -253.09195)
		(end 474.462602 -255.126998)
		(width 0.254)
		(layer "In2.Cu")
		(net "P5V_C_CC")
	)
	(segment
		(start 454.483216 -255.9304)
		(end 453.939402 -256.474214)
		(width 0.254)
		(layer "In2.Cu")
		(net "P5V_C_CC")
	)
	(segment
		(start 473.6592 -255.9304)
		(end 454.483216 -255.9304)
		(width 0.254)
		(layer "In2.Cu")
		(net "P5V_C_CC")
	)
	(segment
		(start 42.548302 -145.72615)
		(end 42.548302 -144.72539)
		(width 0.254)
		(layer "F.Cu")
		(net "P5V_B_VREG")
	)
	(segment
		(start 42.548302 -144.72539)
		(end 42.698162 -144.57553)
		(width 0.254)
		(layer "F.Cu")
		(net "P5V_B_VREG")
	)
	(via
		(at 42.698162 -144.57553)
		(size 0.6604)
		(drill 0.3048)
		(layers "F.Cu" "B.Cu")
		(net "P5V_B_VREG")
	)
	(segment
		(start 41.476422 -144.57553)
		(end 42.698162 -144.57553)
		(width 0.254)
		(layer "B.Cu")
		(net "P5V_B_VREG")
	)
	(segment
		(start 42.704766 -144.568926)
		(end 43.905678 -144.568926)
		(width 0.254)
		(layer "B.Cu")
		(net "P5V_B_VREG")
	)
	(segment
		(start 42.698162 -144.57553)
		(end 42.704766 -144.568926)
		(width 0.254)
		(layer "B.Cu")
		(net "P5V_B_VREG")
	)
	(via
		(at 50.993802 -150.17115)
		(size 0.6096)
		(drill 0.3048)
		(layers "F.Cu" "B.Cu")
		(net "P5V_B_VFB_R")
	)
	(segment
		(start 49.660302 -149.79015)
		(end 50.041302 -150.17115)
		(width 0.254)
		(layer "B.Cu")
		(net "P5V_B_VFB_R")
	)
	(segment
		(start 50.041302 -150.17115)
		(end 50.993802 -150.17115)
		(width 0.254)
		(layer "B.Cu")
		(net "P5V_B_VFB_R")
	)
	(segment
		(start 49.6697 -148.7678)
		(end 51.17719 -148.7678)
		(width 0.254)
		(layer "B.Cu")
		(net "P5V_B_VFB_R")
	)
	(segment
		(start 51.17719 -148.7678)
		(end 51.187604 -148.778214)
		(width 0.254)
		(layer "B.Cu")
		(net "P5V_B_VFB_R")
	)
	(segment
		(start 51.187604 -149.977348)
		(end 50.993802 -150.17115)
		(width 0.254)
		(layer "B.Cu")
		(net "P5V_B_VFB_R")
	)
	(segment
		(start 51.187604 -148.778214)
		(end 51.187604 -149.977348)
		(width 0.254)
		(layer "B.Cu")
		(net "P5V_B_VFB_R")
	)
	(via
		(at 53.127402 -150.98395)
		(size 0.6096)
		(drill 0.3048)
		(layers "F.Cu" "B.Cu")
		(net "P5V_B_VFB")
	)
	(segment
		(start 48.804322 -147.804378)
		(end 48.804322 -146.568922)
		(width 0.254)
		(layer "B.Cu")
		(net "P5V_B_VFB")
	)
	(segment
		(start 48.7807 -148.7678)
		(end 48.7807 -147.828)
		(width 0.254)
		(layer "B.Cu")
		(net "P5V_B_VFB")
	)
	(segment
		(start 48.771302 -149.79015)
		(end 48.771302 -149.98065)
		(width 0.254)
		(layer "B.Cu")
		(net "P5V_B_VFB")
	)
	(segment
		(start 48.4124 -148.7678)
		(end 48.7807 -148.7678)
		(width 0.254)
		(layer "B.Cu")
		(net "P5V_B_VFB")
	)
	(segment
		(start 48.7807 -147.828)
		(end 48.804322 -147.804378)
		(width 0.254)
		(layer "B.Cu")
		(net "P5V_B_VFB")
	)
	(segment
		(start 48.771302 -148.777198)
		(end 48.771302 -149.79015)
		(width 0.254)
		(layer "B.Cu")
		(net "P5V_B_VFB")
	)
	(segment
		(start 54.453028 -150.98395)
		(end 53.127402 -150.98395)
		(width 0.254)
		(layer "B.Cu")
		(net "P5V_B_VFB")
	)
	(segment
		(start 55.373524 -150.063454)
		(end 54.453028 -150.98395)
		(width 0.254)
		(layer "B.Cu")
		(net "P5V_B_VFB")
	)
	(segment
		(start 47.895764 -148.251164)
		(end 48.4124 -148.7678)
		(width 0.254)
		(layer "B.Cu")
		(net "P5V_B_VFB")
	)
	(segment
		(start 49.774602 -150.98395)
		(end 53.127402 -150.98395)
		(width 0.254)
		(layer "B.Cu")
		(net "P5V_B_VFB")
	)
	(segment
		(start 48.7807 -148.7678)
		(end 48.771302 -148.777198)
		(width 0.254)
		(layer "B.Cu")
		(net "P5V_B_VFB")
	)
	(segment
		(start 48.771302 -149.98065)
		(end 49.774602 -150.98395)
		(width 0.254)
		(layer "B.Cu")
		(net "P5V_B_VFB")
	)
	(segment
		(start 47.356014 -148.251164)
		(end 47.895764 -148.251164)
		(width 0.254)
		(layer "B.Cu")
		(net "P5V_B_VFB")
	)
	(segment
		(start 48.961802 -142.70355)
		(end 50.892202 -142.70355)
		(width 0.508)
		(layer "F.Cu")
		(net "P5V_B_VBST_RC")
	)
	(segment
		(start 52.122324 -142.179548)
		(end 51.598322 -142.70355)
		(width 0.508)
		(layer "F.Cu")
		(net "P5V_B_VBST_RC")
	)
	(segment
		(start 51.598322 -142.70355)
		(end 50.892202 -142.70355)
		(width 0.508)
		(layer "F.Cu")
		(net "P5V_B_VBST_RC")
	)
	(via
		(at 50.892202 -142.70355)
		(size 0.6604)
		(drill 0.3302)
		(layers "F.Cu" "B.Cu")
		(net "P5V_B_VBST_RC")
	)
	(segment
		(start 48.961802 -144.22755)
		(end 50.288952 -144.22755)
		(width 0.508)
		(layer "F.Cu")
		(net "P5V_B_VBST")
	)
	(segment
		(start 50.293016 -145.055336)
		(end 50.293016 -144.223486)
		(width 0.508)
		(layer "F.Cu")
		(net "P5V_B_VBST")
	)
	(segment
		(start 50.079402 -145.26895)
		(end 50.293016 -145.055336)
		(width 0.508)
		(layer "F.Cu")
		(net "P5V_B_VBST")
	)
	(segment
		(start 50.288952 -144.22755)
		(end 50.293016 -144.223486)
		(width 0.508)
		(layer "F.Cu")
		(net "P5V_B_VBST")
	)
	(via
		(at 50.079402 -145.26895)
		(size 0.5588)
		(drill 0.3048)
		(layers "F.Cu" "B.Cu")
		(net "P5V_B_VBST")
	)
	(via
		(at 50.293016 -144.223486)
		(size 0.6604)
		(drill 0.3302)
		(layers "F.Cu" "B.Cu")
		(net "P5V_B_VBST")
	)
	(segment
		(start 50.079402 -145.26895)
		(end 49.87925 -145.068798)
		(width 0.3048)
		(layer "B.Cu")
		(net "P5V_B_VBST")
	)
	(segment
		(start 49.87925 -145.068798)
		(end 48.804322 -145.068798)
		(width 0.3048)
		(layer "B.Cu")
		(net "P5V_B_VBST")
	)
	(segment
		(start 43.41622 -147.855432)
		(end 42.878502 -148.39315)
		(width 0.254)
		(layer "F.Cu")
		(net "P5V_B_TRIP")
	)
	(segment
		(start 42.878502 -148.39315)
		(end 42.878502 -148.90115)
		(width 0.254)
		(layer "F.Cu")
		(net "P5V_B_TRIP")
	)
	(segment
		(start 42.878502 -148.90115)
		(end 42.878502 -150.12035)
		(width 0.254)
		(layer "F.Cu")
		(net "P5V_B_TRIP")
	)
	(segment
		(start 43.41622 -147.373086)
		(end 43.41622 -147.855432)
		(width 0.254)
		(layer "F.Cu")
		(net "P5V_B_TRIP")
	)
	(via
		(at 42.878502 -148.90115)
		(size 0.6604)
		(drill 0.3302)
		(layers "F.Cu" "B.Cu")
		(net "P5V_B_TRIP")
	)
	(via
		(at 43.41622 -147.373086)
		(size 0.5588)
		(drill 0.3048)
		(layers "F.Cu" "B.Cu")
		(net "P5V_B_TRIP")
	)
	(segment
		(start 43.069002 -146.296888)
		(end 43.297094 -146.068796)
		(width 0.254)
		(layer "B.Cu")
		(net "P5V_B_TRIP")
	)
	(segment
		(start 43.297094 -146.068796)
		(end 43.905678 -146.068796)
		(width 0.254)
		(layer "B.Cu")
		(net "P5V_B_TRIP")
	)
	(segment
		(start 43.069002 -147.025868)
		(end 43.069002 -146.296888)
		(width 0.254)
		(layer "B.Cu")
		(net "P5V_B_TRIP")
	)
	(segment
		(start 43.41622 -147.373086)
		(end 43.069002 -147.025868)
		(width 0.254)
		(layer "B.Cu")
		(net "P5V_B_TRIP")
	)
	(segment
		(start 49.010316 -140.90269)
		(end 50.358802 -140.90269)
		(width 0.508)
		(layer "F.Cu")
		(net "P5V_B_SNB")
	)
	(segment
		(start 50.358802 -140.90269)
		(end 52.115212 -140.90269)
		(width 0.508)
		(layer "F.Cu")
		(net "P5V_B_SNB")
	)
	(segment
		(start 48.842676 -140.73505)
		(end 49.010316 -140.90269)
		(width 0.508)
		(layer "F.Cu")
		(net "P5V_B_SNB")
	)
	(via
		(at 50.358802 -140.90269)
		(size 0.6604)
		(drill 0.3302)
		(layers "F.Cu" "B.Cu")
		(net "P5V_B_SNB")
	)
	(segment
		(start 45.5168 -147.869148)
		(end 45.974 -147.411948)
		(width 0.254)
		(layer "F.Cu")
		(net "P5V_B_ROVP")
	)
	(segment
		(start 45.5168 -148.21662)
		(end 45.5168 -147.869148)
		(width 0.254)
		(layer "F.Cu")
		(net "P5V_B_ROVP")
	)
	(via
		(at 51.781202 -146.08175)
		(size 0.6604)
		(drill 0.3048)
		(layers "F.Cu" "B.Cu")
		(net "P5V_B_ROVP")
	)
	(via
		(at 45.974 -147.411948)
		(size 0.5588)
		(drill 0.3048)
		(layers "F.Cu" "B.Cu")
		(net "P5V_B_ROVP")
	)
	(segment
		(start 50.446178 -144.568926)
		(end 48.804322 -144.568926)
		(width 0.254)
		(layer "B.Cu")
		(net "P5V_B_ROVP")
	)
	(segment
		(start 51.781202 -145.90395)
		(end 50.446178 -144.568926)
		(width 0.254)
		(layer "B.Cu")
		(net "P5V_B_ROVP")
	)
	(segment
		(start 51.781202 -146.08175)
		(end 51.781202 -145.90395)
		(width 0.254)
		(layer "B.Cu")
		(net "P5V_B_ROVP")
	)
	(segment
		(start 51.781202 -146.08175)
		(end 49.77765 -146.08175)
		(width 0.254)
		(layer "In2.Cu")
		(net "P5V_B_ROVP")
	)
	(segment
		(start 49.77765 -146.08175)
		(end 48.447452 -147.411948)
		(width 0.254)
		(layer "In2.Cu")
		(net "P5V_B_ROVP")
	)
	(segment
		(start 48.447452 -147.411948)
		(end 45.974 -147.411948)
		(width 0.254)
		(layer "In2.Cu")
		(net "P5V_B_ROVP")
	)
	(segment
		(start 43.780202 -145.72615)
		(end 44.389802 -146.33575)
		(width 0.254)
		(layer "F.Cu")
		(net "P5V_B_RF")
	)
	(segment
		(start 44.466002 -147.37715)
		(end 44.389802 -147.30095)
		(width 0.254)
		(layer "F.Cu")
		(net "P5V_B_RF")
	)
	(segment
		(start 43.437302 -145.72615)
		(end 43.780202 -145.72615)
		(width 0.254)
		(layer "F.Cu")
		(net "P5V_B_RF")
	)
	(segment
		(start 44.389802 -147.30095)
		(end 44.389802 -146.33575)
		(width 0.254)
		(layer "F.Cu")
		(net "P5V_B_RF")
	)
	(segment
		(start 44.466002 -148.20265)
		(end 44.466002 -147.37715)
		(width 0.254)
		(layer "F.Cu")
		(net "P5V_B_RF")
	)
	(via
		(at 44.389802 -147.30095)
		(size 0.5588)
		(drill 0.3048)
		(layers "F.Cu" "B.Cu")
		(net "P5V_B_RF")
	)
	(via
		(at 44.389802 -146.33575)
		(size 0.6604)
		(drill 0.3302)
		(layers "F.Cu" "B.Cu")
		(net "P5V_B_RF")
	)
	(segment
		(start 44.389802 -147.30095)
		(end 43.905678 -146.816826)
		(width 0.254)
		(layer "B.Cu")
		(net "P5V_B_RF")
	)
	(segment
		(start 43.905678 -146.816826)
		(end 43.905678 -146.568922)
		(width 0.254)
		(layer "B.Cu")
		(net "P5V_B_RF")
	)
	(segment
		(start 47.53483 -149.354286)
		(end 47.018956 -149.87016)
		(width 0.254)
		(layer "F.Cu")
		(net "P5V_B_MODE")
	)
	(segment
		(start 47.018956 -150.716996)
		(end 46.675802 -151.06015)
		(width 0.254)
		(layer "F.Cu")
		(net "P5V_B_MODE")
	)
	(segment
		(start 47.535338 -149.11451)
		(end 47.53483 -149.115018)
		(width 0.254)
		(layer "F.Cu")
		(net "P5V_B_MODE")
	)
	(segment
		(start 42.713402 -151.31415)
		(end 46.421802 -151.31415)
		(width 0.254)
		(layer "F.Cu")
		(net "P5V_B_MODE")
	)
	(segment
		(start 47.535338 -148.082254)
		(end 47.535338 -149.11451)
		(width 0.254)
		(layer "F.Cu")
		(net "P5V_B_MODE")
	)
	(segment
		(start 47.018956 -149.87016)
		(end 47.018956 -150.716996)
		(width 0.254)
		(layer "F.Cu")
		(net "P5V_B_MODE")
	)
	(segment
		(start 41.951402 -147.481798)
		(end 41.951402 -150.55215)
		(width 0.254)
		(layer "F.Cu")
		(net "P5V_B_MODE")
	)
	(segment
		(start 42.2656 -147.1676)
		(end 41.951402 -147.481798)
		(width 0.254)
		(layer "F.Cu")
		(net "P5V_B_MODE")
	)
	(segment
		(start 41.951402 -150.55215)
		(end 42.713402 -151.31415)
		(width 0.254)
		(layer "F.Cu")
		(net "P5V_B_MODE")
	)
	(segment
		(start 46.421802 -151.31415)
		(end 46.675802 -151.06015)
		(width 0.254)
		(layer "F.Cu")
		(net "P5V_B_MODE")
	)
	(segment
		(start 47.53483 -149.115018)
		(end 47.53483 -149.354286)
		(width 0.254)
		(layer "F.Cu")
		(net "P5V_B_MODE")
	)
	(via
		(at 46.675802 -151.06015)
		(size 0.6604)
		(drill 0.3302)
		(layers "F.Cu" "B.Cu")
		(net "P5V_B_MODE")
	)
	(via
		(at 42.2656 -147.1676)
		(size 0.5588)
		(drill 0.3048)
		(layers "F.Cu" "B.Cu")
		(net "P5V_B_MODE")
	)
	(segment
		(start 43.124628 -145.568924)
		(end 43.905678 -145.568924)
		(width 0.254)
		(layer "B.Cu")
		(net "P5V_B_MODE")
	)
	(segment
		(start 42.2656 -146.427952)
		(end 43.124628 -145.568924)
		(width 0.254)
		(layer "B.Cu")
		(net "P5V_B_MODE")
	)
	(segment
		(start 42.2656 -147.1676)
		(end 42.2656 -146.427952)
		(width 0.254)
		(layer "B.Cu")
		(net "P5V_B_MODE")
	)
	(via
		(at 56.581802 -151.31415)
		(size 0.6096)
		(drill 0.3048)
		(layers "F.Cu" "B.Cu")
		(net "P5V_B_LL_R")
	)
	(segment
		(start 53.406802 -138.86815)
		(end 53.406802 -139.88415)
		(width 0.508)
		(layer "F.Cu")
		(net "P5V_B_LL")
	)
	(segment
		(start 53.305202 -142.473426)
		(end 53.305202 -143.92275)
		(width 0.6096)
		(layer "F.Cu")
		(net "P5V_B_LL")
	)
	(segment
		(start 53.004212 -140.90269)
		(end 53.406802 -140.5001)
		(width 0.508)
		(layer "F.Cu")
		(net "P5V_B_LL")
	)
	(segment
		(start 53.406802 -140.5001)
		(end 53.406802 -139.88415)
		(width 0.508)
		(layer "F.Cu")
		(net "P5V_B_LL")
	)
	(segment
		(start 53.011324 -142.179548)
		(end 53.305202 -142.473426)
		(width 0.6096)
		(layer "F.Cu")
		(net "P5V_B_LL")
	)
	(via
		(at 53.406802 -138.86815)
		(size 0.5588)
		(drill 0.3048)
		(layers "F.Cu" "B.Cu")
		(net "P5V_B_LL")
	)
	(via
		(at 53.406802 -139.88415)
		(size 0.6604)
		(drill 0.3302)
		(layers "F.Cu" "B.Cu")
		(net "P5V_B_LL")
	)
	(via
		(at 53.305202 -143.92275)
		(size 0.7112)
		(drill 0.4064)
		(layers "F.Cu" "B.Cu")
		(net "P5V_B_LL")
	)
	(segment
		(start 55.438802 -142.799054)
		(end 55.438802 -142.04315)
		(width 0.508)
		(layer "B.Cu")
		(net "P5V_B_LL")
	)
	(segment
		(start 55.431944 -147.808696)
		(end 55.431944 -142.805912)
		(width 0.508)
		(layer "B.Cu")
		(net "P5V_B_LL")
	)
	(segment
		(start 55.438802 -142.04315)
		(end 54.645052 -141.2494)
		(width 0.508)
		(layer "B.Cu")
		(net "P5V_B_LL")
	)
	(segment
		(start 54.645052 -141.2494)
		(end 52.067206 -141.2494)
		(width 0.508)
		(layer "B.Cu")
		(net "P5V_B_LL")
	)
	(segment
		(start 55.431944 -142.805912)
		(end 55.438802 -142.799054)
		(width 0.508)
		(layer "B.Cu")
		(net "P5V_B_LL")
	)
	(segment
		(start 51.679602 -150.86965)
		(end 51.768502 -150.78075)
		(width 0.254)
		(layer "F.Cu")
		(net "P5V_B_EN_R")
	)
	(segment
		(start 49.469802 -151.06015)
		(end 50.549302 -151.06015)
		(width 0.254)
		(layer "F.Cu")
		(net "P5V_B_EN_R")
	)
	(segment
		(start 49.469802 -150.36165)
		(end 49.660302 -150.17115)
		(width 0.254)
		(layer "F.Cu")
		(net "P5V_B_EN_R")
	)
	(segment
		(start 50.739802 -150.86965)
		(end 51.679602 -150.86965)
		(width 0.254)
		(layer "F.Cu")
		(net "P5V_B_EN_R")
	)
	(segment
		(start 49.660302 -150.17115)
		(end 49.660302 -149.79015)
		(width 0.254)
		(layer "F.Cu")
		(net "P5V_B_EN_R")
	)
	(segment
		(start 50.549302 -151.06015)
		(end 50.739802 -150.86965)
		(width 0.254)
		(layer "F.Cu")
		(net "P5V_B_EN_R")
	)
	(segment
		(start 49.469802 -151.06015)
		(end 49.469802 -150.36165)
		(width 0.254)
		(layer "F.Cu")
		(net "P5V_B_EN_R")
	)
	(segment
		(start 50.231802 -147.651216)
		(end 50.24374 -147.639278)
		(width 0.254)
		(layer "F.Cu")
		(net "P5V_B_EN_R")
	)
	(segment
		(start 49.660302 -149.79015)
		(end 49.660302 -149.21865)
		(width 0.254)
		(layer "F.Cu")
		(net "P5V_B_EN_R")
	)
	(segment
		(start 50.231802 -148.64715)
		(end 50.231802 -147.651216)
		(width 0.254)
		(layer "F.Cu")
		(net "P5V_B_EN_R")
	)
	(segment
		(start 49.660302 -149.21865)
		(end 50.231802 -148.64715)
		(width 0.254)
		(layer "F.Cu")
		(net "P5V_B_EN_R")
	)
	(via
		(at 50.24374 -147.639278)
		(size 0.5588)
		(drill 0.3048)
		(layers "F.Cu" "B.Cu")
		(net "P5V_B_EN_R")
	)
	(via
		(at 49.469802 -151.06015)
		(size 0.6604)
		(drill 0.3302)
		(layers "F.Cu" "B.Cu")
		(net "P5V_B_EN_R")
	)
	(segment
		(start 50.24374 -147.639278)
		(end 50.257202 -147.625816)
		(width 0.254)
		(layer "B.Cu")
		(net "P5V_B_EN_R")
	)
	(segment
		(start 50.257202 -146.91995)
		(end 49.406048 -146.068796)
		(width 0.254)
		(layer "B.Cu")
		(net "P5V_B_EN_R")
	)
	(segment
		(start 50.257202 -147.625816)
		(end 50.257202 -146.91995)
		(width 0.254)
		(layer "B.Cu")
		(net "P5V_B_EN_R")
	)
	(segment
		(start 49.406048 -146.068796)
		(end 48.804322 -146.068796)
		(width 0.254)
		(layer "B.Cu")
		(net "P5V_B_EN_R")
	)
	(via
		(at 74.615802 -148.06295)
		(size 0.5588)
		(drill 0.3048)
		(layers "F.Cu" "B.Cu")
		(net "P5V_B_CC")
	)
	(via
		(at 53.864002 -148.778214)
		(size 0.6604)
		(drill 0.3048)
		(layers "F.Cu" "B.Cu")
		(net "P5V_B_CC")
	)
	(segment
		(start 53.864002 -148.778214)
		(end 52.711604 -148.778214)
		(width 0.254)
		(layer "B.Cu")
		(net "P5V_B_CC")
	)
	(segment
		(start 74.615802 -147.44065)
		(end 74.615802 -148.06295)
		(width 0.254)
		(layer "B.Cu")
		(net "P5V_B_CC")
	)
	(segment
		(start 53.864002 -148.778214)
		(end 73.900538 -148.778214)
		(width 0.254)
		(layer "In2.Cu")
		(net "P5V_B_CC")
	)
	(segment
		(start 73.900538 -148.778214)
		(end 74.615802 -148.06295)
		(width 0.254)
		(layer "In2.Cu")
		(net "P5V_B_CC")
	)
	(segment
		(start 411.539944 -293.676324)
		(end 410.350208 -293.676324)
		(width 0.508)
		(layer "F.Cu")
		(net "P5V_B")
	)
	(segment
		(start 466.4456 -293.5478)
		(end 466.450934 -293.553134)
		(width 0.508)
		(layer "F.Cu")
		(net "P5V_B")
	)
	(segment
		(start 466.4456 -292.5826)
		(end 466.4456 -293.5478)
		(width 0.508)
		(layer "F.Cu")
		(net "P5V_B")
	)
	(segment
		(start 130.328162 -303.569878)
		(end 130.328162 -302.401478)
		(width 0.508)
		(layer "F.Cu")
		(net "P5V_B")
	)
	(segment
		(start 267.87475 12.97686)
		(end 267.866622 12.984988)
		(width 0.508)
		(layer "F.Cu")
		(net "P5V_B")
	)
	(segment
		(start 343.235534 -293.662862)
		(end 343.235534 -292.748462)
		(width 0.508)
		(layer "F.Cu")
		(net "P5V_B")
	)
	(segment
		(start 374.892062 -293.630858)
		(end 374.892062 -292.716458)
		(width 0.508)
		(layer "F.Cu")
		(net "P5V_B")
	)
	(segment
		(start 341.965534 -293.662862)
		(end 343.235534 -293.662862)
		(width 0.508)
		(layer "F.Cu")
		(net "P5V_B")
	)
	(segment
		(start 267.87475 11.9888)
		(end 267.87475 12.97686)
		(width 0.508)
		(layer "F.Cu")
		(net "P5V_B")
	)
	(segment
		(start 97.497646 -303.591468)
		(end 97.497646 -302.471582)
		(width 0.508)
		(layer "F.Cu")
		(net "P5V_B")
	)
	(segment
		(start 270.82115 11.1633)
		(end 270.82115 10.230612)
		(width 0.508)
		(layer "F.Cu")
		(net "P5V_B")
	)
	(segment
		(start 65.936876 -303.623472)
		(end 65.936876 -302.455072)
		(width 0.508)
		(layer "F.Cu")
		(net "P5V_B")
	)
	(segment
		(start 436.401718 -293.662862)
		(end 436.401718 -292.748462)
		(width 0.508)
		(layer "F.Cu")
		(net "P5V_B")
	)
	(segment
		(start 34.397188 -303.666398)
		(end 34.397188 -302.497998)
		(width 0.508)
		(layer "F.Cu")
		(net "P5V_B")
	)
	(segment
		(start 466.450934 -293.553134)
		(end 467.635336 -293.553134)
		(width 0.508)
		(layer "F.Cu")
		(net "P5V_B")
	)
	(segment
		(start 305.540156 -293.673276)
		(end 304.32502 -292.45814)
		(width 0.508)
		(layer "F.Cu")
		(net "P5V_B")
	)
	(segment
		(start 410.350208 -292.257226)
		(end 410.440886 -292.166548)
		(width 0.508)
		(layer "F.Cu")
		(net "P5V_B")
	)
	(segment
		(start 437.671718 -293.662862)
		(end 437.671718 -292.748462)
		(width 0.508)
		(layer "F.Cu")
		(net "P5V_B")
	)
	(segment
		(start 270.9164 19.189446)
		(end 270.9164 18.4912)
		(width 0.508)
		(layer "F.Cu")
		(net "P5V_B")
	)
	(segment
		(start 308.91607 -293.673276)
		(end 307.64607 -293.673276)
		(width 0.508)
		(layer "F.Cu")
		(net "P5V_B")
	)
	(segment
		(start 410.350208 -293.676324)
		(end 410.350208 -292.257226)
		(width 0.508)
		(layer "F.Cu")
		(net "P5V_B")
	)
	(segment
		(start 267.866622 12.984988)
		(end 267.866622 14.629638)
		(width 0.3048)
		(layer "F.Cu")
		(net "P5V_B")
	)
	(segment
		(start 129.058162 -303.569878)
		(end 129.058162 -302.401478)
		(width 0.508)
		(layer "F.Cu")
		(net "P5V_B")
	)
	(segment
		(start 6.35 -303.53)
		(end 6.35 -302.3616)
		(width 0.508)
		(layer "F.Cu")
		(net "P5V_B")
	)
	(segment
		(start 373.622062 -293.630858)
		(end 373.622062 -292.716458)
		(width 0.508)
		(layer "F.Cu")
		(net "P5V_B")
	)
	(segment
		(start 270.655034 19.450812)
		(end 270.9164 19.189446)
		(width 0.508)
		(layer "F.Cu")
		(net "P5V_B")
	)
	(segment
		(start 35.667188 -303.666398)
		(end 35.667188 -302.497998)
		(width 0.508)
		(layer "F.Cu")
		(net "P5V_B")
	)
	(segment
		(start 7.62 -303.53)
		(end 7.62 -302.3616)
		(width 0.508)
		(layer "F.Cu")
		(net "P5V_B")
	)
	(segment
		(start 67.206876 -303.623472)
		(end 67.206876 -302.455072)
		(width 0.508)
		(layer "F.Cu")
		(net "P5V_B")
	)
	(segment
		(start 161.878264 -303.548796)
		(end 161.878264 -302.380396)
		(width 0.508)
		(layer "F.Cu")
		(net "P5V_B")
	)
	(segment
		(start 160.608264 -303.548796)
		(end 160.608264 -302.380396)
		(width 0.508)
		(layer "F.Cu")
		(net "P5V_B")
	)
	(segment
		(start 307.64607 -293.673276)
		(end 305.540156 -293.673276)
		(width 0.508)
		(layer "F.Cu")
		(net "P5V_B")
	)
	(segment
		(start 98.767646 -303.591468)
		(end 98.767646 -302.551592)
		(width 0.508)
		(layer "F.Cu")
		(net "P5V_B")
	)
	(via
		(at 304.32502 -292.45814)
		(size 0.5588)
		(drill 0.3048)
		(layers "F.Cu" "B.Cu")
		(net "P5V_B")
	)
	(via
		(at 466.4456 -292.5826)
		(size 0.5588)
		(drill 0.3048)
		(layers "F.Cu" "B.Cu")
		(net "P5V_B")
	)
	(via
		(at 222.2246 -361.1626)
		(size 0.5588)
		(drill 0.3048)
		(layers "F.Cu" "B.Cu")
		(net "P5V_B")
	)
	(via
		(at 436.401718 -292.748462)
		(size 0.5588)
		(drill 0.3048)
		(layers "F.Cu" "B.Cu")
		(net "P5V_B")
	)
	(via
		(at 221.536768 -361.820968)
		(size 0.5588)
		(drill 0.3048)
		(layers "F.Cu" "B.Cu")
		(net "P5V_B")
	)
	(via
		(at 343.235534 -292.748462)
		(size 0.5588)
		(drill 0.3048)
		(layers "F.Cu" "B.Cu")
		(net "P5V_B")
	)
	(via
		(at 221.9452 -360.2228)
		(size 0.5588)
		(drill 0.3048)
		(layers "F.Cu" "B.Cu")
		(net "P5V_B")
	)
	(via
		(at 161.878264 -302.380396)
		(size 0.5588)
		(drill 0.3048)
		(layers "F.Cu" "B.Cu")
		(net "P5V_B")
	)
	(via
		(at 267.866622 12.984988)
		(size 0.5588)
		(drill 0.3048)
		(layers "F.Cu" "B.Cu")
		(net "P5V_B")
	)
	(via
		(at 35.667188 -302.497998)
		(size 0.5588)
		(drill 0.3048)
		(layers "F.Cu" "B.Cu")
		(net "P5V_B")
	)
	(via
		(at 374.892062 -292.716458)
		(size 0.5588)
		(drill 0.3048)
		(layers "F.Cu" "B.Cu")
		(net "P5V_B")
	)
	(via
		(at 65.936876 -302.455072)
		(size 0.5588)
		(drill 0.3048)
		(layers "F.Cu" "B.Cu")
		(net "P5V_B")
	)
	(via
		(at 290.1696 -362.6358)
		(size 0.5588)
		(drill 0.3048)
		(layers "F.Cu" "B.Cu")
		(net "P5V_B")
	)
	(via
		(at 97.497646 -302.471582)
		(size 0.5588)
		(drill 0.3048)
		(layers "F.Cu" "B.Cu")
		(net "P5V_B")
	)
	(via
		(at 222.43796 -359.42778)
		(size 0.5588)
		(drill 0.3048)
		(layers "F.Cu" "B.Cu")
		(net "P5V_B")
	)
	(via
		(at 290.5506 -363.474)
		(size 0.5588)
		(drill 0.3048)
		(layers "F.Cu" "B.Cu")
		(net "P5V_B")
	)
	(via
		(at 259.646928 -359.372154)
		(size 0.6096)
		(drill 0.3048)
		(layers "F.Cu" "B.Cu")
		(net "P5V_B")
	)
	(via
		(at 6.35 -302.3616)
		(size 0.5588)
		(drill 0.3048)
		(layers "F.Cu" "B.Cu")
		(net "P5V_B")
	)
	(via
		(at 270.82115 10.230612)
		(size 0.5588)
		(drill 0.3048)
		(layers "F.Cu" "B.Cu")
		(net "P5V_B")
	)
	(via
		(at 291.084508 -362.688124)
		(size 0.5588)
		(drill 0.3048)
		(layers "F.Cu" "B.Cu")
		(net "P5V_B")
	)
	(via
		(at 410.440886 -292.166548)
		(size 0.5588)
		(drill 0.3048)
		(layers "F.Cu" "B.Cu")
		(net "P5V_B")
	)
	(via
		(at 373.622062 -292.716458)
		(size 0.5588)
		(drill 0.3048)
		(layers "F.Cu" "B.Cu")
		(net "P5V_B")
	)
	(via
		(at 291.5666 -361.061)
		(size 0.5588)
		(drill 0.3048)
		(layers "F.Cu" "B.Cu")
		(net "P5V_B")
	)
	(via
		(at 437.671718 -292.748462)
		(size 0.5588)
		(drill 0.3048)
		(layers "F.Cu" "B.Cu")
		(net "P5V_B")
	)
	(via
		(at 129.058162 -302.401478)
		(size 0.5588)
		(drill 0.3048)
		(layers "F.Cu" "B.Cu")
		(net "P5V_B")
	)
	(via
		(at 160.608264 -302.380396)
		(size 0.5588)
		(drill 0.3048)
		(layers "F.Cu" "B.Cu")
		(net "P5V_B")
	)
	(via
		(at 7.62 -302.3616)
		(size 0.5588)
		(drill 0.3048)
		(layers "F.Cu" "B.Cu")
		(net "P5V_B")
	)
	(via
		(at 67.206876 -302.455072)
		(size 0.5588)
		(drill 0.3048)
		(layers "F.Cu" "B.Cu")
		(net "P5V_B")
	)
	(via
		(at 270.9164 18.4912)
		(size 0.5588)
		(drill 0.3048)
		(layers "F.Cu" "B.Cu")
		(net "P5V_B")
	)
	(via
		(at 98.767646 -302.551592)
		(size 0.5588)
		(drill 0.3048)
		(layers "F.Cu" "B.Cu")
		(net "P5V_B")
	)
	(via
		(at 221.343728 -360.916728)
		(size 0.5588)
		(drill 0.3048)
		(layers "F.Cu" "B.Cu")
		(net "P5V_B")
	)
	(via
		(at 130.328162 -302.401478)
		(size 0.5588)
		(drill 0.3048)
		(layers "F.Cu" "B.Cu")
		(net "P5V_B")
	)
	(via
		(at 34.397188 -302.497998)
		(size 0.5588)
		(drill 0.3048)
		(layers "F.Cu" "B.Cu")
		(net "P5V_B")
	)
	(via
		(at 291.733224 -361.964224)
		(size 0.5588)
		(drill 0.3048)
		(layers "F.Cu" "B.Cu")
		(net "P5V_B")
	)
	(via
		(at 222.861124 -360.457496)
		(size 0.5588)
		(drill 0.3048)
		(layers "F.Cu" "B.Cu")
		(net "P5V_B")
	)
	(via
		(at 290.831778 -361.809284)
		(size 0.5588)
		(drill 0.3048)
		(layers "F.Cu" "B.Cu")
		(net "P5V_B")
	)
	(segment
		(start 25.606502 -250.37415)
		(end 25.606502 -249.37339)
		(width 0.254)
		(layer "F.Cu")
		(net "P5V_A_VREG")
	)
	(segment
		(start 25.606502 -249.37339)
		(end 25.756362 -249.22353)
		(width 0.254)
		(layer "F.Cu")
		(net "P5V_A_VREG")
	)
	(via
		(at 25.756362 -249.22353)
		(size 0.6604)
		(drill 0.3048)
		(layers "F.Cu" "B.Cu")
		(net "P5V_A_VREG")
	)
	(segment
		(start 25.756362 -249.22353)
		(end 25.762966 -249.216926)
		(width 0.254)
		(layer "B.Cu")
		(net "P5V_A_VREG")
	)
	(segment
		(start 24.534622 -249.22353)
		(end 25.756362 -249.22353)
		(width 0.254)
		(layer "B.Cu")
		(net "P5V_A_VREG")
	)
	(segment
		(start 25.762966 -249.216926)
		(end 26.963878 -249.216926)
		(width 0.254)
		(layer "B.Cu")
		(net "P5V_A_VREG")
	)
	(via
		(at 34.052002 -254.81915)
		(size 0.6096)
		(drill 0.3048)
		(layers "F.Cu" "B.Cu")
		(net "P5V_A_VFB_R")
	)
	(segment
		(start 32.718502 -254.43815)
		(end 33.099502 -254.81915)
		(width 0.254)
		(layer "B.Cu")
		(net "P5V_A_VFB_R")
	)
	(segment
		(start 34.23539 -253.4158)
		(end 34.245804 -253.426214)
		(width 0.254)
		(layer "B.Cu")
		(net "P5V_A_VFB_R")
	)
	(segment
		(start 32.7787 -253.4158)
		(end 34.23539 -253.4158)
		(width 0.254)
		(layer "B.Cu")
		(net "P5V_A_VFB_R")
	)
	(segment
		(start 33.099502 -254.81915)
		(end 34.052002 -254.81915)
		(width 0.254)
		(layer "B.Cu")
		(net "P5V_A_VFB_R")
	)
	(segment
		(start 34.245804 -254.625348)
		(end 34.052002 -254.81915)
		(width 0.254)
		(layer "B.Cu")
		(net "P5V_A_VFB_R")
	)
	(segment
		(start 34.245804 -253.426214)
		(end 34.245804 -254.625348)
		(width 0.254)
		(layer "B.Cu")
		(net "P5V_A_VFB_R")
	)
	(via
		(at 36.211002 -255.68275)
		(size 0.6096)
		(drill 0.3048)
		(layers "F.Cu" "B.Cu")
		(net "P5V_A_VFB")
	)
	(segment
		(start 32.883602 -255.68275)
		(end 36.211002 -255.68275)
		(width 0.254)
		(layer "B.Cu")
		(net "P5V_A_VFB")
	)
	(segment
		(start 30.414214 -252.899164)
		(end 30.979364 -252.899164)
		(width 0.254)
		(layer "B.Cu")
		(net "P5V_A_VFB")
	)
	(segment
		(start 31.8897 -253.4158)
		(end 31.8897 -254.377952)
		(width 0.254)
		(layer "B.Cu")
		(net "P5V_A_VFB")
	)
	(segment
		(start 31.829502 -254.62865)
		(end 32.883602 -255.68275)
		(width 0.254)
		(layer "B.Cu")
		(net "P5V_A_VFB")
	)
	(segment
		(start 31.496 -253.4158)
		(end 31.8897 -253.4158)
		(width 0.254)
		(layer "B.Cu")
		(net "P5V_A_VFB")
	)
	(segment
		(start 31.8897 -253.4158)
		(end 31.8897 -252.476)
		(width 0.254)
		(layer "B.Cu")
		(net "P5V_A_VFB")
	)
	(segment
		(start 31.829502 -254.43815)
		(end 31.829502 -254.62865)
		(width 0.254)
		(layer "B.Cu")
		(net "P5V_A_VFB")
	)
	(segment
		(start 31.862522 -252.448822)
		(end 31.862522 -251.216922)
		(width 0.254)
		(layer "B.Cu")
		(net "P5V_A_VFB")
	)
	(segment
		(start 31.8897 -252.476)
		(end 31.862522 -252.448822)
		(width 0.254)
		(layer "B.Cu")
		(net "P5V_A_VFB")
	)
	(segment
		(start 37.460428 -255.68275)
		(end 36.211002 -255.68275)
		(width 0.254)
		(layer "B.Cu")
		(net "P5V_A_VFB")
	)
	(segment
		(start 31.8897 -254.377952)
		(end 31.829502 -254.43815)
		(width 0.254)
		(layer "B.Cu")
		(net "P5V_A_VFB")
	)
	(segment
		(start 30.979364 -252.899164)
		(end 31.496 -253.4158)
		(width 0.254)
		(layer "B.Cu")
		(net "P5V_A_VFB")
	)
	(segment
		(start 38.431724 -254.711454)
		(end 37.460428 -255.68275)
		(width 0.254)
		(layer "B.Cu")
		(net "P5V_A_VFB")
	)
	(segment
		(start 32.020002 -247.35155)
		(end 33.950402 -247.35155)
		(width 0.508)
		(layer "F.Cu")
		(net "P5V_A_VBST_RC")
	)
	(segment
		(start 35.180524 -246.827548)
		(end 34.656522 -247.35155)
		(width 0.508)
		(layer "F.Cu")
		(net "P5V_A_VBST_RC")
	)
	(segment
		(start 34.656522 -247.35155)
		(end 33.950402 -247.35155)
		(width 0.508)
		(layer "F.Cu")
		(net "P5V_A_VBST_RC")
	)
	(via
		(at 33.950402 -247.35155)
		(size 0.6604)
		(drill 0.3302)
		(layers "F.Cu" "B.Cu")
		(net "P5V_A_VBST_RC")
	)
	(segment
		(start 33.57245 -249.482102)
		(end 33.57245 -248.87555)
		(width 0.508)
		(layer "F.Cu")
		(net "P5V_A_VBST")
	)
	(segment
		(start 32.020002 -248.87555)
		(end 33.57245 -248.87555)
		(width 0.508)
		(layer "F.Cu")
		(net "P5V_A_VBST")
	)
	(segment
		(start 33.137602 -249.91695)
		(end 33.57245 -249.482102)
		(width 0.508)
		(layer "F.Cu")
		(net "P5V_A_VBST")
	)
	(via
		(at 33.137602 -249.91695)
		(size 0.5588)
		(drill 0.3048)
		(layers "F.Cu" "B.Cu")
		(net "P5V_A_VBST")
	)
	(via
		(at 33.57245 -248.87555)
		(size 0.6604)
		(drill 0.3302)
		(layers "F.Cu" "B.Cu")
		(net "P5V_A_VBST")
	)
	(segment
		(start 33.137602 -249.91695)
		(end 32.93745 -249.716798)
		(width 0.3048)
		(layer "B.Cu")
		(net "P5V_A_VBST")
	)
	(segment
		(start 32.93745 -249.716798)
		(end 31.862522 -249.716798)
		(width 0.3048)
		(layer "B.Cu")
		(net "P5V_A_VBST")
	)
	(segment
		(start 26.47442 -252.021086)
		(end 25.936702 -252.558804)
		(width 0.254)
		(layer "F.Cu")
		(net "P5V_A_TRIP")
	)
	(segment
		(start 25.936702 -252.558804)
		(end 25.936702 -253.54915)
		(width 0.254)
		(layer "F.Cu")
		(net "P5V_A_TRIP")
	)
	(segment
		(start 25.936702 -254.84455)
		(end 25.936702 -253.54915)
		(width 0.254)
		(layer "F.Cu")
		(net "P5V_A_TRIP")
	)
	(via
		(at 25.936702 -253.54915)
		(size 0.6604)
		(drill 0.3302)
		(layers "F.Cu" "B.Cu")
		(net "P5V_A_TRIP")
	)
	(via
		(at 26.47442 -252.021086)
		(size 0.5588)
		(drill 0.3048)
		(layers "F.Cu" "B.Cu")
		(net "P5V_A_TRIP")
	)
	(segment
		(start 26.127202 -251.673868)
		(end 26.127202 -250.944888)
		(width 0.254)
		(layer "B.Cu")
		(net "P5V_A_TRIP")
	)
	(segment
		(start 26.47442 -252.021086)
		(end 26.127202 -251.673868)
		(width 0.254)
		(layer "B.Cu")
		(net "P5V_A_TRIP")
	)
	(segment
		(start 26.127202 -250.944888)
		(end 26.355294 -250.716796)
		(width 0.254)
		(layer "B.Cu")
		(net "P5V_A_TRIP")
	)
	(segment
		(start 26.355294 -250.716796)
		(end 26.963878 -250.716796)
		(width 0.254)
		(layer "B.Cu")
		(net "P5V_A_TRIP")
	)
	(segment
		(start 28.575 -252.517148)
		(end 29.0322 -252.059948)
		(width 0.254)
		(layer "F.Cu")
		(net "P5V_A_ROVP")
	)
	(segment
		(start 28.575 -252.86462)
		(end 28.575 -252.517148)
		(width 0.254)
		(layer "F.Cu")
		(net "P5V_A_ROVP")
	)
	(via
		(at 34.839402 -250.72975)
		(size 0.6604)
		(drill 0.3048)
		(layers "F.Cu" "B.Cu")
		(net "P5V_A_ROVP")
	)
	(via
		(at 29.0322 -252.059948)
		(size 0.5588)
		(drill 0.3048)
		(layers "F.Cu" "B.Cu")
		(net "P5V_A_ROVP")
	)
	(segment
		(start 34.839402 -250.55195)
		(end 33.504378 -249.216926)
		(width 0.254)
		(layer "B.Cu")
		(net "P5V_A_ROVP")
	)
	(segment
		(start 34.839402 -250.72975)
		(end 34.839402 -250.55195)
		(width 0.254)
		(layer "B.Cu")
		(net "P5V_A_ROVP")
	)
	(segment
		(start 33.504378 -249.216926)
		(end 31.862522 -249.216926)
		(width 0.254)
		(layer "B.Cu")
		(net "P5V_A_ROVP")
	)
	(segment
		(start 33.59785 -250.72975)
		(end 34.839402 -250.72975)
		(width 0.254)
		(layer "In2.Cu")
		(net "P5V_A_ROVP")
	)
	(segment
		(start 32.267652 -252.059948)
		(end 33.59785 -250.72975)
		(width 0.254)
		(layer "In2.Cu")
		(net "P5V_A_ROVP")
	)
	(segment
		(start 29.0322 -252.059948)
		(end 32.267652 -252.059948)
		(width 0.254)
		(layer "In2.Cu")
		(net "P5V_A_ROVP")
	)
	(segment
		(start 26.495502 -250.37415)
		(end 26.838402 -250.37415)
		(width 0.254)
		(layer "F.Cu")
		(net "P5V_A_RF")
	)
	(segment
		(start 27.448002 -251.94895)
		(end 27.448002 -250.98375)
		(width 0.254)
		(layer "F.Cu")
		(net "P5V_A_RF")
	)
	(segment
		(start 27.524202 -252.02515)
		(end 27.448002 -251.94895)
		(width 0.254)
		(layer "F.Cu")
		(net "P5V_A_RF")
	)
	(segment
		(start 27.524202 -252.85065)
		(end 27.524202 -252.02515)
		(width 0.254)
		(layer "F.Cu")
		(net "P5V_A_RF")
	)
	(segment
		(start 26.838402 -250.37415)
		(end 27.448002 -250.98375)
		(width 0.254)
		(layer "F.Cu")
		(net "P5V_A_RF")
	)
	(via
		(at 27.448002 -251.94895)
		(size 0.5588)
		(drill 0.3048)
		(layers "F.Cu" "B.Cu")
		(net "P5V_A_RF")
	)
	(via
		(at 27.448002 -250.98375)
		(size 0.6604)
		(drill 0.3302)
		(layers "F.Cu" "B.Cu")
		(net "P5V_A_RF")
	)
	(segment
		(start 27.448002 -251.94895)
		(end 26.963878 -251.464826)
		(width 0.254)
		(layer "B.Cu")
		(net "P5V_A_RF")
	)
	(segment
		(start 26.963878 -251.464826)
		(end 26.963878 -251.216922)
		(width 0.254)
		(layer "B.Cu")
		(net "P5V_A_RF")
	)
	(segment
		(start 30.593538 -252.730254)
		(end 30.593538 -253.76251)
		(width 0.254)
		(layer "F.Cu")
		(net "P5V_A_MODE")
	)
	(segment
		(start 25.009602 -255.20015)
		(end 25.771602 -255.96215)
		(width 0.254)
		(layer "F.Cu")
		(net "P5V_A_MODE")
	)
	(segment
		(start 30.077156 -254.51816)
		(end 30.077156 -255.364996)
		(width 0.254)
		(layer "F.Cu")
		(net "P5V_A_MODE")
	)
	(segment
		(start 30.59303 -254.002286)
		(end 30.077156 -254.51816)
		(width 0.254)
		(layer "F.Cu")
		(net "P5V_A_MODE")
	)
	(segment
		(start 30.593538 -253.76251)
		(end 30.59303 -253.763018)
		(width 0.254)
		(layer "F.Cu")
		(net "P5V_A_MODE")
	)
	(segment
		(start 25.3238 -251.8156)
		(end 25.009602 -252.129798)
		(width 0.254)
		(layer "F.Cu")
		(net "P5V_A_MODE")
	)
	(segment
		(start 29.480002 -255.96215)
		(end 29.734002 -255.70815)
		(width 0.254)
		(layer "F.Cu")
		(net "P5V_A_MODE")
	)
	(segment
		(start 30.077156 -255.364996)
		(end 29.734002 -255.70815)
		(width 0.254)
		(layer "F.Cu")
		(net "P5V_A_MODE")
	)
	(segment
		(start 30.59303 -253.763018)
		(end 30.59303 -254.002286)
		(width 0.254)
		(layer "F.Cu")
		(net "P5V_A_MODE")
	)
	(segment
		(start 25.771602 -255.96215)
		(end 29.480002 -255.96215)
		(width 0.254)
		(layer "F.Cu")
		(net "P5V_A_MODE")
	)
	(segment
		(start 25.009602 -252.129798)
		(end 25.009602 -255.20015)
		(width 0.254)
		(layer "F.Cu")
		(net "P5V_A_MODE")
	)
	(via
		(at 29.734002 -255.70815)
		(size 0.6604)
		(drill 0.3302)
		(layers "F.Cu" "B.Cu")
		(net "P5V_A_MODE")
	)
	(via
		(at 25.3238 -251.8156)
		(size 0.5588)
		(drill 0.3048)
		(layers "F.Cu" "B.Cu")
		(net "P5V_A_MODE")
	)
	(segment
		(start 25.3238 -251.8156)
		(end 25.3238 -251.075952)
		(width 0.254)
		(layer "B.Cu")
		(net "P5V_A_MODE")
	)
	(segment
		(start 26.182828 -250.216924)
		(end 26.963878 -250.216924)
		(width 0.254)
		(layer "B.Cu")
		(net "P5V_A_MODE")
	)
	(segment
		(start 25.3238 -251.075952)
		(end 26.182828 -250.216924)
		(width 0.254)
		(layer "B.Cu")
		(net "P5V_A_MODE")
	)
	(via
		(at 39.640002 -255.96215)
		(size 0.6096)
		(drill 0.3048)
		(layers "F.Cu" "B.Cu")
		(net "P5V_A_LL_R")
	)
	(segment
		(start 36.062412 -245.55069)
		(end 36.062412 -243.477288)
		(width 0.6096)
		(layer "F.Cu")
		(net "P5V_A_LL")
	)
	(segment
		(start 36.069524 -246.827548)
		(end 36.069524 -248.51995)
		(width 0.6096)
		(layer "F.Cu")
		(net "P5V_A_LL")
	)
	(via
		(at 36.062412 -243.477288)
		(size 0.7112)
		(drill 0.4064)
		(layers "F.Cu" "B.Cu")
		(net "P5V_A_LL")
	)
	(via
		(at 36.069524 -248.51995)
		(size 0.7112)
		(drill 0.4064)
		(layers "F.Cu" "B.Cu")
		(net "P5V_A_LL")
	)
	(via
		(at 32.184594 -243.801138)
		(size 0.6096)
		(drill 0.3048)
		(layers "F.Cu" "B.Cu")
		(net "P5V_A_LL")
	)
	(segment
		(start 38.497002 -246.69115)
		(end 37.703252 -245.8974)
		(width 0.508)
		(layer "B.Cu")
		(net "P5V_A_LL")
	)
	(segment
		(start 38.497002 -247.447054)
		(end 38.497002 -246.69115)
		(width 0.508)
		(layer "B.Cu")
		(net "P5V_A_LL")
	)
	(segment
		(start 38.490144 -247.453912)
		(end 38.497002 -247.447054)
		(width 0.508)
		(layer "B.Cu")
		(net "P5V_A_LL")
	)
	(segment
		(start 37.703252 -245.8974)
		(end 35.125406 -245.8974)
		(width 0.508)
		(layer "B.Cu")
		(net "P5V_A_LL")
	)
	(segment
		(start 38.490144 -252.456696)
		(end 38.490144 -247.453912)
		(width 0.508)
		(layer "B.Cu")
		(net "P5V_A_LL")
	)
	(segment
		(start 33.290002 -253.29515)
		(end 32.718502 -253.86665)
		(width 0.254)
		(layer "F.Cu")
		(net "P5V_A_EN_R")
	)
	(segment
		(start 34.737802 -255.51765)
		(end 33.798002 -255.51765)
		(width 0.254)
		(layer "F.Cu")
		(net "P5V_A_EN_R")
	)
	(segment
		(start 32.718502 -254.43815)
		(end 32.718502 -254.81915)
		(width 0.254)
		(layer "F.Cu")
		(net "P5V_A_EN_R")
	)
	(segment
		(start 33.290002 -252.299216)
		(end 33.290002 -253.29515)
		(width 0.254)
		(layer "F.Cu")
		(net "P5V_A_EN_R")
	)
	(segment
		(start 32.528002 -255.00965)
		(end 32.528002 -255.70815)
		(width 0.254)
		(layer "F.Cu")
		(net "P5V_A_EN_R")
	)
	(segment
		(start 32.718502 -253.86665)
		(end 32.718502 -254.43815)
		(width 0.254)
		(layer "F.Cu")
		(net "P5V_A_EN_R")
	)
	(segment
		(start 33.798002 -255.51765)
		(end 33.607502 -255.70815)
		(width 0.254)
		(layer "F.Cu")
		(net "P5V_A_EN_R")
	)
	(segment
		(start 32.718502 -254.81915)
		(end 32.528002 -255.00965)
		(width 0.254)
		(layer "F.Cu")
		(net "P5V_A_EN_R")
	)
	(segment
		(start 33.30194 -252.287278)
		(end 33.290002 -252.299216)
		(width 0.254)
		(layer "F.Cu")
		(net "P5V_A_EN_R")
	)
	(segment
		(start 34.826702 -255.42875)
		(end 34.737802 -255.51765)
		(width 0.254)
		(layer "F.Cu")
		(net "P5V_A_EN_R")
	)
	(segment
		(start 33.607502 -255.70815)
		(end 32.528002 -255.70815)
		(width 0.254)
		(layer "F.Cu")
		(net "P5V_A_EN_R")
	)
	(via
		(at 32.528002 -255.70815)
		(size 0.6604)
		(drill 0.3302)
		(layers "F.Cu" "B.Cu")
		(net "P5V_A_EN_R")
	)
	(via
		(at 33.30194 -252.287278)
		(size 0.5588)
		(drill 0.3048)
		(layers "F.Cu" "B.Cu")
		(net "P5V_A_EN_R")
	)
	(segment
		(start 33.315402 -252.273816)
		(end 33.315402 -251.56795)
		(width 0.254)
		(layer "B.Cu")
		(net "P5V_A_EN_R")
	)
	(segment
		(start 33.315402 -251.56795)
		(end 32.464248 -250.716796)
		(width 0.254)
		(layer "B.Cu")
		(net "P5V_A_EN_R")
	)
	(segment
		(start 33.30194 -252.287278)
		(end 33.315402 -252.273816)
		(width 0.254)
		(layer "B.Cu")
		(net "P5V_A_EN_R")
	)
	(segment
		(start 32.464248 -250.716796)
		(end 31.862522 -250.716796)
		(width 0.254)
		(layer "B.Cu")
		(net "P5V_A_EN_R")
	)
	(segment
		(start 36.922202 -253.426214)
		(end 37.637466 -252.71095)
		(width 0.254)
		(layer "F.Cu")
		(net "P5V_A_CC")
	)
	(segment
		(start 37.637466 -252.71095)
		(end 57.674002 -252.71095)
		(width 0.254)
		(layer "F.Cu")
		(net "P5V_A_CC")
	)
	(via
		(at 36.922202 -253.426214)
		(size 0.6604)
		(drill 0.3048)
		(layers "F.Cu" "B.Cu")
		(net "P5V_A_CC")
	)
	(via
		(at 57.674002 -252.71095)
		(size 0.5588)
		(drill 0.3048)
		(layers "F.Cu" "B.Cu")
		(net "P5V_A_CC")
	)
	(segment
		(start 57.674002 -252.08865)
		(end 57.674002 -252.71095)
		(width 0.254)
		(layer "B.Cu")
		(net "P5V_A_CC")
	)
	(segment
		(start 36.922202 -253.426214)
		(end 35.769804 -253.426214)
		(width 0.254)
		(layer "B.Cu")
		(net "P5V_A_CC")
	)
	(segment
		(start 484.827326 -233.356658)
		(end 483.220014 -231.749346)
		(width 0.254)
		(layer "F.Cu")
		(net "P5V_A_4_PGOOD")
	)
	(segment
		(start 484.827326 -237.040674)
		(end 484.827326 -233.356658)
		(width 0.254)
		(layer "F.Cu")
		(net "P5V_A_4_PGOOD")
	)
	(segment
		(start 483.220014 -231.749346)
		(end 483.220014 -225.679)
		(width 0.254)
		(layer "F.Cu")
		(net "P5V_A_4_PGOOD")
	)
	(segment
		(start 483.616 -238.252)
		(end 484.827326 -237.040674)
		(width 0.254)
		(layer "F.Cu")
		(net "P5V_A_4_PGOOD")
	)
	(via
		(at 483.616 -238.252)
		(size 0.5588)
		(drill 0.3048)
		(layers "F.Cu" "B.Cu")
		(net "P5V_A_4_PGOOD")
	)
	(via
		(at 483.220014 -225.679)
		(size 0.5588)
		(drill 0.3048)
		(layers "F.Cu" "B.Cu")
		(net "P5V_A_4_PGOOD")
	)
	(segment
		(start 480.695 -225.3615)
		(end 481.7745 -225.3615)
		(width 0.254)
		(layer "B.Cu")
		(net "P5V_A_4_PGOOD")
	)
	(segment
		(start 476.346266 -229.284784)
		(end 476.71355 -228.9175)
		(width 0.254)
		(layer "B.Cu")
		(net "P5V_A_4_PGOOD")
	)
	(segment
		(start 481.7745 -225.3615)
		(end 482.092 -225.679)
		(width 0.254)
		(layer "B.Cu")
		(net "P5V_A_4_PGOOD")
	)
	(segment
		(start 477.901 -225.933)
		(end 478.4725 -225.3615)
		(width 0.254)
		(layer "B.Cu")
		(net "P5V_A_4_PGOOD")
	)
	(segment
		(start 476.042228 -230.229664)
		(end 476.042228 -229.56901)
		(width 0.254)
		(layer "B.Cu")
		(net "P5V_A_4_PGOOD")
	)
	(segment
		(start 477.901 -227.981256)
		(end 477.901 -225.933)
		(width 0.254)
		(layer "B.Cu")
		(net "P5V_A_4_PGOOD")
	)
	(segment
		(start 479.552 -225.3615)
		(end 480.695 -225.3615)
		(width 0.254)
		(layer "B.Cu")
		(net "P5V_A_4_PGOOD")
	)
	(segment
		(start 482.6635 -238.252)
		(end 483.616 -238.252)
		(width 0.254)
		(layer "B.Cu")
		(net "P5V_A_4_PGOOD")
	)
	(segment
		(start 476.964756 -228.9175)
		(end 477.901 -227.981256)
		(width 0.254)
		(layer "B.Cu")
		(net "P5V_A_4_PGOOD")
	)
	(segment
		(start 482.092 -225.679)
		(end 483.220014 -225.679)
		(width 0.254)
		(layer "B.Cu")
		(net "P5V_A_4_PGOOD")
	)
	(segment
		(start 476.326454 -229.284784)
		(end 476.346266 -229.284784)
		(width 0.254)
		(layer "B.Cu")
		(net "P5V_A_4_PGOOD")
	)
	(segment
		(start 476.042228 -229.56901)
		(end 476.326454 -229.284784)
		(width 0.254)
		(layer "B.Cu")
		(net "P5V_A_4_PGOOD")
	)
	(segment
		(start 476.71355 -228.9175)
		(end 476.964756 -228.9175)
		(width 0.254)
		(layer "B.Cu")
		(net "P5V_A_4_PGOOD")
	)
	(segment
		(start 478.4725 -225.3615)
		(end 479.552 -225.3615)
		(width 0.254)
		(layer "B.Cu")
		(net "P5V_A_4_PGOOD")
	)
	(segment
		(start 301.765208 -336.884264)
		(end 301.765208 -278.695658)
		(width 0.508)
		(layer "F.Cu")
		(net "P5V_A_4")
	)
	(segment
		(start 285.2166 -365.0488)
		(end 291.3888 -365.0488)
		(width 0.508)
		(layer "F.Cu")
		(net "P5V_A_4")
	)
	(segment
		(start 261.349998 -363.584998)
		(end 283.752798 -363.584998)
		(width 0.508)
		(layer "F.Cu")
		(net "P5V_A_4")
	)
	(segment
		(start 440.694826 -128.016)
		(end 440.694826 -129.1844)
		(width 0.508)
		(layer "F.Cu")
		(net "P5V_A_4")
	)
	(segment
		(start 474.383608 -215.013032)
		(end 474.383608 -219.816934)
		(width 0.508)
		(layer "F.Cu")
		(net "P5V_A_4")
	)
	(segment
		(start 409.144978 -128.016)
		(end 409.144978 -129.1844)
		(width 0.508)
		(layer "F.Cu")
		(net "P5V_A_4")
	)
	(segment
		(start 410.414978 -128.016)
		(end 410.414978 -129.1844)
		(width 0.508)
		(layer "F.Cu")
		(net "P5V_A_4")
	)
	(segment
		(start 472.244928 -128.016)
		(end 472.244928 -129.1844)
		(width 0.508)
		(layer "F.Cu")
		(net "P5V_A_4")
	)
	(segment
		(start 297.21556 -274.14601)
		(end 297.21556 -265.160506)
		(width 0.508)
		(layer "F.Cu")
		(net "P5V_A_4")
	)
	(segment
		(start 292.498526 -363.939074)
		(end 292.498526 -346.150946)
		(width 0.508)
		(layer "F.Cu")
		(net "P5V_A_4")
	)
	(segment
		(start 301.765208 -278.695658)
		(end 297.21556 -274.14601)
		(width 0.508)
		(layer "F.Cu")
		(net "P5V_A_4")
	)
	(segment
		(start 292.498526 -346.150946)
		(end 301.765208 -336.884264)
		(width 0.508)
		(layer "F.Cu")
		(net "P5V_A_4")
	)
	(segment
		(start 242.753642 -344.988642)
		(end 261.349998 -363.584998)
		(width 0.508)
		(layer "F.Cu")
		(net "P5V_A_4")
	)
	(segment
		(start 441.964826 -128.016)
		(end 441.964826 -129.1844)
		(width 0.508)
		(layer "F.Cu")
		(net "P5V_A_4")
	)
	(segment
		(start 474.383608 -222.621856)
		(end 474.383608 -219.816934)
		(width 0.508)
		(layer "F.Cu")
		(net "P5V_A_4")
	)
	(segment
		(start 473.514928 -128.016)
		(end 473.514928 -129.1844)
		(width 0.508)
		(layer "F.Cu")
		(net "P5V_A_4")
	)
	(segment
		(start 240.615724 -344.988642)
		(end 242.753642 -344.988642)
		(width 0.508)
		(layer "F.Cu")
		(net "P5V_A_4")
	)
	(segment
		(start 291.3888 -365.0488)
		(end 292.498526 -363.939074)
		(width 0.508)
		(layer "F.Cu")
		(net "P5V_A_4")
	)
	(segment
		(start 237.988856 -342.864948)
		(end 238.49203 -342.864948)
		(width 0.508)
		(layer "F.Cu")
		(net "P5V_A_4")
	)
	(segment
		(start 283.752798 -363.584998)
		(end 285.2166 -365.0488)
		(width 0.508)
		(layer "F.Cu")
		(net "P5V_A_4")
	)
	(segment
		(start 478.7392 -226.2505)
		(end 478.012252 -226.2505)
		(width 0.508)
		(layer "F.Cu")
		(net "P5V_A_4")
	)
	(segment
		(start 238.49203 -342.864948)
		(end 240.615724 -344.988642)
		(width 0.508)
		(layer "F.Cu")
		(net "P5V_A_4")
	)
	(segment
		(start 478.012252 -226.2505)
		(end 474.383608 -222.621856)
		(width 0.508)
		(layer "F.Cu")
		(net "P5V_A_4")
	)
	(via
		(at 465.1629 -52.237894)
		(size 0.5588)
		(drill 0.3048)
		(layers "F.Cu" "B.Cu")
		(net "P5V_A_4")
	)
	(via
		(at 474.383608 -219.816934)
		(size 0.6604)
		(drill 0.3302)
		(layers "F.Cu" "B.Cu")
		(net "P5V_A_4")
	)
	(via
		(at 402.06295 -52.237894)
		(size 0.5588)
		(drill 0.3048)
		(layers "F.Cu" "B.Cu")
		(net "P5V_A_4")
	)
	(via
		(at 472.244928 -129.1844)
		(size 0.5588)
		(drill 0.3048)
		(layers "F.Cu" "B.Cu")
		(net "P5V_A_4")
	)
	(via
		(at 476.888048 -211.169758)
		(size 0.7112)
		(drill 0.4064)
		(layers "F.Cu" "B.Cu")
		(net "P5V_A_4")
	)
	(via
		(at 409.144978 -129.1844)
		(size 0.5588)
		(drill 0.3048)
		(layers "F.Cu" "B.Cu")
		(net "P5V_A_4")
	)
	(via
		(at 474.411802 -204.568044)
		(size 0.6096)
		(drill 0.3048)
		(layers "F.Cu" "B.Cu")
		(net "P5V_A_4")
	)
	(via
		(at 477.435926 -165.840918)
		(size 0.5588)
		(drill 0.3048)
		(layers "F.Cu" "B.Cu")
		(net "P5V_A_4")
	)
	(via
		(at 338.963 -51.447192)
		(size 0.5588)
		(drill 0.3048)
		(layers "F.Cu" "B.Cu")
		(net "P5V_A_4")
	)
	(via
		(at 433.613052 -53.507894)
		(size 0.5588)
		(drill 0.3048)
		(layers "F.Cu" "B.Cu")
		(net "P5V_A_4")
	)
	(via
		(at 477.037146 -204.1271)
		(size 0.7112)
		(drill 0.4064)
		(layers "F.Cu" "B.Cu")
		(net "P5V_A_4")
	)
	(via
		(at 478.158048 -211.169758)
		(size 0.7112)
		(drill 0.4064)
		(layers "F.Cu" "B.Cu")
		(net "P5V_A_4")
	)
	(via
		(at 478.376742 -215.003888)
		(size 0.7112)
		(drill 0.4064)
		(layers "F.Cu" "B.Cu")
		(net "P5V_A_4")
	)
	(via
		(at 402.06295 -54.777894)
		(size 0.5588)
		(drill 0.3048)
		(layers "F.Cu" "B.Cu")
		(net "P5V_A_4")
	)
	(via
		(at 433.6034 -165.735)
		(size 0.5588)
		(drill 0.3048)
		(layers "F.Cu" "B.Cu")
		(net "P5V_A_4")
	)
	(via
		(at 477.689926 -51.221894)
		(size 0.5588)
		(drill 0.3048)
		(layers "F.Cu" "B.Cu")
		(net "P5V_A_4")
	)
	(via
		(at 477.037146 -206.4131)
		(size 0.7112)
		(drill 0.4064)
		(layers "F.Cu" "B.Cu")
		(net "P5V_A_4")
	)
	(via
		(at 465.1629 -169.777918)
		(size 0.5588)
		(drill 0.3048)
		(layers "F.Cu" "B.Cu")
		(net "P5V_A_4")
	)
	(via
		(at 338.963 -53.987192)
		(size 0.5588)
		(drill 0.3048)
		(layers "F.Cu" "B.Cu")
		(net "P5V_A_4")
	)
	(via
		(at 473.113608 -215.013032)
		(size 0.7112)
		(drill 0.4064)
		(layers "F.Cu" "B.Cu")
		(net "P5V_A_4")
	)
	(via
		(at 441.964826 -129.1844)
		(size 0.5588)
		(drill 0.3048)
		(layers "F.Cu" "B.Cu")
		(net "P5V_A_4")
	)
	(via
		(at 475.767146 -209.8421)
		(size 0.7112)
		(drill 0.4064)
		(layers "F.Cu" "B.Cu")
		(net "P5V_A_4")
	)
	(via
		(at 433.613052 -54.777894)
		(size 0.5588)
		(drill 0.3048)
		(layers "F.Cu" "B.Cu")
		(net "P5V_A_4")
	)
	(via
		(at 465.1502 -165.7604)
		(size 0.5588)
		(drill 0.3048)
		(layers "F.Cu" "B.Cu")
		(net "P5V_A_4")
	)
	(via
		(at 475.767146 -206.4131)
		(size 0.7112)
		(drill 0.4064)
		(layers "F.Cu" "B.Cu")
		(net "P5V_A_4")
	)
	(via
		(at 475.767146 -208.6991)
		(size 0.7112)
		(drill 0.4064)
		(layers "F.Cu" "B.Cu")
		(net "P5V_A_4")
	)
	(via
		(at 440.694826 -129.1844)
		(size 0.5588)
		(drill 0.3048)
		(layers "F.Cu" "B.Cu")
		(net "P5V_A_4")
	)
	(via
		(at 370.526056 -52.83835)
		(size 0.5588)
		(drill 0.3048)
		(layers "F.Cu" "B.Cu")
		(net "P5V_A_4")
	)
	(via
		(at 370.526056 -51.66995)
		(size 0.5588)
		(drill 0.3048)
		(layers "F.Cu" "B.Cu")
		(net "P5V_A_4")
	)
	(via
		(at 402.06295 -53.507894)
		(size 0.5588)
		(drill 0.3048)
		(layers "F.Cu" "B.Cu")
		(net "P5V_A_4")
	)
	(via
		(at 410.414978 -129.1844)
		(size 0.5588)
		(drill 0.3048)
		(layers "F.Cu" "B.Cu")
		(net "P5V_A_4")
	)
	(via
		(at 477.037146 -209.8421)
		(size 0.7112)
		(drill 0.4064)
		(layers "F.Cu" "B.Cu")
		(net "P5V_A_4")
	)
	(via
		(at 297.21556 -265.160506)
		(size 0.5588)
		(drill 0.3048)
		(layers "F.Cu" "B.Cu")
		(net "P5V_A_4")
	)
	(via
		(at 465.1629 -168.507918)
		(size 0.5588)
		(drill 0.3048)
		(layers "F.Cu" "B.Cu")
		(net "P5V_A_4")
	)
	(via
		(at 473.879926 -51.221894)
		(size 0.5588)
		(drill 0.3048)
		(layers "F.Cu" "B.Cu")
		(net "P5V_A_4")
	)
	(via
		(at 338.963 -55.257192)
		(size 0.5588)
		(drill 0.3048)
		(layers "F.Cu" "B.Cu")
		(net "P5V_A_4")
	)
	(via
		(at 465.1629 -54.777894)
		(size 0.5588)
		(drill 0.3048)
		(layers "F.Cu" "B.Cu")
		(net "P5V_A_4")
	)
	(via
		(at 433.613052 -50.967894)
		(size 0.5588)
		(drill 0.3048)
		(layers "F.Cu" "B.Cu")
		(net "P5V_A_4")
	)
	(via
		(at 370.526056 -54.00675)
		(size 0.5588)
		(drill 0.3048)
		(layers "F.Cu" "B.Cu")
		(net "P5V_A_4")
	)
	(via
		(at 475.767146 -207.5561)
		(size 0.7112)
		(drill 0.4064)
		(layers "F.Cu" "B.Cu")
		(net "P5V_A_4")
	)
	(via
		(at 474.895926 -165.840918)
		(size 0.5588)
		(drill 0.3048)
		(layers "F.Cu" "B.Cu")
		(net "P5V_A_4")
	)
	(via
		(at 475.745048 -211.169758)
		(size 0.7112)
		(drill 0.4064)
		(layers "F.Cu" "B.Cu")
		(net "P5V_A_4")
	)
	(via
		(at 476.419926 -51.221894)
		(size 0.5588)
		(drill 0.3048)
		(layers "F.Cu" "B.Cu")
		(net "P5V_A_4")
	)
	(via
		(at 433.613052 -169.777918)
		(size 0.5588)
		(drill 0.3048)
		(layers "F.Cu" "B.Cu")
		(net "P5V_A_4")
	)
	(via
		(at 370.526056 -55.17515)
		(size 0.5588)
		(drill 0.3048)
		(layers "F.Cu" "B.Cu")
		(net "P5V_A_4")
	)
	(via
		(at 477.106742 -215.003888)
		(size 0.7112)
		(drill 0.4064)
		(layers "F.Cu" "B.Cu")
		(net "P5V_A_4")
	)
	(via
		(at 475.767146 -204.1271)
		(size 0.7112)
		(drill 0.4064)
		(layers "F.Cu" "B.Cu")
		(net "P5V_A_4")
	)
	(via
		(at 477.037146 -205.2701)
		(size 0.7112)
		(drill 0.4064)
		(layers "F.Cu" "B.Cu")
		(net "P5V_A_4")
	)
	(via
		(at 338.963 -52.717192)
		(size 0.5588)
		(drill 0.3048)
		(layers "F.Cu" "B.Cu")
		(net "P5V_A_4")
	)
	(via
		(at 475.149926 -51.221894)
		(size 0.5588)
		(drill 0.3048)
		(layers "F.Cu" "B.Cu")
		(net "P5V_A_4")
	)
	(via
		(at 476.165926 -165.840918)
		(size 0.5588)
		(drill 0.3048)
		(layers "F.Cu" "B.Cu")
		(net "P5V_A_4")
	)
	(via
		(at 473.761308 -211.215986)
		(size 0.7112)
		(drill 0.4064)
		(layers "F.Cu" "B.Cu")
		(net "P5V_A_4")
	)
	(via
		(at 477.037146 -207.5561)
		(size 0.7112)
		(drill 0.4064)
		(layers "F.Cu" "B.Cu")
		(net "P5V_A_4")
	)
	(via
		(at 402.06295 -50.967894)
		(size 0.5588)
		(drill 0.3048)
		(layers "F.Cu" "B.Cu")
		(net "P5V_A_4")
	)
	(via
		(at 465.1629 -53.507894)
		(size 0.5588)
		(drill 0.3048)
		(layers "F.Cu" "B.Cu")
		(net "P5V_A_4")
	)
	(via
		(at 465.1629 -50.967894)
		(size 0.5588)
		(drill 0.3048)
		(layers "F.Cu" "B.Cu")
		(net "P5V_A_4")
	)
	(via
		(at 474.383608 -215.013032)
		(size 0.7112)
		(drill 0.4064)
		(layers "F.Cu" "B.Cu")
		(net "P5V_A_4")
	)
	(via
		(at 473.514928 -129.1844)
		(size 0.5588)
		(drill 0.3048)
		(layers "F.Cu" "B.Cu")
		(net "P5V_A_4")
	)
	(via
		(at 433.613052 -167.237918)
		(size 0.5588)
		(drill 0.3048)
		(layers "F.Cu" "B.Cu")
		(net "P5V_A_4")
	)
	(via
		(at 465.1629 -167.237918)
		(size 0.5588)
		(drill 0.3048)
		(layers "F.Cu" "B.Cu")
		(net "P5V_A_4")
	)
	(via
		(at 477.037146 -208.6991)
		(size 0.7112)
		(drill 0.4064)
		(layers "F.Cu" "B.Cu")
		(net "P5V_A_4")
	)
	(via
		(at 433.613052 -52.237894)
		(size 0.5588)
		(drill 0.3048)
		(layers "F.Cu" "B.Cu")
		(net "P5V_A_4")
	)
	(via
		(at 478.7392 -226.2505)
		(size 0.5588)
		(drill 0.3048)
		(layers "F.Cu" "B.Cu")
		(net "P5V_A_4")
	)
	(via
		(at 473.625926 -165.840918)
		(size 0.5588)
		(drill 0.3048)
		(layers "F.Cu" "B.Cu")
		(net "P5V_A_4")
	)
	(via
		(at 475.767146 -205.2701)
		(size 0.7112)
		(drill 0.4064)
		(layers "F.Cu" "B.Cu")
		(net "P5V_A_4")
	)
	(via
		(at 433.613052 -168.507918)
		(size 0.5588)
		(drill 0.3048)
		(layers "F.Cu" "B.Cu")
		(net "P5V_A_4")
	)
	(segment
		(start 479.552 -226.2505)
		(end 478.7392 -226.2505)
		(width 0.508)
		(layer "B.Cu")
		(net "P5V_A_4")
	)
	(segment
		(start 472.091004 -203.399898)
		(end 472.984576 -203.399898)
		(width 0.254)
		(layer "B.Cu")
		(net "P5V_A_4")
	)
	(segment
		(start 471.722704 -221.579186)
		(end 471.722704 -218.172792)
		(width 0.508)
		(layer "B.Cu")
		(net "P5V_A_4")
	)
	(segment
		(start 477.95688 -222.229172)
		(end 472.37269 -222.229172)
		(width 0.508)
		(layer "B.Cu")
		(net "P5V_A_4")
	)
	(segment
		(start 472.37269 -222.229172)
		(end 471.722704 -221.579186)
		(width 0.508)
		(layer "B.Cu")
		(net "P5V_A_4")
	)
	(segment
		(start 473.113608 -215.013032)
		(end 470.152476 -217.974164)
		(width 0.508)
		(layer "In2.Cu")
		(net "P5V_A_4")
	)
	(segment
		(start 470.152476 -217.974164)
		(end 470.152476 -235.32592)
		(width 0.508)
		(layer "In2.Cu")
		(net "P5V_A_4")
	)
	(segment
		(start 302.814482 -265.160506)
		(end 297.21556 -265.160506)
		(width 0.508)
		(layer "In2.Cu")
		(net "P5V_A_4")
	)
	(segment
		(start 410.220414 -253.751334)
		(end 314.223654 -253.751334)
		(width 0.508)
		(layer "In2.Cu")
		(net "P5V_A_4")
	)
	(segment
		(start 425.973748 -237.998)
		(end 410.220414 -253.751334)
		(width 0.508)
		(layer "In2.Cu")
		(net "P5V_A_4")
	)
	(segment
		(start 469.011508 -236.466888)
		(end 466.125052 -236.466888)
		(width 0.508)
		(layer "In2.Cu")
		(net "P5V_A_4")
	)
	(segment
		(start 470.152476 -235.32592)
		(end 469.011508 -236.466888)
		(width 0.508)
		(layer "In2.Cu")
		(net "P5V_A_4")
	)
	(segment
		(start 314.223654 -253.751334)
		(end 302.814482 -265.160506)
		(width 0.508)
		(layer "In2.Cu")
		(net "P5V_A_4")
	)
	(segment
		(start 466.125052 -236.466888)
		(end 464.59394 -237.998)
		(width 0.508)
		(layer "In2.Cu")
		(net "P5V_A_4")
	)
	(segment
		(start 464.59394 -237.998)
		(end 425.973748 -237.998)
		(width 0.508)
		(layer "In2.Cu")
		(net "P5V_A_4")
	)
	(segment
		(start 452.237602 -257.35915)
		(end 453.355202 -257.35915)
		(width 0.254)
		(layer "F.Cu")
		(net "P5V_A_3_PGOOD")
	)
	(segment
		(start 448.849496 -254.544068)
		(end 449.50507 -255.199642)
		(width 0.254)
		(layer "F.Cu")
		(net "P5V_A_3_PGOOD")
	)
	(segment
		(start 453.355202 -257.35915)
		(end 454.371202 -258.37515)
		(width 0.254)
		(layer "F.Cu")
		(net "P5V_A_3_PGOOD")
	)
	(segment
		(start 446.721738 -255.778254)
		(end 447.955924 -254.544068)
		(width 0.254)
		(layer "F.Cu")
		(net "P5V_A_3_PGOOD")
	)
	(segment
		(start 447.955924 -254.544068)
		(end 448.849496 -254.544068)
		(width 0.254)
		(layer "F.Cu")
		(net "P5V_A_3_PGOOD")
	)
	(segment
		(start 451.831202 -255.45415)
		(end 451.833488 -255.456436)
		(width 0.254)
		(layer "F.Cu")
		(net "P5V_A_3_PGOOD")
	)
	(segment
		(start 450.993002 -254.61595)
		(end 451.831202 -255.45415)
		(width 0.254)
		(layer "F.Cu")
		(net "P5V_A_3_PGOOD")
	)
	(segment
		(start 451.833488 -256.955036)
		(end 452.237602 -257.35915)
		(width 0.254)
		(layer "F.Cu")
		(net "P5V_A_3_PGOOD")
	)
	(segment
		(start 449.50507 -255.199642)
		(end 450.088762 -254.61595)
		(width 0.254)
		(layer "F.Cu")
		(net "P5V_A_3_PGOOD")
	)
	(segment
		(start 451.833488 -256.3495)
		(end 451.833488 -256.955036)
		(width 0.254)
		(layer "F.Cu")
		(net "P5V_A_3_PGOOD")
	)
	(segment
		(start 451.833488 -255.456436)
		(end 451.833488 -256.3495)
		(width 0.254)
		(layer "F.Cu")
		(net "P5V_A_3_PGOOD")
	)
	(segment
		(start 450.088762 -254.61595)
		(end 450.993002 -254.61595)
		(width 0.254)
		(layer "F.Cu")
		(net "P5V_A_3_PGOOD")
	)
	(via
		(at 451.831202 -255.45415)
		(size 0.5588)
		(drill 0.3048)
		(layers "F.Cu" "B.Cu")
		(net "P5V_A_3_PGOOD")
	)
	(segment
		(start 449.926202 -253.54915)
		(end 449.824602 -253.54915)
		(width 0.254)
		(layer "B.Cu")
		(net "P5V_A_3_PGOOD")
	)
	(segment
		(start 451.831202 -255.45415)
		(end 449.926202 -253.54915)
		(width 0.254)
		(layer "B.Cu")
		(net "P5V_A_3_PGOOD")
	)
	(segment
		(start 449.824602 -253.54915)
		(end 449.540376 -253.264924)
		(width 0.254)
		(layer "B.Cu")
		(net "P5V_A_3_PGOOD")
	)
	(segment
		(start 449.540376 -253.264924)
		(end 448.879722 -253.264924)
		(width 0.254)
		(layer "B.Cu")
		(net "P5V_A_3_PGOOD")
	)
	(segment
		(start 322.549012 -128.122934)
		(end 321.279012 -128.122934)
		(width 0.508)
		(layer "F.Cu")
		(net "P5V_A_3")
	)
	(segment
		(start 457.93025 -249.71375)
		(end 460.9084 -249.71375)
		(width 0.381)
		(layer "F.Cu")
		(net "P5V_A_3")
	)
	(segment
		(start 468.595202 -249.71375)
		(end 460.9084 -249.71375)
		(width 0.381)
		(layer "F.Cu")
		(net "P5V_A_3")
	)
	(segment
		(start 378.864876 -128.016)
		(end 378.864876 -129.056892)
		(width 0.508)
		(layer "F.Cu")
		(net "P5V_A_3")
	)
	(segment
		(start 452.797164 -243.012976)
		(end 452.797164 -244.181376)
		(width 0.508)
		(layer "F.Cu")
		(net "P5V_A_3")
	)
	(segment
		(start 345.410028 -128.016)
		(end 345.410028 -129.035556)
		(width 0.508)
		(layer "F.Cu")
		(net "P5V_A_3")
	)
	(segment
		(start 410.414978 -243.01577)
		(end 410.414978 -244.18417)
		(width 0.508)
		(layer "F.Cu")
		(net "P5V_A_3")
	)
	(segment
		(start 452.722488 -254.921512)
		(end 457.93025 -249.71375)
		(width 0.381)
		(layer "F.Cu")
		(net "P5V_A_3")
	)
	(segment
		(start 326.31253 -242.972844)
		(end 322.260468 -242.972844)
		(width 0.508)
		(layer "F.Cu")
		(net "P5V_A_3")
	)
	(segment
		(start 440.694826 -243.01577)
		(end 440.694826 -244.18417)
		(width 0.508)
		(layer "F.Cu")
		(net "P5V_A_3")
	)
	(segment
		(start 346.680028 -128.016)
		(end 346.680028 -129.035556)
		(width 0.508)
		(layer "F.Cu")
		(net "P5V_A_3")
	)
	(segment
		(start 241.775488 -346.799408)
		(end 241.775488 -346.804488)
		(width 0.508)
		(layer "F.Cu")
		(net "P5V_A_3")
	)
	(segment
		(start 377.594876 -128.016)
		(end 377.594876 -129.056892)
		(width 0.508)
		(layer "F.Cu")
		(net "P5V_A_3")
	)
	(segment
		(start 377.594876 -243.01577)
		(end 377.594876 -244.18417)
		(width 0.508)
		(layer "F.Cu")
		(net "P5V_A_3")
	)
	(segment
		(start 452.722488 -256.3495)
		(end 452.722488 -254.921512)
		(width 0.381)
		(layer "F.Cu")
		(net "P5V_A_3")
	)
	(segment
		(start 241.775488 -346.804488)
		(end 242.697 -347.726)
		(width 0.508)
		(layer "F.Cu")
		(net "P5V_A_3")
	)
	(segment
		(start 378.864876 -243.01577)
		(end 378.864876 -244.18417)
		(width 0.508)
		(layer "F.Cu")
		(net "P5V_A_3")
	)
	(segment
		(start 347.315028 -243.01577)
		(end 347.315028 -244.18417)
		(width 0.508)
		(layer "F.Cu")
		(net "P5V_A_3")
	)
	(segment
		(start 346.045028 -243.01577)
		(end 346.045028 -244.18417)
		(width 0.508)
		(layer "F.Cu")
		(net "P5V_A_3")
	)
	(segment
		(start 451.527164 -243.012976)
		(end 451.527164 -244.181376)
		(width 0.508)
		(layer "F.Cu")
		(net "P5V_A_3")
	)
	(segment
		(start 322.260468 -242.972844)
		(end 320.990468 -242.972844)
		(width 0.508)
		(layer "F.Cu")
		(net "P5V_A_3")
	)
	(segment
		(start 441.964826 -243.01577)
		(end 441.964826 -244.18417)
		(width 0.508)
		(layer "F.Cu")
		(net "P5V_A_3")
	)
	(segment
		(start 409.144978 -243.01577)
		(end 409.144978 -244.18417)
		(width 0.508)
		(layer "F.Cu")
		(net "P5V_A_3")
	)
	(segment
		(start 321.279012 -128.122934)
		(end 321.279012 -129.049272)
		(width 0.508)
		(layer "F.Cu")
		(net "P5V_A_3")
	)
	(via
		(at 463.738214 -246.17934)
		(size 0.7112)
		(drill 0.4064)
		(layers "F.Cu" "B.Cu")
		(net "P5V_A_3")
	)
	(via
		(at 460.9084 -249.71375)
		(size 0.6604)
		(drill 0.3302)
		(layers "F.Cu" "B.Cu")
		(net "P5V_A_3")
	)
	(via
		(at 470.881202 -248.44375)
		(size 0.7112)
		(drill 0.4064)
		(layers "F.Cu" "B.Cu")
		(net "P5V_A_3")
	)
	(via
		(at 346.045028 -244.18417)
		(size 0.5588)
		(drill 0.3048)
		(layers "F.Cu" "B.Cu")
		(net "P5V_A_3")
	)
	(via
		(at 338.963 -282.237942)
		(size 0.5588)
		(drill 0.3048)
		(layers "F.Cu" "B.Cu")
		(net "P5V_A_3")
	)
	(via
		(at 477.717866 -277.307802)
		(size 0.5588)
		(drill 0.3048)
		(layers "F.Cu" "B.Cu")
		(net "P5V_A_3")
	)
	(via
		(at 467.533482 -247.476772)
		(size 0.7112)
		(drill 0.4064)
		(layers "F.Cu" "B.Cu")
		(net "P5V_A_3")
	)
	(via
		(at 476.447866 -277.307802)
		(size 0.5588)
		(drill 0.3048)
		(layers "F.Cu" "B.Cu")
		(net "P5V_A_3")
	)
	(via
		(at 347.315028 -244.18417)
		(size 0.5588)
		(drill 0.3048)
		(layers "F.Cu" "B.Cu")
		(net "P5V_A_3")
	)
	(via
		(at 472.024202 -248.44375)
		(size 0.7112)
		(drill 0.4064)
		(layers "F.Cu" "B.Cu")
		(net "P5V_A_3")
	)
	(via
		(at 338.836 -168.126918)
		(size 0.5588)
		(drill 0.3048)
		(layers "F.Cu" "B.Cu")
		(net "P5V_A_3")
	)
	(via
		(at 463.738976 -250.446794)
		(size 0.7112)
		(drill 0.4064)
		(layers "F.Cu" "B.Cu")
		(net "P5V_A_3")
	)
	(via
		(at 473.167202 -248.44375)
		(size 0.7112)
		(drill 0.4064)
		(layers "F.Cu" "B.Cu")
		(net "P5V_A_3")
	)
	(via
		(at 338.836 -169.269918)
		(size 0.5588)
		(drill 0.3048)
		(layers "F.Cu" "B.Cu")
		(net "P5V_A_3")
	)
	(via
		(at 464.5279 -280.967942)
		(size 0.5588)
		(drill 0.3048)
		(layers "F.Cu" "B.Cu")
		(net "P5V_A_3")
	)
	(via
		(at 469.738202 -249.71375)
		(size 0.7112)
		(drill 0.4064)
		(layers "F.Cu" "B.Cu")
		(net "P5V_A_3")
	)
	(via
		(at 464.5279 -283.507942)
		(size 0.5588)
		(drill 0.3048)
		(layers "F.Cu" "B.Cu")
		(net "P5V_A_3")
	)
	(via
		(at 338.963 -283.507942)
		(size 0.5588)
		(drill 0.3048)
		(layers "F.Cu" "B.Cu")
		(net "P5V_A_3")
	)
	(via
		(at 377.594876 -244.18417)
		(size 0.5588)
		(drill 0.3048)
		(layers "F.Cu" "B.Cu")
		(net "P5V_A_3")
	)
	(via
		(at 345.410028 -129.035556)
		(size 0.5588)
		(drill 0.3048)
		(layers "F.Cu" "B.Cu")
		(net "P5V_A_3")
	)
	(via
		(at 451.527164 -244.181376)
		(size 0.5588)
		(drill 0.3048)
		(layers "F.Cu" "B.Cu")
		(net "P5V_A_3")
	)
	(via
		(at 467.506812 -251.68479)
		(size 0.7112)
		(drill 0.4064)
		(layers "F.Cu" "B.Cu")
		(net "P5V_A_3")
	)
	(via
		(at 370.513102 -168.507918)
		(size 0.5588)
		(drill 0.3048)
		(layers "F.Cu" "B.Cu")
		(net "P5V_A_3")
	)
	(via
		(at 440.694826 -244.18417)
		(size 0.5588)
		(drill 0.3048)
		(layers "F.Cu" "B.Cu")
		(net "P5V_A_3")
	)
	(via
		(at 326.31253 -242.972844)
		(size 0.5588)
		(drill 0.3048)
		(layers "F.Cu" "B.Cu")
		(net "P5V_A_3")
	)
	(via
		(at 378.864876 -244.18417)
		(size 0.5588)
		(drill 0.3048)
		(layers "F.Cu" "B.Cu")
		(net "P5V_A_3")
	)
	(via
		(at 397.666972 -167.836342)
		(size 0.5588)
		(drill 0.3048)
		(layers "F.Cu" "B.Cu")
		(net "P5V_A_3")
	)
	(via
		(at 409.144978 -244.18417)
		(size 0.5588)
		(drill 0.3048)
		(layers "F.Cu" "B.Cu")
		(net "P5V_A_3")
	)
	(via
		(at 473.167202 -249.71375)
		(size 0.7112)
		(drill 0.4064)
		(layers "F.Cu" "B.Cu")
		(net "P5V_A_3")
	)
	(via
		(at 371.275102 -282.745942)
		(size 0.5588)
		(drill 0.3048)
		(layers "F.Cu" "B.Cu")
		(net "P5V_A_3")
	)
	(via
		(at 242.697 -347.726)
		(size 0.5588)
		(drill 0.3048)
		(layers "F.Cu" "B.Cu")
		(net "P5V_A_3")
	)
	(via
		(at 410.414978 -244.18417)
		(size 0.5588)
		(drill 0.3048)
		(layers "F.Cu" "B.Cu")
		(net "P5V_A_3")
	)
	(via
		(at 395.6812 -279.100026)
		(size 0.5588)
		(drill 0.3048)
		(layers "F.Cu" "B.Cu")
		(net "P5V_A_3")
	)
	(via
		(at 467.533482 -246.206772)
		(size 0.7112)
		(drill 0.4064)
		(layers "F.Cu" "B.Cu")
		(net "P5V_A_3")
	)
	(via
		(at 370.513102 -169.777918)
		(size 0.5588)
		(drill 0.3048)
		(layers "F.Cu" "B.Cu")
		(net "P5V_A_3")
	)
	(via
		(at 433.613052 -282.237942)
		(size 0.5588)
		(drill 0.3048)
		(layers "F.Cu" "B.Cu")
		(net "P5V_A_3")
	)
	(via
		(at 433.6288 -280.7208)
		(size 0.5588)
		(drill 0.3048)
		(layers "F.Cu" "B.Cu")
		(net "P5V_A_3")
	)
	(via
		(at 452.797164 -244.181376)
		(size 0.5588)
		(drill 0.3048)
		(layers "F.Cu" "B.Cu")
		(net "P5V_A_3")
	)
	(via
		(at 338.836 -166.983918)
		(size 0.5588)
		(drill 0.3048)
		(layers "F.Cu" "B.Cu")
		(net "P5V_A_3")
	)
	(via
		(at 468.595202 -249.71375)
		(size 0.7112)
		(drill 0.4064)
		(layers "F.Cu" "B.Cu")
		(net "P5V_A_3")
	)
	(via
		(at 474.310202 -249.71375)
		(size 0.7112)
		(drill 0.4064)
		(layers "F.Cu" "B.Cu")
		(net "P5V_A_3")
	)
	(via
		(at 475.177866 -277.307802)
		(size 0.5588)
		(drill 0.3048)
		(layers "F.Cu" "B.Cu")
		(net "P5V_A_3")
	)
	(via
		(at 396.9512 -279.100026)
		(size 0.5588)
		(drill 0.3048)
		(layers "F.Cu" "B.Cu")
		(net "P5V_A_3")
	)
	(via
		(at 378.864876 -129.056892)
		(size 0.5588)
		(drill 0.3048)
		(layers "F.Cu" "B.Cu")
		(net "P5V_A_3")
	)
	(via
		(at 377.594876 -129.056892)
		(size 0.5588)
		(drill 0.3048)
		(layers "F.Cu" "B.Cu")
		(net "P5V_A_3")
	)
	(via
		(at 394.4112 -279.100026)
		(size 0.5588)
		(drill 0.3048)
		(layers "F.Cu" "B.Cu")
		(net "P5V_A_3")
	)
	(via
		(at 370.513102 -167.237918)
		(size 0.5588)
		(drill 0.3048)
		(layers "F.Cu" "B.Cu")
		(net "P5V_A_3")
	)
	(via
		(at 338.963 -284.777942)
		(size 0.5588)
		(drill 0.3048)
		(layers "F.Cu" "B.Cu")
		(net "P5V_A_3")
	)
	(via
		(at 463.738214 -247.44934)
		(size 0.7112)
		(drill 0.4064)
		(layers "F.Cu" "B.Cu")
		(net "P5V_A_3")
	)
	(via
		(at 397.666972 -169.106342)
		(size 0.5588)
		(drill 0.3048)
		(layers "F.Cu" "B.Cu")
		(net "P5V_A_3")
	)
	(via
		(at 468.595202 -248.44375)
		(size 0.7112)
		(drill 0.4064)
		(layers "F.Cu" "B.Cu")
		(net "P5V_A_3")
	)
	(via
		(at 371.2718 -281.2288)
		(size 0.5588)
		(drill 0.3048)
		(layers "F.Cu" "B.Cu")
		(net "P5V_A_3")
	)
	(via
		(at 397.666972 -170.376342)
		(size 0.5588)
		(drill 0.3048)
		(layers "F.Cu" "B.Cu")
		(net "P5V_A_3")
	)
	(via
		(at 267.340588 -290.868862)
		(size 0.5588)
		(drill 0.3048)
		(layers "F.Cu" "B.Cu")
		(net "P5V_A_3")
	)
	(via
		(at 469.738202 -248.44375)
		(size 0.7112)
		(drill 0.4064)
		(layers "F.Cu" "B.Cu")
		(net "P5V_A_3")
	)
	(via
		(at 464.5279 -284.777942)
		(size 0.5588)
		(drill 0.3048)
		(layers "F.Cu" "B.Cu")
		(net "P5V_A_3")
	)
	(via
		(at 464.5279 -282.237942)
		(size 0.5588)
		(drill 0.3048)
		(layers "F.Cu" "B.Cu")
		(net "P5V_A_3")
	)
	(via
		(at 370.513102 -165.663118)
		(size 0.5588)
		(drill 0.3048)
		(layers "F.Cu" "B.Cu")
		(net "P5V_A_3")
	)
	(via
		(at 474.310202 -248.44375)
		(size 0.7112)
		(drill 0.4064)
		(layers "F.Cu" "B.Cu")
		(net "P5V_A_3")
	)
	(via
		(at 346.680028 -129.035556)
		(size 0.5588)
		(drill 0.3048)
		(layers "F.Cu" "B.Cu")
		(net "P5V_A_3")
	)
	(via
		(at 470.881202 -249.71375)
		(size 0.7112)
		(drill 0.4064)
		(layers "F.Cu" "B.Cu")
		(net "P5V_A_3")
	)
	(via
		(at 433.613052 -283.507942)
		(size 0.5588)
		(drill 0.3048)
		(layers "F.Cu" "B.Cu")
		(net "P5V_A_3")
	)
	(via
		(at 467.506812 -250.41479)
		(size 0.7112)
		(drill 0.4064)
		(layers "F.Cu" "B.Cu")
		(net "P5V_A_3")
	)
	(via
		(at 433.613052 -284.777942)
		(size 0.5588)
		(drill 0.3048)
		(layers "F.Cu" "B.Cu")
		(net "P5V_A_3")
	)
	(via
		(at 371.275102 -284.015942)
		(size 0.5588)
		(drill 0.3048)
		(layers "F.Cu" "B.Cu")
		(net "P5V_A_3")
	)
	(via
		(at 441.964826 -244.18417)
		(size 0.5588)
		(drill 0.3048)
		(layers "F.Cu" "B.Cu")
		(net "P5V_A_3")
	)
	(via
		(at 338.963 -280.5938)
		(size 0.5588)
		(drill 0.3048)
		(layers "F.Cu" "B.Cu")
		(net "P5V_A_3")
	)
	(via
		(at 321.279012 -129.049272)
		(size 0.5588)
		(drill 0.3048)
		(layers "F.Cu" "B.Cu")
		(net "P5V_A_3")
	)
	(via
		(at 463.738976 -251.716794)
		(size 0.7112)
		(drill 0.4064)
		(layers "F.Cu" "B.Cu")
		(net "P5V_A_3")
	)
	(via
		(at 473.667582 -277.220426)
		(size 0.5588)
		(drill 0.3048)
		(layers "F.Cu" "B.Cu")
		(net "P5V_A_3")
	)
	(via
		(at 397.660622 -166.333424)
		(size 0.5588)
		(drill 0.3048)
		(layers "F.Cu" "B.Cu")
		(net "P5V_A_3")
	)
	(via
		(at 338.836 -165.840918)
		(size 0.5588)
		(drill 0.3048)
		(layers "F.Cu" "B.Cu")
		(net "P5V_A_3")
	)
	(via
		(at 393.1412 -279.100026)
		(size 0.5588)
		(drill 0.3048)
		(layers "F.Cu" "B.Cu")
		(net "P5V_A_3")
	)
	(via
		(at 371.275102 -285.285942)
		(size 0.5588)
		(drill 0.3048)
		(layers "F.Cu" "B.Cu")
		(net "P5V_A_3")
	)
	(via
		(at 472.024202 -249.71375)
		(size 0.7112)
		(drill 0.4064)
		(layers "F.Cu" "B.Cu")
		(net "P5V_A_3")
	)
	(segment
		(start 474.462602 -252.34265)
		(end 474.462602 -251.77115)
		(width 0.254)
		(layer "B.Cu")
		(net "P5V_A_3")
	)
	(segment
		(start 456.880214 -255.179576)
		(end 456.880214 -249.595386)
		(width 0.508)
		(layer "B.Cu")
		(net "P5V_A_3")
	)
	(segment
		(start 456.880214 -249.595386)
		(end 457.5302 -248.9454)
		(width 0.508)
		(layer "B.Cu")
		(net "P5V_A_3")
	)
	(segment
		(start 457.5302 -248.9454)
		(end 460.936594 -248.9454)
		(width 0.508)
		(layer "B.Cu")
		(net "P5V_A_3")
	)
	(segment
		(start 376.249184 -127.7112)
		(end 348.004384 -127.7112)
		(width 0.508)
		(layer "In2.Cu")
		(net "P5V_A_3")
	)
	(segment
		(start 287.39719 -287.781492)
		(end 324.23862 -287.781492)
		(width 0.508)
		(layer "In2.Cu")
		(net "P5V_A_3")
	)
	(segment
		(start 326.31253 -242.972844)
		(end 327.48093 -244.141244)
		(width 0.508)
		(layer "In2.Cu")
		(net "P5V_A_3")
	)
	(segment
		(start 378.864876 -129.056892)
		(end 377.594876 -129.056892)
		(width 0.508)
		(layer "In2.Cu")
		(net "P5V_A_3")
	)
	(segment
		(start 346.680028 -129.035556)
		(end 345.410028 -129.035556)
		(width 0.508)
		(layer "In2.Cu")
		(net "P5V_A_3")
	)
	(segment
		(start 327.24217 -284.777942)
		(end 338.963 -284.777942)
		(width 0.508)
		(layer "In2.Cu")
		(net "P5V_A_3")
	)
	(segment
		(start 327.48093 -244.141244)
		(end 346.002102 -244.141244)
		(width 0.508)
		(layer "In2.Cu")
		(net "P5V_A_3")
	)
	(segment
		(start 377.594876 -129.056892)
		(end 376.249184 -127.7112)
		(width 0.508)
		(layer "In2.Cu")
		(net "P5V_A_3")
	)
	(segment
		(start 345.410028 -129.035556)
		(end 345.423744 -129.049272)
		(width 0.508)
		(layer "In2.Cu")
		(net "P5V_A_3")
	)
	(segment
		(start 284.30982 -290.868862)
		(end 287.39719 -287.781492)
		(width 0.508)
		(layer "In2.Cu")
		(net "P5V_A_3")
	)
	(segment
		(start 345.423744 -129.049272)
		(end 321.279012 -129.049272)
		(width 0.508)
		(layer "In2.Cu")
		(net "P5V_A_3")
	)
	(segment
		(start 348.004384 -127.7112)
		(end 346.680028 -129.035556)
		(width 0.508)
		(layer "In2.Cu")
		(net "P5V_A_3")
	)
	(segment
		(start 267.340588 -290.868862)
		(end 284.30982 -290.868862)
		(width 0.508)
		(layer "In2.Cu")
		(net "P5V_A_3")
	)
	(segment
		(start 324.23862 -287.781492)
		(end 327.24217 -284.777942)
		(width 0.508)
		(layer "In2.Cu")
		(net "P5V_A_3")
	)
	(segment
		(start 346.002102 -244.141244)
		(end 346.045028 -244.18417)
		(width 0.508)
		(layer "In2.Cu")
		(net "P5V_A_3")
	)
	(segment
		(start 378.714 -157.46222)
		(end 370.513102 -165.663118)
		(width 0.508)
		(layer "In7.Cu")
		(net "P5V_A_3")
	)
	(segment
		(start 378.864876 -129.056892)
		(end 378.714 -129.207768)
		(width 0.508)
		(layer "In7.Cu")
		(net "P5V_A_3")
	)
	(segment
		(start 378.714 -129.207768)
		(end 378.714 -157.46222)
		(width 0.508)
		(layer "In7.Cu")
		(net "P5V_A_3")
	)
	(segment
		(start 254.229616 -305.044856)
		(end 254.919226 -304.355246)
		(width 0.508)
		(layer "In9.Cu")
		(net "P5V_A_3")
	)
	(segment
		(start 254.919226 -304.355246)
		(end 254.919226 -299.917612)
		(width 0.508)
		(layer "In9.Cu")
		(net "P5V_A_3")
	)
	(segment
		(start 254.229616 -336.193384)
		(end 254.229616 -305.044856)
		(width 0.508)
		(layer "In9.Cu")
		(net "P5V_A_3")
	)
	(segment
		(start 242.697 -347.726)
		(end 254.229616 -336.193384)
		(width 0.508)
		(layer "In9.Cu")
		(net "P5V_A_3")
	)
	(segment
		(start 254.919226 -299.917612)
		(end 263.967976 -290.868862)
		(width 0.508)
		(layer "In9.Cu")
		(net "P5V_A_3")
	)
	(segment
		(start 263.967976 -290.868862)
		(end 267.340588 -290.868862)
		(width 0.508)
		(layer "In9.Cu")
		(net "P5V_A_3")
	)
	(segment
		(start 52.162202 -149.66315)
		(end 53.279802 -149.66315)
		(width 0.254)
		(layer "F.Cu")
		(net "P5V_A_2_PGOOD")
	)
	(segment
		(start 46.646338 -148.082254)
		(end 47.880524 -146.848068)
		(width 0.254)
		(layer "F.Cu")
		(net "P5V_A_2_PGOOD")
	)
	(segment
		(start 51.758088 -148.6535)
		(end 51.758088 -149.259036)
		(width 0.254)
		(layer "F.Cu")
		(net "P5V_A_2_PGOOD")
	)
	(segment
		(start 50.917602 -146.91995)
		(end 51.755802 -147.75815)
		(width 0.254)
		(layer "F.Cu")
		(net "P5V_A_2_PGOOD")
	)
	(segment
		(start 50.013362 -146.91995)
		(end 50.917602 -146.91995)
		(width 0.254)
		(layer "F.Cu")
		(net "P5V_A_2_PGOOD")
	)
	(segment
		(start 51.755802 -147.75815)
		(end 51.758088 -147.760436)
		(width 0.254)
		(layer "F.Cu")
		(net "P5V_A_2_PGOOD")
	)
	(segment
		(start 51.758088 -149.259036)
		(end 52.162202 -149.66315)
		(width 0.254)
		(layer "F.Cu")
		(net "P5V_A_2_PGOOD")
	)
	(segment
		(start 48.774096 -146.848068)
		(end 49.42967 -147.503642)
		(width 0.254)
		(layer "F.Cu")
		(net "P5V_A_2_PGOOD")
	)
	(segment
		(start 47.880524 -146.848068)
		(end 48.774096 -146.848068)
		(width 0.254)
		(layer "F.Cu")
		(net "P5V_A_2_PGOOD")
	)
	(segment
		(start 51.758088 -147.760436)
		(end 51.758088 -148.6535)
		(width 0.254)
		(layer "F.Cu")
		(net "P5V_A_2_PGOOD")
	)
	(segment
		(start 49.42967 -147.503642)
		(end 50.013362 -146.91995)
		(width 0.254)
		(layer "F.Cu")
		(net "P5V_A_2_PGOOD")
	)
	(segment
		(start 53.279802 -149.66315)
		(end 54.295802 -150.67915)
		(width 0.254)
		(layer "F.Cu")
		(net "P5V_A_2_PGOOD")
	)
	(via
		(at 51.755802 -147.75815)
		(size 0.5588)
		(drill 0.3048)
		(layers "F.Cu" "B.Cu")
		(net "P5V_A_2_PGOOD")
	)
	(segment
		(start 51.755802 -147.75815)
		(end 49.850802 -145.85315)
		(width 0.254)
		(layer "B.Cu")
		(net "P5V_A_2_PGOOD")
	)
	(segment
		(start 49.464976 -145.568924)
		(end 48.804322 -145.568924)
		(width 0.254)
		(layer "B.Cu")
		(net "P5V_A_2_PGOOD")
	)
	(segment
		(start 49.749202 -145.85315)
		(end 49.464976 -145.568924)
		(width 0.254)
		(layer "B.Cu")
		(net "P5V_A_2_PGOOD")
	)
	(segment
		(start 49.850802 -145.85315)
		(end 49.749202 -145.85315)
		(width 0.254)
		(layer "B.Cu")
		(net "P5V_A_2_PGOOD")
	)
	(segment
		(start 237.987586 -346.33916)
		(end 237.987586 -345.476322)
		(width 0.508)
		(layer "F.Cu")
		(net "P5V_A_2")
	)
	(segment
		(start 55.36565 -144.71015)
		(end 59.0296 -144.71015)
		(width 0.381)
		(layer "F.Cu")
		(net "P5V_A_2")
	)
	(segment
		(start 135.7249 -128.016)
		(end 135.7249 -129.1844)
		(width 0.508)
		(layer "F.Cu")
		(net "P5V_A_2")
	)
	(segment
		(start 264.746232 17.346168)
		(end 264.922 17.1704)
		(width 0.508)
		(layer "F.Cu")
		(net "P5V_A_2")
	)
	(segment
		(start 262.141462 11.672062)
		(end 262.14832 11.67892)
		(width 0.508)
		(layer "F.Cu")
		(net "P5V_A_2")
	)
	(segment
		(start 164.506402 -130.048)
		(end 164.506402 -131.2164)
		(width 0.508)
		(layer "F.Cu")
		(net "P5V_A_2")
	)
	(segment
		(start 52.647088 -147.428712)
		(end 55.36565 -144.71015)
		(width 0.381)
		(layer "F.Cu")
		(net "P5V_A_2")
	)
	(segment
		(start 68.519802 -144.71015)
		(end 59.0296 -144.71015)
		(width 0.381)
		(layer "F.Cu")
		(net "P5V_A_2")
	)
	(segment
		(start 136.9949 -128.016)
		(end 136.9949 -129.1844)
		(width 0.508)
		(layer "F.Cu")
		(net "P5V_A_2")
	)
	(segment
		(start 111.795052 -128.016)
		(end 111.795052 -129.1844)
		(width 0.508)
		(layer "F.Cu")
		(net "P5V_A_2")
	)
	(segment
		(start 264.746232 18.170144)
		(end 264.746232 17.346168)
		(width 0.508)
		(layer "F.Cu")
		(net "P5V_A_2")
	)
	(segment
		(start 262.14832 11.67892)
		(end 262.14832 13.29817)
		(width 0.381)
		(layer "F.Cu")
		(net "P5V_A_2")
	)
	(segment
		(start 165.776402 -130.048)
		(end 165.776402 -131.2164)
		(width 0.508)
		(layer "F.Cu")
		(net "P5V_A_2")
	)
	(segment
		(start 262.141462 10.67435)
		(end 262.141462 11.672062)
		(width 0.508)
		(layer "F.Cu")
		(net "P5V_A_2")
	)
	(segment
		(start 264.950448 9.793732)
		(end 264.950448 8.867648)
		(width 0.508)
		(layer "F.Cu")
		(net "P5V_A_2")
	)
	(segment
		(start 113.065052 -128.016)
		(end 113.065052 -129.1844)
		(width 0.508)
		(layer "F.Cu")
		(net "P5V_A_2")
	)
	(segment
		(start 52.647088 -148.6535)
		(end 52.647088 -147.428712)
		(width 0.381)
		(layer "F.Cu")
		(net "P5V_A_2")
	)
	(via
		(at 67.45986 -146.761454)
		(size 0.7112)
		(drill 0.4064)
		(layers "F.Cu" "B.Cu")
		(net "P5V_A_2")
	)
	(via
		(at 144.979898 -166.221918)
		(size 0.5588)
		(drill 0.3048)
		(layers "F.Cu" "B.Cu")
		(net "P5V_A_2")
	)
	(via
		(at 146.249898 -166.221918)
		(size 0.5588)
		(drill 0.3048)
		(layers "F.Cu" "B.Cu")
		(net "P5V_A_2")
	)
	(via
		(at 114.699796 -166.221918)
		(size 0.5588)
		(drill 0.3048)
		(layers "F.Cu" "B.Cu")
		(net "P5V_A_2")
	)
	(via
		(at 262.14832 11.67892)
		(size 0.5588)
		(drill 0.3048)
		(layers "F.Cu" "B.Cu")
		(net "P5V_A_2")
	)
	(via
		(at 264.922 17.1704)
		(size 0.5588)
		(drill 0.3048)
		(layers "F.Cu" "B.Cu")
		(net "P5V_A_2")
	)
	(via
		(at 177.8 -166.221918)
		(size 0.5588)
		(drill 0.3048)
		(layers "F.Cu" "B.Cu")
		(net "P5V_A_2")
	)
	(via
		(at 207.8482 -10.12063)
		(size 0.5588)
		(drill 0.3048)
		(layers "F.Cu" "B.Cu")
		(net "P5V_A_2")
	)
	(via
		(at 18.779998 -51.221894)
		(size 0.5588)
		(drill 0.3048)
		(layers "F.Cu" "B.Cu")
		(net "P5V_A_2")
	)
	(via
		(at 68.519802 -143.44015)
		(size 0.7112)
		(drill 0.4064)
		(layers "F.Cu" "B.Cu")
		(net "P5V_A_2")
	)
	(via
		(at 63.6651 -141.477238)
		(size 0.7112)
		(drill 0.4064)
		(layers "F.Cu" "B.Cu")
		(net "P5V_A_2")
	)
	(via
		(at 117.239796 -166.221918)
		(size 0.5588)
		(drill 0.3048)
		(layers "F.Cu" "B.Cu")
		(net "P5V_A_2")
	)
	(via
		(at 52.869846 -51.221894)
		(size 0.5588)
		(drill 0.3048)
		(layers "F.Cu" "B.Cu")
		(net "P5V_A_2")
	)
	(via
		(at 149.275038 -50.988976)
		(size 0.5588)
		(drill 0.3048)
		(layers "F.Cu" "B.Cu")
		(net "P5V_A_2")
	)
	(via
		(at 179.07 -166.221918)
		(size 0.5588)
		(drill 0.3048)
		(layers "F.Cu" "B.Cu")
		(net "P5V_A_2")
	)
	(via
		(at 117.335554 -54.268624)
		(size 0.5588)
		(drill 0.3048)
		(layers "F.Cu" "B.Cu")
		(net "P5V_A_2")
	)
	(via
		(at 216.96172 -9.396984)
		(size 0.5588)
		(drill 0.3048)
		(layers "F.Cu" "B.Cu")
		(net "P5V_A_2")
	)
	(via
		(at 81.879948 -51.221894)
		(size 0.5588)
		(drill 0.3048)
		(layers "F.Cu" "B.Cu")
		(net "P5V_A_2")
	)
	(via
		(at 113.525554 -54.268624)
		(size 0.5588)
		(drill 0.3048)
		(layers "F.Cu" "B.Cu")
		(net "P5V_A_2")
	)
	(via
		(at 114.795554 -54.268624)
		(size 0.5588)
		(drill 0.3048)
		(layers "F.Cu" "B.Cu")
		(net "P5V_A_2")
	)
	(via
		(at 67.45986 -145.491454)
		(size 0.7112)
		(drill 0.4064)
		(layers "F.Cu" "B.Cu")
		(net "P5V_A_2")
	)
	(via
		(at 111.795052 -129.1844)
		(size 0.5588)
		(drill 0.3048)
		(layers "F.Cu" "B.Cu")
		(net "P5V_A_2")
	)
	(via
		(at 68.519802 -144.71015)
		(size 0.7112)
		(drill 0.4064)
		(layers "F.Cu" "B.Cu")
		(net "P5V_A_2")
	)
	(via
		(at 71.948802 -143.44015)
		(size 0.7112)
		(drill 0.4064)
		(layers "F.Cu" "B.Cu")
		(net "P5V_A_2")
	)
	(via
		(at 206.8322 -11.13663)
		(size 0.5588)
		(drill 0.3048)
		(layers "F.Cu" "B.Cu")
		(net "P5V_A_2")
	)
	(via
		(at 165.776402 -131.2164)
		(size 0.5588)
		(drill 0.3048)
		(layers "F.Cu" "B.Cu")
		(net "P5V_A_2")
	)
	(via
		(at 20.049998 -51.221894)
		(size 0.5588)
		(drill 0.3048)
		(layers "F.Cu" "B.Cu")
		(net "P5V_A_2")
	)
	(via
		(at 83.149948 -51.221894)
		(size 0.5588)
		(drill 0.3048)
		(layers "F.Cu" "B.Cu")
		(net "P5V_A_2")
	)
	(via
		(at 196.3166 -337.4517)
		(size 0.5588)
		(drill 0.3048)
		(layers "F.Cu" "B.Cu")
		(net "P5V_A_2")
	)
	(via
		(at 71.948802 -144.71015)
		(size 0.7112)
		(drill 0.4064)
		(layers "F.Cu" "B.Cu")
		(net "P5V_A_2")
	)
	(via
		(at 135.7249 -129.1844)
		(size 0.5588)
		(drill 0.3048)
		(layers "F.Cu" "B.Cu")
		(net "P5V_A_2")
	)
	(via
		(at 70.805802 -144.71015)
		(size 0.7112)
		(drill 0.4064)
		(layers "F.Cu" "B.Cu")
		(net "P5V_A_2")
	)
	(via
		(at 63.667894 -146.795744)
		(size 0.7112)
		(drill 0.4064)
		(layers "F.Cu" "B.Cu")
		(net "P5V_A_2")
	)
	(via
		(at 216.66073 -10.40511)
		(size 0.5588)
		(drill 0.3048)
		(layers "F.Cu" "B.Cu")
		(net "P5V_A_2")
	)
	(via
		(at 21.319998 -51.221894)
		(size 0.5588)
		(drill 0.3048)
		(layers "F.Cu" "B.Cu")
		(net "P5V_A_2")
	)
	(via
		(at 148.789898 -166.221918)
		(size 0.5588)
		(drill 0.3048)
		(layers "F.Cu" "B.Cu")
		(net "P5V_A_2")
	)
	(via
		(at 85.689948 -51.221894)
		(size 0.5588)
		(drill 0.3048)
		(layers "F.Cu" "B.Cu")
		(net "P5V_A_2")
	)
	(via
		(at 54.139846 -51.221894)
		(size 0.5588)
		(drill 0.3048)
		(layers "F.Cu" "B.Cu")
		(net "P5V_A_2")
	)
	(via
		(at 73.091802 -143.44015)
		(size 0.7112)
		(drill 0.4064)
		(layers "F.Cu" "B.Cu")
		(net "P5V_A_2")
	)
	(via
		(at 113.429796 -166.221918)
		(size 0.5588)
		(drill 0.3048)
		(layers "F.Cu" "B.Cu")
		(net "P5V_A_2")
	)
	(via
		(at 177.7873 -51.014884)
		(size 0.5588)
		(drill 0.3048)
		(layers "F.Cu" "B.Cu")
		(net "P5V_A_2")
	)
	(via
		(at 180.3273 -51.014884)
		(size 0.5588)
		(drill 0.3048)
		(layers "F.Cu" "B.Cu")
		(net "P5V_A_2")
	)
	(via
		(at 69.662802 -143.44015)
		(size 0.7112)
		(drill 0.4064)
		(layers "F.Cu" "B.Cu")
		(net "P5V_A_2")
	)
	(via
		(at 176.53 -166.221918)
		(size 0.5588)
		(drill 0.3048)
		(layers "F.Cu" "B.Cu")
		(net "P5V_A_2")
	)
	(via
		(at 207.8482 -11.13663)
		(size 0.5588)
		(drill 0.3048)
		(layers "F.Cu" "B.Cu")
		(net "P5V_A_2")
	)
	(via
		(at 146.735038 -50.988976)
		(size 0.5588)
		(drill 0.3048)
		(layers "F.Cu" "B.Cu")
		(net "P5V_A_2")
	)
	(via
		(at 176.5173 -51.014884)
		(size 0.5588)
		(drill 0.3048)
		(layers "F.Cu" "B.Cu")
		(net "P5V_A_2")
	)
	(via
		(at 63.667894 -145.525744)
		(size 0.7112)
		(drill 0.4064)
		(layers "F.Cu" "B.Cu")
		(net "P5V_A_2")
	)
	(via
		(at 67.44843 -141.425676)
		(size 0.7112)
		(drill 0.4064)
		(layers "F.Cu" "B.Cu")
		(net "P5V_A_2")
	)
	(via
		(at 218.057984 -9.428734)
		(size 0.5588)
		(drill 0.3048)
		(layers "F.Cu" "B.Cu")
		(net "P5V_A_2")
	)
	(via
		(at 264.950448 8.867648)
		(size 0.5588)
		(drill 0.3048)
		(layers "F.Cu" "B.Cu")
		(net "P5V_A_2")
	)
	(via
		(at 164.506402 -131.2164)
		(size 0.5588)
		(drill 0.3048)
		(layers "F.Cu" "B.Cu")
		(net "P5V_A_2")
	)
	(via
		(at 148.005038 -50.988976)
		(size 0.5588)
		(drill 0.3048)
		(layers "F.Cu" "B.Cu")
		(net "P5V_A_2")
	)
	(via
		(at 73.091802 -144.71015)
		(size 0.7112)
		(drill 0.4064)
		(layers "F.Cu" "B.Cu")
		(net "P5V_A_2")
	)
	(via
		(at 74.234802 -143.44015)
		(size 0.7112)
		(drill 0.4064)
		(layers "F.Cu" "B.Cu")
		(net "P5V_A_2")
	)
	(via
		(at 84.419948 -51.221894)
		(size 0.5588)
		(drill 0.3048)
		(layers "F.Cu" "B.Cu")
		(net "P5V_A_2")
	)
	(via
		(at 179.0573 -51.014884)
		(size 0.5588)
		(drill 0.3048)
		(layers "F.Cu" "B.Cu")
		(net "P5V_A_2")
	)
	(via
		(at 217.67673 -10.40511)
		(size 0.5588)
		(drill 0.3048)
		(layers "F.Cu" "B.Cu")
		(net "P5V_A_2")
	)
	(via
		(at 116.065554 -54.268624)
		(size 0.5588)
		(drill 0.3048)
		(layers "F.Cu" "B.Cu")
		(net "P5V_A_2")
	)
	(via
		(at 113.065052 -129.1844)
		(size 0.5588)
		(drill 0.3048)
		(layers "F.Cu" "B.Cu")
		(net "P5V_A_2")
	)
	(via
		(at 70.805802 -143.44015)
		(size 0.7112)
		(drill 0.4064)
		(layers "F.Cu" "B.Cu")
		(net "P5V_A_2")
	)
	(via
		(at 145.465038 -50.988976)
		(size 0.5588)
		(drill 0.3048)
		(layers "F.Cu" "B.Cu")
		(net "P5V_A_2")
	)
	(via
		(at 50.329846 -51.221894)
		(size 0.5588)
		(drill 0.3048)
		(layers "F.Cu" "B.Cu")
		(net "P5V_A_2")
	)
	(via
		(at 237.987586 -345.476322)
		(size 0.5588)
		(drill 0.3048)
		(layers "F.Cu" "B.Cu")
		(net "P5V_A_2")
	)
	(via
		(at 22.589998 -51.221894)
		(size 0.5588)
		(drill 0.3048)
		(layers "F.Cu" "B.Cu")
		(net "P5V_A_2")
	)
	(via
		(at 59.0296 -144.71015)
		(size 0.6604)
		(drill 0.3302)
		(layers "F.Cu" "B.Cu")
		(net "P5V_A_2")
	)
	(via
		(at 69.662802 -144.71015)
		(size 0.7112)
		(drill 0.4064)
		(layers "F.Cu" "B.Cu")
		(net "P5V_A_2")
	)
	(via
		(at 115.969796 -166.221918)
		(size 0.5588)
		(drill 0.3048)
		(layers "F.Cu" "B.Cu")
		(net "P5V_A_2")
	)
	(via
		(at 136.9949 -129.1844)
		(size 0.5588)
		(drill 0.3048)
		(layers "F.Cu" "B.Cu")
		(net "P5V_A_2")
	)
	(via
		(at 147.519898 -166.221918)
		(size 0.5588)
		(drill 0.3048)
		(layers "F.Cu" "B.Cu")
		(net "P5V_A_2")
	)
	(via
		(at 67.44843 -142.695676)
		(size 0.7112)
		(drill 0.4064)
		(layers "F.Cu" "B.Cu")
		(net "P5V_A_2")
	)
	(via
		(at 51.599846 -51.221894)
		(size 0.5588)
		(drill 0.3048)
		(layers "F.Cu" "B.Cu")
		(net "P5V_A_2")
	)
	(via
		(at 74.234802 -144.71015)
		(size 0.7112)
		(drill 0.4064)
		(layers "F.Cu" "B.Cu")
		(net "P5V_A_2")
	)
	(via
		(at 180.34 -166.221918)
		(size 0.5588)
		(drill 0.3048)
		(layers "F.Cu" "B.Cu")
		(net "P5V_A_2")
	)
	(via
		(at 206.8322 -10.12063)
		(size 0.5588)
		(drill 0.3048)
		(layers "F.Cu" "B.Cu")
		(net "P5V_A_2")
	)
	(via
		(at 63.6651 -142.747238)
		(size 0.7112)
		(drill 0.4064)
		(layers "F.Cu" "B.Cu")
		(net "P5V_A_2")
	)
	(segment
		(start 56.804814 -147.483576)
		(end 56.804814 -141.899386)
		(width 0.508)
		(layer "B.Cu")
		(net "P5V_A_2")
	)
	(segment
		(start 74.615802 -147.31365)
		(end 74.615802 -146.74215)
		(width 0.254)
		(layer "B.Cu")
		(net "P5V_A_2")
	)
	(segment
		(start 57.4548 -141.2494)
		(end 60.861194 -141.2494)
		(width 0.508)
		(layer "B.Cu")
		(net "P5V_A_2")
	)
	(segment
		(start 56.804814 -141.899386)
		(end 57.4548 -141.2494)
		(width 0.508)
		(layer "B.Cu")
		(net "P5V_A_2")
	)
	(segment
		(start 253.200916 1.29413)
		(end 258.359148 6.452362)
		(width 0.508)
		(layer "In2.Cu")
		(net "P5V_A_2")
	)
	(segment
		(start 258.359148 6.452362)
		(end 262.535162 6.452362)
		(width 0.508)
		(layer "In2.Cu")
		(net "P5V_A_2")
	)
	(segment
		(start 234.400344 1.29413)
		(end 253.200916 1.29413)
		(width 0.508)
		(layer "In2.Cu")
		(net "P5V_A_2")
	)
	(segment
		(start 220.751146 -6.735572)
		(end 226.370388 -6.735572)
		(width 0.508)
		(layer "In2.Cu")
		(net "P5V_A_2")
	)
	(segment
		(start 226.370388 -6.735572)
		(end 233.559604 0.453644)
		(width 0.508)
		(layer "In2.Cu")
		(net "P5V_A_2")
	)
	(segment
		(start 262.535162 6.452362)
		(end 264.950448 8.867648)
		(width 0.508)
		(layer "In2.Cu")
		(net "P5V_A_2")
	)
	(segment
		(start 218.057984 -9.428734)
		(end 220.751146 -6.735572)
		(width 0.508)
		(layer "In2.Cu")
		(net "P5V_A_2")
	)
	(segment
		(start 233.559858 0.453644)
		(end 234.400344 1.29413)
		(width 0.508)
		(layer "In2.Cu")
		(net "P5V_A_2")
	)
	(segment
		(start 233.559604 0.453644)
		(end 233.559858 0.453644)
		(width 0.508)
		(layer "In2.Cu")
		(net "P5V_A_2")
	)
	(segment
		(start 177.668682 -166.353236)
		(end 177.8 -166.221918)
		(width 0.508)
		(layer "In4.Cu")
		(net "P5V_A_2")
	)
	(segment
		(start 184.0484 -270.98879)
		(end 177.668682 -264.609072)
		(width 0.508)
		(layer "In4.Cu")
		(net "P5V_A_2")
	)
	(segment
		(start 177.668682 -264.609072)
		(end 177.668682 -166.353236)
		(width 0.508)
		(layer "In4.Cu")
		(net "P5V_A_2")
	)
	(segment
		(start 184.0484 -316.7126)
		(end 184.0484 -270.98879)
		(width 0.508)
		(layer "In4.Cu")
		(net "P5V_A_2")
	)
	(segment
		(start 196.3166 -328.9808)
		(end 184.0484 -316.7126)
		(width 0.508)
		(layer "In4.Cu")
		(net "P5V_A_2")
	)
	(segment
		(start 196.3166 -337.4517)
		(end 196.3166 -328.9808)
		(width 0.508)
		(layer "In4.Cu")
		(net "P5V_A_2")
	)
	(segment
		(start 232.430574 -339.91931)
		(end 228.300788 -339.91931)
		(width 0.508)
		(layer "In7.Cu")
		(net "P5V_A_2")
	)
	(segment
		(start 228.300788 -339.91931)
		(end 221.851982 -333.470504)
		(width 0.508)
		(layer "In7.Cu")
		(net "P5V_A_2")
	)
	(segment
		(start 237.987586 -345.476322)
		(end 232.430574 -339.91931)
		(width 0.508)
		(layer "In7.Cu")
		(net "P5V_A_2")
	)
	(segment
		(start 221.851982 -333.470504)
		(end 198.513954 -333.470504)
		(width 0.508)
		(layer "In7.Cu")
		(net "P5V_A_2")
	)
	(segment
		(start 198.513954 -333.470504)
		(end 196.3166 -335.667858)
		(width 0.508)
		(layer "In7.Cu")
		(net "P5V_A_2")
	)
	(segment
		(start 196.3166 -335.667858)
		(end 196.3166 -337.4517)
		(width 0.508)
		(layer "In7.Cu")
		(net "P5V_A_2")
	)
	(segment
		(start 34.816288 -254.069088)
		(end 35.56 -254.8128)
		(width 0.254)
		(layer "F.Cu")
		(net "P5V_A_1_PGOOD")
	)
	(segment
		(start 35.56 -254.8128)
		(end 36.839652 -254.8128)
		(width 0.254)
		(layer "F.Cu")
		(net "P5V_A_1_PGOOD")
	)
	(segment
		(start 36.839652 -254.8128)
		(end 37.354002 -255.32715)
		(width 0.254)
		(layer "F.Cu")
		(net "P5V_A_1_PGOOD")
	)
	(segment
		(start 29.704538 -252.730254)
		(end 30.938724 -251.496068)
		(width 0.254)
		(layer "F.Cu")
		(net "P5V_A_1_PGOOD")
	)
	(segment
		(start 34.816288 -253.3015)
		(end 34.816288 -254.069088)
		(width 0.254)
		(layer "F.Cu")
		(net "P5V_A_1_PGOOD")
	)
	(segment
		(start 32.48787 -252.151642)
		(end 33.071562 -251.56795)
		(width 0.254)
		(layer "F.Cu")
		(net "P5V_A_1_PGOOD")
	)
	(segment
		(start 33.071562 -251.56795)
		(end 33.975802 -251.56795)
		(width 0.254)
		(layer "F.Cu")
		(net "P5V_A_1_PGOOD")
	)
	(segment
		(start 33.975802 -251.56795)
		(end 34.814002 -252.40615)
		(width 0.254)
		(layer "F.Cu")
		(net "P5V_A_1_PGOOD")
	)
	(segment
		(start 34.814002 -252.40615)
		(end 34.816288 -252.408436)
		(width 0.254)
		(layer "F.Cu")
		(net "P5V_A_1_PGOOD")
	)
	(segment
		(start 31.832296 -251.496068)
		(end 32.48787 -252.151642)
		(width 0.254)
		(layer "F.Cu")
		(net "P5V_A_1_PGOOD")
	)
	(segment
		(start 30.938724 -251.496068)
		(end 31.832296 -251.496068)
		(width 0.254)
		(layer "F.Cu")
		(net "P5V_A_1_PGOOD")
	)
	(segment
		(start 34.816288 -252.408436)
		(end 34.816288 -253.3015)
		(width 0.254)
		(layer "F.Cu")
		(net "P5V_A_1_PGOOD")
	)
	(via
		(at 34.814002 -252.40615)
		(size 0.5588)
		(drill 0.3048)
		(layers "F.Cu" "B.Cu")
		(net "P5V_A_1_PGOOD")
	)
	(segment
		(start 32.909002 -250.50115)
		(end 32.807402 -250.50115)
		(width 0.254)
		(layer "B.Cu")
		(net "P5V_A_1_PGOOD")
	)
	(segment
		(start 32.807402 -250.50115)
		(end 32.523176 -250.216924)
		(width 0.254)
		(layer "B.Cu")
		(net "P5V_A_1_PGOOD")
	)
	(segment
		(start 32.523176 -250.216924)
		(end 31.862522 -250.216924)
		(width 0.254)
		(layer "B.Cu")
		(net "P5V_A_1_PGOOD")
	)
	(segment
		(start 34.814002 -252.40615)
		(end 32.909002 -250.50115)
		(width 0.254)
		(layer "B.Cu")
		(net "P5V_A_1_PGOOD")
	)
	(segment
		(start 80.24495 -128.016)
		(end 80.24495 -129.1844)
		(width 0.508)
		(layer "F.Cu")
		(net "P5V_A_1")
	)
	(segment
		(start 174.895002 -243.01577)
		(end 174.895002 -244.18417)
		(width 0.508)
		(layer "F.Cu")
		(net "P5V_A_1")
	)
	(segment
		(start 36.0934 -254.2413)
		(end 37.7317 -254.2413)
		(width 0.381)
		(layer "F.Cu")
		(net "P5V_A_1")
	)
	(segment
		(start 143.3449 -243.01577)
		(end 143.3449 -244.18417)
		(width 0.508)
		(layer "F.Cu")
		(net "P5V_A_1")
	)
	(segment
		(start 176.165002 -243.01577)
		(end 176.165002 -244.18417)
		(width 0.508)
		(layer "F.Cu")
		(net "P5V_A_1")
	)
	(segment
		(start 113.065052 -243.01577)
		(end 113.065052 -244.18417)
		(width 0.508)
		(layer "F.Cu")
		(net "P5V_A_1")
	)
	(segment
		(start 144.6149 -243.01577)
		(end 144.6149 -244.18417)
		(width 0.508)
		(layer "F.Cu")
		(net "P5V_A_1")
	)
	(segment
		(start 57.293002 -249.35815)
		(end 58.452766 -249.35815)
		(width 0.381)
		(layer "F.Cu")
		(net "P5V_A_1")
	)
	(segment
		(start 48.694848 -128.016)
		(end 48.694848 -129.1844)
		(width 0.508)
		(layer "F.Cu")
		(net "P5V_A_1")
	)
	(segment
		(start 218.846908 -381.426974)
		(end 218.737434 -381.3175)
		(width 0.508)
		(layer "F.Cu")
		(net "P5V_A_1")
	)
	(segment
		(start 56.314848 -242.96497)
		(end 56.314848 -244.13337)
		(width 0.508)
		(layer "F.Cu")
		(net "P5V_A_1")
	)
	(segment
		(start 39.5605 -259.9563)
		(end 53.0098 -259.9563)
		(width 0.381)
		(layer "F.Cu")
		(net "P5V_A_1")
	)
	(segment
		(start 35.705288 -253.3015)
		(end 35.705288 -253.853188)
		(width 0.381)
		(layer "F.Cu")
		(net "P5V_A_1")
	)
	(segment
		(start 38.5064 -255.016)
		(end 38.5064 -258.9022)
		(width 0.381)
		(layer "F.Cu")
		(net "P5V_A_1")
	)
	(segment
		(start 58.452766 -249.35815)
		(end 60.1726 -251.077984)
		(width 0.381)
		(layer "F.Cu")
		(net "P5V_A_1")
	)
	(segment
		(start 18.415 -244.18417)
		(end 18.415 -243.01577)
		(width 0.508)
		(layer "F.Cu")
		(net "P5V_A_1")
	)
	(segment
		(start 218.737434 -381.3175)
		(end 218.44 -381.3175)
		(width 0.508)
		(layer "F.Cu")
		(net "P5V_A_1")
	)
	(segment
		(start 57.2135 -259.9563)
		(end 53.0098 -259.9563)
		(width 0.381)
		(layer "F.Cu")
		(net "P5V_A_1")
	)
	(segment
		(start 241.68735 -348.718378)
		(end 241.68735 -347.753178)
		(width 0.508)
		(layer "F.Cu")
		(net "P5V_A_1")
	)
	(segment
		(start 55.044848 -242.96497)
		(end 55.044848 -244.13337)
		(width 0.508)
		(layer "F.Cu")
		(net "P5V_A_1")
	)
	(segment
		(start 111.795052 -243.01577)
		(end 111.795052 -244.18417)
		(width 0.508)
		(layer "F.Cu")
		(net "P5V_A_1")
	)
	(segment
		(start 17.145 -128.016)
		(end 17.145 -129.1844)
		(width 0.508)
		(layer "F.Cu")
		(net "P5V_A_1")
	)
	(segment
		(start 81.51495 -128.016)
		(end 81.51495 -129.1844)
		(width 0.508)
		(layer "F.Cu")
		(net "P5V_A_1")
	)
	(segment
		(start 17.145 -244.18417)
		(end 17.145 -243.01577)
		(width 0.508)
		(layer "F.Cu")
		(net "P5V_A_1")
	)
	(segment
		(start 60.1726 -251.077984)
		(end 60.1726 -256.9972)
		(width 0.381)
		(layer "F.Cu")
		(net "P5V_A_1")
	)
	(segment
		(start 81.51495 -243.01577)
		(end 81.51495 -244.18417)
		(width 0.508)
		(layer "F.Cu")
		(net "P5V_A_1")
	)
	(segment
		(start 80.24495 -243.01577)
		(end 80.24495 -244.18417)
		(width 0.508)
		(layer "F.Cu")
		(net "P5V_A_1")
	)
	(segment
		(start 49.964848 -128.016)
		(end 49.964848 -129.1844)
		(width 0.508)
		(layer "F.Cu")
		(net "P5V_A_1")
	)
	(segment
		(start 60.1726 -256.9972)
		(end 57.2135 -259.9563)
		(width 0.381)
		(layer "F.Cu")
		(net "P5V_A_1")
	)
	(segment
		(start 18.415 -128.016)
		(end 18.415 -129.1844)
		(width 0.508)
		(layer "F.Cu")
		(net "P5V_A_1")
	)
	(segment
		(start 38.5064 -258.9022)
		(end 39.5605 -259.9563)
		(width 0.381)
		(layer "F.Cu")
		(net "P5V_A_1")
	)
	(segment
		(start 219.418154 -381.426974)
		(end 218.846908 -381.426974)
		(width 0.508)
		(layer "F.Cu")
		(net "P5V_A_1")
	)
	(segment
		(start 37.7317 -254.2413)
		(end 38.5064 -255.016)
		(width 0.381)
		(layer "F.Cu")
		(net "P5V_A_1")
	)
	(segment
		(start 35.705288 -253.853188)
		(end 36.0934 -254.2413)
		(width 0.381)
		(layer "F.Cu")
		(net "P5V_A_1")
	)
	(via
		(at 55.007002 -248.08815)
		(size 0.7112)
		(drill 0.4064)
		(layers "F.Cu" "B.Cu")
		(net "P5V_A_1")
	)
	(via
		(at 219.4052 -332.708504)
		(size 0.5588)
		(drill 0.3048)
		(layers "F.Cu" "B.Cu")
		(net "P5V_A_1")
	)
	(via
		(at 51.578002 -249.35815)
		(size 0.7112)
		(drill 0.4064)
		(layers "F.Cu" "B.Cu")
		(net "P5V_A_1")
	)
	(via
		(at 55.044848 -244.13337)
		(size 0.5588)
		(drill 0.3048)
		(layers "F.Cu" "B.Cu")
		(net "P5V_A_1")
	)
	(via
		(at 46.630336 -246.326406)
		(size 0.7112)
		(drill 0.4064)
		(layers "F.Cu" "B.Cu")
		(net "P5V_A_1")
	)
	(via
		(at 56.150002 -249.35815)
		(size 0.7112)
		(drill 0.4064)
		(layers "F.Cu" "B.Cu")
		(net "P5V_A_1")
	)
	(via
		(at 18.415 -129.1844)
		(size 0.5588)
		(drill 0.3048)
		(layers "F.Cu" "B.Cu")
		(net "P5V_A_1")
	)
	(via
		(at 143.3449 -244.18417)
		(size 0.5588)
		(drill 0.3048)
		(layers "F.Cu" "B.Cu")
		(net "P5V_A_1")
	)
	(via
		(at 176.165002 -244.18417)
		(size 0.5588)
		(drill 0.3048)
		(layers "F.Cu" "B.Cu")
		(net "P5V_A_1")
	)
	(via
		(at 174.895002 -244.18417)
		(size 0.5588)
		(drill 0.3048)
		(layers "F.Cu" "B.Cu")
		(net "P5V_A_1")
	)
	(via
		(at 85.689948 -281.221942)
		(size 0.5588)
		(drill 0.3048)
		(layers "F.Cu" "B.Cu")
		(net "P5V_A_1")
	)
	(via
		(at 81.879948 -166.221918)
		(size 0.5588)
		(drill 0.3048)
		(layers "F.Cu" "B.Cu")
		(net "P5V_A_1")
	)
	(via
		(at 131.946396 -281.196542)
		(size 0.5588)
		(drill 0.3048)
		(layers "F.Cu" "B.Cu")
		(net "P5V_A_1")
	)
	(via
		(at 22.589998 -281.221942)
		(size 0.5588)
		(drill 0.3048)
		(layers "F.Cu" "B.Cu")
		(net "P5V_A_1")
	)
	(via
		(at 50.645568 -251.488702)
		(size 0.7112)
		(drill 0.4064)
		(layers "F.Cu" "B.Cu")
		(net "P5V_A_1")
	)
	(via
		(at 130.676396 -281.196542)
		(size 0.5588)
		(drill 0.3048)
		(layers "F.Cu" "B.Cu")
		(net "P5V_A_1")
	)
	(via
		(at 83.149948 -166.221918)
		(size 0.5588)
		(drill 0.3048)
		(layers "F.Cu" "B.Cu")
		(net "P5V_A_1")
	)
	(via
		(at 18.415 -244.18417)
		(size 0.5588)
		(drill 0.3048)
		(layers "F.Cu" "B.Cu")
		(net "P5V_A_1")
	)
	(via
		(at 180.34 -281.221942)
		(size 0.5588)
		(drill 0.3048)
		(layers "F.Cu" "B.Cu")
		(net "P5V_A_1")
	)
	(via
		(at 50.329846 -166.221918)
		(size 0.5588)
		(drill 0.3048)
		(layers "F.Cu" "B.Cu")
		(net "P5V_A_1")
	)
	(via
		(at 51.599846 -166.221918)
		(size 0.5588)
		(drill 0.3048)
		(layers "F.Cu" "B.Cu")
		(net "P5V_A_1")
	)
	(via
		(at 55.007002 -249.35815)
		(size 0.7112)
		(drill 0.4064)
		(layers "F.Cu" "B.Cu")
		(net "P5V_A_1")
	)
	(via
		(at 46.621954 -250.136406)
		(size 0.7112)
		(drill 0.4064)
		(layers "F.Cu" "B.Cu")
		(net "P5V_A_1")
	)
	(via
		(at 22.589998 -166.221918)
		(size 0.5588)
		(drill 0.3048)
		(layers "F.Cu" "B.Cu")
		(net "P5V_A_1")
	)
	(via
		(at 56.314848 -244.13337)
		(size 0.5588)
		(drill 0.3048)
		(layers "F.Cu" "B.Cu")
		(net "P5V_A_1")
	)
	(via
		(at 18.779998 -281.221942)
		(size 0.5588)
		(drill 0.3048)
		(layers "F.Cu" "B.Cu")
		(net "P5V_A_1")
	)
	(via
		(at 219.418154 -381.426974)
		(size 0.5588)
		(drill 0.3048)
		(layers "F.Cu" "B.Cu")
		(net "P5V_A_1")
	)
	(via
		(at 176.53 -281.221942)
		(size 0.5588)
		(drill 0.3048)
		(layers "F.Cu" "B.Cu")
		(net "P5V_A_1")
	)
	(via
		(at 52.721002 -248.08815)
		(size 0.7112)
		(drill 0.4064)
		(layers "F.Cu" "B.Cu")
		(net "P5V_A_1")
	)
	(via
		(at 83.149948 -281.221942)
		(size 0.5588)
		(drill 0.3048)
		(layers "F.Cu" "B.Cu")
		(net "P5V_A_1")
	)
	(via
		(at 113.065052 -244.18417)
		(size 0.5588)
		(drill 0.3048)
		(layers "F.Cu" "B.Cu")
		(net "P5V_A_1")
	)
	(via
		(at 144.979898 -281.221942)
		(size 0.5588)
		(drill 0.3048)
		(layers "F.Cu" "B.Cu")
		(net "P5V_A_1")
	)
	(via
		(at 81.51495 -129.1844)
		(size 0.5588)
		(drill 0.3048)
		(layers "F.Cu" "B.Cu")
		(net "P5V_A_1")
	)
	(via
		(at 144.6149 -244.18417)
		(size 0.5588)
		(drill 0.3048)
		(layers "F.Cu" "B.Cu")
		(net "P5V_A_1")
	)
	(via
		(at 177.8 -281.221942)
		(size 0.5588)
		(drill 0.3048)
		(layers "F.Cu" "B.Cu")
		(net "P5V_A_1")
	)
	(via
		(at 17.145 -244.18417)
		(size 0.5588)
		(drill 0.3048)
		(layers "F.Cu" "B.Cu")
		(net "P5V_A_1")
	)
	(via
		(at 84.419948 -281.221942)
		(size 0.5588)
		(drill 0.3048)
		(layers "F.Cu" "B.Cu")
		(net "P5V_A_1")
	)
	(via
		(at 85.689948 -166.221918)
		(size 0.5588)
		(drill 0.3048)
		(layers "F.Cu" "B.Cu")
		(net "P5V_A_1")
	)
	(via
		(at 21.319998 -281.221942)
		(size 0.5588)
		(drill 0.3048)
		(layers "F.Cu" "B.Cu")
		(net "P5V_A_1")
	)
	(via
		(at 57.293002 -248.08815)
		(size 0.7112)
		(drill 0.4064)
		(layers "F.Cu" "B.Cu")
		(net "P5V_A_1")
	)
	(via
		(at 81.51495 -244.18417)
		(size 0.5588)
		(drill 0.3048)
		(layers "F.Cu" "B.Cu")
		(net "P5V_A_1")
	)
	(via
		(at 51.599846 -281.221942)
		(size 0.5588)
		(drill 0.3048)
		(layers "F.Cu" "B.Cu")
		(net "P5V_A_1")
	)
	(via
		(at 179.07 -281.221942)
		(size 0.5588)
		(drill 0.3048)
		(layers "F.Cu" "B.Cu")
		(net "P5V_A_1")
	)
	(via
		(at 48.694848 -129.1844)
		(size 0.5588)
		(drill 0.3048)
		(layers "F.Cu" "B.Cu")
		(net "P5V_A_1")
	)
	(via
		(at 134.486396 -281.196542)
		(size 0.5588)
		(drill 0.3048)
		(layers "F.Cu" "B.Cu")
		(net "P5V_A_1")
	)
	(via
		(at 241.68735 -347.753178)
		(size 0.5588)
		(drill 0.3048)
		(layers "F.Cu" "B.Cu")
		(net "P5V_A_1")
	)
	(via
		(at 53.0098 -259.9563)
		(size 0.6604)
		(drill 0.3302)
		(layers "F.Cu" "B.Cu")
		(net "P5V_A_1")
	)
	(via
		(at 50.571908 -247.578118)
		(size 0.7112)
		(drill 0.4064)
		(layers "F.Cu" "B.Cu")
		(net "P5V_A_1")
	)
	(via
		(at 56.150002 -248.08815)
		(size 0.7112)
		(drill 0.4064)
		(layers "F.Cu" "B.Cu")
		(net "P5V_A_1")
	)
	(via
		(at 195.510912 -336.739738)
		(size 0.5588)
		(drill 0.3048)
		(layers "F.Cu" "B.Cu")
		(net "P5V_A_1")
	)
	(via
		(at 53.864002 -248.08815)
		(size 0.7112)
		(drill 0.4064)
		(layers "F.Cu" "B.Cu")
		(net "P5V_A_1")
	)
	(via
		(at 17.145 -129.1844)
		(size 0.5588)
		(drill 0.3048)
		(layers "F.Cu" "B.Cu")
		(net "P5V_A_1")
	)
	(via
		(at 80.24495 -129.1844)
		(size 0.5588)
		(drill 0.3048)
		(layers "F.Cu" "B.Cu")
		(net "P5V_A_1")
	)
	(via
		(at 84.419948 -166.221918)
		(size 0.5588)
		(drill 0.3048)
		(layers "F.Cu" "B.Cu")
		(net "P5V_A_1")
	)
	(via
		(at 111.795052 -244.18417)
		(size 0.5588)
		(drill 0.3048)
		(layers "F.Cu" "B.Cu")
		(net "P5V_A_1")
	)
	(via
		(at 53.864002 -249.35815)
		(size 0.7112)
		(drill 0.4064)
		(layers "F.Cu" "B.Cu")
		(net "P5V_A_1")
	)
	(via
		(at 147.519898 -281.221942)
		(size 0.5588)
		(drill 0.3048)
		(layers "F.Cu" "B.Cu")
		(net "P5V_A_1")
	)
	(via
		(at 20.049998 -281.221942)
		(size 0.5588)
		(drill 0.3048)
		(layers "F.Cu" "B.Cu")
		(net "P5V_A_1")
	)
	(via
		(at 46.621954 -251.406406)
		(size 0.7112)
		(drill 0.4064)
		(layers "F.Cu" "B.Cu")
		(net "P5V_A_1")
	)
	(via
		(at 54.139846 -166.221918)
		(size 0.5588)
		(drill 0.3048)
		(layers "F.Cu" "B.Cu")
		(net "P5V_A_1")
	)
	(via
		(at 51.578002 -248.08815)
		(size 0.7112)
		(drill 0.4064)
		(layers "F.Cu" "B.Cu")
		(net "P5V_A_1")
	)
	(via
		(at 146.249898 -281.221942)
		(size 0.5588)
		(drill 0.3048)
		(layers "F.Cu" "B.Cu")
		(net "P5V_A_1")
	)
	(via
		(at 54.139846 -281.221942)
		(size 0.5588)
		(drill 0.3048)
		(layers "F.Cu" "B.Cu")
		(net "P5V_A_1")
	)
	(via
		(at 50.329846 -281.221942)
		(size 0.5588)
		(drill 0.3048)
		(layers "F.Cu" "B.Cu")
		(net "P5V_A_1")
	)
	(via
		(at 81.879948 -281.221942)
		(size 0.5588)
		(drill 0.3048)
		(layers "F.Cu" "B.Cu")
		(net "P5V_A_1")
	)
	(via
		(at 21.319998 -166.221918)
		(size 0.5588)
		(drill 0.3048)
		(layers "F.Cu" "B.Cu")
		(net "P5V_A_1")
	)
	(via
		(at 49.964848 -129.1844)
		(size 0.5588)
		(drill 0.3048)
		(layers "F.Cu" "B.Cu")
		(net "P5V_A_1")
	)
	(via
		(at 52.869846 -281.221942)
		(size 0.5588)
		(drill 0.3048)
		(layers "F.Cu" "B.Cu")
		(net "P5V_A_1")
	)
	(via
		(at 50.571908 -246.308118)
		(size 0.7112)
		(drill 0.4064)
		(layers "F.Cu" "B.Cu")
		(net "P5V_A_1")
	)
	(via
		(at 52.721002 -249.35815)
		(size 0.7112)
		(drill 0.4064)
		(layers "F.Cu" "B.Cu")
		(net "P5V_A_1")
	)
	(via
		(at 50.645568 -250.218702)
		(size 0.7112)
		(drill 0.4064)
		(layers "F.Cu" "B.Cu")
		(net "P5V_A_1")
	)
	(via
		(at 133.216396 -281.196542)
		(size 0.5588)
		(drill 0.3048)
		(layers "F.Cu" "B.Cu")
		(net "P5V_A_1")
	)
	(via
		(at 148.789898 -281.221942)
		(size 0.5588)
		(drill 0.3048)
		(layers "F.Cu" "B.Cu")
		(net "P5V_A_1")
	)
	(via
		(at 52.869846 -166.221918)
		(size 0.5588)
		(drill 0.3048)
		(layers "F.Cu" "B.Cu")
		(net "P5V_A_1")
	)
	(via
		(at 18.779998 -166.221918)
		(size 0.5588)
		(drill 0.3048)
		(layers "F.Cu" "B.Cu")
		(net "P5V_A_1")
	)
	(via
		(at 57.293002 -249.35815)
		(size 0.7112)
		(drill 0.4064)
		(layers "F.Cu" "B.Cu")
		(net "P5V_A_1")
	)
	(via
		(at 80.24495 -244.18417)
		(size 0.5588)
		(drill 0.3048)
		(layers "F.Cu" "B.Cu")
		(net "P5V_A_1")
	)
	(via
		(at 20.049998 -166.221918)
		(size 0.5588)
		(drill 0.3048)
		(layers "F.Cu" "B.Cu")
		(net "P5V_A_1")
	)
	(via
		(at 46.630336 -247.596406)
		(size 0.7112)
		(drill 0.4064)
		(layers "F.Cu" "B.Cu")
		(net "P5V_A_1")
	)
	(segment
		(start 40.513 -245.8974)
		(end 39.863014 -246.547386)
		(width 0.508)
		(layer "B.Cu")
		(net "P5V_A_1")
	)
	(segment
		(start 17.4752 -129.5146)
		(end 17.145 -129.1844)
		(width 0.508)
		(layer "B.Cu")
		(net "P5V_A_1")
	)
	(segment
		(start 43.919394 -245.8974)
		(end 40.513 -245.8974)
		(width 0.508)
		(layer "B.Cu")
		(net "P5V_A_1")
	)
	(segment
		(start 176.165002 -244.18417)
		(end 174.895002 -244.18417)
		(width 0.508)
		(layer "B.Cu")
		(net "P5V_A_1")
	)
	(segment
		(start 57.674002 -251.96165)
		(end 57.674002 -251.39015)
		(width 0.254)
		(layer "B.Cu")
		(net "P5V_A_1")
	)
	(segment
		(start 18.779998 -166.221918)
		(end 17.4752 -164.91712)
		(width 0.508)
		(layer "B.Cu")
		(net "P5V_A_1")
	)
	(segment
		(start 17.4752 -164.91712)
		(end 17.4752 -129.5146)
		(width 0.508)
		(layer "B.Cu")
		(net "P5V_A_1")
	)
	(segment
		(start 39.863014 -246.547386)
		(end 39.863014 -252.131576)
		(width 0.508)
		(layer "B.Cu")
		(net "P5V_A_1")
	)
	(segment
		(start 174.895002 -244.18417)
		(end 144.6149 -244.18417)
		(width 0.508)
		(layer "B.Cu")
		(net "P5V_A_1")
	)
	(segment
		(start 80.24495 -129.1844)
		(end 81.51495 -129.1844)
		(width 0.508)
		(layer "In2.Cu")
		(net "P5V_A_1")
	)
	(segment
		(start 48.694848 -129.1844)
		(end 49.964848 -129.1844)
		(width 0.508)
		(layer "In2.Cu")
		(net "P5V_A_1")
	)
	(segment
		(start 17.145 -129.1844)
		(end 18.415 -129.1844)
		(width 0.508)
		(layer "In2.Cu")
		(net "P5V_A_1")
	)
	(segment
		(start 18.415 -129.1844)
		(end 48.694848 -129.1844)
		(width 0.508)
		(layer "In2.Cu")
		(net "P5V_A_1")
	)
	(segment
		(start 49.964848 -129.1844)
		(end 80.24495 -129.1844)
		(width 0.508)
		(layer "In2.Cu")
		(net "P5V_A_1")
	)
	(segment
		(start 183.2864 -317.101728)
		(end 195.510912 -329.32624)
		(width 0.508)
		(layer "In4.Cu")
		(net "P5V_A_1")
	)
	(segment
		(start 180.34 -281.221942)
		(end 183.2864 -284.168342)
		(width 0.508)
		(layer "In4.Cu")
		(net "P5V_A_1")
	)
	(segment
		(start 219.977208 -333.280512)
		(end 219.4052 -332.708504)
		(width 0.508)
		(layer "In4.Cu")
		(net "P5V_A_1")
	)
	(segment
		(start 219.977208 -380.86792)
		(end 219.977208 -333.280512)
		(width 0.508)
		(layer "In4.Cu")
		(net "P5V_A_1")
	)
	(segment
		(start 219.418154 -381.426974)
		(end 219.977208 -380.86792)
		(width 0.508)
		(layer "In4.Cu")
		(net "P5V_A_1")
	)
	(segment
		(start 183.2864 -284.168342)
		(end 183.2864 -317.101728)
		(width 0.508)
		(layer "In4.Cu")
		(net "P5V_A_1")
	)
	(segment
		(start 195.510912 -329.32624)
		(end 195.510912 -336.739738)
		(width 0.508)
		(layer "In4.Cu")
		(net "P5V_A_1")
	)
	(segment
		(start 197.853554 -332.708504)
		(end 195.510912 -335.051146)
		(width 0.508)
		(layer "In7.Cu")
		(net "P5V_A_1")
	)
	(segment
		(start 228.547422 -339.088222)
		(end 236.35462 -339.088222)
		(width 0.508)
		(layer "In7.Cu")
		(net "P5V_A_1")
	)
	(segment
		(start 219.4052 -332.708504)
		(end 197.853554 -332.708504)
		(width 0.508)
		(layer "In7.Cu")
		(net "P5V_A_1")
	)
	(segment
		(start 195.510912 -335.051146)
		(end 195.510912 -336.739738)
		(width 0.508)
		(layer "In7.Cu")
		(net "P5V_A_1")
	)
	(segment
		(start 236.35462 -339.088222)
		(end 241.68735 -344.420952)
		(width 0.508)
		(layer "In7.Cu")
		(net "P5V_A_1")
	)
	(segment
		(start 241.68735 -344.420952)
		(end 241.68735 -347.753178)
		(width 0.508)
		(layer "In7.Cu")
		(net "P5V_A_1")
	)
	(segment
		(start 222.167704 -332.708504)
		(end 228.547422 -339.088222)
		(width 0.508)
		(layer "In7.Cu")
		(net "P5V_A_1")
	)
	(segment
		(start 219.4052 -332.708504)
		(end 222.167704 -332.708504)
		(width 0.508)
		(layer "In7.Cu")
		(net "P5V_A_1")
	)
	(segment
		(start 222.00108 -358.405938)
		(end 222.87103 -358.405938)
		(width 0.508)
		(layer "F.Cu")
		(net "P3V3_STBY_A")
	)
	(segment
		(start 476.742252 -47.125128)
		(end 476.742252 -45.989748)
		(width 0.508)
		(layer "F.Cu")
		(net "P3V3_STBY_A")
	)
	(segment
		(start 149.640798 -161.040318)
		(end 150.466298 -161.040318)
		(width 0.508)
		(layer "F.Cu")
		(net "P3V3_STBY_A")
	)
	(segment
		(start 380.91745 -177.169318)
		(end 380.91745 -177.892202)
		(width 0.508)
		(layer "F.Cu")
		(net "P3V3_STBY_A")
	)
	(segment
		(start 118.090696 -161.014918)
		(end 118.916196 -161.014918)
		(width 0.508)
		(layer "F.Cu")
		(net "P3V3_STBY_A")
	)
	(segment
		(start 175.404018 -28.592526)
		(end 174.641764 -27.830272)
		(width 0.508)
		(layer "F.Cu")
		(net "P3V3_STBY_A")
	)
	(segment
		(start 36.242498 -292.169342)
		(end 36.242498 -292.994842)
		(width 0.508)
		(layer "F.Cu")
		(net "P3V3_STBY_A")
	)
	(segment
		(start 130.892296 -62.143894)
		(end 130.892296 -64.137794)
		(width 0.508)
		(layer "F.Cu")
		(net "P3V3_STBY_A")
	)
	(segment
		(start 222.686626 -345.066112)
		(end 221.518988 -345.066112)
		(width 0.508)
		(layer "F.Cu")
		(net "P3V3_STBY_A")
	)
	(segment
		(start 396.34795 -272.141442)
		(end 396.34795 -271.315942)
		(width 0.508)
		(layer "F.Cu")
		(net "P3V3_STBY_A")
	)
	(segment
		(start 380.307342 -292.194742)
		(end 379.9586 -291.846)
		(width 0.508)
		(layer "F.Cu")
		(net "P3V3_STBY_A")
	)
	(segment
		(start 286.7152 -284.9753)
		(end 286.7152 -285.7754)
		(width 0.508)
		(layer "F.Cu")
		(net "P3V3_STBY_A")
	)
	(segment
		(start 222.200978 -96.13773)
		(end 222.200978 -95.299022)
		(width 0.508)
		(layer "F.Cu")
		(net "P3V3_STBY_A")
	)
	(segment
		(start 23.440898 -276.014942)
		(end 24.266398 -276.014942)
		(width 0.508)
		(layer "F.Cu")
		(net "P3V3_STBY_A")
	)
	(segment
		(start 349.367602 -177.169318)
		(end 349.367602 -177.567336)
		(width 0.508)
		(layer "F.Cu")
		(net "P3V3_STBY_A")
	)
	(segment
		(start 255.993646 -260.174486)
		(end 255.872488 -260.053328)
		(width 0.508)
		(layer "F.Cu")
		(net "P3V3_STBY_A")
	)
	(segment
		(start 318.3255 -62.194694)
		(end 318.051688 -62.194694)
		(width 0.508)
		(layer "F.Cu")
		(net "P3V3_STBY_A")
	)
	(segment
		(start 476.672148 -268.903704)
		(end 476.672148 -268.078204)
		(width 0.508)
		(layer "F.Cu")
		(net "P3V3_STBY_A")
	)
	(segment
		(start 275.17217 -284.290262)
		(end 275.17217 -283.490162)
		(width 0.508)
		(layer "F.Cu")
		(net "P3V3_STBY_A")
	)
	(segment
		(start 23.415498 -46.014894)
		(end 24.240998 -46.014894)
		(width 0.508)
		(layer "F.Cu")
		(net "P3V3_STBY_A")
	)
	(segment
		(start 54.990746 -276.065742)
		(end 55.816246 -276.065742)
		(width 0.508)
		(layer "F.Cu")
		(net "P3V3_STBY_A")
	)
	(segment
		(start 222.1992 -91.2114)
		(end 222.1992 -90.372692)
		(width 0.508)
		(layer "F.Cu")
		(net "P3V3_STBY_A")
	)
	(segment
		(start 304.261266 -262.971534)
		(end 303.6062 -263.6266)
		(width 0.508)
		(layer "F.Cu")
		(net "P3V3_STBY_A")
	)
	(segment
		(start 255.925828 11.049)
		(end 255.925828 10.012172)
		(width 0.508)
		(layer "F.Cu")
		(net "P3V3_STBY_A")
	)
	(segment
		(start 82.811366 -17.35963)
		(end 81.915 -17.35963)
		(width 0.508)
		(layer "F.Cu")
		(net "P3V3_STBY_A")
	)
	(segment
		(start 271.81937 -284.290262)
		(end 271.81937 -283.490162)
		(width 0.508)
		(layer "F.Cu")
		(net "P3V3_STBY_A")
	)
	(segment
		(start 364.798102 -42.141394)
		(end 364.795816 -42.141394)
		(width 0.508)
		(layer "F.Cu")
		(net "P3V3_STBY_A")
	)
	(segment
		(start 349.367602 -292.169342)
		(end 348.729808 -292.169342)
		(width 0.508)
		(layer "F.Cu")
		(net "P3V3_STBY_A")
	)
	(segment
		(start 364.798102 -272.141442)
		(end 364.798102 -271.315942)
		(width 0.508)
		(layer "F.Cu")
		(net "P3V3_STBY_A")
	)
	(segment
		(start 444.5762 -62.143894)
		(end 443.611 -62.143894)
		(width 0.508)
		(layer "F.Cu")
		(net "P3V3_STBY_A")
	)
	(segment
		(start 175.404018 -28.635452)
		(end 175.404018 -28.592526)
		(width 0.508)
		(layer "F.Cu")
		(net "P3V3_STBY_A")
	)
	(segment
		(start 77.96657 -17.380966)
		(end 76.969366 -17.380966)
		(width 0.508)
		(layer "F.Cu")
		(net "P3V3_STBY_A")
	)
	(segment
		(start 348.729808 -292.169342)
		(end 348.161864 -291.601398)
		(width 0.508)
		(layer "F.Cu")
		(net "P3V3_STBY_A")
	)
	(segment
		(start 221.807786 -346.91447)
		(end 221.807786 -346.9132)
		(width 0.508)
		(layer "F.Cu")
		(net "P3V3_STBY_A")
	)
	(segment
		(start 181.1909 -46.014894)
		(end 182.0164 -46.014894)
		(width 0.508)
		(layer "F.Cu")
		(net "P3V3_STBY_A")
	)
	(segment
		(start 223.623124 -346.9132)
		(end 223.839024 -346.6973)
		(width 0.508)
		(layer "F.Cu")
		(net "P3V3_STBY_A")
	)
	(segment
		(start 380.91745 -177.892202)
		(end 379.85192 -178.957732)
		(width 0.508)
		(layer "F.Cu")
		(net "P3V3_STBY_A")
	)
	(segment
		(start 67.792346 -292.169342)
		(end 68.088256 -292.169342)
		(width 0.508)
		(layer "F.Cu")
		(net "P3V3_STBY_A")
	)
	(segment
		(start 162.442398 -62.169294)
		(end 162.442398 -62.994794)
		(width 0.508)
		(layer "F.Cu")
		(net "P3V3_STBY_A")
	)
	(segment
		(start 444.0174 -292.169342)
		(end 444.0174 -293.032942)
		(width 0.508)
		(layer "F.Cu")
		(net "P3V3_STBY_A")
	)
	(segment
		(start 246.92356 -292.989)
		(end 246.92356 -291.60978)
		(width 0.508)
		(layer "F.Cu")
		(net "P3V3_STBY_A")
	)
	(segment
		(start 318.051688 -62.194694)
		(end 317.504064 -62.742318)
		(width 0.508)
		(layer "F.Cu")
		(net "P3V3_STBY_A")
	)
	(segment
		(start 86.566248 -276.040342)
		(end 87.391748 -276.040342)
		(width 0.508)
		(layer "F.Cu")
		(net "P3V3_STBY_A")
	)
	(segment
		(start 36.242498 -177.169318)
		(end 36.242498 -177.994818)
		(width 0.508)
		(layer "F.Cu")
		(net "P3V3_STBY_A")
	)
	(segment
		(start 54.990746 -46.065694)
		(end 55.816246 -46.065694)
		(width 0.508)
		(layer "F.Cu")
		(net "P3V3_STBY_A")
	)
	(segment
		(start 252.73 -289.7505)
		(end 252.73 -288.94151)
		(width 0.508)
		(layer "F.Cu")
		(net "P3V3_STBY_A")
	)
	(segment
		(start 271.526 -271.8435)
		(end 271.526 -271.0434)
		(width 0.508)
		(layer "F.Cu")
		(net "P3V3_STBY_A")
	)
	(segment
		(start 85.781134 -31.85287)
		(end 85.781134 -32.974534)
		(width 0.508)
		(layer "F.Cu")
		(net "P3V3_STBY_A")
	)
	(segment
		(start 225.844354 -346.7227)
		(end 225.983292 -346.583762)
		(width 0.3556)
		(layer "F.Cu")
		(net "P3V3_STBY_A")
	)
	(segment
		(start 149.640798 -276.065742)
		(end 150.466298 -276.065742)
		(width 0.508)
		(layer "F.Cu")
		(net "P3V3_STBY_A")
	)
	(segment
		(start 263.137142 -209.29473)
		(end 263.137142 -205.428342)
		(width 0.508)
		(layer "F.Cu")
		(net "P3V3_STBY_A")
	)
	(segment
		(start 222.69196 -343.017856)
		(end 221.529656 -343.017856)
		(width 0.508)
		(layer "F.Cu")
		(net "P3V3_STBY_A")
	)
	(segment
		(start 256.2098 -289.7505)
		(end 256.2098 -288.925)
		(width 0.508)
		(layer "F.Cu")
		(net "P3V3_STBY_A")
	)
	(segment
		(start 223.139 -120.904)
		(end 222.1865 -119.9515)
		(width 0.508)
		(layer "F.Cu")
		(net "P3V3_STBY_A")
	)
	(segment
		(start 36.242498 -62.169294)
		(end 36.242498 -63.0174)
		(width 0.508)
		(layer "F.Cu")
		(net "P3V3_STBY_A")
	)
	(segment
		(start 351.652586 -62.186566)
		(end 351.652586 -64.979042)
		(width 0.508)
		(layer "F.Cu")
		(net "P3V3_STBY_A")
	)
	(segment
		(start 286.7406 -271.8689)
		(end 286.7406 -271.0688)
		(width 0.508)
		(layer "F.Cu")
		(net "P3V3_STBY_A")
	)
	(segment
		(start 173.342808 -28.64358)
		(end 175.39589 -28.64358)
		(width 0.381)
		(layer "F.Cu")
		(net "P3V3_STBY_A")
	)
	(segment
		(start 333.248 -157.141418)
		(end 333.248 -156.315918)
		(width 0.508)
		(layer "F.Cu")
		(net "P3V3_STBY_A")
	)
	(segment
		(start 23.415498 -161.014918)
		(end 24.240998 -161.014918)
		(width 0.508)
		(layer "F.Cu")
		(net "P3V3_STBY_A")
	)
	(segment
		(start 191.2493 -52.197)
		(end 193.685414 -52.197)
		(width 0.508)
		(layer "F.Cu")
		(net "P3V3_STBY_A")
	)
	(segment
		(start 222.1865 -119.9515)
		(end 222.1865 -119.6594)
		(width 0.508)
		(layer "F.Cu")
		(net "P3V3_STBY_A")
	)
	(segment
		(start 86.098634 -16.29029)
		(end 86.098634 -14.923262)
		(width 0.3048)
		(layer "F.Cu")
		(net "P3V3_STBY_A")
	)
	(segment
		(start 321.096132 -177.2539)
		(end 321.536314 -177.694082)
		(width 0.508)
		(layer "F.Cu")
		(net "P3V3_STBY_A")
	)
	(segment
		(start 304.261266 -261.373874)
		(end 304.261266 -262.567674)
		(width 0.508)
		(layer "F.Cu")
		(net "P3V3_STBY_A")
	)
	(segment
		(start 181.1909 -161.014918)
		(end 182.0164 -161.014918)
		(width 0.508)
		(layer "F.Cu")
		(net "P3V3_STBY_A")
	)
	(segment
		(start 224.14103 -358.405938)
		(end 224.170748 -358.435656)
		(width 0.508)
		(layer "F.Cu")
		(net "P3V3_STBY_A")
	)
	(segment
		(start 396.34795 -157.141418)
		(end 396.34795 -156.315918)
		(width 0.508)
		(layer "F.Cu")
		(net "P3V3_STBY_A")
	)
	(segment
		(start 225.983292 -346.583762)
		(end 227.501704 -346.583762)
		(width 0.3556)
		(layer "F.Cu")
		(net "P3V3_STBY_A")
	)
	(segment
		(start 118.666768 -46.014894)
		(end 118.991888 -46.340014)
		(width 0.508)
		(layer "F.Cu")
		(net "P3V3_STBY_A")
	)
	(segment
		(start 252.73 -288.94151)
		(end 252.710442 -288.921952)
		(width 0.508)
		(layer "F.Cu")
		(net "P3V3_STBY_A")
	)
	(segment
		(start 249.611388 -288.921952)
		(end 252.710442 -288.921952)
		(width 0.508)
		(layer "F.Cu")
		(net "P3V3_STBY_A")
	)
	(segment
		(start 303.6062 -263.6266)
		(end 303.276 -263.6266)
		(width 0.508)
		(layer "F.Cu")
		(net "P3V3_STBY_A")
	)
	(segment
		(start 54.990746 -158.347918)
		(end 55.816246 -158.347918)
		(width 0.508)
		(layer "F.Cu")
		(net "P3V3_STBY_A")
	)
	(segment
		(start 86.098634 -14.923262)
		(end 86.100666 -14.92123)
		(width 0.3048)
		(layer "F.Cu")
		(net "P3V3_STBY_A")
	)
	(segment
		(start 260.790944 -341.037672)
		(end 260.422136 -340.668864)
		(width 0.508)
		(layer "F.Cu")
		(net "P3V3_STBY_A")
	)
	(segment
		(start 86.540848 -46.014894)
		(end 87.366348 -46.014894)
		(width 0.508)
		(layer "F.Cu")
		(net "P3V3_STBY_A")
	)
	(segment
		(start 396.34795 -42.141394)
		(end 396.34795 -41.315894)
		(width 0.508)
		(layer "F.Cu")
		(net "P3V3_STBY_A")
	)
	(segment
		(start 253.873 -300.7995)
		(end 253.873 -298.323)
		(width 0.508)
		(layer "F.Cu")
		(net "P3V3_STBY_A")
	)
	(segment
		(start 255.993646 -260.881622)
		(end 255.993646 -260.174486)
		(width 0.508)
		(layer "F.Cu")
		(net "P3V3_STBY_A")
	)
	(segment
		(start 68.088256 -292.169342)
		(end 68.87591 -291.381688)
		(width 0.508)
		(layer "F.Cu")
		(net "P3V3_STBY_A")
	)
	(segment
		(start 221.975172 -358.431846)
		(end 222.00108 -358.405938)
		(width 0.508)
		(layer "F.Cu")
		(net "P3V3_STBY_A")
	)
	(segment
		(start 412.467552 -177.169318)
		(end 411.599126 -177.169318)
		(width 0.508)
		(layer "F.Cu")
		(net "P3V3_STBY_A")
	)
	(segment
		(start 193.685414 -52.197)
		(end 194.92087 -53.432456)
		(width 0.508)
		(layer "F.Cu")
		(net "P3V3_STBY_A")
	)
	(segment
		(start 223.9645 -10.541)
		(end 223.9645 -9.498838)
		(width 0.508)
		(layer "F.Cu")
		(net "P3V3_STBY_A")
	)
	(segment
		(start 447.8655 -183.007)
		(end 448.747134 -183.007)
		(width 0.508)
		(layer "F.Cu")
		(net "P3V3_STBY_A")
	)
	(segment
		(start 319.5955 -292.143942)
		(end 322.312792 -292.143942)
		(width 0.508)
		(layer "F.Cu")
		(net "P3V3_STBY_A")
	)
	(segment
		(start 261.487666 -336.350864)
		(end 260.43509 -336.350864)
		(width 0.508)
		(layer "F.Cu")
		(net "P3V3_STBY_A")
	)
	(segment
		(start 258.5212 -289.7505)
		(end 258.5212 -288.925)
		(width 0.508)
		(layer "F.Cu")
		(net "P3V3_STBY_A")
	)
	(segment
		(start 415.464752 -292.169342)
		(end 415.464752 -293.058342)
		(width 0.508)
		(layer "F.Cu")
		(net "P3V3_STBY_A")
	)
	(segment
		(start 99.342448 -177.169318)
		(end 99.342448 -177.994818)
		(width 0.508)
		(layer "F.Cu")
		(net "P3V3_STBY_A")
	)
	(segment
		(start 222.746824 -346.9132)
		(end 223.623124 -346.9132)
		(width 0.508)
		(layer "F.Cu")
		(net "P3V3_STBY_A")
	)
	(segment
		(start 478.74809 -269.224252)
		(end 479.57359 -269.224252)
		(width 0.508)
		(layer "F.Cu")
		(net "P3V3_STBY_A")
	)
	(segment
		(start 333.248 -42.141394)
		(end 333.957676 -41.431718)
		(width 0.508)
		(layer "F.Cu")
		(net "P3V3_STBY_A")
	)
	(segment
		(start 261.487666 -338.052664)
		(end 260.43509 -338.052664)
		(width 0.508)
		(layer "F.Cu")
		(net "P3V3_STBY_A")
	)
	(segment
		(start 87.315548 -161.040318)
		(end 87.340948 -161.014918)
		(width 0.508)
		(layer "F.Cu")
		(net "P3V3_STBY_A")
	)
	(segment
		(start 86.540848 -161.040318)
		(end 87.315548 -161.040318)
		(width 0.508)
		(layer "F.Cu")
		(net "P3V3_STBY_A")
	)
	(segment
		(start 113.581942 -272.281904)
		(end 113.581942 -271.456404)
		(width 0.508)
		(layer "F.Cu")
		(net "P3V3_STBY_A")
	)
	(segment
		(start 261.487666 -339.754464)
		(end 260.43509 -339.754464)
		(width 0.508)
		(layer "F.Cu")
		(net "P3V3_STBY_A")
	)
	(segment
		(start 82.248502 -30.955488)
		(end 82.248502 -30.102048)
		(width 0.508)
		(layer "F.Cu")
		(net "P3V3_STBY_A")
	)
	(segment
		(start 477.2406 -47.623476)
		(end 476.742252 -47.125128)
		(width 0.508)
		(layer "F.Cu")
		(net "P3V3_STBY_A")
	)
	(segment
		(start 221.518988 -345.066112)
		(end 221.518988 -344.125042)
		(width 0.508)
		(layer "F.Cu")
		(net "P3V3_STBY_A")
	)
	(segment
		(start 175.39589 -28.64358)
		(end 175.404018 -28.635452)
		(width 0.381)
		(layer "F.Cu")
		(net "P3V3_STBY_A")
	)
	(segment
		(start 459.4479 -157.141418)
		(end 459.4479 -156.315918)
		(width 0.508)
		(layer "F.Cu")
		(net "P3V3_STBY_A")
	)
	(segment
		(start 86.100666 -14.92123)
		(end 85.05063 -14.92123)
		(width 0.508)
		(layer "F.Cu")
		(net "P3V3_STBY_A")
	)
	(segment
		(start 221.807786 -346.9132)
		(end 222.746824 -346.9132)
		(width 0.508)
		(layer "F.Cu")
		(net "P3V3_STBY_A")
	)
	(segment
		(start 427.898052 -42.141394)
		(end 427.898052 -41.315894)
		(width 0.508)
		(layer "F.Cu")
		(net "P3V3_STBY_A")
	)
	(segment
		(start 127.844296 -291.077142)
		(end 128.7018 -291.077142)
		(width 0.508)
		(layer "F.Cu")
		(net "P3V3_STBY_A")
	)
	(segment
		(start 261.513066 -341.037672)
		(end 260.790944 -341.037672)
		(width 0.508)
		(layer "F.Cu")
		(net "P3V3_STBY_A")
	)
	(segment
		(start 351.652586 -64.979042)
		(end 351.65665 -64.983106)
		(width 0.508)
		(layer "F.Cu")
		(net "P3V3_STBY_A")
	)
	(segment
		(start 380.94285 -62.143894)
		(end 380.94285 -63.007494)
		(width 0.508)
		(layer "F.Cu")
		(net "P3V3_STBY_A")
	)
	(segment
		(start 477.2406 -162.6235)
		(end 477.2406 -161.798)
		(width 0.508)
		(layer "F.Cu")
		(net "P3V3_STBY_A")
	)
	(segment
		(start 255.0414 18.664428)
		(end 254.258572 18.664428)
		(width 0.508)
		(layer "F.Cu")
		(net "P3V3_STBY_A")
	)
	(segment
		(start 255.070102 26.404824)
		(end 255.070102 24.342598)
		(width 0.508)
		(layer "F.Cu")
		(net "P3V3_STBY_A")
	)
	(segment
		(start 349.367602 -177.567336)
		(end 348.882462 -178.052476)
		(width 0.508)
		(layer "F.Cu")
		(net "P3V3_STBY_A")
	)
	(segment
		(start 319.5955 -177.2539)
		(end 321.096132 -177.2539)
		(width 0.508)
		(layer "F.Cu")
		(net "P3V3_STBY_A")
	)
	(segment
		(start 223.839024 -346.6973)
		(end 223.864424 -346.7227)
		(width 0.508)
		(layer "F.Cu")
		(net "P3V3_STBY_A")
	)
	(segment
		(start 162.442398 -177.169318)
		(end 162.442398 -177.994818)
		(width 0.508)
		(layer "F.Cu")
		(net "P3V3_STBY_A")
	)
	(segment
		(start 258.367276 -261.79526)
		(end 258.367276 -262.59536)
		(width 0.508)
		(layer "F.Cu")
		(net "P3V3_STBY_A")
	)
	(segment
		(start 332.6384 -272.141442)
		(end 332.6384 -271.315942)
		(width 0.508)
		(layer "F.Cu")
		(net "P3V3_STBY_A")
	)
	(segment
		(start 246.92356 -291.60978)
		(end 249.611388 -288.921952)
		(width 0.508)
		(layer "F.Cu")
		(net "P3V3_STBY_A")
	)
	(segment
		(start 459.4479 -42.141394)
		(end 459.4479 -41.315894)
		(width 0.508)
		(layer "F.Cu")
		(net "P3V3_STBY_A")
	)
	(segment
		(start 427.898052 -272.141442)
		(end 427.898052 -271.315942)
		(width 0.508)
		(layer "F.Cu")
		(net "P3V3_STBY_A")
	)
	(segment
		(start 364.795816 -42.141394)
		(end 364.795816 -40.448738)
		(width 0.508)
		(layer "F.Cu")
		(net "P3V3_STBY_A")
	)
	(segment
		(start 223.864424 -346.7227)
		(end 225.402648 -346.7227)
		(width 0.508)
		(layer "F.Cu")
		(net "P3V3_STBY_A")
	)
	(segment
		(start 237.996476 -349.655892)
		(end 237.996476 -350.49333)
		(width 0.508)
		(layer "F.Cu")
		(net "P3V3_STBY_A")
	)
	(segment
		(start 225.402648 -346.7227)
		(end 225.844354 -346.7227)
		(width 0.3556)
		(layer "F.Cu")
		(net "P3V3_STBY_A")
	)
	(segment
		(start 458.5335 -272.090642)
		(end 458.5335 -271.265142)
		(width 0.508)
		(layer "F.Cu")
		(net "P3V3_STBY_A")
	)
	(segment
		(start 364.798102 -157.141418)
		(end 364.798102 -156.315918)
		(width 0.508)
		(layer "F.Cu")
		(net "P3V3_STBY_A")
	)
	(segment
		(start 99.342448 -62.816994)
		(end 99.164648 -62.994794)
		(width 0.508)
		(layer "F.Cu")
		(net "P3V3_STBY_A")
	)
	(segment
		(start 380.91745 -292.194742)
		(end 380.307342 -292.194742)
		(width 0.508)
		(layer "F.Cu")
		(net "P3V3_STBY_A")
	)
	(segment
		(start 468.735918 -156.078174)
		(end 468.735918 -155.252674)
		(width 0.508)
		(layer "F.Cu")
		(net "P3V3_STBY_A")
	)
	(segment
		(start 171.691808 -28.64358)
		(end 173.342808 -28.64358)
		(width 0.381)
		(layer "F.Cu")
		(net "P3V3_STBY_A")
	)
	(segment
		(start 191.135 -292.5445)
		(end 192.0875 -292.5445)
		(width 0.508)
		(layer "F.Cu")
		(net "P3V3_STBY_A")
	)
	(segment
		(start 99.342448 -62.169294)
		(end 99.342448 -62.816994)
		(width 0.508)
		(layer "F.Cu")
		(net "P3V3_STBY_A")
	)
	(segment
		(start 304.261266 -262.567674)
		(end 304.261266 -262.971534)
		(width 0.508)
		(layer "F.Cu")
		(net "P3V3_STBY_A")
	)
	(segment
		(start 118.090696 -46.014894)
		(end 118.666768 -46.014894)
		(width 0.508)
		(layer "F.Cu")
		(net "P3V3_STBY_A")
	)
	(segment
		(start 412.873952 -62.143894)
		(end 411.7594 -62.143894)
		(width 0.508)
		(layer "F.Cu")
		(net "P3V3_STBY_A")
	)
	(segment
		(start 222.693992 -345.073478)
		(end 222.686626 -345.066112)
		(width 0.508)
		(layer "F.Cu")
		(net "P3V3_STBY_A")
	)
	(segment
		(start 151.572214 -46.602904)
		(end 151.951944 -46.223174)
		(width 0.508)
		(layer "F.Cu")
		(net "P3V3_STBY_A")
	)
	(segment
		(start 333.957676 -41.431718)
		(end 333.957676 -41.387776)
		(width 0.508)
		(layer "F.Cu")
		(net "P3V3_STBY_A")
	)
	(segment
		(start 150.178008 -46.602904)
		(end 151.572214 -46.602904)
		(width 0.508)
		(layer "F.Cu")
		(net "P3V3_STBY_A")
	)
	(segment
		(start 190.9445 -172.1358)
		(end 191.77 -172.1358)
		(width 0.508)
		(layer "F.Cu")
		(net "P3V3_STBY_A")
	)
	(segment
		(start 263.137142 -205.428342)
		(end 257.773424 -200.064624)
		(width 0.508)
		(layer "F.Cu")
		(net "P3V3_STBY_A")
	)
	(segment
		(start 443.611 -62.143894)
		(end 443.5856 -62.118494)
		(width 0.508)
		(layer "F.Cu")
		(net "P3V3_STBY_A")
	)
	(segment
		(start 277.4188 -285.1531)
		(end 277.4188 -285.9532)
		(width 0.508)
		(layer "F.Cu")
		(net "P3V3_STBY_A")
	)
	(segment
		(start 162.442398 -292.169342)
		(end 162.442398 -292.994842)
		(width 0.508)
		(layer "F.Cu")
		(net "P3V3_STBY_A")
	)
	(segment
		(start 252.970792 -300.7995)
		(end 253.873 -300.7995)
		(width 0.508)
		(layer "F.Cu")
		(net "P3V3_STBY_A")
	)
	(segment
		(start 130.892296 -177.143918)
		(end 130.892296 -177.969418)
		(width 0.508)
		(layer "F.Cu")
		(net "P3V3_STBY_A")
	)
	(segment
		(start 221.518988 -344.125042)
		(end 221.533974 -344.110056)
		(width 0.508)
		(layer "F.Cu")
		(net "P3V3_STBY_A")
	)
	(segment
		(start 181.1909 -276.014942)
		(end 182.0164 -276.014942)
		(width 0.508)
		(layer "F.Cu")
		(net "P3V3_STBY_A")
	)
	(segment
		(start 427.898052 -157.141418)
		(end 427.898052 -156.315918)
		(width 0.508)
		(layer "F.Cu")
		(net "P3V3_STBY_A")
	)
	(segment
		(start 67.792346 -177.169318)
		(end 67.792346 -177.994818)
		(width 0.508)
		(layer "F.Cu")
		(net "P3V3_STBY_A")
	)
	(segment
		(start 222.87103 -358.405938)
		(end 224.14103 -358.405938)
		(width 0.508)
		(layer "F.Cu")
		(net "P3V3_STBY_A")
	)
	(segment
		(start 224.170748 -358.435656)
		(end 225.245168 -358.435656)
		(width 0.508)
		(layer "F.Cu")
		(net "P3V3_STBY_A")
	)
	(segment
		(start 80.18907 -17.368266)
		(end 79.268066 -17.368266)
		(width 0.508)
		(layer "F.Cu")
		(net "P3V3_STBY_A")
	)
	(segment
		(start 99.342448 -292.169342)
		(end 99.342448 -292.989)
		(width 0.508)
		(layer "F.Cu")
		(net "P3V3_STBY_A")
	)
	(segment
		(start 257.773424 -200.064624)
		(end 257.773424 -140.851128)
		(width 0.508)
		(layer "F.Cu")
		(net "P3V3_STBY_A")
	)
	(segment
		(start 222.928942 -219.748862)
		(end 222.928942 -220.693742)
		(width 0.508)
		(layer "F.Cu")
		(net "P3V3_STBY_A")
	)
	(segment
		(start 468.761318 -41.07815)
		(end 468.761318 -40.25265)
		(width 0.508)
		(layer "F.Cu")
		(net "P3V3_STBY_A")
	)
	(segment
		(start 156.248354 -28.531566)
		(end 157.269434 -28.531566)
		(width 0.508)
		(layer "F.Cu")
		(net "P3V3_STBY_A")
	)
	(segment
		(start 79.84998 -30.960314)
		(end 79.84998 -30.086808)
		(width 0.508)
		(layer "F.Cu")
		(net "P3V3_STBY_A")
	)
	(segment
		(start 263.1186 -284.8737)
		(end 263.1186 -285.6738)
		(width 0.508)
		(layer "F.Cu")
		(net "P3V3_STBY_A")
	)
	(segment
		(start 149.640798 -46.065694)
		(end 150.178008 -46.602904)
		(width 0.508)
		(layer "F.Cu")
		(net "P3V3_STBY_A")
	)
	(segment
		(start 254.258572 18.664428)
		(end 254.0762 18.8468)
		(width 0.508)
		(layer "F.Cu")
		(net "P3V3_STBY_A")
	)
	(segment
		(start 271.4498 -280.7589)
		(end 271.4498 -281.6098)
		(width 0.508)
		(layer "F.Cu")
		(net "P3V3_STBY_A")
	)
	(segment
		(start 67.792346 -62.169294)
		(end 67.792346 -62.994794)
		(width 0.508)
		(layer "F.Cu")
		(net "P3V3_STBY_A")
	)
	(via
		(at 217.7542 -115.3922)
		(size 0.5588)
		(drill 0.3048)
		(layers "F.Cu" "B.Cu")
		(net "P3V3_STBY_A")
	)
	(via
		(at 479.57359 -269.224252)
		(size 0.5588)
		(drill 0.3048)
		(layers "F.Cu" "B.Cu")
		(net "P3V3_STBY_A")
	)
	(via
		(at 260.43509 -338.052664)
		(size 0.5588)
		(drill 0.3048)
		(layers "F.Cu" "B.Cu")
		(net "P3V3_STBY_A")
	)
	(via
		(at 477.2406 -161.798)
		(size 0.5588)
		(drill 0.3048)
		(layers "F.Cu" "B.Cu")
		(net "P3V3_STBY_A")
	)
	(via
		(at 118.916196 -161.014918)
		(size 0.5588)
		(drill 0.3048)
		(layers "F.Cu" "B.Cu")
		(net "P3V3_STBY_A")
	)
	(via
		(at 194.92087 -53.432456)
		(size 0.5588)
		(drill 0.3048)
		(layers "F.Cu" "B.Cu")
		(net "P3V3_STBY_A")
	)
	(via
		(at 187.168282 -236.014006)
		(size 0.5588)
		(drill 0.3048)
		(layers "F.Cu" "B.Cu")
		(net "P3V3_STBY_A")
	)
	(via
		(at 333.957676 -41.387776)
		(size 0.5588)
		(drill 0.3048)
		(layers "F.Cu" "B.Cu")
		(net "P3V3_STBY_A")
	)
	(via
		(at 396.34795 -156.315918)
		(size 0.5588)
		(drill 0.3048)
		(layers "F.Cu" "B.Cu")
		(net "P3V3_STBY_A")
	)
	(via
		(at 271.526 -271.0434)
		(size 0.5588)
		(drill 0.3048)
		(layers "F.Cu" "B.Cu")
		(net "P3V3_STBY_A")
	)
	(via
		(at 351.65665 -64.983106)
		(size 0.5588)
		(drill 0.3048)
		(layers "F.Cu" "B.Cu")
		(net "P3V3_STBY_A")
	)
	(via
		(at 411.599126 -177.169318)
		(size 0.5588)
		(drill 0.3048)
		(layers "F.Cu" "B.Cu")
		(net "P3V3_STBY_A")
	)
	(via
		(at 380.94285 -63.007494)
		(size 0.5588)
		(drill 0.3048)
		(layers "F.Cu" "B.Cu")
		(net "P3V3_STBY_A")
	)
	(via
		(at 118.991888 -46.340014)
		(size 0.5588)
		(drill 0.3048)
		(layers "F.Cu" "B.Cu")
		(net "P3V3_STBY_A")
	)
	(via
		(at 150.466298 -161.040318)
		(size 0.5588)
		(drill 0.3048)
		(layers "F.Cu" "B.Cu")
		(net "P3V3_STBY_A")
	)
	(via
		(at 186.406282 -238.935006)
		(size 0.5588)
		(drill 0.3048)
		(layers "F.Cu" "B.Cu")
		(net "P3V3_STBY_A")
	)
	(via
		(at 427.898052 -271.315942)
		(size 0.5588)
		(drill 0.3048)
		(layers "F.Cu" "B.Cu")
		(net "P3V3_STBY_A")
	)
	(via
		(at 364.798102 -156.315918)
		(size 0.5588)
		(drill 0.3048)
		(layers "F.Cu" "B.Cu")
		(net "P3V3_STBY_A")
	)
	(via
		(at 396.34795 -271.315942)
		(size 0.5588)
		(drill 0.3048)
		(layers "F.Cu" "B.Cu")
		(net "P3V3_STBY_A")
	)
	(via
		(at 221.975172 -358.431846)
		(size 0.5588)
		(drill 0.3048)
		(layers "F.Cu" "B.Cu")
		(net "P3V3_STBY_A")
	)
	(via
		(at 222.928942 -220.693742)
		(size 0.5588)
		(drill 0.3048)
		(layers "F.Cu" "B.Cu")
		(net "P3V3_STBY_A")
	)
	(via
		(at 87.391748 -276.040342)
		(size 0.5588)
		(drill 0.3048)
		(layers "F.Cu" "B.Cu")
		(net "P3V3_STBY_A")
	)
	(via
		(at 427.898052 -41.315894)
		(size 0.5588)
		(drill 0.3048)
		(layers "F.Cu" "B.Cu")
		(net "P3V3_STBY_A")
	)
	(via
		(at 151.951944 -46.223174)
		(size 0.5588)
		(drill 0.3048)
		(layers "F.Cu" "B.Cu")
		(net "P3V3_STBY_A")
	)
	(via
		(at 191.77 -172.1358)
		(size 0.5588)
		(drill 0.3048)
		(layers "F.Cu" "B.Cu")
		(net "P3V3_STBY_A")
	)
	(via
		(at 128.7018 -291.077142)
		(size 0.5588)
		(drill 0.3048)
		(layers "F.Cu" "B.Cu")
		(net "P3V3_STBY_A")
	)
	(via
		(at 85.781134 -32.974534)
		(size 0.5588)
		(drill 0.3048)
		(layers "F.Cu" "B.Cu")
		(net "P3V3_STBY_A")
	)
	(via
		(at 99.164648 -62.994794)
		(size 0.5588)
		(drill 0.3048)
		(layers "F.Cu" "B.Cu")
		(net "P3V3_STBY_A")
	)
	(via
		(at 252.970792 -300.7995)
		(size 0.5588)
		(drill 0.3048)
		(layers "F.Cu" "B.Cu")
		(net "P3V3_STBY_A")
	)
	(via
		(at 364.795816 -40.448738)
		(size 0.5588)
		(drill 0.3048)
		(layers "F.Cu" "B.Cu")
		(net "P3V3_STBY_A")
	)
	(via
		(at 55.816246 -276.065742)
		(size 0.5588)
		(drill 0.3048)
		(layers "F.Cu" "B.Cu")
		(net "P3V3_STBY_A")
	)
	(via
		(at 36.242498 -63.0174)
		(size 0.5588)
		(drill 0.3048)
		(layers "F.Cu" "B.Cu")
		(net "P3V3_STBY_A")
	)
	(via
		(at 67.792346 -62.994794)
		(size 0.5588)
		(drill 0.3048)
		(layers "F.Cu" "B.Cu")
		(net "P3V3_STBY_A")
	)
	(via
		(at 187.168282 -238.427006)
		(size 0.5588)
		(drill 0.3048)
		(layers "F.Cu" "B.Cu")
		(net "P3V3_STBY_A")
	)
	(via
		(at 255.872488 -260.053328)
		(size 0.5588)
		(drill 0.3048)
		(layers "F.Cu" "B.Cu")
		(net "P3V3_STBY_A")
	)
	(via
		(at 411.7594 -62.143894)
		(size 0.5588)
		(drill 0.3048)
		(layers "F.Cu" "B.Cu")
		(net "P3V3_STBY_A")
	)
	(via
		(at 187.061348 -241.044984)
		(size 0.5588)
		(drill 0.3048)
		(layers "F.Cu" "B.Cu")
		(net "P3V3_STBY_A")
	)
	(via
		(at 271.81937 -283.490162)
		(size 0.5588)
		(drill 0.3048)
		(layers "F.Cu" "B.Cu")
		(net "P3V3_STBY_A")
	)
	(via
		(at 55.816246 -158.347918)
		(size 0.5588)
		(drill 0.3048)
		(layers "F.Cu" "B.Cu")
		(net "P3V3_STBY_A")
	)
	(via
		(at 459.4479 -156.315918)
		(size 0.5588)
		(drill 0.3048)
		(layers "F.Cu" "B.Cu")
		(net "P3V3_STBY_A")
	)
	(via
		(at 379.9586 -291.846)
		(size 0.5588)
		(drill 0.3048)
		(layers "F.Cu" "B.Cu")
		(net "P3V3_STBY_A")
	)
	(via
		(at 322.312792 -292.143942)
		(size 0.5588)
		(drill 0.3048)
		(layers "F.Cu" "B.Cu")
		(net "P3V3_STBY_A")
	)
	(via
		(at 348.161864 -291.601398)
		(size 0.5588)
		(drill 0.3048)
		(layers "F.Cu" "B.Cu")
		(net "P3V3_STBY_A")
	)
	(via
		(at 277.4188 -285.9532)
		(size 0.5588)
		(drill 0.3048)
		(layers "F.Cu" "B.Cu")
		(net "P3V3_STBY_A")
	)
	(via
		(at 192.0875 -292.5445)
		(size 0.5588)
		(drill 0.3048)
		(layers "F.Cu" "B.Cu")
		(net "P3V3_STBY_A")
	)
	(via
		(at 113.581942 -271.456404)
		(size 0.5588)
		(drill 0.3048)
		(layers "F.Cu" "B.Cu")
		(net "P3V3_STBY_A")
	)
	(via
		(at 186.406282 -237.665006)
		(size 0.5588)
		(drill 0.3048)
		(layers "F.Cu" "B.Cu")
		(net "P3V3_STBY_A")
	)
	(via
		(at 286.7406 -271.0688)
		(size 0.5588)
		(drill 0.3048)
		(layers "F.Cu" "B.Cu")
		(net "P3V3_STBY_A")
	)
	(via
		(at 260.43509 -339.754464)
		(size 0.5588)
		(drill 0.3048)
		(layers "F.Cu" "B.Cu")
		(net "P3V3_STBY_A")
	)
	(via
		(at 379.85192 -178.957732)
		(size 0.5588)
		(drill 0.3048)
		(layers "F.Cu" "B.Cu")
		(net "P3V3_STBY_A")
	)
	(via
		(at 188.184282 -233.728006)
		(size 0.6096)
		(drill 0.3048)
		(layers "F.Cu" "B.Cu")
		(net "P3V3_STBY_A")
	)
	(via
		(at 267.822426 -210.332574)
		(size 0.5588)
		(drill 0.3048)
		(layers "F.Cu" "B.Cu")
		(net "P3V3_STBY_A")
	)
	(via
		(at 79.268066 -17.368266)
		(size 0.5588)
		(drill 0.3048)
		(layers "F.Cu" "B.Cu")
		(net "P3V3_STBY_A")
	)
	(via
		(at 182.0164 -276.014942)
		(size 0.5588)
		(drill 0.3048)
		(layers "F.Cu" "B.Cu")
		(net "P3V3_STBY_A")
	)
	(via
		(at 182.0164 -161.014918)
		(size 0.5588)
		(drill 0.3048)
		(layers "F.Cu" "B.Cu")
		(net "P3V3_STBY_A")
	)
	(via
		(at 415.464752 -293.058342)
		(size 0.5588)
		(drill 0.3048)
		(layers "F.Cu" "B.Cu")
		(net "P3V3_STBY_A")
	)
	(via
		(at 427.898052 -156.315918)
		(size 0.5588)
		(drill 0.3048)
		(layers "F.Cu" "B.Cu")
		(net "P3V3_STBY_A")
	)
	(via
		(at 99.342448 -177.994818)
		(size 0.5588)
		(drill 0.3048)
		(layers "F.Cu" "B.Cu")
		(net "P3V3_STBY_A")
	)
	(via
		(at 36.242498 -177.994818)
		(size 0.5588)
		(drill 0.3048)
		(layers "F.Cu" "B.Cu")
		(net "P3V3_STBY_A")
	)
	(via
		(at 174.641764 -27.830272)
		(size 0.5588)
		(drill 0.3048)
		(layers "F.Cu" "B.Cu")
		(net "P3V3_STBY_A")
	)
	(via
		(at 24.266398 -276.014942)
		(size 0.5588)
		(drill 0.3048)
		(layers "F.Cu" "B.Cu")
		(net "P3V3_STBY_A")
	)
	(via
		(at 157.269434 -28.531566)
		(size 0.5588)
		(drill 0.3048)
		(layers "F.Cu" "B.Cu")
		(net "P3V3_STBY_A")
	)
	(via
		(at 79.661512 -28.683204)
		(size 0.5588)
		(drill 0.3048)
		(layers "F.Cu" "B.Cu")
		(net "P3V3_STBY_A")
	)
	(via
		(at 348.882462 -178.052476)
		(size 0.5588)
		(drill 0.3048)
		(layers "F.Cu" "B.Cu")
		(net "P3V3_STBY_A")
	)
	(via
		(at 246.243602 -299.110146)
		(size 0.5588)
		(drill 0.3048)
		(layers "F.Cu" "B.Cu")
		(net "P3V3_STBY_A")
	)
	(via
		(at 321.536314 -177.694082)
		(size 0.5588)
		(drill 0.3048)
		(layers "F.Cu" "B.Cu")
		(net "P3V3_STBY_A")
	)
	(via
		(at 252.710442 -288.921952)
		(size 0.5588)
		(drill 0.3048)
		(layers "F.Cu" "B.Cu")
		(net "P3V3_STBY_A")
	)
	(via
		(at 24.240998 -46.014894)
		(size 0.5588)
		(drill 0.3048)
		(layers "F.Cu" "B.Cu")
		(net "P3V3_STBY_A")
	)
	(via
		(at 275.17217 -283.490162)
		(size 0.5588)
		(drill 0.3048)
		(layers "F.Cu" "B.Cu")
		(net "P3V3_STBY_A")
	)
	(via
		(at 254.0762 18.8468)
		(size 0.5588)
		(drill 0.3048)
		(layers "F.Cu" "B.Cu")
		(net "P3V3_STBY_A")
	)
	(via
		(at 459.4479 -41.315894)
		(size 0.5588)
		(drill 0.3048)
		(layers "F.Cu" "B.Cu")
		(net "P3V3_STBY_A")
	)
	(via
		(at 458.5335 -271.265142)
		(size 0.5588)
		(drill 0.3048)
		(layers "F.Cu" "B.Cu")
		(net "P3V3_STBY_A")
	)
	(via
		(at 87.366348 -46.014894)
		(size 0.5588)
		(drill 0.3048)
		(layers "F.Cu" "B.Cu")
		(net "P3V3_STBY_A")
	)
	(via
		(at 130.892296 -64.137794)
		(size 0.5588)
		(drill 0.3048)
		(layers "F.Cu" "B.Cu")
		(net "P3V3_STBY_A")
	)
	(via
		(at 221.807786 -346.91447)
		(size 0.5588)
		(drill 0.3048)
		(layers "F.Cu" "B.Cu")
		(net "P3V3_STBY_A")
	)
	(via
		(at 255.925828 10.012172)
		(size 0.5588)
		(drill 0.3048)
		(layers "F.Cu" "B.Cu")
		(net "P3V3_STBY_A")
	)
	(via
		(at 24.240998 -161.014918)
		(size 0.5588)
		(drill 0.3048)
		(layers "F.Cu" "B.Cu")
		(net "P3V3_STBY_A")
	)
	(via
		(at 221.533974 -344.110056)
		(size 0.5588)
		(drill 0.3048)
		(layers "F.Cu" "B.Cu")
		(net "P3V3_STBY_A")
	)
	(via
		(at 332.6384 -271.315942)
		(size 0.5588)
		(drill 0.3048)
		(layers "F.Cu" "B.Cu")
		(net "P3V3_STBY_A")
	)
	(via
		(at 258.367276 -262.59536)
		(size 0.5588)
		(drill 0.3048)
		(layers "F.Cu" "B.Cu")
		(net "P3V3_STBY_A")
	)
	(via
		(at 260.422136 -340.668864)
		(size 0.5588)
		(drill 0.3048)
		(layers "F.Cu" "B.Cu")
		(net "P3V3_STBY_A")
	)
	(via
		(at 255.070102 24.342598)
		(size 0.5588)
		(drill 0.3048)
		(layers "F.Cu" "B.Cu")
		(net "P3V3_STBY_A")
	)
	(via
		(at 223.139 -120.904)
		(size 0.5588)
		(drill 0.3048)
		(layers "F.Cu" "B.Cu")
		(net "P3V3_STBY_A")
	)
	(via
		(at 237.996476 -350.49333)
		(size 0.5588)
		(drill 0.3048)
		(layers "F.Cu" "B.Cu")
		(net "P3V3_STBY_A")
	)
	(via
		(at 222.200978 -95.299022)
		(size 0.5588)
		(drill 0.3048)
		(layers "F.Cu" "B.Cu")
		(net "P3V3_STBY_A")
	)
	(via
		(at 55.816246 -46.065694)
		(size 0.5588)
		(drill 0.3048)
		(layers "F.Cu" "B.Cu")
		(net "P3V3_STBY_A")
	)
	(via
		(at 320.8655 -209.152744)
		(size 0.5588)
		(drill 0.3048)
		(layers "F.Cu" "B.Cu")
		(net "P3V3_STBY_A")
	)
	(via
		(at 76.969366 -17.380966)
		(size 0.5588)
		(drill 0.3048)
		(layers "F.Cu" "B.Cu")
		(net "P3V3_STBY_A")
	)
	(via
		(at 476.742252 -45.989748)
		(size 0.5588)
		(drill 0.3048)
		(layers "F.Cu" "B.Cu")
		(net "P3V3_STBY_A")
	)
	(via
		(at 303.276 -263.6266)
		(size 0.5588)
		(drill 0.3048)
		(layers "F.Cu" "B.Cu")
		(net "P3V3_STBY_A")
	)
	(via
		(at 333.248 -156.315918)
		(size 0.5588)
		(drill 0.3048)
		(layers "F.Cu" "B.Cu")
		(net "P3V3_STBY_A")
	)
	(via
		(at 271.4498 -281.6098)
		(size 0.5588)
		(drill 0.3048)
		(layers "F.Cu" "B.Cu")
		(net "P3V3_STBY_A")
	)
	(via
		(at 443.5856 -62.118494)
		(size 0.5588)
		(drill 0.3048)
		(layers "F.Cu" "B.Cu")
		(net "P3V3_STBY_A")
	)
	(via
		(at 317.504064 -62.742318)
		(size 0.5588)
		(drill 0.3048)
		(layers "F.Cu" "B.Cu")
		(net "P3V3_STBY_A")
	)
	(via
		(at 182.0164 -46.014894)
		(size 0.5588)
		(drill 0.3048)
		(layers "F.Cu" "B.Cu")
		(net "P3V3_STBY_A")
	)
	(via
		(at 476.672148 -268.078204)
		(size 0.5588)
		(drill 0.3048)
		(layers "F.Cu" "B.Cu")
		(net "P3V3_STBY_A")
	)
	(via
		(at 150.466298 -276.065742)
		(size 0.5588)
		(drill 0.3048)
		(layers "F.Cu" "B.Cu")
		(net "P3V3_STBY_A")
	)
	(via
		(at 468.735918 -155.252674)
		(size 0.5588)
		(drill 0.3048)
		(layers "F.Cu" "B.Cu")
		(net "P3V3_STBY_A")
	)
	(via
		(at 260.43509 -336.350864)
		(size 0.5588)
		(drill 0.3048)
		(layers "F.Cu" "B.Cu")
		(net "P3V3_STBY_A")
	)
	(via
		(at 187.168282 -239.570006)
		(size 0.5588)
		(drill 0.3048)
		(layers "F.Cu" "B.Cu")
		(net "P3V3_STBY_A")
	)
	(via
		(at 82.248502 -30.102048)
		(size 0.5588)
		(drill 0.3048)
		(layers "F.Cu" "B.Cu")
		(net "P3V3_STBY_A")
	)
	(via
		(at 99.342448 -292.989)
		(size 0.5588)
		(drill 0.3048)
		(layers "F.Cu" "B.Cu")
		(net "P3V3_STBY_A")
	)
	(via
		(at 36.242498 -292.994842)
		(size 0.5588)
		(drill 0.3048)
		(layers "F.Cu" "B.Cu")
		(net "P3V3_STBY_A")
	)
	(via
		(at 261.112 -356.7938)
		(size 0.5588)
		(drill 0.3048)
		(layers "F.Cu" "B.Cu")
		(net "P3V3_STBY_A")
	)
	(via
		(at 162.442398 -292.994842)
		(size 0.5588)
		(drill 0.3048)
		(layers "F.Cu" "B.Cu")
		(net "P3V3_STBY_A")
	)
	(via
		(at 67.792346 -177.994818)
		(size 0.5588)
		(drill 0.3048)
		(layers "F.Cu" "B.Cu")
		(net "P3V3_STBY_A")
	)
	(via
		(at 468.761318 -40.25265)
		(size 0.5588)
		(drill 0.3048)
		(layers "F.Cu" "B.Cu")
		(net "P3V3_STBY_A")
	)
	(via
		(at 130.892296 -177.969418)
		(size 0.5588)
		(drill 0.3048)
		(layers "F.Cu" "B.Cu")
		(net "P3V3_STBY_A")
	)
	(via
		(at 162.442398 -62.994794)
		(size 0.5588)
		(drill 0.3048)
		(layers "F.Cu" "B.Cu")
		(net "P3V3_STBY_A")
	)
	(via
		(at 85.05063 -14.92123)
		(size 0.5588)
		(drill 0.3048)
		(layers "F.Cu" "B.Cu")
		(net "P3V3_STBY_A")
	)
	(via
		(at 187.168282 -237.157006)
		(size 0.5588)
		(drill 0.3048)
		(layers "F.Cu" "B.Cu")
		(net "P3V3_STBY_A")
	)
	(via
		(at 223.9645 -9.498838)
		(size 0.5588)
		(drill 0.3048)
		(layers "F.Cu" "B.Cu")
		(net "P3V3_STBY_A")
	)
	(via
		(at 214.9856 -120.3706)
		(size 0.5588)
		(drill 0.3048)
		(layers "F.Cu" "B.Cu")
		(net "P3V3_STBY_A")
	)
	(via
		(at 223.182942 -204.349858)
		(size 0.5588)
		(drill 0.3048)
		(layers "F.Cu" "B.Cu")
		(net "P3V3_STBY_A")
	)
	(via
		(at 68.87591 -291.381688)
		(size 0.5588)
		(drill 0.3048)
		(layers "F.Cu" "B.Cu")
		(net "P3V3_STBY_A")
	)
	(via
		(at 79.84998 -30.086808)
		(size 0.5588)
		(drill 0.3048)
		(layers "F.Cu" "B.Cu")
		(net "P3V3_STBY_A")
	)
	(via
		(at 87.340948 -161.014918)
		(size 0.5588)
		(drill 0.3048)
		(layers "F.Cu" "B.Cu")
		(net "P3V3_STBY_A")
	)
	(via
		(at 222.1992 -90.372692)
		(size 0.5588)
		(drill 0.3048)
		(layers "F.Cu" "B.Cu")
		(net "P3V3_STBY_A")
	)
	(via
		(at 286.7152 -285.7754)
		(size 0.5588)
		(drill 0.3048)
		(layers "F.Cu" "B.Cu")
		(net "P3V3_STBY_A")
	)
	(via
		(at 396.34795 -41.315894)
		(size 0.5588)
		(drill 0.3048)
		(layers "F.Cu" "B.Cu")
		(net "P3V3_STBY_A")
	)
	(via
		(at 448.747134 -183.007)
		(size 0.5588)
		(drill 0.3048)
		(layers "F.Cu" "B.Cu")
		(net "P3V3_STBY_A")
	)
	(via
		(at 364.798102 -271.315942)
		(size 0.5588)
		(drill 0.3048)
		(layers "F.Cu" "B.Cu")
		(net "P3V3_STBY_A")
	)
	(via
		(at 81.915 -17.35963)
		(size 0.5588)
		(drill 0.3048)
		(layers "F.Cu" "B.Cu")
		(net "P3V3_STBY_A")
	)
	(via
		(at 162.442398 -177.994818)
		(size 0.5588)
		(drill 0.3048)
		(layers "F.Cu" "B.Cu")
		(net "P3V3_STBY_A")
	)
	(via
		(at 221.529656 -343.017856)
		(size 0.5588)
		(drill 0.3048)
		(layers "F.Cu" "B.Cu")
		(net "P3V3_STBY_A")
	)
	(via
		(at 225.8822 -393.954)
		(size 0.5588)
		(drill 0.3048)
		(layers "F.Cu" "B.Cu")
		(net "P3V3_STBY_A")
	)
	(via
		(at 444.0174 -293.032942)
		(size 0.5588)
		(drill 0.3048)
		(layers "F.Cu" "B.Cu")
		(net "P3V3_STBY_A")
	)
	(segment
		(start 455.513694 -42.001694)
		(end 454.827894 -41.315894)
		(width 0.508)
		(layer "B.Cu")
		(net "P3V3_STBY_A")
	)
	(segment
		(start 361.237276 -282.061666)
		(end 361.237276 -274.876768)
		(width 0.508)
		(layer "B.Cu")
		(net "P3V3_STBY_A")
	)
	(segment
		(start 364.798102 -271.315942)
		(end 392.378184 -271.315942)
		(width 0.508)
		(layer "B.Cu")
		(net "P3V3_STBY_A")
	)
	(segment
		(start 114.375438 -161.014918)
		(end 109.231684 -155.871164)
		(width 0.508)
		(layer "B.Cu")
		(net "P3V3_STBY_A")
	)
	(segment
		(start 58.167016 -44.118784)
		(end 58.167016 -42.443654)
		(width 0.508)
		(layer "B.Cu")
		(net "P3V3_STBY_A")
	)
	(segment
		(start 393.508992 -155.218638)
		(end 395.25067 -155.218638)
		(width 0.508)
		(layer "B.Cu")
		(net "P3V3_STBY_A")
	)
	(segment
		(start 425.774104 -42.001694)
		(end 427.212252 -42.001694)
		(width 0.508)
		(layer "B.Cu")
		(net "P3V3_STBY_A")
	)
	(segment
		(start 182.0164 -281.044142)
		(end 182.0164 -276.014942)
		(width 0.508)
		(layer "B.Cu")
		(net "P3V3_STBY_A")
	)
	(segment
		(start 483.689152 -160.159192)
		(end 487.913934 -164.383974)
		(width 0.508)
		(layer "B.Cu")
		(net "P3V3_STBY_A")
	)
	(segment
		(start 348.161864 -291.601398)
		(end 348.704408 -292.143942)
		(width 0.508)
		(layer "B.Cu")
		(net "P3V3_STBY_A")
	)
	(segment
		(start 215.9254 -120.2055)
		(end 215.7603 -120.3706)
		(width 0.508)
		(layer "B.Cu")
		(net "P3V3_STBY_A")
	)
	(segment
		(start 81.906364 -17.368266)
		(end 81.915 -17.35963)
		(width 0.508)
		(layer "B.Cu")
		(net "P3V3_STBY_A")
	)
	(segment
		(start 217.6526 -120.01119)
		(end 216.70391 -120.01119)
		(width 0.3048)
		(layer "B.Cu")
		(net "P3V3_STBY_A")
	)
	(segment
		(start 459.4479 -156.315918)
		(end 462.738216 -156.315918)
		(width 0.508)
		(layer "B.Cu")
		(net "P3V3_STBY_A")
	)
	(segment
		(start 79.84998 -28.871672)
		(end 79.661512 -28.683204)
		(width 0.508)
		(layer "B.Cu")
		(net "P3V3_STBY_A")
	)
	(segment
		(start 472.639644 -159.1564)
		(end 468.735918 -155.252674)
		(width 0.508)
		(layer "B.Cu")
		(net "P3V3_STBY_A")
	)
	(segment
		(start 223.139 -120.904)
		(end 223.139 -120.3198)
		(width 0.508)
		(layer "B.Cu")
		(net "P3V3_STBY_A")
	)
	(segment
		(start 82.908648 -30.102048)
		(end 82.248502 -30.102048)
		(width 0.508)
		(layer "B.Cu")
		(net "P3V3_STBY_A")
	)
	(segment
		(start 24.240998 -161.014918)
		(end 24.240998 -165.993318)
		(width 0.508)
		(layer "B.Cu")
		(net "P3V3_STBY_A")
	)
	(segment
		(start 348.704408 -292.143942)
		(end 351.155 -292.143942)
		(width 0.508)
		(layer "B.Cu")
		(net "P3V3_STBY_A")
	)
	(segment
		(start 322.312792 -292.143942)
		(end 328.9554 -285.501334)
		(width 0.508)
		(layer "B.Cu")
		(net "P3V3_STBY_A")
	)
	(segment
		(start 193.7385 -241.7699)
		(end 187.786264 -241.7699)
		(width 0.508)
		(layer "B.Cu")
		(net "P3V3_STBY_A")
	)
	(segment
		(start 151.786082 -161.040318)
		(end 150.466298 -161.040318)
		(width 0.508)
		(layer "B.Cu")
		(net "P3V3_STBY_A")
	)
	(segment
		(start 423.3672 -54.3306)
		(end 415.553906 -62.143894)
		(width 0.508)
		(layer "B.Cu")
		(net "P3V3_STBY_A")
	)
	(segment
		(start 460.218282 -266.975336)
		(end 463.864706 -263.328912)
		(width 0.508)
		(layer "B.Cu")
		(net "P3V3_STBY_A")
	)
	(segment
		(start 348.882462 -178.052476)
		(end 321.894708 -178.052476)
		(width 0.508)
		(layer "B.Cu")
		(net "P3V3_STBY_A")
	)
	(segment
		(start 424.0022 -160.21177)
		(end 424.0022 -164.766244)
		(width 0.508)
		(layer "B.Cu")
		(net "P3V3_STBY_A")
	)
	(segment
		(start 222.5929 -119.7737)
		(end 222.2246 -119.7737)
		(width 0.508)
		(layer "B.Cu")
		(net "P3V3_STBY_A")
	)
	(segment
		(start 251.067062 -349.347028)
		(end 258.513834 -356.7938)
		(width 0.508)
		(layer "B.Cu")
		(net "P3V3_STBY_A")
	)
	(segment
		(start 477.818196 -269.224252)
		(end 476.672148 -268.078204)
		(width 0.508)
		(layer "B.Cu")
		(net "P3V3_STBY_A")
	)
	(segment
		(start 86.299548 -274.948142)
		(end 87.391748 -276.040342)
		(width 0.508)
		(layer "B.Cu")
		(net "P3V3_STBY_A")
	)
	(segment
		(start 217.2843 -115.8621)
		(end 217.7542 -115.3922)
		(width 0.508)
		(layer "B.Cu")
		(net "P3V3_STBY_A")
	)
	(segment
		(start 476.914972 -46.162468)
		(end 476.742252 -45.989748)
		(width 0.508)
		(layer "B.Cu")
		(net "P3V3_STBY_A")
	)
	(segment
		(start 468.761318 -40.25265)
		(end 468.735918 -40.27805)
		(width 0.508)
		(layer "B.Cu")
		(net "P3V3_STBY_A")
	)
	(segment
		(start 222.1992 -118.7323)
		(end 222.1992 -119.7483)
		(width 0.508)
		(layer "B.Cu")
		(net "P3V3_STBY_A")
	)
	(segment
		(start 477.8756 -162.433)
		(end 480.32035 -162.433)
		(width 0.508)
		(layer "B.Cu")
		(net "P3V3_STBY_A")
	)
	(segment
		(start 459.4479 -152.83561)
		(end 453.244966 -146.632676)
		(width 0.508)
		(layer "B.Cu")
		(net "P3V3_STBY_A")
	)
	(segment
		(start 454.827894 -41.315894)
		(end 427.898052 -41.315894)
		(width 0.508)
		(layer "B.Cu")
		(net "P3V3_STBY_A")
	)
	(segment
		(start 113.581942 -276.649942)
		(end 113.581942 -271.456404)
		(width 0.508)
		(layer "B.Cu")
		(net "P3V3_STBY_A")
	)
	(segment
		(start 150.466298 -161.040318)
		(end 150.466298 -165.993318)
		(width 0.508)
		(layer "B.Cu")
		(net "P3V3_STBY_A")
	)
	(segment
		(start 328.9554 -285.501334)
		(end 328.9554 -274.998942)
		(width 0.508)
		(layer "B.Cu")
		(net "P3V3_STBY_A")
	)
	(segment
		(start 88.448388 -162.122358)
		(end 87.340948 -161.014918)
		(width 0.508)
		(layer "B.Cu")
		(net "P3V3_STBY_A")
	)
	(segment
		(start 150.466298 -281.018742)
		(end 150.466298 -276.065742)
		(width 0.508)
		(layer "B.Cu")
		(net "P3V3_STBY_A")
	)
	(segment
		(start 222.928942 -220.693742)
		(end 214.814658 -220.693742)
		(width 0.508)
		(layer "B.Cu")
		(net "P3V3_STBY_A")
	)
	(segment
		(start 351.155 -292.143942)
		(end 361.237276 -282.061666)
		(width 0.508)
		(layer "B.Cu")
		(net "P3V3_STBY_A")
	)
	(segment
		(start 63.4238 -56.2864)
		(end 55.816246 -48.678846)
		(width 0.508)
		(layer "B.Cu")
		(net "P3V3_STBY_A")
	)
	(segment
		(start 63.4238 -58.626248)
		(end 63.4238 -56.2864)
		(width 0.508)
		(layer "B.Cu")
		(net "P3V3_STBY_A")
	)
	(segment
		(start 423.34561 -271.315942)
		(end 396.34795 -271.315942)
		(width 0.508)
		(layer "B.Cu")
		(net "P3V3_STBY_A")
	)
	(segment
		(start 487.913934 -238.47679)
		(end 477.214184 -249.17654)
		(width 0.508)
		(layer "B.Cu")
		(net "P3V3_STBY_A")
	)
	(segment
		(start 255.070102 24.342598)
		(end 255.070102 20.551902)
		(width 0.508)
		(layer "B.Cu")
		(net "P3V3_STBY_A")
	)
	(segment
		(start 55.816246 -48.678846)
		(end 55.816246 -46.065694)
		(width 0.508)
		(layer "B.Cu")
		(net "P3V3_STBY_A")
	)
	(segment
		(start 472.63685 -40.25265)
		(end 468.761318 -40.25265)
		(width 0.508)
		(layer "B.Cu")
		(net "P3V3_STBY_A")
	)
	(segment
		(start 222.5675 -124.5489)
		(end 222.5675 -122.3391)
		(width 0.508)
		(layer "B.Cu")
		(net "P3V3_STBY_A")
	)
	(segment
		(start 460.218282 -269.58036)
		(end 460.218282 -266.975336)
		(width 0.508)
		(layer "B.Cu")
		(net "P3V3_STBY_A")
	)
	(segment
		(start 55.289704 -275.5392)
		(end 41.275 -275.5392)
		(width 0.508)
		(layer "B.Cu")
		(net "P3V3_STBY_A")
	)
	(segment
		(start 333.248 -156.315918)
		(end 361.508548 -156.315918)
		(width 0.508)
		(layer "B.Cu")
		(net "P3V3_STBY_A")
	)
	(segment
		(start 113.581942 -271.456404)
		(end 110.362746 -274.6756)
		(width 0.508)
		(layer "B.Cu")
		(net "P3V3_STBY_A")
	)
	(segment
		(start 254.0762 18.8468)
		(end 255.0922 17.8308)
		(width 0.508)
		(layer "B.Cu")
		(net "P3V3_STBY_A")
	)
	(segment
		(start 361.508548 -156.315918)
		(end 362.194348 -157.001718)
		(width 0.508)
		(layer "B.Cu")
		(net "P3V3_STBY_A")
	)
	(segment
		(start 118.916196 -161.014918)
		(end 118.890796 -161.040318)
		(width 0.508)
		(layer "B.Cu")
		(net "P3V3_STBY_A")
	)
	(segment
		(start 36.242498 -292.994842)
		(end 24.266398 -281.018742)
		(width 0.508)
		(layer "B.Cu")
		(net "P3V3_STBY_A")
	)
	(segment
		(start 55.816246 -46.065694)
		(end 56.220106 -46.065694)
		(width 0.508)
		(layer "B.Cu")
		(net "P3V3_STBY_A")
	)
	(segment
		(start 25.914096 -44.341796)
		(end 25.914096 -42.678604)
		(width 0.508)
		(layer "B.Cu")
		(net "P3V3_STBY_A")
	)
	(segment
		(start 222.5675 -122.3391)
		(end 223.139 -121.7676)
		(width 0.508)
		(layer "B.Cu")
		(net "P3V3_STBY_A")
	)
	(segment
		(start 55.816246 -158.347918)
		(end 58.271918 -158.347918)
		(width 0.508)
		(layer "B.Cu")
		(net "P3V3_STBY_A")
	)
	(segment
		(start 477.2406 -161.798)
		(end 474.599 -159.1564)
		(width 0.508)
		(layer "B.Cu")
		(net "P3V3_STBY_A")
	)
	(segment
		(start 475.092776 -266.498832)
		(end 476.672148 -268.078204)
		(width 0.508)
		(layer "B.Cu")
		(net "P3V3_STBY_A")
	)
	(segment
		(start 393.248388 -165.983412)
		(end 380.274068 -178.957732)
		(width 0.508)
		(layer "B.Cu")
		(net "P3V3_STBY_A")
	)
	(segment
		(start 58.167016 -42.443654)
		(end 59.451494 -41.159176)
		(width 0.508)
		(layer "B.Cu")
		(net "P3V3_STBY_A")
	)
	(segment
		(start 85.781134 -44.42968)
		(end 85.781134 -32.974534)
		(width 0.508)
		(layer "B.Cu")
		(net "P3V3_STBY_A")
	)
	(segment
		(start 424.744896 -269.916656)
		(end 423.34561 -271.315942)
		(width 0.508)
		(layer "B.Cu")
		(net "P3V3_STBY_A")
	)
	(segment
		(start 216.70391 -120.01119)
		(end 216.5096 -120.2055)
		(width 0.3048)
		(layer "B.Cu")
		(net "P3V3_STBY_A")
	)
	(segment
		(start 79.268066 -17.368266)
		(end 81.906364 -17.368266)
		(width 0.508)
		(layer "B.Cu")
		(net "P3V3_STBY_A")
	)
	(segment
		(start 153.812494 -159.013906)
		(end 151.786082 -161.040318)
		(width 0.508)
		(layer "B.Cu")
		(net "P3V3_STBY_A")
	)
	(segment
		(start 76.969366 -17.380966)
		(end 76.982066 -17.368266)
		(width 0.508)
		(layer "B.Cu")
		(net "P3V3_STBY_A")
	)
	(segment
		(start 25.914096 -42.678604)
		(end 27.326844 -41.265856)
		(width 0.508)
		(layer "B.Cu")
		(net "P3V3_STBY_A")
	)
	(segment
		(start 55.816246 -276.065742)
		(end 56.933846 -274.948142)
		(width 0.508)
		(layer "B.Cu")
		(net "P3V3_STBY_A")
	)
	(segment
		(start 40.5638 -274.828)
		(end 25.45334 -274.828)
		(width 0.508)
		(layer "B.Cu")
		(net "P3V3_STBY_A")
	)
	(segment
		(start 55.816246 -158.347918)
		(end 25.92197 -158.347918)
		(width 0.508)
		(layer "B.Cu")
		(net "P3V3_STBY_A")
	)
	(segment
		(start 361.237276 -274.876768)
		(end 364.798102 -271.315942)
		(width 0.508)
		(layer "B.Cu")
		(net "P3V3_STBY_A")
	)
	(segment
		(start 24.240998 -51.0159)
		(end 24.240998 -46.014894)
		(width 0.508)
		(layer "B.Cu")
		(net "P3V3_STBY_A")
	)
	(segment
		(start 393.77747 -269.916656)
		(end 394.948664 -269.916656)
		(width 0.508)
		(layer "B.Cu")
		(net "P3V3_STBY_A")
	)
	(segment
		(start 128.7018 -291.077142)
		(end 128.009142 -291.077142)
		(width 0.508)
		(layer "B.Cu")
		(net "P3V3_STBY_A")
	)
	(segment
		(start 223.139 -120.3198)
		(end 222.5929 -119.7737)
		(width 0.508)
		(layer "B.Cu")
		(net "P3V3_STBY_A")
	)
	(segment
		(start 68.87591 -291.381688)
		(end 66.159888 -291.381688)
		(width 0.508)
		(layer "B.Cu")
		(net "P3V3_STBY_A")
	)
	(segment
		(start 55.816246 -281.038046)
		(end 55.816246 -276.065742)
		(width 0.508)
		(layer "B.Cu")
		(net "P3V3_STBY_A")
	)
	(segment
		(start 182.0164 -161.014918)
		(end 172.9486 -161.014918)
		(width 0.508)
		(layer "B.Cu")
		(net "P3V3_STBY_A")
	)
	(segment
		(start 50.257456 -41.265856)
		(end 55.057294 -46.065694)
		(width 0.508)
		(layer "B.Cu")
		(net "P3V3_STBY_A")
	)
	(segment
		(start 459.4479 -41.315894)
		(end 458.7621 -42.001694)
		(width 0.508)
		(layer "B.Cu")
		(net "P3V3_STBY_A")
	)
	(segment
		(start 391.7696 -282.042362)
		(end 391.7696 -275.894292)
		(width 0.508)
		(layer "B.Cu")
		(net "P3V3_STBY_A")
	)
	(segment
		(start 182.0164 -163.797488)
		(end 182.0164 -161.014918)
		(width 0.508)
		(layer "B.Cu")
		(net "P3V3_STBY_A")
	)
	(segment
		(start 459.4479 -156.315918)
		(end 459.4479 -152.83561)
		(width 0.508)
		(layer "B.Cu")
		(net "P3V3_STBY_A")
	)
	(segment
		(start 183.394604 -276.014942)
		(end 182.0164 -276.014942)
		(width 0.508)
		(layer "B.Cu")
		(net "P3V3_STBY_A")
	)
	(segment
		(start 99.342448 -292.989)
		(end 87.391748 -281.0383)
		(width 0.508)
		(layer "B.Cu")
		(net "P3V3_STBY_A")
	)
	(segment
		(start 455.45375 -271.315942)
		(end 456.13955 -272.001742)
		(width 0.508)
		(layer "B.Cu")
		(net "P3V3_STBY_A")
	)
	(segment
		(start 218.3257 -115.9637)
		(end 217.7542 -115.3922)
		(width 0.508)
		(layer "B.Cu")
		(net "P3V3_STBY_A")
	)
	(segment
		(start 424.0022 -164.766244)
		(end 411.599126 -177.169318)
		(width 0.508)
		(layer "B.Cu")
		(net "P3V3_STBY_A")
	)
	(segment
		(start 223.139 -121.7676)
		(end 223.139 -120.904)
		(width 0.508)
		(layer "B.Cu")
		(net "P3V3_STBY_A")
	)
	(segment
		(start 476.742252 -45.989748)
		(end 476.742252 -44.358052)
		(width 0.508)
		(layer "B.Cu")
		(net "P3V3_STBY_A")
	)
	(segment
		(start 467.649306 -41.315894)
		(end 459.4479 -41.315894)
		(width 0.508)
		(layer "B.Cu")
		(net "P3V3_STBY_A")
	)
	(segment
		(start 395.25067 -155.218638)
		(end 396.34795 -156.315918)
		(width 0.508)
		(layer "B.Cu")
		(net "P3V3_STBY_A")
	)
	(segment
		(start 86.274148 -159.948118)
		(end 87.340948 -161.014918)
		(width 0.508)
		(layer "B.Cu")
		(net "P3V3_STBY_A")
	)
	(segment
		(start 260.422644 -339.754464)
		(end 260.422644 -340.668864)
		(width 0.508)
		(layer "B.Cu")
		(net "P3V3_STBY_A")
	)
	(segment
		(start 415.553906 -62.143894)
		(end 411.7594 -62.143894)
		(width 0.508)
		(layer "B.Cu")
		(net "P3V3_STBY_A")
	)
	(segment
		(start 88.75649 -274.6756)
		(end 87.391748 -276.040342)
		(width 0.508)
		(layer "B.Cu")
		(net "P3V3_STBY_A")
	)
	(segment
		(start 379.9586 -291.846)
		(end 381.965962 -291.846)
		(width 0.508)
		(layer "B.Cu")
		(net "P3V3_STBY_A")
	)
	(segment
		(start 24.240998 -165.993318)
		(end 36.242498 -177.994818)
		(width 0.508)
		(layer "B.Cu")
		(net "P3V3_STBY_A")
	)
	(segment
		(start 427.212252 -155.630118)
		(end 427.898052 -156.315918)
		(width 0.508)
		(layer "B.Cu")
		(net "P3V3_STBY_A")
	)
	(segment
		(start 427.898052 -271.315942)
		(end 426.498766 -269.916656)
		(width 0.508)
		(layer "B.Cu")
		(net "P3V3_STBY_A")
	)
	(segment
		(start 321.894708 -178.052476)
		(end 321.536314 -177.694082)
		(width 0.508)
		(layer "B.Cu")
		(net "P3V3_STBY_A")
	)
	(segment
		(start 255.0922 17.8308)
		(end 255.0922 12.319)
		(width 0.508)
		(layer "B.Cu")
		(net "P3V3_STBY_A")
	)
	(segment
		(start 480.085908 -268.711934)
		(end 479.57359 -269.224252)
		(width 0.508)
		(layer "B.Cu")
		(net "P3V3_STBY_A")
	)
	(segment
		(start 363.22635 -269.74419)
		(end 364.798102 -271.315942)
		(width 0.508)
		(layer "B.Cu")
		(net "P3V3_STBY_A")
	)
	(segment
		(start 182.0164 -161.014918)
		(end 184.193434 -161.014918)
		(width 0.508)
		(layer "B.Cu")
		(net "P3V3_STBY_A")
	)
	(segment
		(start 477.214184 -249.17654)
		(end 477.214184 -261.669784)
		(width 0.508)
		(layer "B.Cu")
		(net "P3V3_STBY_A")
	)
	(segment
		(start 468.735918 -40.27805)
		(end 468.68715 -40.27805)
		(width 0.508)
		(layer "B.Cu")
		(net "P3V3_STBY_A")
	)
	(segment
		(start 476.742252 -44.358052)
		(end 472.63685 -40.25265)
		(width 0.508)
		(layer "B.Cu")
		(net "P3V3_STBY_A")
	)
	(segment
		(start 187.061348 -245.455948)
		(end 188.5188 -246.9134)
		(width 0.508)
		(layer "B.Cu")
		(net "P3V3_STBY_A")
	)
	(segment
		(start 82.233262 -30.086808)
		(end 79.84998 -30.086808)
		(width 0.508)
		(layer "B.Cu")
		(net "P3V3_STBY_A")
	)
	(segment
		(start 24.240998 -160.02889)
		(end 24.240998 -161.014918)
		(width 0.508)
		(layer "B.Cu")
		(net "P3V3_STBY_A")
	)
	(segment
		(start 82.248502 -30.102048)
		(end 82.233262 -30.086808)
		(width 0.508)
		(layer "B.Cu")
		(net "P3V3_STBY_A")
	)
	(segment
		(start 189.009782 -234.871006)
		(end 188.438282 -234.871006)
		(width 0.254)
		(layer "B.Cu")
		(net "P3V3_STBY_A")
	)
	(segment
		(start 462.738216 -156.315918)
		(end 463.77606 -155.278074)
		(width 0.508)
		(layer "B.Cu")
		(net "P3V3_STBY_A")
	)
	(segment
		(start 59.872118 -159.948118)
		(end 86.274148 -159.948118)
		(width 0.508)
		(layer "B.Cu")
		(net "P3V3_STBY_A")
	)
	(segment
		(start 232.827576 25.61082)
		(end 253.80188 25.61082)
		(width 0.508)
		(layer "B.Cu")
		(net "P3V3_STBY_A")
	)
	(segment
		(start 190.354712 -172.1358)
		(end 182.0164 -163.797488)
		(width 0.508)
		(layer "B.Cu")
		(net "P3V3_STBY_A")
	)
	(segment
		(start 129.558288 -159.741616)
		(end 149.167596 -159.741616)
		(width 0.508)
		(layer "B.Cu")
		(net "P3V3_STBY_A")
	)
	(segment
		(start 320.8655 -181.080918)
		(end 320.8655 -209.152744)
		(width 0.508)
		(layer "B.Cu")
		(net "P3V3_STBY_A")
	)
	(segment
		(start 271.526 -271.0434)
		(end 272.415 -271.9324)
		(width 0.508)
		(layer "B.Cu")
		(net "P3V3_STBY_A")
	)
	(segment
		(start 41.275 -275.5392)
		(end 40.5638 -274.828)
		(width 0.508)
		(layer "B.Cu")
		(net "P3V3_STBY_A")
	)
	(segment
		(start 286.7406 -271.0688)
		(end 291.0586 -271.0688)
		(width 0.508)
		(layer "B.Cu")
		(net "P3V3_STBY_A")
	)
	(segment
		(start 253.80188 25.61082)
		(end 255.070102 24.342598)
		(width 0.508)
		(layer "B.Cu")
		(net "P3V3_STBY_A")
	)
	(segment
		(start 164.076126 -276.014942)
		(end 162.990784 -274.9296)
		(width 0.508)
		(layer "B.Cu")
		(net "P3V3_STBY_A")
	)
	(segment
		(start 82.61223 -17.35963)
		(end 85.05063 -14.92123)
		(width 0.508)
		(layer "B.Cu")
		(net "P3V3_STBY_A")
	)
	(segment
		(start 36.242498 -63.0174)
		(end 24.240998 -51.0159)
		(width 0.508)
		(layer "B.Cu")
		(net "P3V3_STBY_A")
	)
	(segment
		(start 260.43509 -339.754464)
		(end 260.422644 -339.754464)
		(width 0.508)
		(layer "B.Cu")
		(net "P3V3_STBY_A")
	)
	(segment
		(start 437.581294 -146.632676)
		(end 427.898052 -156.315918)
		(width 0.508)
		(layer "B.Cu")
		(net "P3V3_STBY_A")
	)
	(segment
		(start 192.0875 -291.115242)
		(end 182.0164 -281.044142)
		(width 0.508)
		(layer "B.Cu")
		(net "P3V3_STBY_A")
	)
	(segment
		(start 482.594158 -160.159192)
		(end 483.689152 -160.159192)
		(width 0.508)
		(layer "B.Cu")
		(net "P3V3_STBY_A")
	)
	(segment
		(start 255.0922 12.319)
		(end 255.925828 11.485372)
		(width 0.508)
		(layer "B.Cu")
		(net "P3V3_STBY_A")
	)
	(segment
		(start 258.513834 -356.7938)
		(end 261.112 -356.7938)
		(width 0.508)
		(layer "B.Cu")
		(net "P3V3_STBY_A")
	)
	(segment
		(start 87.366348 -46.014894)
		(end 85.781134 -44.42968)
		(width 0.508)
		(layer "B.Cu")
		(net "P3V3_STBY_A")
	)
	(segment
		(start 188.5188 -270.890746)
		(end 183.394604 -276.014942)
		(width 0.508)
		(layer "B.Cu")
		(net "P3V3_STBY_A")
	)
	(segment
		(start 88.448388 -167.100758)
		(end 88.448388 -162.122358)
		(width 0.508)
		(layer "B.Cu")
		(net "P3V3_STBY_A")
	)
	(segment
		(start 222.1992 -118.7323)
		(end 221.8817 -118.7323)
		(width 0.3048)
		(layer "B.Cu")
		(net "P3V3_STBY_A")
	)
	(segment
		(start 182.0164 -276.014942)
		(end 164.076126 -276.014942)
		(width 0.508)
		(layer "B.Cu")
		(net "P3V3_STBY_A")
	)
	(segment
		(start 95.1738 -59.003946)
		(end 95.1738 -56.4388)
		(width 0.508)
		(layer "B.Cu")
		(net "P3V3_STBY_A")
	)
	(segment
		(start 364.112302 -157.001718)
		(end 364.798102 -156.315918)
		(width 0.508)
		(layer "B.Cu")
		(net "P3V3_STBY_A")
	)
	(segment
		(start 209.89417 -137.22223)
		(end 222.5675 -124.5489)
		(width 0.508)
		(layer "B.Cu")
		(net "P3V3_STBY_A")
	)
	(segment
		(start 362.194348 -157.001718)
		(end 364.112302 -157.001718)
		(width 0.508)
		(layer "B.Cu")
		(net "P3V3_STBY_A")
	)
	(segment
		(start 221.8817 -118.7323)
		(end 221.10319 -119.51081)
		(width 0.3048)
		(layer "B.Cu")
		(net "P3V3_STBY_A")
	)
	(segment
		(start 427.212252 -42.001694)
		(end 427.898052 -41.315894)
		(width 0.508)
		(layer "B.Cu")
		(net "P3V3_STBY_A")
	)
	(segment
		(start 121.995438 -155.626562)
		(end 125.443234 -155.626562)
		(width 0.508)
		(layer "B.Cu")
		(net "P3V3_STBY_A")
	)
	(segment
		(start 24.240998 -46.014894)
		(end 25.914096 -44.341796)
		(width 0.508)
		(layer "B.Cu")
		(net "P3V3_STBY_A")
	)
	(segment
		(start 87.391748 -281.0383)
		(end 87.391748 -276.040342)
		(width 0.508)
		(layer "B.Cu")
		(net "P3V3_STBY_A")
	)
	(segment
		(start 172.9486 -161.014918)
		(end 170.947588 -159.013906)
		(width 0.508)
		(layer "B.Cu")
		(net "P3V3_STBY_A")
	)
	(segment
		(start 99.164648 -62.994794)
		(end 95.1738 -59.003946)
		(width 0.508)
		(layer "B.Cu")
		(net "P3V3_STBY_A")
	)
	(segment
		(start 343.5858 -276.0218)
		(end 348.742 -270.8656)
		(width 0.508)
		(layer "B.Cu")
		(net "P3V3_STBY_A")
	)
	(segment
		(start 59.451494 -41.159176)
		(end 78.708504 -41.159176)
		(width 0.508)
		(layer "B.Cu")
		(net "P3V3_STBY_A")
	)
	(segment
		(start 485.868726 -47.338742)
		(end 483.689152 -45.159168)
		(width 0.508)
		(layer "B.Cu")
		(net "P3V3_STBY_A")
	)
	(segment
		(start 260.422644 -340.668864)
		(end 260.422136 -340.668864)
		(width 0.508)
		(layer "B.Cu")
		(net "P3V3_STBY_A")
	)
	(segment
		(start 118.916196 -161.014918)
		(end 118.916196 -158.705804)
		(width 0.508)
		(layer "B.Cu")
		(net "P3V3_STBY_A")
	)
	(segment
		(start 187.786264 -241.7699)
		(end 187.061348 -241.044984)
		(width 0.508)
		(layer "B.Cu")
		(net "P3V3_STBY_A")
	)
	(segment
		(start 222.1992 -119.7483)
		(end 222.2246 -119.7737)
		(width 0.508)
		(layer "B.Cu")
		(net "P3V3_STBY_A")
	)
	(segment
		(start 426.498766 -269.916656)
		(end 424.744896 -269.916656)
		(width 0.508)
		(layer "B.Cu")
		(net "P3V3_STBY_A")
	)
	(segment
		(start 78.359 -18.7706)
		(end 76.969366 -17.380966)
		(width 0.508)
		(layer "B.Cu")
		(net "P3V3_STBY_A")
	)
	(segment
		(start 332.6384 -271.315942)
		(end 337.344258 -276.0218)
		(width 0.508)
		(layer "B.Cu")
		(net "P3V3_STBY_A")
	)
	(segment
		(start 217.2843 -116.459)
		(end 217.2843 -115.8621)
		(width 0.508)
		(layer "B.Cu")
		(net "P3V3_STBY_A")
	)
	(segment
		(start 381.965962 -291.846)
		(end 391.7696 -282.042362)
		(width 0.508)
		(layer "B.Cu")
		(net "P3V3_STBY_A")
	)
	(segment
		(start 396.34795 -41.315894)
		(end 425.088304 -41.315894)
		(width 0.508)
		(layer "B.Cu")
		(net "P3V3_STBY_A")
	)
	(segment
		(start 216.5096 -120.2055)
		(end 215.9254 -120.2055)
		(width 0.3048)
		(layer "B.Cu")
		(net "P3V3_STBY_A")
	)
	(segment
		(start 328.9554 -274.998942)
		(end 332.6384 -271.315942)
		(width 0.508)
		(layer "B.Cu")
		(net "P3V3_STBY_A")
	)
	(segment
		(start 479.051112 -150.35657)
		(end 485.868726 -143.538956)
		(width 0.508)
		(layer "B.Cu")
		(net "P3V3_STBY_A")
	)
	(segment
		(start 424.189652 -155.630118)
		(end 427.212252 -155.630118)
		(width 0.508)
		(layer "B.Cu")
		(net "P3V3_STBY_A")
	)
	(segment
		(start 423.3672 -46.9138)
		(end 423.3672 -54.3306)
		(width 0.508)
		(layer "B.Cu")
		(net "P3V3_STBY_A")
	)
	(segment
		(start 427.898052 -42.382948)
		(end 423.3672 -46.9138)
		(width 0.508)
		(layer "B.Cu")
		(net "P3V3_STBY_A")
	)
	(segment
		(start 361.88904 -269.74419)
		(end 363.22635 -269.74419)
		(width 0.508)
		(layer "B.Cu")
		(net "P3V3_STBY_A")
	)
	(segment
		(start 67.792346 -62.994794)
		(end 63.4238 -58.626248)
		(width 0.508)
		(layer "B.Cu")
		(net "P3V3_STBY_A")
	)
	(segment
		(start 391.7696 -275.894292)
		(end 396.34795 -271.315942)
		(width 0.508)
		(layer "B.Cu")
		(net "P3V3_STBY_A")
	)
	(segment
		(start 480.32035 -162.433)
		(end 482.594158 -160.159192)
		(width 0.508)
		(layer "B.Cu")
		(net "P3V3_STBY_A")
	)
	(segment
		(start 56.933846 -274.948142)
		(end 86.299548 -274.948142)
		(width 0.508)
		(layer "B.Cu")
		(net "P3V3_STBY_A")
	)
	(segment
		(start 477.72574 -161.31286)
		(end 478.1296 -161.31286)
		(width 0.508)
		(layer "B.Cu")
		(net "P3V3_STBY_A")
	)
	(segment
		(start 81.915 -17.35963)
		(end 82.61223 -17.35963)
		(width 0.508)
		(layer "B.Cu")
		(net "P3V3_STBY_A")
	)
	(segment
		(start 425.088304 -41.315894)
		(end 425.774104 -42.001694)
		(width 0.508)
		(layer "B.Cu")
		(net "P3V3_STBY_A")
	)
	(segment
		(start 191.77 -194.120262)
		(end 191.77 -172.1358)
		(width 0.508)
		(layer "B.Cu")
		(net "P3V3_STBY_A")
	)
	(segment
		(start 221.10319 -119.51081)
		(end 219.9894 -119.51081)
		(width 0.3048)
		(layer "B.Cu")
		(net "P3V3_STBY_A")
	)
	(segment
		(start 128.009142 -291.077142)
		(end 113.581942 -276.649942)
		(width 0.508)
		(layer "B.Cu")
		(net "P3V3_STBY_A")
	)
	(segment
		(start 152.6032 -276.065742)
		(end 150.466298 -276.065742)
		(width 0.508)
		(layer "B.Cu")
		(net "P3V3_STBY_A")
	)
	(segment
		(start 113.581942 -271.456404)
		(end 114.045746 -270.9926)
		(width 0.508)
		(layer "B.Cu")
		(net "P3V3_STBY_A")
	)
	(segment
		(start 255.872488 -260.053328)
		(end 255.872488 -260.100572)
		(width 0.508)
		(layer "B.Cu")
		(net "P3V3_STBY_A")
	)
	(segment
		(start 463.77606 -155.278074)
		(end 468.710518 -155.278074)
		(width 0.508)
		(layer "B.Cu")
		(net "P3V3_STBY_A")
	)
	(segment
		(start 321.536314 -177.694082)
		(end 321.536314 -180.410104)
		(width 0.508)
		(layer "B.Cu")
		(net "P3V3_STBY_A")
	)
	(segment
		(start 55.816246 -276.065742)
		(end 55.289704 -275.5392)
		(width 0.508)
		(layer "B.Cu")
		(net "P3V3_STBY_A")
	)
	(segment
		(start 58.271918 -158.347918)
		(end 59.872118 -159.948118)
		(width 0.508)
		(layer "B.Cu")
		(net "P3V3_STBY_A")
	)
	(segment
		(start 214.814658 -220.693742)
		(end 193.7385 -241.7699)
		(width 0.508)
		(layer "B.Cu")
		(net "P3V3_STBY_A")
	)
	(segment
		(start 392.411712 -156.315918)
		(end 393.508992 -155.218638)
		(width 0.508)
		(layer "B.Cu")
		(net "P3V3_STBY_A")
	)
	(segment
		(start 468.710518 -155.278074)
		(end 468.735918 -155.252674)
		(width 0.508)
		(layer "B.Cu")
		(net "P3V3_STBY_A")
	)
	(segment
		(start 85.781134 -32.974534)
		(end 82.908648 -30.102048)
		(width 0.508)
		(layer "B.Cu")
		(net "P3V3_STBY_A")
	)
	(segment
		(start 478.409254 -46.162468)
		(end 476.914972 -46.162468)
		(width 0.508)
		(layer "B.Cu")
		(net "P3V3_STBY_A")
	)
	(segment
		(start 118.890796 -165.967918)
		(end 130.892296 -177.969418)
		(width 0.508)
		(layer "B.Cu")
		(net "P3V3_STBY_A")
	)
	(segment
		(start 223.9645 -9.498838)
		(end 223.9645 16.747744)
		(width 0.508)
		(layer "B.Cu")
		(net "P3V3_STBY_A")
	)
	(segment
		(start 468.68715 -40.27805)
		(end 467.649306 -41.315894)
		(width 0.508)
		(layer "B.Cu")
		(net "P3V3_STBY_A")
	)
	(segment
		(start 170.947588 -159.013906)
		(end 153.812494 -159.013906)
		(width 0.508)
		(layer "B.Cu")
		(net "P3V3_STBY_A")
	)
	(segment
		(start 474.599 -159.1564)
		(end 472.639644 -159.1564)
		(width 0.508)
		(layer "B.Cu")
		(net "P3V3_STBY_A")
	)
	(segment
		(start 272.415 -271.9324)
		(end 272.415 -280.6446)
		(width 0.508)
		(layer "B.Cu")
		(net "P3V3_STBY_A")
	)
	(segment
		(start 162.990784 -274.9296)
		(end 153.739342 -274.9296)
		(width 0.508)
		(layer "B.Cu")
		(net "P3V3_STBY_A")
	)
	(segment
		(start 453.244966 -146.632676)
		(end 437.581294 -146.632676)
		(width 0.508)
		(layer "B.Cu")
		(net "P3V3_STBY_A")
	)
	(segment
		(start 473.069412 -266.498832)
		(end 475.092776 -266.498832)
		(width 0.508)
		(layer "B.Cu")
		(net "P3V3_STBY_A")
	)
	(segment
		(start 239.142778 -349.347028)
		(end 251.067062 -349.347028)
		(width 0.508)
		(layer "B.Cu")
		(net "P3V3_STBY_A")
	)
	(segment
		(start 55.816246 -158.347918)
		(end 55.816246 -166.018718)
		(width 0.508)
		(layer "B.Cu")
		(net "P3V3_STBY_A")
	)
	(segment
		(start 56.220106 -46.065694)
		(end 58.167016 -44.118784)
		(width 0.508)
		(layer "B.Cu")
		(net "P3V3_STBY_A")
	)
	(segment
		(start 118.916196 -161.014918)
		(end 114.375438 -161.014918)
		(width 0.508)
		(layer "B.Cu")
		(net "P3V3_STBY_A")
	)
	(segment
		(start 184.193434 -161.014918)
		(end 207.986122 -137.22223)
		(width 0.508)
		(layer "B.Cu")
		(net "P3V3_STBY_A")
	)
	(segment
		(start 88.92794 -158.18104)
		(end 88.92794 -159.427926)
		(width 0.508)
		(layer "B.Cu")
		(net "P3V3_STBY_A")
	)
	(segment
		(start 396.34795 -156.315918)
		(end 423.503852 -156.315918)
		(width 0.508)
		(layer "B.Cu")
		(net "P3V3_STBY_A")
	)
	(segment
		(start 78.359 -27.380692)
		(end 78.359 -18.7706)
		(width 0.508)
		(layer "B.Cu")
		(net "P3V3_STBY_A")
	)
	(segment
		(start 469.899492 -263.328912)
		(end 473.069412 -266.498832)
		(width 0.508)
		(layer "B.Cu")
		(net "P3V3_STBY_A")
	)
	(segment
		(start 76.982066 -17.368266)
		(end 79.268066 -17.368266)
		(width 0.508)
		(layer "B.Cu")
		(net "P3V3_STBY_A")
	)
	(segment
		(start 392.378184 -271.315942)
		(end 393.77747 -269.916656)
		(width 0.508)
		(layer "B.Cu")
		(net "P3V3_STBY_A")
	)
	(segment
		(start 149.167596 -159.741616)
		(end 150.466298 -161.040318)
		(width 0.508)
		(layer "B.Cu")
		(net "P3V3_STBY_A")
	)
	(segment
		(start 99.342448 -177.994818)
		(end 88.448388 -167.100758)
		(width 0.508)
		(layer "B.Cu")
		(net "P3V3_STBY_A")
	)
	(segment
		(start 118.916196 -158.705804)
		(end 121.995438 -155.626562)
		(width 0.508)
		(layer "B.Cu")
		(net "P3V3_STBY_A")
	)
	(segment
		(start 91.237816 -155.871164)
		(end 88.92794 -158.18104)
		(width 0.508)
		(layer "B.Cu")
		(net "P3V3_STBY_A")
	)
	(segment
		(start 423.503852 -156.315918)
		(end 424.189652 -155.630118)
		(width 0.508)
		(layer "B.Cu")
		(net "P3V3_STBY_A")
	)
	(segment
		(start 187.061348 -241.044984)
		(end 187.061348 -245.455948)
		(width 0.508)
		(layer "B.Cu")
		(net "P3V3_STBY_A")
	)
	(segment
		(start 55.816246 -166.018718)
		(end 67.792346 -177.994818)
		(width 0.508)
		(layer "B.Cu")
		(net "P3V3_STBY_A")
	)
	(segment
		(start 348.742 -270.8656)
		(end 360.76763 -270.8656)
		(width 0.508)
		(layer "B.Cu")
		(net "P3V3_STBY_A")
	)
	(segment
		(start 394.948664 -269.916656)
		(end 396.34795 -271.315942)
		(width 0.508)
		(layer "B.Cu")
		(net "P3V3_STBY_A")
	)
	(segment
		(start 396.34795 -156.315918)
		(end 393.248388 -159.41548)
		(width 0.508)
		(layer "B.Cu")
		(net "P3V3_STBY_A")
	)
	(segment
		(start 380.274068 -178.957732)
		(end 379.85192 -178.957732)
		(width 0.508)
		(layer "B.Cu")
		(net "P3V3_STBY_A")
	)
	(segment
		(start 215.7603 -120.3706)
		(end 214.9856 -120.3706)
		(width 0.508)
		(layer "B.Cu")
		(net "P3V3_STBY_A")
	)
	(segment
		(start 150.466298 -165.993318)
		(end 162.442398 -177.969418)
		(width 0.508)
		(layer "B.Cu")
		(net "P3V3_STBY_A")
	)
	(segment
		(start 427.898052 -271.315942)
		(end 455.45375 -271.315942)
		(width 0.508)
		(layer "B.Cu")
		(net "P3V3_STBY_A")
	)
	(segment
		(start 255.872488 -260.100572)
		(end 258.367276 -262.59536)
		(width 0.508)
		(layer "B.Cu")
		(net "P3V3_STBY_A")
	)
	(segment
		(start 110.362746 -274.6756)
		(end 88.75649 -274.6756)
		(width 0.508)
		(layer "B.Cu")
		(net "P3V3_STBY_A")
	)
	(segment
		(start 477.2406 -161.798)
		(end 477.8756 -162.433)
		(width 0.508)
		(layer "B.Cu")
		(net "P3V3_STBY_A")
	)
	(segment
		(start 162.442398 -292.994842)
		(end 150.466298 -281.018742)
		(width 0.508)
		(layer "B.Cu")
		(net "P3V3_STBY_A")
	)
	(segment
		(start 291.0586 -271.0688)
		(end 295.7068 -271.1958)
		(width 0.508)
		(layer "B.Cu")
		(net "P3V3_STBY_A")
	)
	(segment
		(start 458.7621 -42.001694)
		(end 455.513694 -42.001694)
		(width 0.508)
		(layer "B.Cu")
		(net "P3V3_STBY_A")
	)
	(segment
		(start 95.1738 -56.4388)
		(end 87.366348 -48.631348)
		(width 0.508)
		(layer "B.Cu")
		(net "P3V3_STBY_A")
	)
	(segment
		(start 83.564222 -46.014894)
		(end 87.366348 -46.014894)
		(width 0.508)
		(layer "B.Cu")
		(net "P3V3_STBY_A")
	)
	(segment
		(start 458.5335 -271.265142)
		(end 460.218282 -269.58036)
		(width 0.508)
		(layer "B.Cu")
		(net "P3V3_STBY_A")
	)
	(segment
		(start 480.085908 -264.541508)
		(end 480.085908 -268.711934)
		(width 0.508)
		(layer "B.Cu")
		(net "P3V3_STBY_A")
	)
	(segment
		(start 260.43509 -336.350864)
		(end 260.43509 -338.052664)
		(width 0.508)
		(layer "B.Cu")
		(net "P3V3_STBY_A")
	)
	(segment
		(start 477.2406 -161.798)
		(end 477.72574 -161.31286)
		(width 0.508)
		(layer "B.Cu")
		(net "P3V3_STBY_A")
	)
	(segment
		(start 427.898052 -41.315894)
		(end 427.898052 -42.382948)
		(width 0.508)
		(layer "B.Cu")
		(net "P3V3_STBY_A")
	)
	(segment
		(start 321.536314 -180.410104)
		(end 320.8655 -181.080918)
		(width 0.508)
		(layer "B.Cu")
		(net "P3V3_STBY_A")
	)
	(segment
		(start 393.248388 -159.41548)
		(end 393.248388 -165.983412)
		(width 0.508)
		(layer "B.Cu")
		(net "P3V3_STBY_A")
	)
	(segment
		(start 188.5188 -246.9134)
		(end 188.5188 -270.890746)
		(width 0.508)
		(layer "B.Cu")
		(net "P3V3_STBY_A")
	)
	(segment
		(start 479.051112 -160.391348)
		(end 479.051112 -150.35657)
		(width 0.508)
		(layer "B.Cu")
		(net "P3V3_STBY_A")
	)
	(segment
		(start 483.689152 -45.159168)
		(end 479.412554 -45.159168)
		(width 0.508)
		(layer "B.Cu")
		(net "P3V3_STBY_A")
	)
	(segment
		(start 255.925828 11.485372)
		(end 255.925828 10.012172)
		(width 0.508)
		(layer "B.Cu")
		(net "P3V3_STBY_A")
	)
	(segment
		(start 463.864706 -263.328912)
		(end 469.899492 -263.328912)
		(width 0.508)
		(layer "B.Cu")
		(net "P3V3_STBY_A")
	)
	(segment
		(start 118.890796 -161.040318)
		(end 118.890796 -165.967918)
		(width 0.508)
		(layer "B.Cu")
		(net "P3V3_STBY_A")
	)
	(segment
		(start 477.214184 -261.669784)
		(end 480.085908 -264.541508)
		(width 0.508)
		(layer "B.Cu")
		(net "P3V3_STBY_A")
	)
	(segment
		(start 24.266398 -281.018742)
		(end 24.266398 -276.014942)
		(width 0.508)
		(layer "B.Cu")
		(net "P3V3_STBY_A")
	)
	(segment
		(start 66.159888 -291.381688)
		(end 55.816246 -281.038046)
		(width 0.508)
		(layer "B.Cu")
		(net "P3V3_STBY_A")
	)
	(segment
		(start 479.57359 -269.224252)
		(end 477.818196 -269.224252)
		(width 0.508)
		(layer "B.Cu")
		(net "P3V3_STBY_A")
	)
	(segment
		(start 364.798102 -156.315918)
		(end 392.411712 -156.315918)
		(width 0.508)
		(layer "B.Cu")
		(net "P3V3_STBY_A")
	)
	(segment
		(start 479.412554 -45.159168)
		(end 478.409254 -46.162468)
		(width 0.508)
		(layer "B.Cu")
		(net "P3V3_STBY_A")
	)
	(segment
		(start 424.2816 -274.932394)
		(end 424.2816 -284.241494)
		(width 0.508)
		(layer "B.Cu")
		(net "P3V3_STBY_A")
	)
	(segment
		(start 145.077942 -276.065742)
		(end 150.466298 -276.065742)
		(width 0.508)
		(layer "B.Cu")
		(net "P3V3_STBY_A")
	)
	(segment
		(start 255.070102 20.551902)
		(end 254.0762 19.558)
		(width 0.508)
		(layer "B.Cu")
		(net "P3V3_STBY_A")
	)
	(segment
		(start 78.708504 -41.159176)
		(end 83.564222 -46.014894)
		(width 0.508)
		(layer "B.Cu")
		(net "P3V3_STBY_A")
	)
	(segment
		(start 55.057294 -46.065694)
		(end 55.816246 -46.065694)
		(width 0.508)
		(layer "B.Cu")
		(net "P3V3_STBY_A")
	)
	(segment
		(start 79.84998 -30.086808)
		(end 79.84998 -28.871672)
		(width 0.508)
		(layer "B.Cu")
		(net "P3V3_STBY_A")
	)
	(segment
		(start 153.739342 -274.9296)
		(end 152.6032 -276.065742)
		(width 0.508)
		(layer "B.Cu")
		(net "P3V3_STBY_A")
	)
	(segment
		(start 223.182942 -204.349858)
		(end 201.999596 -204.349858)
		(width 0.508)
		(layer "B.Cu")
		(net "P3V3_STBY_A")
	)
	(segment
		(start 223.9645 16.747744)
		(end 232.827576 25.61082)
		(width 0.508)
		(layer "B.Cu")
		(net "P3V3_STBY_A")
	)
	(segment
		(start 88.92794 -159.427926)
		(end 87.340948 -161.014918)
		(width 0.508)
		(layer "B.Cu")
		(net "P3V3_STBY_A")
	)
	(segment
		(start 87.366348 -48.631348)
		(end 87.366348 -46.014894)
		(width 0.508)
		(layer "B.Cu")
		(net "P3V3_STBY_A")
	)
	(segment
		(start 485.868726 -143.538956)
		(end 485.868726 -47.338742)
		(width 0.508)
		(layer "B.Cu")
		(net "P3V3_STBY_A")
	)
	(segment
		(start 457.7969 -272.001742)
		(end 458.5335 -271.265142)
		(width 0.508)
		(layer "B.Cu")
		(net "P3V3_STBY_A")
	)
	(segment
		(start 254.0762 19.558)
		(end 254.0762 18.8468)
		(width 0.508)
		(layer "B.Cu")
		(net "P3V3_STBY_A")
	)
	(segment
		(start 114.045746 -270.9926)
		(end 140.0048 -270.9926)
		(width 0.508)
		(layer "B.Cu")
		(net "P3V3_STBY_A")
	)
	(segment
		(start 79.661512 -28.683204)
		(end 78.359 -27.380692)
		(width 0.508)
		(layer "B.Cu")
		(net "P3V3_STBY_A")
	)
	(segment
		(start 427.898052 -271.315942)
		(end 424.2816 -274.932394)
		(width 0.508)
		(layer "B.Cu")
		(net "P3V3_STBY_A")
	)
	(segment
		(start 478.1296 -161.31286)
		(end 479.051112 -160.391348)
		(width 0.508)
		(layer "B.Cu")
		(net "P3V3_STBY_A")
	)
	(segment
		(start 25.45334 -274.828)
		(end 24.266398 -276.014942)
		(width 0.508)
		(layer "B.Cu")
		(net "P3V3_STBY_A")
	)
	(segment
		(start 295.7068 -271.1958)
		(end 303.276 -263.6266)
		(width 0.508)
		(layer "B.Cu")
		(net "P3V3_STBY_A")
	)
	(segment
		(start 218.3257 -116.4844)
		(end 218.3257 -115.9637)
		(width 0.508)
		(layer "B.Cu")
		(net "P3V3_STBY_A")
	)
	(segment
		(start 109.231684 -155.871164)
		(end 91.237816 -155.871164)
		(width 0.508)
		(layer "B.Cu")
		(net "P3V3_STBY_A")
	)
	(segment
		(start 272.415 -280.6446)
		(end 271.4498 -281.6098)
		(width 0.508)
		(layer "B.Cu")
		(net "P3V3_STBY_A")
	)
	(segment
		(start 201.999596 -204.349858)
		(end 191.77 -194.120262)
		(width 0.508)
		(layer "B.Cu")
		(net "P3V3_STBY_A")
	)
	(segment
		(start 424.2816 -284.241494)
		(end 415.464752 -293.058342)
		(width 0.508)
		(layer "B.Cu")
		(net "P3V3_STBY_A")
	)
	(segment
		(start 237.996476 -350.49333)
		(end 239.142778 -349.347028)
		(width 0.508)
		(layer "B.Cu")
		(net "P3V3_STBY_A")
	)
	(segment
		(start 260.43509 -338.052664)
		(end 260.43509 -339.754464)
		(width 0.508)
		(layer "B.Cu")
		(net "P3V3_STBY_A")
	)
	(segment
		(start 487.913934 -164.383974)
		(end 487.913934 -238.47679)
		(width 0.508)
		(layer "B.Cu")
		(net "P3V3_STBY_A")
	)
	(segment
		(start 140.0048 -270.9926)
		(end 145.077942 -276.065742)
		(width 0.508)
		(layer "B.Cu")
		(net "P3V3_STBY_A")
	)
	(segment
		(start 27.326844 -41.265856)
		(end 50.257456 -41.265856)
		(width 0.508)
		(layer "B.Cu")
		(net "P3V3_STBY_A")
	)
	(segment
		(start 207.986122 -137.22223)
		(end 209.89417 -137.22223)
		(width 0.508)
		(layer "B.Cu")
		(net "P3V3_STBY_A")
	)
	(segment
		(start 427.898052 -156.315918)
		(end 424.0022 -160.21177)
		(width 0.508)
		(layer "B.Cu")
		(net "P3V3_STBY_A")
	)
	(segment
		(start 25.92197 -158.347918)
		(end 24.240998 -160.02889)
		(width 0.508)
		(layer "B.Cu")
		(net "P3V3_STBY_A")
	)
	(segment
		(start 125.443234 -155.626562)
		(end 129.558288 -159.741616)
		(width 0.508)
		(layer "B.Cu")
		(net "P3V3_STBY_A")
	)
	(segment
		(start 360.76763 -270.8656)
		(end 361.88904 -269.74419)
		(width 0.508)
		(layer "B.Cu")
		(net "P3V3_STBY_A")
	)
	(segment
		(start 337.344258 -276.0218)
		(end 343.5858 -276.0218)
		(width 0.508)
		(layer "B.Cu")
		(net "P3V3_STBY_A")
	)
	(segment
		(start 191.77 -172.1358)
		(end 190.354712 -172.1358)
		(width 0.508)
		(layer "B.Cu")
		(net "P3V3_STBY_A")
	)
	(segment
		(start 192.0875 -292.5445)
		(end 192.0875 -291.115242)
		(width 0.508)
		(layer "B.Cu")
		(net "P3V3_STBY_A")
	)
	(segment
		(start 456.13955 -272.001742)
		(end 457.7969 -272.001742)
		(width 0.508)
		(layer "B.Cu")
		(net "P3V3_STBY_A")
	)
	(segment
		(start 162.442398 -177.969418)
		(end 162.442398 -177.994818)
		(width 0.508)
		(layer "B.Cu")
		(net "P3V3_STBY_A")
	)
	(segment
		(start 378.967238 -64.983106)
		(end 380.94285 -63.007494)
		(width 0.508)
		(layer "In2.Cu")
		(net "P3V3_STBY_A")
	)
	(segment
		(start 331.9653 -271.989042)
		(end 332.6384 -271.315942)
		(width 0.508)
		(layer "In2.Cu")
		(net "P3V3_STBY_A")
	)
	(segment
		(start 347.247718 -62.742318)
		(end 317.504064 -62.742318)
		(width 0.508)
		(layer "In2.Cu")
		(net "P3V3_STBY_A")
	)
	(segment
		(start 214.55253 -12.365736)
		(end 210.267804 -16.650462)
		(width 0.508)
		(layer "In2.Cu")
		(net "P3V3_STBY_A")
	)
	(segment
		(start 236.2962 -349.6564)
		(end 234.0864 -347.4466)
		(width 0.508)
		(layer "In2.Cu")
		(net "P3V3_STBY_A")
	)
	(segment
		(start 176.597056 -26.387806)
		(end 175.15459 -27.830272)
		(width 0.508)
		(layer "In2.Cu")
		(net "P3V3_STBY_A")
	)
	(segment
		(start 224.603056 -347.4466)
		(end 224.070926 -346.91447)
		(width 0.508)
		(layer "In2.Cu")
		(net "P3V3_STBY_A")
	)
	(segment
		(start 210.267804 -20.98167)
		(end 204.861668 -26.387806)
		(width 0.508)
		(layer "In2.Cu")
		(net "P3V3_STBY_A")
	)
	(segment
		(start 330.074016 -274.496784)
		(end 331.9653 -272.6055)
		(width 0.508)
		(layer "In2.Cu")
		(net "P3V3_STBY_A")
	)
	(segment
		(start 329.17384 -281.454606)
		(end 330.074016 -280.55443)
		(width 0.508)
		(layer "In2.Cu")
		(net "P3V3_STBY_A")
	)
	(segment
		(start 222.621856 -12.365736)
		(end 214.55253 -12.365736)
		(width 0.508)
		(layer "In2.Cu")
		(net "P3V3_STBY_A")
	)
	(segment
		(start 223.9645 -11.023092)
		(end 222.621856 -12.365736)
		(width 0.508)
		(layer "In2.Cu")
		(net "P3V3_STBY_A")
	)
	(segment
		(start 320.8655 -209.152744)
		(end 269.002256 -209.152744)
		(width 0.508)
		(layer "In2.Cu")
		(net "P3V3_STBY_A")
	)
	(segment
		(start 237.996476 -350.49333)
		(end 237.159546 -349.6564)
		(width 0.508)
		(layer "In2.Cu")
		(net "P3V3_STBY_A")
	)
	(segment
		(start 318.536066 -286.719518)
		(end 323.800978 -281.454606)
		(width 0.508)
		(layer "In2.Cu")
		(net "P3V3_STBY_A")
	)
	(segment
		(start 223.9645 -9.498838)
		(end 223.9645 -11.023092)
		(width 0.508)
		(layer "In2.Cu")
		(net "P3V3_STBY_A")
	)
	(segment
		(start 157.269434 -28.531566)
		(end 173.94047 -28.531566)
		(width 0.508)
		(layer "In2.Cu")
		(net "P3V3_STBY_A")
	)
	(segment
		(start 234.0864 -347.4466)
		(end 224.603056 -347.4466)
		(width 0.508)
		(layer "In2.Cu")
		(net "P3V3_STBY_A")
	)
	(segment
		(start 224.070926 -346.91447)
		(end 221.807786 -346.91447)
		(width 0.508)
		(layer "In2.Cu")
		(net "P3V3_STBY_A")
	)
	(segment
		(start 351.65665 -64.983106)
		(end 378.967238 -64.983106)
		(width 0.508)
		(layer "In2.Cu")
		(net "P3V3_STBY_A")
	)
	(segment
		(start 204.861668 -26.387806)
		(end 176.597056 -26.387806)
		(width 0.508)
		(layer "In2.Cu")
		(net "P3V3_STBY_A")
	)
	(segment
		(start 331.9653 -272.6055)
		(end 331.9653 -271.989042)
		(width 0.508)
		(layer "In2.Cu")
		(net "P3V3_STBY_A")
	)
	(segment
		(start 175.15459 -27.830272)
		(end 174.641764 -27.830272)
		(width 0.508)
		(layer "In2.Cu")
		(net "P3V3_STBY_A")
	)
	(segment
		(start 237.159546 -349.6564)
		(end 236.2962 -349.6564)
		(width 0.508)
		(layer "In2.Cu")
		(net "P3V3_STBY_A")
	)
	(segment
		(start 330.074016 -280.55443)
		(end 330.074016 -274.496784)
		(width 0.508)
		(layer "In2.Cu")
		(net "P3V3_STBY_A")
	)
	(segment
		(start 349.488506 -64.983106)
		(end 347.247718 -62.742318)
		(width 0.508)
		(layer "In2.Cu")
		(net "P3V3_STBY_A")
	)
	(segment
		(start 323.800978 -281.454606)
		(end 329.17384 -281.454606)
		(width 0.508)
		(layer "In2.Cu")
		(net "P3V3_STBY_A")
	)
	(segment
		(start 287.659318 -286.719518)
		(end 318.536066 -286.719518)
		(width 0.508)
		(layer "In2.Cu")
		(net "P3V3_STBY_A")
	)
	(segment
		(start 351.65665 -64.983106)
		(end 349.488506 -64.983106)
		(width 0.508)
		(layer "In2.Cu")
		(net "P3V3_STBY_A")
	)
	(segment
		(start 286.7152 -285.7754)
		(end 287.659318 -286.719518)
		(width 0.508)
		(layer "In2.Cu")
		(net "P3V3_STBY_A")
	)
	(segment
		(start 210.267804 -16.650462)
		(end 210.267804 -20.98167)
		(width 0.508)
		(layer "In2.Cu")
		(net "P3V3_STBY_A")
	)
	(segment
		(start 269.002256 -209.152744)
		(end 267.822426 -210.332574)
		(width 0.508)
		(layer "In2.Cu")
		(net "P3V3_STBY_A")
	)
	(segment
		(start 173.94047 -28.531566)
		(end 174.641764 -27.830272)
		(width 0.508)
		(layer "In2.Cu")
		(net "P3V3_STBY_A")
	)
	(segment
		(start 247.258586 -322.093844)
		(end 260.43509 -335.270348)
		(width 0.508)
		(layer "In4.Cu")
		(net "P3V3_STBY_A")
	)
	(segment
		(start 221.2594 -105.3846)
		(end 221.2594 -97.2566)
		(width 0.508)
		(layer "In4.Cu")
		(net "P3V3_STBY_A")
	)
	(segment
		(start 157.269434 -28.531566)
		(end 151.951944 -33.849056)
		(width 0.508)
		(layer "In4.Cu")
		(net "P3V3_STBY_A")
	)
	(segment
		(start 247.258586 -300.12513)
		(end 247.258586 -322.093844)
		(width 0.508)
		(layer "In4.Cu")
		(net "P3V3_STBY_A")
	)
	(segment
		(start 260.46049 -356.14229)
		(end 260.422136 -356.14229)
		(width 0.508)
		(layer "In4.Cu")
		(net "P3V3_STBY_A")
	)
	(segment
		(start 222.200978 -95.299022)
		(end 222.200978 -90.37447)
		(width 0.508)
		(layer "In4.Cu")
		(net "P3V3_STBY_A")
	)
	(segment
		(start 125.184154 -57.126886)
		(end 125.184154 -58.429652)
		(width 0.508)
		(layer "In4.Cu")
		(net "P3V3_STBY_A")
	)
	(segment
		(start 261.112 -356.7938)
		(end 260.46049 -356.14229)
		(width 0.508)
		(layer "In4.Cu")
		(net "P3V3_STBY_A")
	)
	(segment
		(start 260.422136 -356.14229)
		(end 260.422136 -340.668864)
		(width 0.508)
		(layer "In4.Cu")
		(net "P3V3_STBY_A")
	)
	(segment
		(start 333.186024 -41.387776)
		(end 328.527918 -46.045882)
		(width 0.508)
		(layer "In4.Cu")
		(net "P3V3_STBY_A")
	)
	(segment
		(start 151.951944 -46.223174)
		(end 151.951944 -47.059342)
		(width 0.508)
		(layer "In4.Cu")
		(net "P3V3_STBY_A")
	)
	(segment
		(start 223.139 -120.904)
		(end 223.139 -120.5738)
		(width 0.508)
		(layer "In4.Cu")
		(net "P3V3_STBY_A")
	)
	(segment
		(start 223.139 -120.5738)
		(end 222.17634 -119.61114)
		(width 0.508)
		(layer "In4.Cu")
		(net "P3V3_STBY_A")
	)
	(segment
		(start 221.2594 -97.2566)
		(end 222.200978 -96.315022)
		(width 0.508)
		(layer "In4.Cu")
		(net "P3V3_STBY_A")
	)
	(segment
		(start 222.17634 -106.30154)
		(end 221.2594 -105.3846)
		(width 0.508)
		(layer "In4.Cu")
		(net "P3V3_STBY_A")
	)
	(segment
		(start 118.966742 -50.909474)
		(end 125.184154 -57.126886)
		(width 0.508)
		(layer "In4.Cu")
		(net "P3V3_STBY_A")
	)
	(segment
		(start 154.6352 -55.187596)
		(end 162.442398 -62.994794)
		(width 0.508)
		(layer "In4.Cu")
		(net "P3V3_STBY_A")
	)
	(segment
		(start 118.966742 -46.36516)
		(end 118.966742 -50.909474)
		(width 0.508)
		(layer "In4.Cu")
		(net "P3V3_STBY_A")
	)
	(segment
		(start 260.43509 -335.270348)
		(end 260.43509 -336.350864)
		(width 0.508)
		(layer "In4.Cu")
		(net "P3V3_STBY_A")
	)
	(segment
		(start 151.951944 -33.849056)
		(end 151.951944 -46.223174)
		(width 0.508)
		(layer "In4.Cu")
		(net "P3V3_STBY_A")
	)
	(segment
		(start 277.4188 -285.9532)
		(end 277.4188 -285.736792)
		(width 0.508)
		(layer "In4.Cu")
		(net "P3V3_STBY_A")
	)
	(segment
		(start 221.975172 -358.431846)
		(end 221.154752 -357.611426)
		(width 0.508)
		(layer "In4.Cu")
		(net "P3V3_STBY_A")
	)
	(segment
		(start 221.154752 -357.611426)
		(end 221.154752 -347.567504)
		(width 0.508)
		(layer "In4.Cu")
		(net "P3V3_STBY_A")
	)
	(segment
		(start 328.527918 -52.388262)
		(end 318.173862 -62.742318)
		(width 0.508)
		(layer "In4.Cu")
		(net "P3V3_STBY_A")
	)
	(segment
		(start 318.173862 -62.742318)
		(end 317.504064 -62.742318)
		(width 0.508)
		(layer "In4.Cu")
		(net "P3V3_STBY_A")
	)
	(segment
		(start 154.6352 -49.742598)
		(end 154.6352 -55.187596)
		(width 0.508)
		(layer "In4.Cu")
		(net "P3V3_STBY_A")
	)
	(segment
		(start 222.17634 -119.61114)
		(end 222.17634 -106.30154)
		(width 0.508)
		(layer "In4.Cu")
		(net "P3V3_STBY_A")
	)
	(segment
		(start 151.951944 -47.059342)
		(end 154.6352 -49.742598)
		(width 0.508)
		(layer "In4.Cu")
		(net "P3V3_STBY_A")
	)
	(segment
		(start 246.243602 -299.110146)
		(end 247.258586 -300.12513)
		(width 0.508)
		(layer "In4.Cu")
		(net "P3V3_STBY_A")
	)
	(segment
		(start 277.4188 -285.736792)
		(end 275.17217 -283.490162)
		(width 0.508)
		(layer "In4.Cu")
		(net "P3V3_STBY_A")
	)
	(segment
		(start 125.184154 -58.429652)
		(end 130.892296 -64.137794)
		(width 0.508)
		(layer "In4.Cu")
		(net "P3V3_STBY_A")
	)
	(segment
		(start 333.957676 -41.387776)
		(end 333.186024 -41.387776)
		(width 0.508)
		(layer "In4.Cu")
		(net "P3V3_STBY_A")
	)
	(segment
		(start 222.200978 -90.37447)
		(end 222.1992 -90.372692)
		(width 0.508)
		(layer "In4.Cu")
		(net "P3V3_STBY_A")
	)
	(segment
		(start 328.527918 -46.045882)
		(end 328.527918 -52.388262)
		(width 0.508)
		(layer "In4.Cu")
		(net "P3V3_STBY_A")
	)
	(segment
		(start 221.154752 -347.567504)
		(end 221.807786 -346.91447)
		(width 0.508)
		(layer "In4.Cu")
		(net "P3V3_STBY_A")
	)
	(segment
		(start 118.991888 -46.340014)
		(end 118.966742 -46.36516)
		(width 0.508)
		(layer "In4.Cu")
		(net "P3V3_STBY_A")
	)
	(segment
		(start 222.200978 -96.315022)
		(end 222.200978 -95.299022)
		(width 0.508)
		(layer "In4.Cu")
		(net "P3V3_STBY_A")
	)
	(segment
		(start 458.5335 -271.81302)
		(end 456.0316 -274.31492)
		(width 0.508)
		(layer "In7.Cu")
		(net "P3V3_STBY_A")
	)
	(segment
		(start 353.855782 -59.052714)
		(end 361.061 -51.847496)
		(width 0.508)
		(layer "In7.Cu")
		(net "P3V3_STBY_A")
	)
	(segment
		(start 361.061 -44.948856)
		(end 362.897928 -43.111928)
		(width 0.508)
		(layer "In7.Cu")
		(net "P3V3_STBY_A")
	)
	(segment
		(start 145.911824 -48.969422)
		(end 147.576286 -47.30496)
		(width 0.508)
		(layer "In7.Cu")
		(net "P3V3_STBY_A")
	)
	(segment
		(start 456.6793 -44.084494)
		(end 459.4479 -41.315894)
		(width 0.508)
		(layer "In7.Cu")
		(net "P3V3_STBY_A")
	)
	(segment
		(start 348.882462 -178.052476)
		(end 350.038924 -178.052476)
		(width 0.508)
		(layer "In7.Cu")
		(net "P3V3_STBY_A")
	)
	(segment
		(start 120.958864 -44.373038)
		(end 129.074164 -44.373038)
		(width 0.508)
		(layer "In7.Cu")
		(net "P3V3_STBY_A")
	)
	(segment
		(start 180.9496 -44.948094)
		(end 182.0164 -46.014894)
		(width 0.508)
		(layer "In7.Cu")
		(net "P3V3_STBY_A")
	)
	(segment
		(start 456.0316 -281.018742)
		(end 444.0174 -293.032942)
		(width 0.508)
		(layer "In7.Cu")
		(net "P3V3_STBY_A")
	)
	(segment
		(start 224.213928 -385.245356)
		(end 224.213928 -390.771888)
		(width 0.508)
		(layer "In7.Cu")
		(net "P3V3_STBY_A")
	)
	(segment
		(start 219.54109 -360.865674)
		(end 219.54109 -377.723908)
		(width 0.508)
		(layer "In7.Cu")
		(net "P3V3_STBY_A")
	)
	(segment
		(start 147.576286 -47.30496)
		(end 150.870158 -47.30496)
		(width 0.508)
		(layer "In7.Cu")
		(net "P3V3_STBY_A")
	)
	(segment
		(start 455.168 -160.595818)
		(end 459.4479 -156.315918)
		(width 0.508)
		(layer "In7.Cu")
		(net "P3V3_STBY_A")
	)
	(segment
		(start 194.92087 -47.449994)
		(end 194.92087 -53.432456)
		(width 0.508)
		(layer "In7.Cu")
		(net "P3V3_STBY_A")
	)
	(segment
		(start 182.0164 -46.014894)
		(end 184.008776 -46.014894)
		(width 0.508)
		(layer "In7.Cu")
		(net "P3V3_STBY_A")
	)
	(segment
		(start 221.536514 -382.567942)
		(end 224.213928 -385.245356)
		(width 0.508)
		(layer "In7.Cu")
		(net "P3V3_STBY_A")
	)
	(segment
		(start 150.870158 -47.30496)
		(end 151.951944 -46.223174)
		(width 0.508)
		(layer "In7.Cu")
		(net "P3V3_STBY_A")
	)
	(segment
		(start 221.533974 -344.110056)
		(end 221.807786 -344.383868)
		(width 0.508)
		(layer "In7.Cu")
		(net "P3V3_STBY_A")
	)
	(segment
		(start 455.168 -176.586134)
		(end 455.168 -160.595818)
		(width 0.508)
		(layer "In7.Cu")
		(net "P3V3_STBY_A")
	)
	(segment
		(start 360.9848 -167.1066)
		(end 360.9848 -160.12922)
		(width 0.508)
		(layer "In7.Cu")
		(net "P3V3_STBY_A")
	)
	(segment
		(start 192.441322 -44.970446)
		(end 194.92087 -47.449994)
		(width 0.508)
		(layer "In7.Cu")
		(net "P3V3_STBY_A")
	)
	(segment
		(start 98.716592 -41.201848)
		(end 103.854758 -46.340014)
		(width 0.508)
		(layer "In7.Cu")
		(net "P3V3_STBY_A")
	)
	(segment
		(start 361.061 -51.847496)
		(end 361.061 -44.948856)
		(width 0.508)
		(layer "In7.Cu")
		(net "P3V3_STBY_A")
	)
	(segment
		(start 153.227024 -44.948094)
		(end 180.9496 -44.948094)
		(width 0.508)
		(layer "In7.Cu")
		(net "P3V3_STBY_A")
	)
	(segment
		(start 151.951944 -46.223174)
		(end 153.227024 -44.948094)
		(width 0.508)
		(layer "In7.Cu")
		(net "P3V3_STBY_A")
	)
	(segment
		(start 363.312202 -42.710354)
		(end 363.312202 -42.697654)
		(width 0.508)
		(layer "In7.Cu")
		(net "P3V3_STBY_A")
	)
	(segment
		(start 391.7696 -46.7106)
		(end 391.7696 -52.180744)
		(width 0.508)
		(layer "In7.Cu")
		(net "P3V3_STBY_A")
	)
	(segment
		(start 222.1992 -67.112896)
		(end 222.1992 -90.372692)
		(width 0.508)
		(layer "In7.Cu")
		(net "P3V3_STBY_A")
	)
	(segment
		(start 90.911934 -41.201848)
		(end 98.716592 -41.201848)
		(width 0.508)
		(layer "In7.Cu")
		(net "P3V3_STBY_A")
	)
	(segment
		(start 391.7696 -52.180744)
		(end 380.94285 -63.007494)
		(width 0.508)
		(layer "In7.Cu")
		(net "P3V3_STBY_A")
	)
	(segment
		(start 221.533974 -343.022174)
		(end 221.533974 -344.110056)
		(width 0.508)
		(layer "In7.Cu")
		(net "P3V3_STBY_A")
	)
	(segment
		(start 221.529656 -343.017856)
		(end 221.533974 -343.022174)
		(width 0.508)
		(layer "In7.Cu")
		(net "P3V3_STBY_A")
	)
	(segment
		(start 271.81937 -283.490162)
		(end 275.17217 -283.490162)
		(width 0.508)
		(layer "In7.Cu")
		(net "P3V3_STBY_A")
	)
	(segment
		(start 225.8822 -392.44016)
		(end 225.8822 -393.954)
		(width 0.508)
		(layer "In7.Cu")
		(net "P3V3_STBY_A")
	)
	(segment
		(start 362.897928 -43.111928)
		(end 362.910628 -43.111928)
		(width 0.508)
		(layer "In7.Cu")
		(net "P3V3_STBY_A")
	)
	(segment
		(start 194.92087 -53.432456)
		(end 208.51876 -53.432456)
		(width 0.508)
		(layer "In7.Cu")
		(net "P3V3_STBY_A")
	)
	(segment
		(start 360.9848 -160.12922)
		(end 364.798102 -156.315918)
		(width 0.508)
		(layer "In7.Cu")
		(net "P3V3_STBY_A")
	)
	(segment
		(start 208.51876 -53.432456)
		(end 222.1992 -67.112896)
		(width 0.508)
		(layer "In7.Cu")
		(net "P3V3_STBY_A")
	)
	(segment
		(start 221.807786 -344.383868)
		(end 221.807786 -346.91447)
		(width 0.508)
		(layer "In7.Cu")
		(net "P3V3_STBY_A")
	)
	(segment
		(start 221.536514 -379.719332)
		(end 221.536514 -382.567942)
		(width 0.508)
		(layer "In7.Cu")
		(net "P3V3_STBY_A")
	)
	(segment
		(start 129.074164 -44.373038)
		(end 133.670548 -48.969422)
		(width 0.508)
		(layer "In7.Cu")
		(net "P3V3_STBY_A")
	)
	(segment
		(start 443.5856 -62.118494)
		(end 447.9798 -62.118494)
		(width 0.508)
		(layer "In7.Cu")
		(net "P3V3_STBY_A")
	)
	(segment
		(start 219.54109 -377.723908)
		(end 221.536514 -379.719332)
		(width 0.508)
		(layer "In7.Cu")
		(net "P3V3_STBY_A")
	)
	(segment
		(start 220.04909 -360.357674)
		(end 219.54109 -360.865674)
		(width 0.508)
		(layer "In7.Cu")
		(net "P3V3_STBY_A")
	)
	(segment
		(start 87.366348 -46.014894)
		(end 89.670636 -43.710606)
		(width 0.508)
		(layer "In7.Cu")
		(net "P3V3_STBY_A")
	)
	(segment
		(start 184.008776 -46.014894)
		(end 185.053224 -44.970446)
		(width 0.508)
		(layer "In7.Cu")
		(net "P3V3_STBY_A")
	)
	(segment
		(start 89.670636 -43.710606)
		(end 89.670636 -42.443146)
		(width 0.508)
		(layer "In7.Cu")
		(net "P3V3_STBY_A")
	)
	(segment
		(start 221.975172 -358.431846)
		(end 220.049344 -360.357674)
		(width 0.508)
		(layer "In7.Cu")
		(net "P3V3_STBY_A")
	)
	(segment
		(start 89.670636 -42.443146)
		(end 90.911934 -41.201848)
		(width 0.508)
		(layer "In7.Cu")
		(net "P3V3_STBY_A")
	)
	(segment
		(start 458.5335 -271.265142)
		(end 458.5335 -271.81302)
		(width 0.508)
		(layer "In7.Cu")
		(net "P3V3_STBY_A")
	)
	(segment
		(start 118.991888 -46.340014)
		(end 120.958864 -44.373038)
		(width 0.508)
		(layer "In7.Cu")
		(net "P3V3_STBY_A")
	)
	(segment
		(start 362.910628 -43.111928)
		(end 363.312202 -42.710354)
		(width 0.508)
		(layer "In7.Cu")
		(net "P3V3_STBY_A")
	)
	(segment
		(start 396.34795 -42.13225)
		(end 391.7696 -46.7106)
		(width 0.508)
		(layer "In7.Cu")
		(net "P3V3_STBY_A")
	)
	(segment
		(start 350.038924 -178.052476)
		(end 360.9848 -167.1066)
		(width 0.508)
		(layer "In7.Cu")
		(net "P3V3_STBY_A")
	)
	(segment
		(start 103.854758 -46.340014)
		(end 118.991888 -46.340014)
		(width 0.508)
		(layer "In7.Cu")
		(net "P3V3_STBY_A")
	)
	(segment
		(start 456.0316 -274.31492)
		(end 456.0316 -281.018742)
		(width 0.508)
		(layer "In7.Cu")
		(net "P3V3_STBY_A")
	)
	(segment
		(start 396.34795 -41.315894)
		(end 396.34795 -42.13225)
		(width 0.508)
		(layer "In7.Cu")
		(net "P3V3_STBY_A")
	)
	(segment
		(start 363.312202 -42.697654)
		(end 364.798102 -41.211754)
		(width 0.508)
		(layer "In7.Cu")
		(net "P3V3_STBY_A")
	)
	(segment
		(start 133.670548 -48.969422)
		(end 145.911824 -48.969422)
		(width 0.508)
		(layer "In7.Cu")
		(net "P3V3_STBY_A")
	)
	(segment
		(start 224.213928 -390.771888)
		(end 225.8822 -392.44016)
		(width 0.508)
		(layer "In7.Cu")
		(net "P3V3_STBY_A")
	)
	(segment
		(start 447.9798 -62.118494)
		(end 456.6793 -53.418994)
		(width 0.508)
		(layer "In7.Cu")
		(net "P3V3_STBY_A")
	)
	(segment
		(start 448.747134 -183.007)
		(end 455.168 -176.586134)
		(width 0.508)
		(layer "In7.Cu")
		(net "P3V3_STBY_A")
	)
	(segment
		(start 353.855782 -62.783974)
		(end 353.855782 -59.052714)
		(width 0.508)
		(layer "In7.Cu")
		(net "P3V3_STBY_A")
	)
	(segment
		(start 456.6793 -53.418994)
		(end 456.6793 -44.084494)
		(width 0.508)
		(layer "In7.Cu")
		(net "P3V3_STBY_A")
	)
	(segment
		(start 364.798102 -40.448738)
		(end 364.795816 -40.448738)
		(width 0.508)
		(layer "In7.Cu")
		(net "P3V3_STBY_A")
	)
	(segment
		(start 185.053224 -44.970446)
		(end 192.441322 -44.970446)
		(width 0.508)
		(layer "In7.Cu")
		(net "P3V3_STBY_A")
	)
	(segment
		(start 220.049344 -360.357674)
		(end 220.04909 -360.357674)
		(width 0.508)
		(layer "In7.Cu")
		(net "P3V3_STBY_A")
	)
	(segment
		(start 364.798102 -41.211754)
		(end 364.798102 -40.448738)
		(width 0.508)
		(layer "In7.Cu")
		(net "P3V3_STBY_A")
	)
	(segment
		(start 351.65665 -64.983106)
		(end 353.855782 -62.783974)
		(width 0.508)
		(layer "In7.Cu")
		(net "P3V3_STBY_A")
	)
	(segment
		(start 248.330466 -301.319692)
		(end 247.5992 -300.588426)
		(width 0.508)
		(layer "In9.Cu")
		(net "P3V3_STBY_A")
	)
	(segment
		(start 252.970792 -289.182302)
		(end 252.710442 -288.921952)
		(width 0.508)
		(layer "In9.Cu")
		(net "P3V3_STBY_A")
	)
	(segment
		(start 282.347924 -356.7938)
		(end 261.112 -356.7938)
		(width 0.508)
		(layer "In9.Cu")
		(net "P3V3_STBY_A")
	)
	(segment
		(start 283.23667 -355.905054)
		(end 282.347924 -356.7938)
		(width 0.508)
		(layer "In9.Cu")
		(net "P3V3_STBY_A")
	)
	(segment
		(start 252.970792 -300.7995)
		(end 252.970792 -289.182302)
		(width 0.508)
		(layer "In9.Cu")
		(net "P3V3_STBY_A")
	)
	(segment
		(start 247.5992 -300.588426)
		(end 247.5992 -300.465744)
		(width 0.508)
		(layer "In9.Cu")
		(net "P3V3_STBY_A")
	)
	(segment
		(start 247.5992 -300.465744)
		(end 246.243602 -299.110146)
		(width 0.508)
		(layer "In9.Cu")
		(net "P3V3_STBY_A")
	)
	(segment
		(start 252.4506 -301.319692)
		(end 248.330466 -301.319692)
		(width 0.508)
		(layer "In9.Cu")
		(net "P3V3_STBY_A")
	)
	(segment
		(start 252.970792 -300.7995)
		(end 252.4506 -301.319692)
		(width 0.508)
		(layer "In9.Cu")
		(net "P3V3_STBY_A")
	)
	(segment
		(start 228.96576 -387.36524)
		(end 230.6193 -387.36524)
		(width 0.254)
		(layer "F.Cu")
		(net "P12V_IN_PGOOD")
	)
	(segment
		(start 228.6 -387.731)
		(end 228.96576 -387.36524)
		(width 0.254)
		(layer "F.Cu")
		(net "P12V_IN_PGOOD")
	)
	(via
		(at 225.769424 -390.561576)
		(size 0.6096)
		(drill 0.3048)
		(layers "F.Cu" "B.Cu")
		(net "P12V_IN_PGOOD")
	)
	(via
		(at 228.6 -387.731)
		(size 0.5588)
		(drill 0.3048)
		(layers "F.Cu" "B.Cu")
		(net "P12V_IN_PGOOD")
	)
	(segment
		(start 225.769424 -390.561576)
		(end 228.6 -387.731)
		(width 0.254)
		(layer "B.Cu")
		(net "P12V_IN_PGOOD")
	)
	(segment
		(start 225.800412 -413.100012)
		(end 224.9678 -412.2674)
		(width 0.254)
		(layer "B.Cu")
		(net "P12V_IN_PGOOD")
	)
	(segment
		(start 224.9678 -412.2674)
		(end 224.9678 -391.3632)
		(width 0.254)
		(layer "B.Cu")
		(net "P12V_IN_PGOOD")
	)
	(segment
		(start 224.9678 -391.3632)
		(end 225.769424 -390.561576)
		(width 0.254)
		(layer "B.Cu")
		(net "P12V_IN_PGOOD")
	)
	(segment
		(start 226.200208 -413.100012)
		(end 225.800412 -413.100012)
		(width 0.254)
		(layer "B.Cu")
		(net "P12V_IN_PGOOD")
	)
	(segment
		(start 279.635966 22.062948)
		(end 279.635966 22.954234)
		(width 0.508)
		(layer "F.Cu")
		(net "P12V_IN")
	)
	(segment
		(start 275.242782 -236.771688)
		(end 275.242782 -229.192328)
		(width 0.508)
		(layer "F.Cu")
		(net "P12V_IN")
	)
	(segment
		(start 279.5524 10.8204)
		(end 277.9268 10.8204)
		(width 0.508)
		(layer "F.Cu")
		(net "P12V_IN")
	)
	(segment
		(start 246.034052 -390.633204)
		(end 245.943628 -390.723628)
		(width 0.508)
		(layer "F.Cu")
		(net "P12V_IN")
	)
	(segment
		(start 282.796234 21.726652)
		(end 283.6164 21.726652)
		(width 0.508)
		(layer "F.Cu")
		(net "P12V_IN")
	)
	(segment
		(start 277.9268 10.8204)
		(end 277.9268 9.7536)
		(width 0.508)
		(layer "F.Cu")
		(net "P12V_IN")
	)
	(segment
		(start 247.701308 -390.633204)
		(end 246.034052 -390.633204)
		(width 0.508)
		(layer "F.Cu")
		(net "P12V_IN")
	)
	(segment
		(start 260.199124 -199.035924)
		(end 275.242782 -214.079582)
		(width 0.508)
		(layer "F.Cu")
		(net "P12V_IN")
	)
	(segment
		(start 248.910602 -392.605006)
		(end 248.910602 -391.842498)
		(width 0.508)
		(layer "F.Cu")
		(net "P12V_IN")
	)
	(segment
		(start 228.419152 -391.04824)
		(end 226.836732 -391.04824)
		(width 0.508)
		(layer "F.Cu")
		(net "P12V_IN")
	)
	(segment
		(start 248.910602 -394.580364)
		(end 248.910602 -393.538964)
		(width 0.508)
		(layer "F.Cu")
		(net "P12V_IN")
	)
	(segment
		(start 226.836732 -391.04824)
		(end 226.7458 -391.139172)
		(width 0.508)
		(layer "F.Cu")
		(net "P12V_IN")
	)
	(segment
		(start 227.66909 -388.228332)
		(end 226.709732 -388.228332)
		(width 0.508)
		(layer "F.Cu")
		(net "P12V_IN")
	)
	(segment
		(start 260.199124 -71.641462)
		(end 260.199124 -199.035924)
		(width 0.508)
		(layer "F.Cu")
		(net "P12V_IN")
	)
	(segment
		(start 226.7458 -391.139172)
		(end 226.7458 -392.1506)
		(width 0.508)
		(layer "F.Cu")
		(net "P12V_IN")
	)
	(segment
		(start 266.753086 -65.0875)
		(end 260.199124 -71.641462)
		(width 0.508)
		(layer "F.Cu")
		(net "P12V_IN")
	)
	(segment
		(start 277.9268 9.7536)
		(end 266.753086 -1.420114)
		(width 0.508)
		(layer "F.Cu")
		(net "P12V_IN")
	)
	(segment
		(start 275.242782 -219.48394)
		(end 275.242782 -229.192328)
		(width 0.508)
		(layer "F.Cu")
		(net "P12V_IN")
	)
	(segment
		(start 266.753086 -1.420114)
		(end 266.753086 -65.0875)
		(width 0.508)
		(layer "F.Cu")
		(net "P12V_IN")
	)
	(segment
		(start 248.910602 -393.538964)
		(end 248.910602 -392.605006)
		(width 0.508)
		(layer "F.Cu")
		(net "P12V_IN")
	)
	(segment
		(start 248.910602 -391.842498)
		(end 247.701308 -390.633204)
		(width 0.508)
		(layer "F.Cu")
		(net "P12V_IN")
	)
	(segment
		(start 279.6032 10.8712)
		(end 279.5524 10.8204)
		(width 0.508)
		(layer "F.Cu")
		(net "P12V_IN")
	)
	(segment
		(start 275.242782 -214.079582)
		(end 275.242782 -219.48394)
		(width 0.508)
		(layer "F.Cu")
		(net "P12V_IN")
	)
	(via
		(at 272.480532 -399.36547)
		(size 1.0668)
		(drill 0.7112)
		(layers "F.Cu" "B.Cu")
		(net "P12V_IN")
	)
	(via
		(at 257.803396 -391.174986)
		(size 1.0668)
		(drill 0.7112)
		(layers "F.Cu" "B.Cu")
		(net "P12V_IN")
	)
	(via
		(at 258.323842 -397.195802)
		(size 1.0668)
		(drill 0.7112)
		(layers "F.Cu" "B.Cu")
		(net "P12V_IN")
	)
	(via
		(at 268.126972 -394.94079)
		(size 1.0668)
		(drill 0.7112)
		(layers "F.Cu" "B.Cu")
		(net "P12V_IN")
	)
	(via
		(at 259.225796 -391.174986)
		(size 1.0668)
		(drill 0.7112)
		(layers "F.Cu" "B.Cu")
		(net "P12V_IN")
	)
	(via
		(at 258.374642 -400.040602)
		(size 1.0668)
		(drill 0.7112)
		(layers "F.Cu" "B.Cu")
		(net "P12V_IN")
	)
	(via
		(at 269.635732 -399.36547)
		(size 1.0668)
		(drill 0.7112)
		(layers "F.Cu" "B.Cu")
		(net "P12V_IN")
	)
	(via
		(at 268.165072 -399.35785)
		(size 1.0668)
		(drill 0.7112)
		(layers "F.Cu" "B.Cu")
		(net "P12V_IN")
	)
	(via
		(at 273.902932 -399.36547)
		(size 1.0668)
		(drill 0.7112)
		(layers "F.Cu" "B.Cu")
		(net "P12V_IN")
	)
	(via
		(at 264.098532 -396.13967)
		(size 1.0668)
		(drill 0.7112)
		(layers "F.Cu" "B.Cu")
		(net "P12V_IN")
	)
	(via
		(at 268.126972 -392.09599)
		(size 1.0668)
		(drill 0.7112)
		(layers "F.Cu" "B.Cu")
		(net "P12V_IN")
	)
	(via
		(at 272.480532 -396.52067)
		(size 1.0668)
		(drill 0.7112)
		(layers "F.Cu" "B.Cu")
		(net "P12V_IN")
	)
	(via
		(at 261.168642 -398.618202)
		(size 1.0668)
		(drill 0.7112)
		(layers "F.Cu" "B.Cu")
		(net "P12V_IN")
	)
	(via
		(at 259.225796 -392.597386)
		(size 1.0668)
		(drill 0.7112)
		(layers "F.Cu" "B.Cu")
		(net "P12V_IN")
	)
	(via
		(at 255.437132 -397.51127)
		(size 1.0668)
		(drill 0.7112)
		(layers "F.Cu" "B.Cu")
		(net "P12V_IN")
	)
	(via
		(at 263.996932 -399.03527)
		(size 1.0668)
		(drill 0.7112)
		(layers "F.Cu" "B.Cu")
		(net "P12V_IN")
	)
	(via
		(at 263.996932 -400.45767)
		(size 1.0668)
		(drill 0.7112)
		(layers "F.Cu" "B.Cu")
		(net "P12V_IN")
	)
	(via
		(at 256.914904 -397.55445)
		(size 1.0668)
		(drill 0.7112)
		(layers "F.Cu" "B.Cu")
		(net "P12V_IN")
	)
	(via
		(at 283.6164 21.726652)
		(size 0.5588)
		(drill 0.3048)
		(layers "F.Cu" "B.Cu")
		(net "P12V_IN")
	)
	(via
		(at 259.797042 -400.040602)
		(size 1.0668)
		(drill 0.7112)
		(layers "F.Cu" "B.Cu")
		(net "P12V_IN")
	)
	(via
		(at 268.076172 -396.43939)
		(size 1.0668)
		(drill 0.7112)
		(layers "F.Cu" "B.Cu")
		(net "P12V_IN")
	)
	(via
		(at 226.709732 -388.228332)
		(size 0.5588)
		(drill 0.3048)
		(layers "F.Cu" "B.Cu")
		(net "P12V_IN")
	)
	(via
		(at 259.746242 -397.195802)
		(size 1.0668)
		(drill 0.7112)
		(layers "F.Cu" "B.Cu")
		(net "P12V_IN")
	)
	(via
		(at 248.910602 -392.605006)
		(size 0.5588)
		(drill 0.3048)
		(layers "F.Cu" "B.Cu")
		(net "P12V_IN")
	)
	(via
		(at 254.014732 -398.93367)
		(size 1.0668)
		(drill 0.7112)
		(layers "F.Cu" "B.Cu")
		(net "P12V_IN")
	)
	(via
		(at 264.149332 -391.79627)
		(size 1.0668)
		(drill 0.7112)
		(layers "F.Cu" "B.Cu")
		(net "P12V_IN")
	)
	(via
		(at 262.564118 -397.163036)
		(size 1.0668)
		(drill 0.7112)
		(layers "F.Cu" "B.Cu")
		(net "P12V_IN")
	)
	(via
		(at 279.635966 22.954234)
		(size 0.5588)
		(drill 0.3048)
		(layers "F.Cu" "B.Cu")
		(net "P12V_IN")
	)
	(via
		(at 261.168642 -397.195802)
		(size 1.0668)
		(drill 0.7112)
		(layers "F.Cu" "B.Cu")
		(net "P12V_IN")
	)
	(via
		(at 258.323842 -398.618202)
		(size 1.0668)
		(drill 0.7112)
		(layers "F.Cu" "B.Cu")
		(net "P12V_IN")
	)
	(via
		(at 275.242782 -219.48394)
		(size 0.6604)
		(drill 0.3302)
		(layers "F.Cu" "B.Cu")
		(net "P12V_IN")
	)
	(via
		(at 260.630924 -392.58113)
		(size 1.0668)
		(drill 0.7112)
		(layers "F.Cu" "B.Cu")
		(net "P12V_IN")
	)
	(via
		(at 273.902932 -397.94307)
		(size 1.0668)
		(drill 0.7112)
		(layers "F.Cu" "B.Cu")
		(net "P12V_IN")
	)
	(via
		(at 259.746242 -398.618202)
		(size 1.0668)
		(drill 0.7112)
		(layers "F.Cu" "B.Cu")
		(net "P12V_IN")
	)
	(via
		(at 262.053324 -391.15873)
		(size 1.0668)
		(drill 0.7112)
		(layers "F.Cu" "B.Cu")
		(net "P12V_IN")
	)
	(via
		(at 252.59284 -400.61896)
		(size 1.0668)
		(drill 0.7112)
		(layers "F.Cu" "B.Cu")
		(net "P12V_IN")
	)
	(via
		(at 268.165072 -397.93545)
		(size 1.0668)
		(drill 0.7112)
		(layers "F.Cu" "B.Cu")
		(net "P12V_IN")
	)
	(via
		(at 275.242782 -229.192328)
		(size 0.6604)
		(drill 0.3302)
		(layers "F.Cu" "B.Cu")
		(net "P12V_IN")
	)
	(via
		(at 263.996932 -397.61287)
		(size 1.0668)
		(drill 0.7112)
		(layers "F.Cu" "B.Cu")
		(net "P12V_IN")
	)
	(via
		(at 262.053324 -392.58113)
		(size 1.0668)
		(drill 0.7112)
		(layers "F.Cu" "B.Cu")
		(net "P12V_IN")
	)
	(via
		(at 255.437132 -398.93367)
		(size 1.0668)
		(drill 0.7112)
		(layers "F.Cu" "B.Cu")
		(net "P12V_IN")
	)
	(via
		(at 269.635732 -397.94307)
		(size 1.0668)
		(drill 0.7112)
		(layers "F.Cu" "B.Cu")
		(net "P12V_IN")
	)
	(via
		(at 257.803396 -392.597386)
		(size 1.0668)
		(drill 0.7112)
		(layers "F.Cu" "B.Cu")
		(net "P12V_IN")
	)
	(via
		(at 226.7458 -392.1506)
		(size 0.5588)
		(drill 0.3048)
		(layers "F.Cu" "B.Cu")
		(net "P12V_IN")
	)
	(via
		(at 262.614918 -400.007836)
		(size 1.0668)
		(drill 0.7112)
		(layers "F.Cu" "B.Cu")
		(net "P12V_IN")
	)
	(via
		(at 256.914904 -398.97685)
		(size 1.0668)
		(drill 0.7112)
		(layers "F.Cu" "B.Cu")
		(net "P12V_IN")
	)
	(via
		(at 261.219442 -400.040602)
		(size 1.0668)
		(drill 0.7112)
		(layers "F.Cu" "B.Cu")
		(net "P12V_IN")
	)
	(via
		(at 252.55347 -399.273268)
		(size 1.0668)
		(drill 0.7112)
		(layers "F.Cu" "B.Cu")
		(net "P12V_IN")
	)
	(via
		(at 269.635732 -396.52067)
		(size 1.0668)
		(drill 0.7112)
		(layers "F.Cu" "B.Cu")
		(net "P12V_IN")
	)
	(via
		(at 256.965704 -400.39925)
		(size 1.0668)
		(drill 0.7112)
		(layers "F.Cu" "B.Cu")
		(net "P12V_IN")
	)
	(via
		(at 262.564118 -398.585436)
		(size 1.0668)
		(drill 0.7112)
		(layers "F.Cu" "B.Cu")
		(net "P12V_IN")
	)
	(via
		(at 275.242782 -236.771688)
		(size 0.5588)
		(drill 0.3048)
		(layers "F.Cu" "B.Cu")
		(net "P12V_IN")
	)
	(via
		(at 264.149332 -393.21867)
		(size 1.0668)
		(drill 0.7112)
		(layers "F.Cu" "B.Cu")
		(net "P12V_IN")
	)
	(via
		(at 260.630924 -391.15873)
		(size 1.0668)
		(drill 0.7112)
		(layers "F.Cu" "B.Cu")
		(net "P12V_IN")
	)
	(via
		(at 251.15393 -399.048732)
		(size 1.0668)
		(drill 0.7112)
		(layers "F.Cu" "B.Cu")
		(net "P12V_IN")
	)
	(via
		(at 271.058132 -396.52067)
		(size 1.0668)
		(drill 0.7112)
		(layers "F.Cu" "B.Cu")
		(net "P12V_IN")
	)
	(via
		(at 268.165072 -400.78025)
		(size 1.0668)
		(drill 0.7112)
		(layers "F.Cu" "B.Cu")
		(net "P12V_IN")
	)
	(via
		(at 273.902932 -396.52067)
		(size 1.0668)
		(drill 0.7112)
		(layers "F.Cu" "B.Cu")
		(net "P12V_IN")
	)
	(via
		(at 252.55347 -397.850868)
		(size 1.0668)
		(drill 0.7112)
		(layers "F.Cu" "B.Cu")
		(net "P12V_IN")
	)
	(via
		(at 272.480532 -397.94307)
		(size 1.0668)
		(drill 0.7112)
		(layers "F.Cu" "B.Cu")
		(net "P12V_IN")
	)
	(via
		(at 271.058132 -397.94307)
		(size 1.0668)
		(drill 0.7112)
		(layers "F.Cu" "B.Cu")
		(net "P12V_IN")
	)
	(via
		(at 271.058132 -399.36547)
		(size 1.0668)
		(drill 0.7112)
		(layers "F.Cu" "B.Cu")
		(net "P12V_IN")
	)
	(via
		(at 254.014732 -400.27987)
		(size 1.0668)
		(drill 0.7112)
		(layers "F.Cu" "B.Cu")
		(net "P12V_IN")
	)
	(via
		(at 268.126972 -393.51839)
		(size 1.0668)
		(drill 0.7112)
		(layers "F.Cu" "B.Cu")
		(net "P12V_IN")
	)
	(via
		(at 254.014732 -397.51127)
		(size 1.0668)
		(drill 0.7112)
		(layers "F.Cu" "B.Cu")
		(net "P12V_IN")
	)
	(via
		(at 264.149332 -394.64107)
		(size 1.0668)
		(drill 0.7112)
		(layers "F.Cu" "B.Cu")
		(net "P12V_IN")
	)
	(via
		(at 255.437132 -400.27987)
		(size 1.0668)
		(drill 0.7112)
		(layers "F.Cu" "B.Cu")
		(net "P12V_IN")
	)
	(via
		(at 277.9268 9.7536)
		(size 0.5588)
		(drill 0.3048)
		(layers "F.Cu" "B.Cu")
		(net "P12V_IN")
	)
	(via
		(at 251.15393 -400.471132)
		(size 1.0668)
		(drill 0.7112)
		(layers "F.Cu" "B.Cu")
		(net "P12V_IN")
	)
	(segment
		(start 278.1046 22.2504)
		(end 278.1046 17.83588)
		(width 0.508)
		(layer "In9.Cu")
		(net "P12V_IN")
	)
	(segment
		(start 278.1046 17.83588)
		(end 278.79548 17.145)
		(width 0.508)
		(layer "In9.Cu")
		(net "P12V_IN")
	)
	(segment
		(start 254.157226 -298.445682)
		(end 269.24 -283.362908)
		(width 0.508)
		(layer "In9.Cu")
		(net "P12V_IN")
	)
	(segment
		(start 247.219724 -394.295884)
		(end 230.421688 -394.295884)
		(width 0.508)
		(layer "In9.Cu")
		(net "P12V_IN")
	)
	(segment
		(start 227.047298 -388.228332)
		(end 232.381552 -382.894078)
		(width 0.508)
		(layer "In9.Cu")
		(net "P12V_IN")
	)
	(segment
		(start 230.421688 -394.295884)
		(end 228.276404 -392.1506)
		(width 0.508)
		(layer "In9.Cu")
		(net "P12V_IN")
	)
	(segment
		(start 250.720606 -392.605006)
		(end 248.910602 -392.605006)
		(width 0.508)
		(layer "In9.Cu")
		(net "P12V_IN")
	)
	(segment
		(start 226.709732 -392.114532)
		(end 226.709732 -388.228332)
		(width 0.508)
		(layer "In9.Cu")
		(net "P12V_IN")
	)
	(segment
		(start 226.709732 -388.228332)
		(end 227.047298 -388.228332)
		(width 0.508)
		(layer "In9.Cu")
		(net "P12V_IN")
	)
	(segment
		(start 269.24 -270.694912)
		(end 275.242782 -264.69213)
		(width 0.508)
		(layer "In9.Cu")
		(net "P12V_IN")
	)
	(segment
		(start 254.157226 -304.039524)
		(end 254.157226 -298.445682)
		(width 0.508)
		(layer "In9.Cu")
		(net "P12V_IN")
	)
	(segment
		(start 232.381552 -382.894078)
		(end 232.381552 -339.324442)
		(width 0.508)
		(layer "In9.Cu")
		(net "P12V_IN")
	)
	(segment
		(start 275.242782 -264.69213)
		(end 275.242782 -236.771688)
		(width 0.508)
		(layer "In9.Cu")
		(net "P12V_IN")
	)
	(segment
		(start 269.24 -283.362908)
		(end 269.24 -270.694912)
		(width 0.508)
		(layer "In9.Cu")
		(net "P12V_IN")
	)
	(segment
		(start 280.417778 22.172422)
		(end 279.635966 22.954234)
		(width 0.508)
		(layer "In9.Cu")
		(net "P12V_IN")
	)
	(segment
		(start 252.55347 -397.850868)
		(end 252.55347 -394.43787)
		(width 0.508)
		(layer "In9.Cu")
		(net "P12V_IN")
	)
	(segment
		(start 226.7458 -392.1506)
		(end 226.709732 -392.114532)
		(width 0.508)
		(layer "In9.Cu")
		(net "P12V_IN")
	)
	(segment
		(start 232.381552 -339.324442)
		(end 250.847098 -320.858896)
		(width 0.508)
		(layer "In9.Cu")
		(net "P12V_IN")
	)
	(segment
		(start 250.847098 -307.349652)
		(end 254.157226 -304.039524)
		(width 0.508)
		(layer "In9.Cu")
		(net "P12V_IN")
	)
	(segment
		(start 279.635966 22.954234)
		(end 278.808434 22.954234)
		(width 0.508)
		(layer "In9.Cu")
		(net "P12V_IN")
	)
	(segment
		(start 283.17063 22.172422)
		(end 280.417778 22.172422)
		(width 0.508)
		(layer "In9.Cu")
		(net "P12V_IN")
	)
	(segment
		(start 252.55347 -394.43787)
		(end 250.720606 -392.605006)
		(width 0.508)
		(layer "In9.Cu")
		(net "P12V_IN")
	)
	(segment
		(start 278.79548 10.62228)
		(end 277.9268 9.7536)
		(width 0.508)
		(layer "In9.Cu")
		(net "P12V_IN")
	)
	(segment
		(start 278.808434 22.954234)
		(end 278.1046 22.2504)
		(width 0.508)
		(layer "In9.Cu")
		(net "P12V_IN")
	)
	(segment
		(start 283.6164 21.726652)
		(end 283.17063 22.172422)
		(width 0.508)
		(layer "In9.Cu")
		(net "P12V_IN")
	)
	(segment
		(start 250.847098 -320.858896)
		(end 250.847098 -307.349652)
		(width 0.508)
		(layer "In9.Cu")
		(net "P12V_IN")
	)
	(segment
		(start 248.910602 -392.605006)
		(end 247.219724 -394.295884)
		(width 0.508)
		(layer "In9.Cu")
		(net "P12V_IN")
	)
	(segment
		(start 228.276404 -392.1506)
		(end 226.7458 -392.1506)
		(width 0.508)
		(layer "In9.Cu")
		(net "P12V_IN")
	)
	(segment
		(start 278.79548 17.145)
		(end 278.79548 10.62228)
		(width 0.508)
		(layer "In9.Cu")
		(net "P12V_IN")
	)
	(via
		(at 17.509998 -296.588942)
		(size 0.6604)
		(drill 0.3302)
		(layers "F.Cu" "B.Cu")
		(net "P12V_HDD0")
	)
	(segment
		(start 380.453646 -138.497056)
		(end 380.4412 -138.48461)
		(width 0.254)
		(layer "F.Cu")
		(net "P12V_B_PGOOD")
	)
	(segment
		(start 380.4412 -138.48461)
		(end 378.741432 -138.48461)
		(width 0.254)
		(layer "F.Cu")
		(net "P12V_B_PGOOD")
	)
	(via
		(at 222.5548 -394.6906)
		(size 0.5588)
		(drill 0.3048)
		(layers "F.Cu" "B.Cu")
		(net "P12V_B_PGOOD")
	)
	(via
		(at 398.272 -139.319)
		(size 0.5588)
		(drill 0.3048)
		(layers "F.Cu" "B.Cu")
		(net "P12V_B_PGOOD")
	)
	(via
		(at 387.604 -184.912)
		(size 0.5588)
		(drill 0.3048)
		(layers "F.Cu" "B.Cu")
		(net "P12V_B_PGOOD")
	)
	(via
		(at 394.922502 -139.319)
		(size 0.6096)
		(drill 0.3048)
		(layers "F.Cu" "B.Cu")
		(net "P12V_B_PGOOD")
	)
	(via
		(at 248.315988 -177.663856)
		(size 0.5588)
		(drill 0.3048)
		(layers "F.Cu" "B.Cu")
		(net "P12V_B_PGOOD")
	)
	(via
		(at 380.453646 -138.497056)
		(size 0.5588)
		(drill 0.3048)
		(layers "F.Cu" "B.Cu")
		(net "P12V_B_PGOOD")
	)
	(via
		(at 371.806216 -35.20567)
		(size 0.5588)
		(drill 0.3048)
		(layers "F.Cu" "B.Cu")
		(net "P12V_B_PGOOD")
	)
	(segment
		(start 380.453646 -138.518646)
		(end 381.254 -139.319)
		(width 0.254)
		(layer "B.Cu")
		(net "P12V_B_PGOOD")
	)
	(segment
		(start 381.254 -139.319)
		(end 394.922502 -139.319)
		(width 0.254)
		(layer "B.Cu")
		(net "P12V_B_PGOOD")
	)
	(segment
		(start 398.272 -139.319)
		(end 394.922502 -139.319)
		(width 0.254)
		(layer "B.Cu")
		(net "P12V_B_PGOOD")
	)
	(segment
		(start 380.453646 -138.497056)
		(end 380.453646 -138.518646)
		(width 0.254)
		(layer "B.Cu")
		(net "P12V_B_PGOOD")
	)
	(segment
		(start 263.809988 -193.157856)
		(end 311.716166 -193.157856)
		(width 0.254)
		(layer "In2.Cu")
		(net "P12V_B_PGOOD")
	)
	(segment
		(start 377.8504 -30.447996)
		(end 373.855742 -34.442654)
		(width 0.254)
		(layer "In2.Cu")
		(net "P12V_B_PGOOD")
	)
	(segment
		(start 311.716166 -193.157856)
		(end 320.45783 -184.416192)
		(width 0.254)
		(layer "In2.Cu")
		(net "P12V_B_PGOOD")
	)
	(segment
		(start 372.569232 -34.442654)
		(end 371.806216 -35.20567)
		(width 0.254)
		(layer "In2.Cu")
		(net "P12V_B_PGOOD")
	)
	(segment
		(start 373.855742 -34.442654)
		(end 372.569232 -34.442654)
		(width 0.254)
		(layer "In2.Cu")
		(net "P12V_B_PGOOD")
	)
	(segment
		(start 320.45783 -184.416192)
		(end 387.108192 -184.416192)
		(width 0.254)
		(layer "In2.Cu")
		(net "P12V_B_PGOOD")
	)
	(segment
		(start 377.8504 -29.849572)
		(end 377.8504 -30.447996)
		(width 0.254)
		(layer "In2.Cu")
		(net "P12V_B_PGOOD")
	)
	(segment
		(start 221.8182 -397.4846)
		(end 221.8182 -395.4272)
		(width 0.254)
		(layer "In2.Cu")
		(net "P12V_B_PGOOD")
	)
	(segment
		(start 221.8182 -395.4272)
		(end 222.5548 -394.6906)
		(width 0.254)
		(layer "In2.Cu")
		(net "P12V_B_PGOOD")
	)
	(segment
		(start 224.826068 -400.492468)
		(end 221.8182 -397.4846)
		(width 0.254)
		(layer "In2.Cu")
		(net "P12V_B_PGOOD")
	)
	(segment
		(start 224.826068 -410.906468)
		(end 224.826068 -400.492468)
		(width 0.254)
		(layer "In2.Cu")
		(net "P12V_B_PGOOD")
	)
	(segment
		(start 387.108192 -184.416192)
		(end 387.604 -184.912)
		(width 0.254)
		(layer "In2.Cu")
		(net "P12V_B_PGOOD")
	)
	(segment
		(start 378.549916 -29.150056)
		(end 377.8504 -29.849572)
		(width 0.254)
		(layer "In2.Cu")
		(net "P12V_B_PGOOD")
	)
	(segment
		(start 226.200208 -412.000192)
		(end 225.919792 -412.000192)
		(width 0.254)
		(layer "In2.Cu")
		(net "P12V_B_PGOOD")
	)
	(segment
		(start 225.919792 -412.000192)
		(end 224.826068 -410.906468)
		(width 0.254)
		(layer "In2.Cu")
		(net "P12V_B_PGOOD")
	)
	(segment
		(start 248.315988 -177.663856)
		(end 263.809988 -193.157856)
		(width 0.254)
		(layer "In2.Cu")
		(net "P12V_B_PGOOD")
	)
	(segment
		(start 222.5548 -394.6906)
		(end 221.4626 -393.5984)
		(width 0.254)
		(layer "In4.Cu")
		(net "P12V_B_PGOOD")
	)
	(segment
		(start 389.7122 -169.0878)
		(end 387.604 -171.196)
		(width 0.254)
		(layer "In4.Cu")
		(net "P12V_B_PGOOD")
	)
	(segment
		(start 226.379278 -359.966768)
		(end 223.526604 -357.114094)
		(width 0.254)
		(layer "In4.Cu")
		(net "P12V_B_PGOOD")
	)
	(segment
		(start 225.911664 -321.21475)
		(end 225.911664 -250.19508)
		(width 0.254)
		(layer "In4.Cu")
		(net "P12V_B_PGOOD")
	)
	(segment
		(start 223.526604 -357.114094)
		(end 223.526604 -323.59981)
		(width 0.254)
		(layer "In4.Cu")
		(net "P12V_B_PGOOD")
	)
	(segment
		(start 225.872294 -250.15571)
		(end 225.872294 -223.9391)
		(width 0.254)
		(layer "In4.Cu")
		(net "P12V_B_PGOOD")
	)
	(segment
		(start 248.315988 -201.495406)
		(end 248.315988 -177.663856)
		(width 0.254)
		(layer "In4.Cu")
		(net "P12V_B_PGOOD")
	)
	(segment
		(start 223.526604 -323.59981)
		(end 225.911664 -321.21475)
		(width 0.254)
		(layer "In4.Cu")
		(net "P12V_B_PGOOD")
	)
	(segment
		(start 368.303302 -122.848624)
		(end 368.303302 -47.56785)
		(width 0.254)
		(layer "In4.Cu")
		(net "P12V_B_PGOOD")
	)
	(segment
		(start 389.7122 -155.499562)
		(end 389.7122 -169.0878)
		(width 0.254)
		(layer "In4.Cu")
		(net "P12V_B_PGOOD")
	)
	(segment
		(start 375.652284 -130.197606)
		(end 368.303302 -122.848624)
		(width 0.254)
		(layer "In4.Cu")
		(net "P12V_B_PGOOD")
	)
	(segment
		(start 398.272 -139.319)
		(end 398.272 -146.939762)
		(width 0.254)
		(layer "In4.Cu")
		(net "P12V_B_PGOOD")
	)
	(segment
		(start 398.272 -146.939762)
		(end 389.7122 -155.499562)
		(width 0.254)
		(layer "In4.Cu")
		(net "P12V_B_PGOOD")
	)
	(segment
		(start 223.6724 -378.635514)
		(end 223.6724 -376.874532)
		(width 0.254)
		(layer "In4.Cu")
		(net "P12V_B_PGOOD")
	)
	(segment
		(start 387.604 -171.196)
		(end 387.604 -184.912)
		(width 0.254)
		(layer "In4.Cu")
		(net "P12V_B_PGOOD")
	)
	(segment
		(start 221.4626 -393.5984)
		(end 221.4626 -380.845314)
		(width 0.254)
		(layer "In4.Cu")
		(net "P12V_B_PGOOD")
	)
	(segment
		(start 367.922302 -47.18685)
		(end 367.922302 -40.686482)
		(width 0.254)
		(layer "In4.Cu")
		(net "P12V_B_PGOOD")
	)
	(segment
		(start 225.872294 -223.9391)
		(end 248.315988 -201.495406)
		(width 0.254)
		(layer "In4.Cu")
		(net "P12V_B_PGOOD")
	)
	(segment
		(start 380.453646 -138.497056)
		(end 380.453646 -136.613646)
		(width 0.254)
		(layer "In4.Cu")
		(net "P12V_B_PGOOD")
	)
	(segment
		(start 371.067584 -37.5412)
		(end 371.067584 -35.944302)
		(width 0.254)
		(layer "In4.Cu")
		(net "P12V_B_PGOOD")
	)
	(segment
		(start 371.067584 -35.944302)
		(end 371.806216 -35.20567)
		(width 0.254)
		(layer "In4.Cu")
		(net "P12V_B_PGOOD")
	)
	(segment
		(start 375.652284 -131.812284)
		(end 375.652284 -130.197606)
		(width 0.254)
		(layer "In4.Cu")
		(net "P12V_B_PGOOD")
	)
	(segment
		(start 226.379278 -365.336836)
		(end 226.379278 -359.966768)
		(width 0.254)
		(layer "In4.Cu")
		(net "P12V_B_PGOOD")
	)
	(segment
		(start 225.911664 -250.19508)
		(end 225.872294 -250.15571)
		(width 0.254)
		(layer "In4.Cu")
		(net "P12V_B_PGOOD")
	)
	(segment
		(start 224.15627 -376.390662)
		(end 224.15627 -367.559844)
		(width 0.254)
		(layer "In4.Cu")
		(net "P12V_B_PGOOD")
	)
	(segment
		(start 380.453646 -136.613646)
		(end 375.652284 -131.812284)
		(width 0.254)
		(layer "In4.Cu")
		(net "P12V_B_PGOOD")
	)
	(segment
		(start 223.6724 -376.874532)
		(end 224.15627 -376.390662)
		(width 0.254)
		(layer "In4.Cu")
		(net "P12V_B_PGOOD")
	)
	(segment
		(start 367.922302 -40.686482)
		(end 371.067584 -37.5412)
		(width 0.254)
		(layer "In4.Cu")
		(net "P12V_B_PGOOD")
	)
	(segment
		(start 221.4626 -380.845314)
		(end 223.6724 -378.635514)
		(width 0.254)
		(layer "In4.Cu")
		(net "P12V_B_PGOOD")
	)
	(segment
		(start 224.15627 -367.559844)
		(end 226.379278 -365.336836)
		(width 0.254)
		(layer "In4.Cu")
		(net "P12V_B_PGOOD")
	)
	(segment
		(start 368.303302 -47.56785)
		(end 367.922302 -47.18685)
		(width 0.254)
		(layer "In4.Cu")
		(net "P12V_B_PGOOD")
	)
	(segment
		(start 374.5738 -147.0914)
		(end 374.5738 -146.2659)
		(width 0.508)
		(layer "F.Cu")
		(net "P12V_B_COMP")
	)
	(segment
		(start 367.7158 -147.2184)
		(end 367.7158 -146.2659)
		(width 0.508)
		(layer "F.Cu")
		(net "P12V_B_COMP")
	)
	(via
		(at 273.8374 -102.2604)
		(size 0.5588)
		(drill 0.3048)
		(layers "F.Cu" "B.Cu")
		(net "P12V_B_COMP")
	)
	(via
		(at 300.194472 -12.844272)
		(size 0.5588)
		(drill 0.3048)
		(layers "F.Cu" "B.Cu")
		(net "P12V_B_COMP")
	)
	(via
		(at 351.1042 -135.7376)
		(size 0.7112)
		(drill 0.4064)
		(layers "F.Cu" "B.Cu")
		(net "P12V_B_COMP")
	)
	(via
		(at 300.550072 -17.543272)
		(size 0.5588)
		(drill 0.3048)
		(layers "F.Cu" "B.Cu")
		(net "P12V_B_COMP")
	)
	(via
		(at 299.280072 -17.543272)
		(size 0.5588)
		(drill 0.3048)
		(layers "F.Cu" "B.Cu")
		(net "P12V_B_COMP")
	)
	(via
		(at 346.837 -136.8044)
		(size 0.7112)
		(drill 0.4064)
		(layers "F.Cu" "B.Cu")
		(net "P12V_B_COMP")
	)
	(via
		(at 351.1042 -134.6708)
		(size 0.7112)
		(drill 0.4064)
		(layers "F.Cu" "B.Cu")
		(net "P12V_B_COMP")
	)
	(via
		(at 299.280072 -21.607272)
		(size 0.5588)
		(drill 0.3048)
		(layers "F.Cu" "B.Cu")
		(net "P12V_B_COMP")
	)
	(via
		(at 350.0374 -135.7376)
		(size 0.7112)
		(drill 0.4064)
		(layers "F.Cu" "B.Cu")
		(net "P12V_B_COMP")
	)
	(via
		(at 300.118272 -15.282672)
		(size 0.5588)
		(drill 0.3048)
		(layers "F.Cu" "B.Cu")
		(net "P12V_B_COMP")
	)
	(via
		(at 298.035472 -184.5818)
		(size 0.5588)
		(drill 0.3048)
		(layers "F.Cu" "B.Cu")
		(net "P12V_B_COMP")
	)
	(via
		(at 273.8374 -100.9904)
		(size 0.5588)
		(drill 0.3048)
		(layers "F.Cu" "B.Cu")
		(net "P12V_B_COMP")
	)
	(via
		(at 300.550072 -16.273272)
		(size 0.5588)
		(drill 0.3048)
		(layers "F.Cu" "B.Cu")
		(net "P12V_B_COMP")
	)
	(via
		(at 272.4404 -100.965)
		(size 0.5588)
		(drill 0.3048)
		(layers "F.Cu" "B.Cu")
		(net "P12V_B_COMP")
	)
	(via
		(at 300.550072 -22.623272)
		(size 0.5588)
		(drill 0.3048)
		(layers "F.Cu" "B.Cu")
		(net "P12V_B_COMP")
	)
	(via
		(at 301.820072 -22.623272)
		(size 0.5588)
		(drill 0.3048)
		(layers "F.Cu" "B.Cu")
		(net "P12V_B_COMP")
	)
	(via
		(at 299.280072 -22.623272)
		(size 0.5588)
		(drill 0.3048)
		(layers "F.Cu" "B.Cu")
		(net "P12V_B_COMP")
	)
	(via
		(at 352.171 -134.6708)
		(size 0.7112)
		(drill 0.4064)
		(layers "F.Cu" "B.Cu")
		(net "P12V_B_COMP")
	)
	(via
		(at 273.8374 -103.5304)
		(size 0.5588)
		(drill 0.3048)
		(layers "F.Cu" "B.Cu")
		(net "P12V_B_COMP")
	)
	(via
		(at 297.679872 -181.8386)
		(size 0.5588)
		(drill 0.3048)
		(layers "F.Cu" "B.Cu")
		(net "P12V_B_COMP")
	)
	(via
		(at 297.121072 -185.4962)
		(size 0.5588)
		(drill 0.3048)
		(layers "F.Cu" "B.Cu")
		(net "P12V_B_COMP")
	)
	(via
		(at 367.7158 -147.2184)
		(size 0.5588)
		(drill 0.3048)
		(layers "F.Cu" "B.Cu")
		(net "P12V_B_COMP")
	)
	(via
		(at 298.594272 -182.753)
		(size 0.5588)
		(drill 0.3048)
		(layers "F.Cu" "B.Cu")
		(net "P12V_B_COMP")
	)
	(via
		(at 300.550072 -21.607272)
		(size 0.5588)
		(drill 0.3048)
		(layers "F.Cu" "B.Cu")
		(net "P12V_B_COMP")
	)
	(via
		(at 300.194472 -11.574272)
		(size 0.5588)
		(drill 0.3048)
		(layers "F.Cu" "B.Cu")
		(net "P12V_B_COMP")
	)
	(via
		(at 297.679872 -182.753)
		(size 0.5588)
		(drill 0.3048)
		(layers "F.Cu" "B.Cu")
		(net "P12V_B_COMP")
	)
	(via
		(at 298.035472 -185.4962)
		(size 0.5588)
		(drill 0.3048)
		(layers "F.Cu" "B.Cu")
		(net "P12V_B_COMP")
	)
	(via
		(at 347.9038 -134.6708)
		(size 0.7112)
		(drill 0.4064)
		(layers "F.Cu" "B.Cu")
		(net "P12V_B_COMP")
	)
	(via
		(at 374.5738 -147.0914)
		(size 0.5588)
		(drill 0.3048)
		(layers "F.Cu" "B.Cu")
		(net "P12V_B_COMP")
	)
	(via
		(at 346.837 -135.7376)
		(size 0.7112)
		(drill 0.4064)
		(layers "F.Cu" "B.Cu")
		(net "P12V_B_COMP")
	)
	(via
		(at 301.820072 -17.543272)
		(size 0.5588)
		(drill 0.3048)
		(layers "F.Cu" "B.Cu")
		(net "P12V_B_COMP")
	)
	(via
		(at 350.0374 -134.6708)
		(size 0.7112)
		(drill 0.4064)
		(layers "F.Cu" "B.Cu")
		(net "P12V_B_COMP")
	)
	(via
		(at 348.9706 -134.6708)
		(size 0.7112)
		(drill 0.4064)
		(layers "F.Cu" "B.Cu")
		(net "P12V_B_COMP")
	)
	(via
		(at 273.8374 -99.7204)
		(size 0.5588)
		(drill 0.3048)
		(layers "F.Cu" "B.Cu")
		(net "P12V_B_COMP")
	)
	(via
		(at 272.4404 -99.695)
		(size 0.5588)
		(drill 0.3048)
		(layers "F.Cu" "B.Cu")
		(net "P12V_B_COMP")
	)
	(via
		(at 347.51391 -137.770108)
		(size 0.6604)
		(drill 0.3302)
		(layers "F.Cu" "B.Cu")
		(net "P12V_B_COMP")
	)
	(via
		(at 301.820072 -16.273272)
		(size 0.5588)
		(drill 0.3048)
		(layers "F.Cu" "B.Cu")
		(net "P12V_B_COMP")
	)
	(via
		(at 298.594272 -180.9242)
		(size 0.5588)
		(drill 0.3048)
		(layers "F.Cu" "B.Cu")
		(net "P12V_B_COMP")
	)
	(via
		(at 298.594272 -181.8386)
		(size 0.5588)
		(drill 0.3048)
		(layers "F.Cu" "B.Cu")
		(net "P12V_B_COMP")
	)
	(via
		(at 347.9038 -135.7376)
		(size 0.7112)
		(drill 0.4064)
		(layers "F.Cu" "B.Cu")
		(net "P12V_B_COMP")
	)
	(via
		(at 299.280072 -16.273272)
		(size 0.5588)
		(drill 0.3048)
		(layers "F.Cu" "B.Cu")
		(net "P12V_B_COMP")
	)
	(via
		(at 348.9706 -135.7376)
		(size 0.7112)
		(drill 0.4064)
		(layers "F.Cu" "B.Cu")
		(net "P12V_B_COMP")
	)
	(via
		(at 297.121072 -184.5818)
		(size 0.5588)
		(drill 0.3048)
		(layers "F.Cu" "B.Cu")
		(net "P12V_B_COMP")
	)
	(via
		(at 300.118272 -14.012672)
		(size 0.5588)
		(drill 0.3048)
		(layers "F.Cu" "B.Cu")
		(net "P12V_B_COMP")
	)
	(via
		(at 272.4404 -103.505)
		(size 0.5588)
		(drill 0.3048)
		(layers "F.Cu" "B.Cu")
		(net "P12V_B_COMP")
	)
	(via
		(at 297.121072 -183.6674)
		(size 0.5588)
		(drill 0.3048)
		(layers "F.Cu" "B.Cu")
		(net "P12V_B_COMP")
	)
	(via
		(at 301.820072 -21.607272)
		(size 0.5588)
		(drill 0.3048)
		(layers "F.Cu" "B.Cu")
		(net "P12V_B_COMP")
	)
	(via
		(at 272.4404 -102.235)
		(size 0.5588)
		(drill 0.3048)
		(layers "F.Cu" "B.Cu")
		(net "P12V_B_COMP")
	)
	(via
		(at 347.9038 -136.8044)
		(size 0.7112)
		(drill 0.4064)
		(layers "F.Cu" "B.Cu")
		(net "P12V_B_COMP")
	)
	(via
		(at 346.837 -134.6708)
		(size 0.7112)
		(drill 0.4064)
		(layers "F.Cu" "B.Cu")
		(net "P12V_B_COMP")
	)
	(via
		(at 352.171 -135.7376)
		(size 0.7112)
		(drill 0.4064)
		(layers "F.Cu" "B.Cu")
		(net "P12V_B_COMP")
	)
	(via
		(at 298.035472 -183.6674)
		(size 0.5588)
		(drill 0.3048)
		(layers "F.Cu" "B.Cu")
		(net "P12V_B_COMP")
	)
	(via
		(at 297.679872 -180.9242)
		(size 0.5588)
		(drill 0.3048)
		(layers "F.Cu" "B.Cu")
		(net "P12V_B_COMP")
	)
	(segment
		(start 359.0036 -136.4488)
		(end 352.8822 -136.4488)
		(width 0.508)
		(layer "In7.Cu")
		(net "P12V_B_COMP")
	)
	(segment
		(start 367.7158 -147.2184)
		(end 368.61496 -146.31924)
		(width 0.508)
		(layer "In7.Cu")
		(net "P12V_B_COMP")
	)
	(segment
		(start 352.8822 -136.4488)
		(end 352.171 -135.7376)
		(width 0.508)
		(layer "In7.Cu")
		(net "P12V_B_COMP")
	)
	(segment
		(start 373.80164 -146.31924)
		(end 374.5738 -147.0914)
		(width 0.508)
		(layer "In7.Cu")
		(net "P12V_B_COMP")
	)
	(segment
		(start 368.61496 -146.31924)
		(end 373.80164 -146.31924)
		(width 0.508)
		(layer "In7.Cu")
		(net "P12V_B_COMP")
	)
	(segment
		(start 367.7158 -147.2184)
		(end 360.553 -140.0556)
		(width 0.508)
		(layer "In7.Cu")
		(net "P12V_B_COMP")
	)
	(segment
		(start 360.553 -137.9982)
		(end 359.0036 -136.4488)
		(width 0.508)
		(layer "In7.Cu")
		(net "P12V_B_COMP")
	)
	(segment
		(start 360.553 -140.0556)
		(end 360.553 -137.9982)
		(width 0.508)
		(layer "In7.Cu")
		(net "P12V_B_COMP")
	)
	(segment
		(start 131.0132 -261.112)
		(end 129.4892 -262.636)
		(width 0.254)
		(layer "F.Cu")
		(net "P12V_A_PGOOD")
	)
	(segment
		(start 454.99909 -260.218682)
		(end 475.990412 -260.218682)
		(width 0.254)
		(layer "F.Cu")
		(net "P12V_A_PGOOD")
	)
	(segment
		(start 59.7916 -261.8232)
		(end 58.5978 -260.6294)
		(width 0.254)
		(layer "F.Cu")
		(net "P12V_A_PGOOD")
	)
	(segment
		(start 38.8366 -260.6294)
		(end 35.715702 -257.508502)
		(width 0.254)
		(layer "F.Cu")
		(net "P12V_A_PGOOD")
	)
	(segment
		(start 292.158928 -334.354932)
		(end 291.565584 -334.948276)
		(width 0.254)
		(layer "F.Cu")
		(net "P12V_A_PGOOD")
	)
	(segment
		(start 452.732902 -261.216902)
		(end 452.732902 -258.47675)
		(width 0.254)
		(layer "F.Cu")
		(net "P12V_A_PGOOD")
	)
	(segment
		(start 236.855 -384.3528)
		(end 236.855 -382.397)
		(width 0.254)
		(layer "F.Cu")
		(net "P12V_A_PGOOD")
	)
	(segment
		(start 234.315 -383.4638)
		(end 234.315 -382.6383)
		(width 0.254)
		(layer "F.Cu")
		(net "P12V_A_PGOOD")
	)
	(segment
		(start 52.657502 -150.78075)
		(end 52.657502 -151.920702)
		(width 0.254)
		(layer "F.Cu")
		(net "P12V_A_PGOOD")
	)
	(segment
		(start 35.715702 -257.508502)
		(end 35.715702 -255.42875)
		(width 0.254)
		(layer "F.Cu")
		(net "P12V_A_PGOOD")
	)
	(segment
		(start 235.5723 -382.397)
		(end 236.855 -382.397)
		(width 0.254)
		(layer "F.Cu")
		(net "P12V_A_PGOOD")
	)
	(segment
		(start 237.510066 -385.9403)
		(end 237.510066 -385.007866)
		(width 0.254)
		(layer "F.Cu")
		(net "P12V_A_PGOOD")
	)
	(segment
		(start 237.510066 -385.007866)
		(end 236.855 -384.3528)
		(width 0.254)
		(layer "F.Cu")
		(net "P12V_A_PGOOD")
	)
	(segment
		(start 485.335326 -240.512346)
		(end 485.335326 -233.146092)
		(width 0.254)
		(layer "F.Cu")
		(net "P12V_A_PGOOD")
	)
	(segment
		(start 288.0614 -362.93552)
		(end 288.0614 -364.0582)
		(width 0.254)
		(layer "F.Cu")
		(net "P12V_A_PGOOD")
	)
	(segment
		(start 58.5978 -260.6294)
		(end 38.8366 -260.6294)
		(width 0.254)
		(layer "F.Cu")
		(net "P12V_A_PGOOD")
	)
	(segment
		(start 475.990412 -260.218682)
		(end 477.397064 -258.81203)
		(width 0.254)
		(layer "F.Cu")
		(net "P12V_A_PGOOD")
	)
	(segment
		(start 485.335326 -233.146092)
		(end 483.833932 -231.644698)
		(width 0.254)
		(layer "F.Cu")
		(net "P12V_A_PGOOD")
	)
	(segment
		(start 483.833932 -229.108)
		(end 484.976932 -227.965)
		(width 0.254)
		(layer "F.Cu")
		(net "P12V_A_PGOOD")
	)
	(segment
		(start 454.336404 -262.820404)
		(end 452.732902 -261.216902)
		(width 0.254)
		(layer "F.Cu")
		(net "P12V_A_PGOOD")
	)
	(segment
		(start 453.257158 -258.47675)
		(end 454.99909 -260.218682)
		(width 0.254)
		(layer "F.Cu")
		(net "P12V_A_PGOOD")
	)
	(segment
		(start 483.833932 -231.644698)
		(end 483.833932 -229.108)
		(width 0.254)
		(layer "F.Cu")
		(net "P12V_A_PGOOD")
	)
	(segment
		(start 129.4892 -262.636)
		(end 87.6808 -262.636)
		(width 0.254)
		(layer "F.Cu")
		(net "P12V_A_PGOOD")
	)
	(segment
		(start 291.565584 -334.948276)
		(end 291.565584 -359.431336)
		(width 0.254)
		(layer "F.Cu")
		(net "P12V_A_PGOOD")
	)
	(segment
		(start 477.397064 -258.81203)
		(end 477.397064 -248.450608)
		(width 0.254)
		(layer "F.Cu")
		(net "P12V_A_PGOOD")
	)
	(segment
		(start 235.331 -382.6383)
		(end 235.5723 -382.397)
		(width 0.254)
		(layer "F.Cu")
		(net "P12V_A_PGOOD")
	)
	(segment
		(start 452.732902 -258.47675)
		(end 453.257158 -258.47675)
		(width 0.254)
		(layer "F.Cu")
		(net "P12V_A_PGOOD")
	)
	(segment
		(start 134.65302 -138.980418)
		(end 134.665466 -138.992864)
		(width 0.254)
		(layer "F.Cu")
		(net "P12V_A_PGOOD")
	)
	(segment
		(start 134.665466 -138.992864)
		(end 136.365234 -138.992864)
		(width 0.254)
		(layer "F.Cu")
		(net "P12V_A_PGOOD")
	)
	(segment
		(start 87.6808 -262.636)
		(end 86.868 -261.8232)
		(width 0.254)
		(layer "F.Cu")
		(net "P12V_A_PGOOD")
	)
	(segment
		(start 234.315 -382.6383)
		(end 235.331 -382.6383)
		(width 0.254)
		(layer "F.Cu")
		(net "P12V_A_PGOOD")
	)
	(segment
		(start 86.868 -261.8232)
		(end 59.7916 -261.8232)
		(width 0.254)
		(layer "F.Cu")
		(net "P12V_A_PGOOD")
	)
	(segment
		(start 291.565584 -359.431336)
		(end 288.0614 -362.93552)
		(width 0.254)
		(layer "F.Cu")
		(net "P12V_A_PGOOD")
	)
	(segment
		(start 477.397064 -248.450608)
		(end 485.335326 -240.512346)
		(width 0.254)
		(layer "F.Cu")
		(net "P12V_A_PGOOD")
	)
	(via
		(at 454.336404 -262.820404)
		(size 0.5588)
		(drill 0.3048)
		(layers "F.Cu" "B.Cu")
		(net "P12V_A_PGOOD")
	)
	(via
		(at 292.158928 -334.354932)
		(size 0.5588)
		(drill 0.3048)
		(layers "F.Cu" "B.Cu")
		(net "P12V_A_PGOOD")
	)
	(via
		(at 288.0614 -364.0582)
		(size 0.5588)
		(drill 0.3048)
		(layers "F.Cu" "B.Cu")
		(net "P12V_A_PGOOD")
	)
	(via
		(at 475.869 -337.566)
		(size 0.5588)
		(drill 0.3048)
		(layers "F.Cu" "B.Cu")
		(net "P12V_A_PGOOD")
	)
	(via
		(at 129.33172 -36.936426)
		(size 0.5588)
		(drill 0.3048)
		(layers "F.Cu" "B.Cu")
		(net "P12V_A_PGOOD")
	)
	(via
		(at 131.0132 -261.112)
		(size 0.5588)
		(drill 0.3048)
		(layers "F.Cu" "B.Cu")
		(net "P12V_A_PGOOD")
	)
	(via
		(at 234.315 -383.4638)
		(size 0.5588)
		(drill 0.3048)
		(layers "F.Cu" "B.Cu")
		(net "P12V_A_PGOOD")
	)
	(via
		(at 179.345336 -223.8883)
		(size 0.6096)
		(drill 0.3048)
		(layers "F.Cu" "B.Cu")
		(net "P12V_A_PGOOD")
	)
	(via
		(at 119.893588 -147.843748)
		(size 0.5588)
		(drill 0.3048)
		(layers "F.Cu" "B.Cu")
		(net "P12V_A_PGOOD")
	)
	(via
		(at 134.65302 -138.980418)
		(size 0.5588)
		(drill 0.3048)
		(layers "F.Cu" "B.Cu")
		(net "P12V_A_PGOOD")
	)
	(via
		(at 484.976932 -227.965)
		(size 0.5588)
		(drill 0.3048)
		(layers "F.Cu" "B.Cu")
		(net "P12V_A_PGOOD")
	)
	(via
		(at 234.652566 -352.809048)
		(size 0.5588)
		(drill 0.3048)
		(layers "F.Cu" "B.Cu")
		(net "P12V_A_PGOOD")
	)
	(via
		(at 130.2766 -341.7824)
		(size 0.5588)
		(drill 0.3048)
		(layers "F.Cu" "B.Cu")
		(net "P12V_A_PGOOD")
	)
	(via
		(at 52.657502 -151.920702)
		(size 0.5588)
		(drill 0.3048)
		(layers "F.Cu" "B.Cu")
		(net "P12V_A_PGOOD")
	)
	(segment
		(start 179.345336 -223.8883)
		(end 180.774594 -223.8883)
		(width 0.254)
		(layer "B.Cu")
		(net "P12V_A_PGOOD")
	)
	(segment
		(start 125.78969 -147.843748)
		(end 119.893588 -147.843748)
		(width 0.254)
		(layer "B.Cu")
		(net "P12V_A_PGOOD")
	)
	(segment
		(start 161.631376 -223.8883)
		(end 179.345336 -223.8883)
		(width 0.254)
		(layer "B.Cu")
		(net "P12V_A_PGOOD")
	)
	(segment
		(start 131.0132 -261.112)
		(end 131.0132 -254.506476)
		(width 0.254)
		(layer "B.Cu")
		(net "P12V_A_PGOOD")
	)
	(segment
		(start 131.0132 -254.506476)
		(end 161.631376 -223.8883)
		(width 0.254)
		(layer "B.Cu")
		(net "P12V_A_PGOOD")
	)
	(segment
		(start 484.109522 -227.965)
		(end 484.976932 -227.965)
		(width 0.254)
		(layer "B.Cu")
		(net "P12V_A_PGOOD")
	)
	(segment
		(start 134.65302 -138.980418)
		(end 125.78969 -147.843748)
		(width 0.254)
		(layer "B.Cu")
		(net "P12V_A_PGOOD")
	)
	(segment
		(start 231.925368 -351.2312)
		(end 233.503216 -352.809048)
		(width 0.254)
		(layer "In2.Cu")
		(net "P12V_A_PGOOD")
	)
	(segment
		(start 350.9518 -338.6074)
		(end 474.8276 -338.6074)
		(width 0.254)
		(layer "In2.Cu")
		(net "P12V_A_PGOOD")
	)
	(segment
		(start 53.241702 -151.920702)
		(end 56.714898 -155.393898)
		(width 0.254)
		(layer "In2.Cu")
		(net "P12V_A_PGOOD")
	)
	(segment
		(start 131.715256 -29.9847)
		(end 131.715256 -32.520636)
		(width 0.254)
		(layer "In2.Cu")
		(net "P12V_A_PGOOD")
	)
	(segment
		(start 294.922194 -337.118198)
		(end 349.462598 -337.118198)
		(width 0.254)
		(layer "In2.Cu")
		(net "P12V_A_PGOOD")
	)
	(segment
		(start 56.714898 -155.393898)
		(end 80.489552 -155.393898)
		(width 0.254)
		(layer "In2.Cu")
		(net "P12V_A_PGOOD")
	)
	(segment
		(start 166.2938 -343.535)
		(end 168.8846 -340.9442)
		(width 0.254)
		(layer "In2.Cu")
		(net "P12V_A_PGOOD")
	)
	(segment
		(start 130.892804 -342.398604)
		(end 139.369038 -342.398604)
		(width 0.254)
		(layer "In2.Cu")
		(net "P12V_A_PGOOD")
	)
	(segment
		(start 219.695522 -351.2312)
		(end 231.925368 -351.2312)
		(width 0.254)
		(layer "In2.Cu")
		(net "P12V_A_PGOOD")
	)
	(segment
		(start 80.489552 -155.393898)
		(end 88.039702 -147.843748)
		(width 0.254)
		(layer "In2.Cu")
		(net "P12V_A_PGOOD")
	)
	(segment
		(start 474.8276 -338.6074)
		(end 475.869 -337.566)
		(width 0.254)
		(layer "In2.Cu")
		(net "P12V_A_PGOOD")
	)
	(segment
		(start 168.8846 -340.9442)
		(end 209.408522 -340.9442)
		(width 0.254)
		(layer "In2.Cu")
		(net "P12V_A_PGOOD")
	)
	(segment
		(start 52.657502 -151.920702)
		(end 53.241702 -151.920702)
		(width 0.254)
		(layer "In2.Cu")
		(net "P12V_A_PGOOD")
	)
	(segment
		(start 131.715256 -32.520636)
		(end 129.33172 -34.904172)
		(width 0.254)
		(layer "In2.Cu")
		(net "P12V_A_PGOOD")
	)
	(segment
		(start 132.5499 -29.150056)
		(end 131.715256 -29.9847)
		(width 0.254)
		(layer "In2.Cu")
		(net "P12V_A_PGOOD")
	)
	(segment
		(start 349.462598 -337.118198)
		(end 350.9518 -338.6074)
		(width 0.254)
		(layer "In2.Cu")
		(net "P12V_A_PGOOD")
	)
	(segment
		(start 233.503216 -352.809048)
		(end 234.652566 -352.809048)
		(width 0.254)
		(layer "In2.Cu")
		(net "P12V_A_PGOOD")
	)
	(segment
		(start 292.158928 -334.354932)
		(end 294.922194 -337.118198)
		(width 0.254)
		(layer "In2.Cu")
		(net "P12V_A_PGOOD")
	)
	(segment
		(start 140.505434 -343.535)
		(end 166.2938 -343.535)
		(width 0.254)
		(layer "In2.Cu")
		(net "P12V_A_PGOOD")
	)
	(segment
		(start 209.408522 -340.9442)
		(end 219.695522 -351.2312)
		(width 0.254)
		(layer "In2.Cu")
		(net "P12V_A_PGOOD")
	)
	(segment
		(start 88.039702 -147.843748)
		(end 119.893588 -147.843748)
		(width 0.254)
		(layer "In2.Cu")
		(net "P12V_A_PGOOD")
	)
	(segment
		(start 129.33172 -34.904172)
		(end 129.33172 -36.936426)
		(width 0.254)
		(layer "In2.Cu")
		(net "P12V_A_PGOOD")
	)
	(segment
		(start 130.2766 -341.7824)
		(end 130.892804 -342.398604)
		(width 0.254)
		(layer "In2.Cu")
		(net "P12V_A_PGOOD")
	)
	(segment
		(start 139.369038 -342.398604)
		(end 140.505434 -343.535)
		(width 0.254)
		(layer "In2.Cu")
		(net "P12V_A_PGOOD")
	)
	(segment
		(start 475.889066 -277.076154)
		(end 475.889066 -277.53945)
		(width 0.254)
		(layer "In4.Cu")
		(net "P12V_A_PGOOD")
	)
	(segment
		(start 476.1103 -277.760684)
		(end 476.1103 -337.3247)
		(width 0.254)
		(layer "In4.Cu")
		(net "P12V_A_PGOOD")
	)
	(segment
		(start 130.911346 -341.147654)
		(end 130.2766 -341.7824)
		(width 0.254)
		(layer "In4.Cu")
		(net "P12V_A_PGOOD")
	)
	(segment
		(start 129.540254 -180.430424)
		(end 129.540254 -171.28744)
		(width 0.254)
		(layer "In4.Cu")
		(net "P12V_A_PGOOD")
	)
	(segment
		(start 130.911346 -315.620654)
		(end 130.911346 -341.147654)
		(width 0.254)
		(layer "In4.Cu")
		(net "P12V_A_PGOOD")
	)
	(segment
		(start 130.949954 -183.980074)
		(end 130.949954 -182.378096)
		(width 0.254)
		(layer "In4.Cu")
		(net "P12V_A_PGOOD")
	)
	(segment
		(start 123.875546 -123.074176)
		(end 123.875546 -88.53424)
		(width 0.254)
		(layer "In4.Cu")
		(net "P12V_A_PGOOD")
	)
	(segment
		(start 129.539746 -180.430932)
		(end 129.540254 -180.430424)
		(width 0.254)
		(layer "In4.Cu")
		(net "P12V_A_PGOOD")
	)
	(segment
		(start 131.45262 -63.483998)
		(end 129.33172 -61.363098)
		(width 0.254)
		(layer "In4.Cu")
		(net "P12V_A_PGOOD")
	)
	(segment
		(start 232.7402 -381.4064)
		(end 234.315 -382.9812)
		(width 0.254)
		(layer "In4.Cu")
		(net "P12V_A_PGOOD")
	)
	(segment
		(start 234.315 -382.9812)
		(end 234.315 -383.4638)
		(width 0.254)
		(layer "In4.Cu")
		(net "P12V_A_PGOOD")
	)
	(segment
		(start 123.875546 -88.53424)
		(end 128.397 -84.012786)
		(width 0.254)
		(layer "In4.Cu")
		(net "P12V_A_PGOOD")
	)
	(segment
		(start 123.51512 -165.262306)
		(end 123.51512 -163.41598)
		(width 0.254)
		(layer "In4.Cu")
		(net "P12V_A_PGOOD")
	)
	(segment
		(start 130.949954 -182.378096)
		(end 129.539746 -180.967888)
		(width 0.254)
		(layer "In4.Cu")
		(net "P12V_A_PGOOD")
	)
	(segment
		(start 476.1103 -276.85492)
		(end 475.889066 -277.076154)
		(width 0.254)
		(layer "In4.Cu")
		(net "P12V_A_PGOOD")
	)
	(segment
		(start 129.33172 -61.363098)
		(end 129.33172 -36.936426)
		(width 0.254)
		(layer "In4.Cu")
		(net "P12V_A_PGOOD")
	)
	(segment
		(start 131.0132 -261.112)
		(end 131.8514 -260.2738)
		(width 0.254)
		(layer "In4.Cu")
		(net "P12V_A_PGOOD")
	)
	(segment
		(start 119.893588 -127.056134)
		(end 123.875546 -123.074176)
		(width 0.254)
		(layer "In4.Cu")
		(net "P12V_A_PGOOD")
	)
	(segment
		(start 475.889066 -277.53945)
		(end 476.1103 -277.760684)
		(width 0.254)
		(layer "In4.Cu")
		(net "P12V_A_PGOOD")
	)
	(segment
		(start 129.540254 -171.28744)
		(end 123.51512 -165.262306)
		(width 0.254)
		(layer "In4.Cu")
		(net "P12V_A_PGOOD")
	)
	(segment
		(start 235.574078 -373.046244)
		(end 232.7402 -375.880122)
		(width 0.254)
		(layer "In4.Cu")
		(net "P12V_A_PGOOD")
	)
	(segment
		(start 476.1103 -337.3247)
		(end 475.869 -337.566)
		(width 0.254)
		(layer "In4.Cu")
		(net "P12V_A_PGOOD")
	)
	(segment
		(start 131.8514 -236.11205)
		(end 142.240508 -225.722942)
		(width 0.254)
		(layer "In4.Cu")
		(net "P12V_A_PGOOD")
	)
	(segment
		(start 454.336404 -262.820404)
		(end 475.20733 -262.820404)
		(width 0.254)
		(layer "In4.Cu")
		(net "P12V_A_PGOOD")
	)
	(segment
		(start 131.45262 -65.57518)
		(end 131.45262 -63.483998)
		(width 0.254)
		(layer "In4.Cu")
		(net "P12V_A_PGOOD")
	)
	(segment
		(start 131.8514 -260.2738)
		(end 131.8514 -236.11205)
		(width 0.254)
		(layer "In4.Cu")
		(net "P12V_A_PGOOD")
	)
	(segment
		(start 131.6228 -314.9092)
		(end 130.911346 -315.620654)
		(width 0.254)
		(layer "In4.Cu")
		(net "P12V_A_PGOOD")
	)
	(segment
		(start 131.6228 -284.750002)
		(end 131.6228 -314.9092)
		(width 0.254)
		(layer "In4.Cu")
		(net "P12V_A_PGOOD")
	)
	(segment
		(start 131.0132 -261.112)
		(end 130.057398 -262.067802)
		(width 0.254)
		(layer "In4.Cu")
		(net "P12V_A_PGOOD")
	)
	(segment
		(start 476.1103 -263.723374)
		(end 476.1103 -276.85492)
		(width 0.254)
		(layer "In4.Cu")
		(net "P12V_A_PGOOD")
	)
	(segment
		(start 235.574078 -353.73056)
		(end 235.574078 -373.046244)
		(width 0.254)
		(layer "In4.Cu")
		(net "P12V_A_PGOOD")
	)
	(segment
		(start 119.893588 -147.843748)
		(end 119.893588 -127.056134)
		(width 0.254)
		(layer "In4.Cu")
		(net "P12V_A_PGOOD")
	)
	(segment
		(start 232.7402 -375.880122)
		(end 232.7402 -381.4064)
		(width 0.254)
		(layer "In4.Cu")
		(net "P12V_A_PGOOD")
	)
	(segment
		(start 475.20733 -262.820404)
		(end 476.1103 -263.723374)
		(width 0.254)
		(layer "In4.Cu")
		(net "P12V_A_PGOOD")
	)
	(segment
		(start 142.240508 -225.722942)
		(end 142.240508 -195.270628)
		(width 0.254)
		(layer "In4.Cu")
		(net "P12V_A_PGOOD")
	)
	(segment
		(start 130.057398 -262.067802)
		(end 130.057398 -283.1846)
		(width 0.254)
		(layer "In4.Cu")
		(net "P12V_A_PGOOD")
	)
	(segment
		(start 129.539746 -180.967888)
		(end 129.539746 -180.430932)
		(width 0.254)
		(layer "In4.Cu")
		(net "P12V_A_PGOOD")
	)
	(segment
		(start 142.240508 -195.270628)
		(end 130.949954 -183.980074)
		(width 0.254)
		(layer "In4.Cu")
		(net "P12V_A_PGOOD")
	)
	(segment
		(start 128.397 -68.6308)
		(end 131.45262 -65.57518)
		(width 0.254)
		(layer "In4.Cu")
		(net "P12V_A_PGOOD")
	)
	(segment
		(start 130.057398 -283.1846)
		(end 131.6228 -284.750002)
		(width 0.254)
		(layer "In4.Cu")
		(net "P12V_A_PGOOD")
	)
	(segment
		(start 119.893588 -159.794448)
		(end 119.893588 -147.843748)
		(width 0.254)
		(layer "In4.Cu")
		(net "P12V_A_PGOOD")
	)
	(segment
		(start 123.51512 -163.41598)
		(end 119.893588 -159.794448)
		(width 0.254)
		(layer "In4.Cu")
		(net "P12V_A_PGOOD")
	)
	(segment
		(start 128.397 -84.012786)
		(end 128.397 -68.6308)
		(width 0.254)
		(layer "In4.Cu")
		(net "P12V_A_PGOOD")
	)
	(segment
		(start 234.652566 -352.809048)
		(end 235.574078 -353.73056)
		(width 0.254)
		(layer "In4.Cu")
		(net "P12V_A_PGOOD")
	)
	(segment
		(start 236.1184 -381.6604)
		(end 234.315 -383.4638)
		(width 0.254)
		(layer "In7.Cu")
		(net "P12V_A_PGOOD")
	)
	(segment
		(start 240.338864 -352.5266)
		(end 236.1184 -356.747064)
		(width 0.254)
		(layer "In7.Cu")
		(net "P12V_A_PGOOD")
	)
	(segment
		(start 288.0614 -364.0582)
		(end 286.394652 -362.391452)
		(width 0.254)
		(layer "In7.Cu")
		(net "P12V_A_PGOOD")
	)
	(segment
		(start 247.938544 -352.5266)
		(end 240.338864 -352.5266)
		(width 0.254)
		(layer "In7.Cu")
		(net "P12V_A_PGOOD")
	)
	(segment
		(start 286.394652 -362.391452)
		(end 257.803396 -362.391452)
		(width 0.254)
		(layer "In7.Cu")
		(net "P12V_A_PGOOD")
	)
	(segment
		(start 257.803396 -362.391452)
		(end 247.938544 -352.5266)
		(width 0.254)
		(layer "In7.Cu")
		(net "P12V_A_PGOOD")
	)
	(segment
		(start 236.1184 -356.747064)
		(end 236.1184 -381.6604)
		(width 0.254)
		(layer "In7.Cu")
		(net "P12V_A_PGOOD")
	)
	(segment
		(start 147.390866 -130.259074)
		(end 147.390866 -131.211574)
		(width 0.508)
		(layer "F.Cu")
		(net "P12V_A_COMP")
	)
	(segment
		(start 140.532866 -130.386074)
		(end 140.532866 -131.211574)
		(width 0.508)
		(layer "F.Cu")
		(net "P12V_A_COMP")
	)
	(via
		(at 163.015168 -152.802844)
		(size 0.7112)
		(drill 0.4064)
		(layers "F.Cu" "B.Cu")
		(net "P12V_A_COMP")
	)
	(via
		(at 159.814768 -152.802844)
		(size 0.7112)
		(drill 0.4064)
		(layers "F.Cu" "B.Cu")
		(net "P12V_A_COMP")
	)
	(via
		(at 223.151446 -21.05787)
		(size 0.5588)
		(drill 0.3048)
		(layers "F.Cu" "B.Cu")
		(net "P12V_A_COMP")
	)
	(via
		(at 223.151446 -20.04187)
		(size 0.5588)
		(drill 0.3048)
		(layers "F.Cu" "B.Cu")
		(net "P12V_A_COMP")
	)
	(via
		(at 223.197928 -101.3968)
		(size 0.5588)
		(drill 0.3048)
		(layers "F.Cu" "B.Cu")
		(net "P12V_A_COMP")
	)
	(via
		(at 222.82531 -13.34516)
		(size 0.5588)
		(drill 0.3048)
		(layers "F.Cu" "B.Cu")
		(net "P12V_A_COMP")
	)
	(via
		(at 222.842328 -102.3112)
		(size 0.5588)
		(drill 0.3048)
		(layers "F.Cu" "B.Cu")
		(net "P12V_A_COMP")
	)
	(via
		(at 160.881568 -150.669244)
		(size 0.7112)
		(drill 0.4064)
		(layers "F.Cu" "B.Cu")
		(net "P12V_A_COMP")
	)
	(via
		(at 222.842328 -103.2256)
		(size 0.5588)
		(drill 0.3048)
		(layers "F.Cu" "B.Cu")
		(net "P12V_A_COMP")
	)
	(via
		(at 224.85731 -14.36116)
		(size 0.5588)
		(drill 0.3048)
		(layers "F.Cu" "B.Cu")
		(net "P12V_A_COMP")
	)
	(via
		(at 222.885 -179.1208)
		(size 0.5588)
		(drill 0.3048)
		(layers "F.Cu" "B.Cu")
		(net "P12V_A_COMP")
	)
	(via
		(at 221.753176 -17.01419)
		(size 0.5588)
		(drill 0.3048)
		(layers "F.Cu" "B.Cu")
		(net "P12V_A_COMP")
	)
	(via
		(at 221.80931 -13.34516)
		(size 0.5588)
		(drill 0.3048)
		(layers "F.Cu" "B.Cu")
		(net "P12V_A_COMP")
	)
	(via
		(at 163.015168 -150.669244)
		(size 0.7112)
		(drill 0.4064)
		(layers "F.Cu" "B.Cu")
		(net "P12V_A_COMP")
	)
	(via
		(at 140.532866 -130.386074)
		(size 0.5588)
		(drill 0.3048)
		(layers "F.Cu" "B.Cu")
		(net "P12V_A_COMP")
	)
	(via
		(at 161.948368 -153.869644)
		(size 0.7112)
		(drill 0.4064)
		(layers "F.Cu" "B.Cu")
		(net "P12V_A_COMP")
	)
	(via
		(at 161.948368 -152.802844)
		(size 0.7112)
		(drill 0.4064)
		(layers "F.Cu" "B.Cu")
		(net "P12V_A_COMP")
	)
	(via
		(at 159.814768 -153.869644)
		(size 0.7112)
		(drill 0.4064)
		(layers "F.Cu" "B.Cu")
		(net "P12V_A_COMP")
	)
	(via
		(at 222.793306 -16.999204)
		(size 0.5588)
		(drill 0.3048)
		(layers "F.Cu" "B.Cu")
		(net "P12V_A_COMP")
	)
	(via
		(at 159.814768 -150.669244)
		(size 0.7112)
		(drill 0.4064)
		(layers "F.Cu" "B.Cu")
		(net "P12V_A_COMP")
	)
	(via
		(at 224.907856 -21.133054)
		(size 0.5588)
		(drill 0.3048)
		(layers "F.Cu" "B.Cu")
		(net "P12V_A_COMP")
	)
	(via
		(at 224.7138 -179.1208)
		(size 0.5588)
		(drill 0.3048)
		(layers "F.Cu" "B.Cu")
		(net "P12V_A_COMP")
	)
	(via
		(at 222.283528 -99.568)
		(size 0.5588)
		(drill 0.3048)
		(layers "F.Cu" "B.Cu")
		(net "P12V_A_COMP")
	)
	(via
		(at 161.948368 -151.736044)
		(size 0.7112)
		(drill 0.4064)
		(layers "F.Cu" "B.Cu")
		(net "P12V_A_COMP")
	)
	(via
		(at 222.283528 -101.3968)
		(size 0.5588)
		(drill 0.3048)
		(layers "F.Cu" "B.Cu")
		(net "P12V_A_COMP")
	)
	(via
		(at 223.756728 -103.2256)
		(size 0.5588)
		(drill 0.3048)
		(layers "F.Cu" "B.Cu")
		(net "P12V_A_COMP")
	)
	(via
		(at 160.41116 -149.720554)
		(size 0.6096)
		(drill 0.3048)
		(layers "F.Cu" "B.Cu")
		(net "P12V_A_COMP")
	)
	(via
		(at 160.881568 -152.802844)
		(size 0.7112)
		(drill 0.4064)
		(layers "F.Cu" "B.Cu")
		(net "P12V_A_COMP")
	)
	(via
		(at 220.34881 -179.743354)
		(size 0.5588)
		(drill 0.3048)
		(layers "F.Cu" "B.Cu")
		(net "P12V_A_COMP")
	)
	(via
		(at 220.842586 -14.383004)
		(size 0.5588)
		(drill 0.3048)
		(layers "F.Cu" "B.Cu")
		(net "P12V_A_COMP")
	)
	(via
		(at 159.814768 -151.736044)
		(size 0.7112)
		(drill 0.4064)
		(layers "F.Cu" "B.Cu")
		(net "P12V_A_COMP")
	)
	(via
		(at 222.17761 -179.743354)
		(size 0.5588)
		(drill 0.3048)
		(layers "F.Cu" "B.Cu")
		(net "P12V_A_COMP")
	)
	(via
		(at 163.015168 -153.869644)
		(size 0.7112)
		(drill 0.4064)
		(layers "F.Cu" "B.Cu")
		(net "P12V_A_COMP")
	)
	(via
		(at 223.84131 -13.34516)
		(size 0.5588)
		(drill 0.3048)
		(layers "F.Cu" "B.Cu")
		(net "P12V_A_COMP")
	)
	(via
		(at 223.7994 -179.1208)
		(size 0.5588)
		(drill 0.3048)
		(layers "F.Cu" "B.Cu")
		(net "P12V_A_COMP")
	)
	(via
		(at 223.756728 -102.3112)
		(size 0.5588)
		(drill 0.3048)
		(layers "F.Cu" "B.Cu")
		(net "P12V_A_COMP")
	)
	(via
		(at 221.753176 -18.03019)
		(size 0.5588)
		(drill 0.3048)
		(layers "F.Cu" "B.Cu")
		(net "P12V_A_COMP")
	)
	(via
		(at 163.015168 -151.736044)
		(size 0.7112)
		(drill 0.4064)
		(layers "F.Cu" "B.Cu")
		(net "P12V_A_COMP")
	)
	(via
		(at 222.842328 -104.14)
		(size 0.5588)
		(drill 0.3048)
		(layers "F.Cu" "B.Cu")
		(net "P12V_A_COMP")
	)
	(via
		(at 220.79331 -13.34516)
		(size 0.5588)
		(drill 0.3048)
		(layers "F.Cu" "B.Cu")
		(net "P12V_A_COMP")
	)
	(via
		(at 224.167446 -19.53387)
		(size 0.5588)
		(drill 0.3048)
		(layers "F.Cu" "B.Cu")
		(net "P12V_A_COMP")
	)
	(via
		(at 160.881568 -153.869644)
		(size 0.7112)
		(drill 0.4064)
		(layers "F.Cu" "B.Cu")
		(net "P12V_A_COMP")
	)
	(via
		(at 222.283528 -100.4824)
		(size 0.5588)
		(drill 0.3048)
		(layers "F.Cu" "B.Cu")
		(net "P12V_A_COMP")
	)
	(via
		(at 224.167446 -20.54987)
		(size 0.5588)
		(drill 0.3048)
		(layers "F.Cu" "B.Cu")
		(net "P12V_A_COMP")
	)
	(via
		(at 220.737176 -18.03019)
		(size 0.5588)
		(drill 0.3048)
		(layers "F.Cu" "B.Cu")
		(net "P12V_A_COMP")
	)
	(via
		(at 220.737176 -17.01419)
		(size 0.5588)
		(drill 0.3048)
		(layers "F.Cu" "B.Cu")
		(net "P12V_A_COMP")
	)
	(via
		(at 161.948368 -150.669244)
		(size 0.7112)
		(drill 0.4064)
		(layers "F.Cu" "B.Cu")
		(net "P12V_A_COMP")
	)
	(via
		(at 160.881568 -151.736044)
		(size 0.7112)
		(drill 0.4064)
		(layers "F.Cu" "B.Cu")
		(net "P12V_A_COMP")
	)
	(via
		(at 147.390866 -130.259074)
		(size 0.5588)
		(drill 0.3048)
		(layers "F.Cu" "B.Cu")
		(net "P12V_A_COMP")
	)
	(via
		(at 223.197928 -100.4824)
		(size 0.5588)
		(drill 0.3048)
		(layers "F.Cu" "B.Cu")
		(net "P12V_A_COMP")
	)
	(via
		(at 221.26321 -179.743354)
		(size 0.5588)
		(drill 0.3048)
		(layers "F.Cu" "B.Cu")
		(net "P12V_A_COMP")
	)
	(via
		(at 224.85731 -13.34516)
		(size 0.5588)
		(drill 0.3048)
		(layers "F.Cu" "B.Cu")
		(net "P12V_A_COMP")
	)
	(via
		(at 225.062542 -20.021296)
		(size 0.5588)
		(drill 0.3048)
		(layers "F.Cu" "B.Cu")
		(net "P12V_A_COMP")
	)
	(via
		(at 224.85731 -15.37716)
		(size 0.5588)
		(drill 0.3048)
		(layers "F.Cu" "B.Cu")
		(net "P12V_A_COMP")
	)
	(via
		(at 223.756728 -104.14)
		(size 0.5588)
		(drill 0.3048)
		(layers "F.Cu" "B.Cu")
		(net "P12V_A_COMP")
	)
	(via
		(at 220.842586 -15.653004)
		(size 0.5588)
		(drill 0.3048)
		(layers "F.Cu" "B.Cu")
		(net "P12V_A_COMP")
	)
	(via
		(at 223.197928 -99.568)
		(size 0.5588)
		(drill 0.3048)
		(layers "F.Cu" "B.Cu")
		(net "P12V_A_COMP")
	)
	(segment
		(start 146.578066 -131.071874)
		(end 141.26464 -131.071874)
		(width 0.508)
		(layer "In7.Cu")
		(net "P12V_A_COMP")
	)
	(segment
		(start 140.57884 -130.386074)
		(end 140.532866 -130.386074)
		(width 0.508)
		(layer "In7.Cu")
		(net "P12V_A_COMP")
	)
	(segment
		(start 149.731984 -132.600192)
		(end 149.731984 -140.58646)
		(width 0.508)
		(layer "In7.Cu")
		(net "P12V_A_COMP")
	)
	(segment
		(start 141.26464 -131.071874)
		(end 140.57884 -130.386074)
		(width 0.508)
		(layer "In7.Cu")
		(net "P12V_A_COMP")
	)
	(segment
		(start 147.390866 -130.259074)
		(end 146.578066 -131.071874)
		(width 0.508)
		(layer "In7.Cu")
		(net "P12V_A_COMP")
	)
	(segment
		(start 147.390866 -130.259074)
		(end 149.731984 -132.600192)
		(width 0.508)
		(layer "In7.Cu")
		(net "P12V_A_COMP")
	)
	(segment
		(start 149.731984 -140.58646)
		(end 159.814768 -150.669244)
		(width 0.508)
		(layer "In7.Cu")
		(net "P12V_A_COMP")
	)
	(segment
		(start 249.560842 -384.070098)
		(end 249.963686 -384.472942)
		(width 0.254)
		(layer "F.Cu")
		(net "MB3_TEMP_E")
	)
	(segment
		(start 246.652288 -384.603498)
		(end 247.185688 -384.070098)
		(width 0.254)
		(layer "F.Cu")
		(net "MB3_TEMP_E")
	)
	(segment
		(start 251.097542 -383.530348)
		(end 251.097542 -384.472942)
		(width 0.254)
		(layer "F.Cu")
		(net "MB3_TEMP_E")
	)
	(segment
		(start 249.963686 -384.472942)
		(end 251.097542 -384.472942)
		(width 0.254)
		(layer "F.Cu")
		(net "MB3_TEMP_E")
	)
	(segment
		(start 246.652288 -385.310126)
		(end 246.652288 -384.603498)
		(width 0.254)
		(layer "F.Cu")
		(net "MB3_TEMP_E")
	)
	(segment
		(start 247.185688 -384.070098)
		(end 249.560842 -384.070098)
		(width 0.254)
		(layer "F.Cu")
		(net "MB3_TEMP_E")
	)
	(via
		(at 251.097542 -384.472942)
		(size 0.6604)
		(drill 0.3302)
		(layers "F.Cu" "B.Cu")
		(net "MB3_TEMP_E")
	)
	(segment
		(start 246.973598 -383.085848)
		(end 247.655842 -383.085848)
		(width 0.254)
		(layer "F.Cu")
		(net "MB3_TEMP_B")
	)
	(segment
		(start 244.725952 -385.315206)
		(end 245.758208 -385.315206)
		(width 0.254)
		(layer "F.Cu")
		(net "MB3_TEMP_B")
	)
	(segment
		(start 245.763288 -385.310126)
		(end 245.763288 -384.296158)
		(width 0.254)
		(layer "F.Cu")
		(net "MB3_TEMP_B")
	)
	(segment
		(start 248.767092 -382.101598)
		(end 249.560842 -382.101598)
		(width 0.254)
		(layer "F.Cu")
		(net "MB3_TEMP_B")
	)
	(segment
		(start 247.782842 -383.085848)
		(end 248.767092 -382.101598)
		(width 0.254)
		(layer "F.Cu")
		(net "MB3_TEMP_B")
	)
	(segment
		(start 245.871492 -384.187954)
		(end 246.973598 -383.085848)
		(width 0.254)
		(layer "F.Cu")
		(net "MB3_TEMP_B")
	)
	(segment
		(start 245.763288 -384.296158)
		(end 245.871492 -384.187954)
		(width 0.254)
		(layer "F.Cu")
		(net "MB3_TEMP_B")
	)
	(segment
		(start 247.655842 -383.085848)
		(end 247.782842 -383.085848)
		(width 0.254)
		(layer "F.Cu")
		(net "MB3_TEMP_B")
	)
	(segment
		(start 245.758208 -385.315206)
		(end 245.763288 -385.310126)
		(width 0.254)
		(layer "F.Cu")
		(net "MB3_TEMP_B")
	)
	(via
		(at 245.871492 -384.187954)
		(size 0.6604)
		(drill 0.3302)
		(layers "F.Cu" "B.Cu")
		(net "MB3_TEMP_B")
	)
	(segment
		(start 231.577134 -384.2004)
		(end 234.5436 -387.166866)
		(width 0.17145)
		(layer "F.Cu")
		(net "MB3_SDA_R")
	)
	(segment
		(start 236.2835 -387.166866)
		(end 234.5436 -387.166866)
		(width 0.17145)
		(layer "F.Cu")
		(net "MB3_SDA_R")
	)
	(segment
		(start 231.2289 -384.2004)
		(end 231.577134 -384.2004)
		(width 0.17145)
		(layer "F.Cu")
		(net "MB3_SDA_R")
	)
	(via
		(at 234.5436 -387.166866)
		(size 0.6604)
		(drill 0.3302)
		(layers "F.Cu" "B.Cu")
		(net "MB3_SDA_R")
	)
	(segment
		(start 236.2073 -386.66674)
		(end 235.99394 -386.66674)
		(width 0.17145)
		(layer "F.Cu")
		(net "MB3_SCL_R")
	)
	(segment
		(start 231.6226 -383.0574)
		(end 234.188 -385.6228)
		(width 0.17145)
		(layer "F.Cu")
		(net "MB3_SCL_R")
	)
	(segment
		(start 235.99394 -386.66674)
		(end 234.95 -385.6228)
		(width 0.17145)
		(layer "F.Cu")
		(net "MB3_SCL_R")
	)
	(segment
		(start 234.188 -385.6228)
		(end 234.696 -385.6228)
		(width 0.17145)
		(layer "F.Cu")
		(net "MB3_SCL_R")
	)
	(segment
		(start 231.2289 -383.0574)
		(end 231.6226 -383.0574)
		(width 0.17145)
		(layer "F.Cu")
		(net "MB3_SCL_R")
	)
	(segment
		(start 234.95 -385.6228)
		(end 234.696 -385.6228)
		(width 0.17145)
		(layer "F.Cu")
		(net "MB3_SCL_R")
	)
	(via
		(at 234.696 -385.6228)
		(size 0.6604)
		(drill 0.3302)
		(layers "F.Cu" "B.Cu")
		(net "MB3_SCL_R")
	)
	(via
		(at 273.985482 -381.404622)
		(size 0.8636)
		(drill 0.508)
		(layers "F.Cu" "B.Cu")
		(net "MB3_P12V_IN_R")
	)
	(via
		(at 273.985482 -386.738622)
		(size 0.8636)
		(drill 0.508)
		(layers "F.Cu" "B.Cu")
		(net "MB3_P12V_IN_R")
	)
	(via
		(at 263.0424 -386.2324)
		(size 0.6096)
		(drill 0.3048)
		(layers "F.Cu" "B.Cu")
		(net "MB3_P12V_IN_R")
	)
	(via
		(at 256.58826 -383.839212)
		(size 0.8636)
		(drill 0.508)
		(layers "F.Cu" "B.Cu")
		(net "MB3_P12V_IN_R")
	)
	(via
		(at 270.33474 -383.815336)
		(size 0.8636)
		(drill 0.508)
		(layers "F.Cu" "B.Cu")
		(net "MB3_P12V_IN_R")
	)
	(via
		(at 273.985482 -382.928622)
		(size 0.8636)
		(drill 0.508)
		(layers "F.Cu" "B.Cu")
		(net "MB3_P12V_IN_R")
	)
	(via
		(at 264.308082 -387.066282)
		(size 0.8636)
		(drill 0.508)
		(layers "F.Cu" "B.Cu")
		(net "MB3_P12V_IN_R")
	)
	(via
		(at 259.990082 -379.880622)
		(size 0.8636)
		(drill 0.508)
		(layers "F.Cu" "B.Cu")
		(net "MB3_P12V_IN_R")
	)
	(via
		(at 252.928882 -379.880622)
		(size 0.8636)
		(drill 0.508)
		(layers "F.Cu" "B.Cu")
		(net "MB3_P12V_IN_R")
	)
	(via
		(at 254.127 -383.8956)
		(size 0.8636)
		(drill 0.508)
		(layers "F.Cu" "B.Cu")
		(net "MB3_P12V_IN_R")
	)
	(via
		(at 264.61974 -383.815336)
		(size 0.8636)
		(drill 0.508)
		(layers "F.Cu" "B.Cu")
		(net "MB3_P12V_IN_R")
	)
	(via
		(at 255.44526 -383.839212)
		(size 0.8636)
		(drill 0.508)
		(layers "F.Cu" "B.Cu")
		(net "MB3_P12V_IN_R")
	)
	(via
		(at 263.290812 -383.84734)
		(size 0.8636)
		(drill 0.508)
		(layers "F.Cu" "B.Cu")
		(net "MB3_P12V_IN_R")
	)
	(via
		(at 273.985482 -385.214622)
		(size 0.8636)
		(drill 0.508)
		(layers "F.Cu" "B.Cu")
		(net "MB3_P12V_IN_R")
	)
	(via
		(at 267.051282 -378.356622)
		(size 0.8636)
		(drill 0.508)
		(layers "F.Cu" "B.Cu")
		(net "MB3_P12V_IN_R")
	)
	(via
		(at 252.928882 -382.928622)
		(size 0.8636)
		(drill 0.508)
		(layers "F.Cu" "B.Cu")
		(net "MB3_P12V_IN_R")
	)
	(via
		(at 259.15366 -389.735568)
		(size 0.8636)
		(drill 0.508)
		(layers "F.Cu" "B.Cu")
		(net "MB3_P12V_IN_R")
	)
	(via
		(at 259.990082 -382.928622)
		(size 0.8636)
		(drill 0.508)
		(layers "F.Cu" "B.Cu")
		(net "MB3_P12V_IN_R")
	)
	(via
		(at 257.73126 -383.839212)
		(size 0.8636)
		(drill 0.508)
		(layers "F.Cu" "B.Cu")
		(net "MB3_P12V_IN_R")
	)
	(via
		(at 262.07466 -383.813812)
		(size 0.8636)
		(drill 0.508)
		(layers "F.Cu" "B.Cu")
		(net "MB3_P12V_IN_R")
	)
	(via
		(at 268.04874 -383.815336)
		(size 0.8636)
		(drill 0.508)
		(layers "F.Cu" "B.Cu")
		(net "MB3_P12V_IN_R")
	)
	(via
		(at 264.287 -388.43966)
		(size 0.8636)
		(drill 0.508)
		(layers "F.Cu" "B.Cu")
		(net "MB3_P12V_IN_R")
	)
	(via
		(at 260.699504 -389.718804)
		(size 0.8636)
		(drill 0.508)
		(layers "F.Cu" "B.Cu")
		(net "MB3_P12V_IN_R")
	)
	(via
		(at 252.928882 -378.356622)
		(size 0.8636)
		(drill 0.508)
		(layers "F.Cu" "B.Cu")
		(net "MB3_P12V_IN_R")
	)
	(via
		(at 271.8816 -386.334)
		(size 0.6604)
		(drill 0.3302)
		(layers "F.Cu" "B.Cu")
		(net "MB3_P12V_IN_R")
	)
	(via
		(at 273.985482 -379.880622)
		(size 0.8636)
		(drill 0.508)
		(layers "F.Cu" "B.Cu")
		(net "MB3_P12V_IN_R")
	)
	(via
		(at 259.990082 -381.404622)
		(size 0.8636)
		(drill 0.508)
		(layers "F.Cu" "B.Cu")
		(net "MB3_P12V_IN_R")
	)
	(via
		(at 259.174742 -388.36219)
		(size 0.8636)
		(drill 0.508)
		(layers "F.Cu" "B.Cu")
		(net "MB3_P12V_IN_R")
	)
	(via
		(at 260.720586 -388.345426)
		(size 0.8636)
		(drill 0.508)
		(layers "F.Cu" "B.Cu")
		(net "MB3_P12V_IN_R")
	)
	(via
		(at 267.051282 -379.880622)
		(size 0.8636)
		(drill 0.508)
		(layers "F.Cu" "B.Cu")
		(net "MB3_P12V_IN_R")
	)
	(via
		(at 262.076946 -389.735568)
		(size 0.8636)
		(drill 0.508)
		(layers "F.Cu" "B.Cu")
		(net "MB3_P12V_IN_R")
	)
	(via
		(at 252.928882 -381.404622)
		(size 0.8636)
		(drill 0.508)
		(layers "F.Cu" "B.Cu")
		(net "MB3_P12V_IN_R")
	)
	(via
		(at 272.62074 -383.815336)
		(size 0.8636)
		(drill 0.508)
		(layers "F.Cu" "B.Cu")
		(net "MB3_P12V_IN_R")
	)
	(via
		(at 271.47774 -383.815336)
		(size 0.8636)
		(drill 0.508)
		(layers "F.Cu" "B.Cu")
		(net "MB3_P12V_IN_R")
	)
	(via
		(at 262.098028 -388.36219)
		(size 0.8636)
		(drill 0.508)
		(layers "F.Cu" "B.Cu")
		(net "MB3_P12V_IN_R")
	)
	(via
		(at 257.7973 -388.345426)
		(size 0.8636)
		(drill 0.508)
		(layers "F.Cu" "B.Cu")
		(net "MB3_P12V_IN_R")
	)
	(via
		(at 259.990082 -378.356622)
		(size 0.8636)
		(drill 0.508)
		(layers "F.Cu" "B.Cu")
		(net "MB3_P12V_IN_R")
	)
	(via
		(at 269.19174 -383.815336)
		(size 0.8636)
		(drill 0.508)
		(layers "F.Cu" "B.Cu")
		(net "MB3_P12V_IN_R")
	)
	(via
		(at 257.776218 -389.718804)
		(size 0.8636)
		(drill 0.508)
		(layers "F.Cu" "B.Cu")
		(net "MB3_P12V_IN_R")
	)
	(via
		(at 258.9784 -383.8194)
		(size 0.8636)
		(drill 0.508)
		(layers "F.Cu" "B.Cu")
		(net "MB3_P12V_IN_R")
	)
	(via
		(at 273.985482 -378.356622)
		(size 0.8636)
		(drill 0.508)
		(layers "F.Cu" "B.Cu")
		(net "MB3_P12V_IN_R")
	)
	(via
		(at 264.308082 -385.542282)
		(size 0.8636)
		(drill 0.508)
		(layers "F.Cu" "B.Cu")
		(net "MB3_P12V_IN_R")
	)
	(via
		(at 267.051282 -381.404622)
		(size 0.8636)
		(drill 0.508)
		(layers "F.Cu" "B.Cu")
		(net "MB3_P12V_IN_R")
	)
	(via
		(at 267.051282 -382.928622)
		(size 0.8636)
		(drill 0.508)
		(layers "F.Cu" "B.Cu")
		(net "MB3_P12V_IN_R")
	)
	(via
		(at 260.93166 -383.813812)
		(size 0.8636)
		(drill 0.508)
		(layers "F.Cu" "B.Cu")
		(net "MB3_P12V_IN_R")
	)
	(segment
		(start 360.5403 -144.20215)
		(end 361.52455 -144.20215)
		(width 0.254)
		(layer "F.Cu")
		(net "MB1_TEMP_E")
	)
	(segment
		(start 360.50855 -144.2339)
		(end 360.5403 -144.20215)
		(width 0.254)
		(layer "F.Cu")
		(net "MB1_TEMP_E")
	)
	(segment
		(start 359.0036 -144.2339)
		(end 360.50855 -144.2339)
		(width 0.254)
		(layer "F.Cu")
		(net "MB1_TEMP_E")
	)
	(segment
		(start 364.0328 -142.9639)
		(end 362.7628 -142.9639)
		(width 0.254)
		(layer "F.Cu")
		(net "MB1_TEMP_E")
	)
	(segment
		(start 361.52455 -144.20215)
		(end 362.7628 -142.9639)
		(width 0.254)
		(layer "F.Cu")
		(net "MB1_TEMP_E")
	)
	(via
		(at 362.7628 -142.9639)
		(size 0.6604)
		(drill 0.3302)
		(layers "F.Cu" "B.Cu")
		(net "MB1_TEMP_E")
	)
	(segment
		(start 362.4453 -145.1864)
		(end 361.46105 -146.17065)
		(width 0.254)
		(layer "F.Cu")
		(net "MB1_TEMP_B")
	)
	(segment
		(start 361.46105 -146.17065)
		(end 360.5403 -146.17065)
		(width 0.254)
		(layer "F.Cu")
		(net "MB1_TEMP_B")
	)
	(segment
		(start 365.0488 -143.8529)
		(end 364.0328 -143.8529)
		(width 0.254)
		(layer "F.Cu")
		(net "MB1_TEMP_B")
	)
	(segment
		(start 364.0328 -145.1864)
		(end 362.4453 -145.1864)
		(width 0.254)
		(layer "F.Cu")
		(net "MB1_TEMP_B")
	)
	(segment
		(start 364.0328 -143.8529)
		(end 364.0328 -145.1864)
		(width 0.254)
		(layer "F.Cu")
		(net "MB1_TEMP_B")
	)
	(via
		(at 364.0328 -145.1864)
		(size 0.6604)
		(drill 0.3302)
		(layers "F.Cu" "B.Cu")
		(net "MB1_TEMP_B")
	)
	(segment
		(start 376.115834 -140.848334)
		(end 374.5738 -140.848334)
		(width 0.17145)
		(layer "F.Cu")
		(net "MB1_SDA_R")
	)
	(segment
		(start 376.5169 -141.2494)
		(end 376.115834 -140.848334)
		(width 0.17145)
		(layer "F.Cu")
		(net "MB1_SDA_R")
	)
	(segment
		(start 374.5738 -140.848334)
		(end 372.6053 -140.848334)
		(width 0.17145)
		(layer "F.Cu")
		(net "MB1_SDA_R")
	)
	(via
		(at 374.5738 -140.848334)
		(size 0.6604)
		(drill 0.3302)
		(layers "F.Cu" "B.Cu")
		(net "MB1_SDA_R")
	)
	(segment
		(start 376.2375 -142.621)
		(end 374.5738 -142.621)
		(width 0.17145)
		(layer "F.Cu")
		(net "MB1_SCL_R")
	)
	(segment
		(start 373.30126 -141.34846)
		(end 374.5738 -142.621)
		(width 0.17145)
		(layer "F.Cu")
		(net "MB1_SCL_R")
	)
	(segment
		(start 372.6815 -141.34846)
		(end 373.30126 -141.34846)
		(width 0.17145)
		(layer "F.Cu")
		(net "MB1_SCL_R")
	)
	(segment
		(start 376.5169 -142.3416)
		(end 376.2375 -142.621)
		(width 0.17145)
		(layer "F.Cu")
		(net "MB1_SCL_R")
	)
	(via
		(at 374.5738 -142.621)
		(size 0.6604)
		(drill 0.3302)
		(layers "F.Cu" "B.Cu")
		(net "MB1_SCL_R")
	)
	(segment
		(start 154.665172 -132.17398)
		(end 154.665172 -133.034278)
		(width 0.254)
		(layer "F.Cu")
		(net "MB0_TEMP_E")
	)
	(segment
		(start 156.23032 -132.17398)
		(end 154.665172 -132.17398)
		(width 0.254)
		(layer "F.Cu")
		(net "MB0_TEMP_E")
	)
	(segment
		(start 156.2354 -132.1689)
		(end 156.23032 -132.17398)
		(width 0.254)
		(layer "F.Cu")
		(net "MB0_TEMP_E")
	)
	(segment
		(start 152.870154 -134.7724)
		(end 152.870154 -134.126986)
		(width 0.254)
		(layer "F.Cu")
		(net "MB0_TEMP_E")
	)
	(segment
		(start 153.446226 -133.550914)
		(end 154.148536 -133.550914)
		(width 0.254)
		(layer "F.Cu")
		(net "MB0_TEMP_E")
	)
	(segment
		(start 152.870154 -134.126986)
		(end 153.446226 -133.550914)
		(width 0.254)
		(layer "F.Cu")
		(net "MB0_TEMP_E")
	)
	(segment
		(start 154.665172 -133.034278)
		(end 154.148536 -133.550914)
		(width 0.254)
		(layer "F.Cu")
		(net "MB0_TEMP_E")
	)
	(via
		(at 154.148536 -133.550914)
		(size 0.6604)
		(drill 0.3302)
		(layers "F.Cu" "B.Cu")
		(net "MB0_TEMP_E")
	)
	(segment
		(start 150.943818 -134.77748)
		(end 151.976074 -134.77748)
		(width 0.254)
		(layer "F.Cu")
		(net "MB0_TEMP_B")
	)
	(segment
		(start 151.981154 -134.7724)
		(end 151.981154 -133.75386)
		(width 0.254)
		(layer "F.Cu")
		(net "MB0_TEMP_B")
	)
	(segment
		(start 152.760172 -132.974842)
		(end 152.208738 -133.526276)
		(width 0.254)
		(layer "F.Cu")
		(net "MB0_TEMP_B")
	)
	(segment
		(start 151.976074 -134.77748)
		(end 151.981154 -134.7724)
		(width 0.254)
		(layer "F.Cu")
		(net "MB0_TEMP_B")
	)
	(segment
		(start 152.760172 -131.18973)
		(end 152.760172 -132.974842)
		(width 0.254)
		(layer "F.Cu")
		(net "MB0_TEMP_B")
	)
	(segment
		(start 154.665172 -130.20548)
		(end 153.744422 -130.20548)
		(width 0.254)
		(layer "F.Cu")
		(net "MB0_TEMP_B")
	)
	(segment
		(start 151.981154 -133.75386)
		(end 152.208738 -133.526276)
		(width 0.254)
		(layer "F.Cu")
		(net "MB0_TEMP_B")
	)
	(segment
		(start 153.744422 -130.20548)
		(end 152.760172 -131.18973)
		(width 0.254)
		(layer "F.Cu")
		(net "MB0_TEMP_B")
	)
	(via
		(at 152.208738 -133.526276)
		(size 0.6604)
		(drill 0.3302)
		(layers "F.Cu" "B.Cu")
		(net "MB0_TEMP_B")
	)
	(segment
		(start 138.462766 -135.339074)
		(end 139.2428 -135.339074)
		(width 0.17145)
		(layer "F.Cu")
		(net "MB0_SDA_R")
	)
	(segment
		(start 139.2428 -135.339074)
		(end 140.532866 -136.62914)
		(width 0.17145)
		(layer "F.Cu")
		(net "MB0_SDA_R")
	)
	(segment
		(start 140.532866 -136.62914)
		(end 142.501366 -136.62914)
		(width 0.17145)
		(layer "F.Cu")
		(net "MB0_SDA_R")
	)
	(via
		(at 140.532866 -136.62914)
		(size 0.6604)
		(drill 0.3302)
		(layers "F.Cu" "B.Cu")
		(net "MB0_SDA_R")
	)
	(segment
		(start 142.425166 -136.129014)
		(end 141.805406 -136.129014)
		(width 0.17145)
		(layer "F.Cu")
		(net "MB0_SCL_R")
	)
	(segment
		(start 141.805406 -136.129014)
		(end 140.532866 -134.856474)
		(width 0.17145)
		(layer "F.Cu")
		(net "MB0_SCL_R")
	)
	(segment
		(start 139.377674 -134.246874)
		(end 139.987274 -134.856474)
		(width 0.17145)
		(layer "F.Cu")
		(net "MB0_SCL_R")
	)
	(segment
		(start 139.987274 -134.856474)
		(end 140.532866 -134.856474)
		(width 0.17145)
		(layer "F.Cu")
		(net "MB0_SCL_R")
	)
	(segment
		(start 138.462766 -134.246874)
		(end 139.377674 -134.246874)
		(width 0.17145)
		(layer "F.Cu")
		(net "MB0_SCL_R")
	)
	(via
		(at 140.532866 -134.856474)
		(size 0.6604)
		(drill 0.3302)
		(layers "F.Cu" "B.Cu")
		(net "MB0_SCL_R")
	)
	(segment
		(start 330.090526 -23.099014)
		(end 330.090526 -24.449532)
		(width 0.17145)
		(layer "F.Cu")
		(net "IOM_B_SLOT_ID_1")
	)
	(segment
		(start 330.090526 -24.449532)
		(end 330.090526 -25.562306)
		(width 0.17145)
		(layer "F.Cu")
		(net "IOM_B_SLOT_ID_1")
	)
	(via
		(at 330.090526 -25.562306)
		(size 0.5588)
		(drill 0.3048)
		(layers "F.Cu" "B.Cu")
		(net "IOM_B_SLOT_ID_1")
	)
	(via
		(at 330.090526 -24.449532)
		(size 0.6604)
		(drill 0.3302)
		(layers "F.Cu" "B.Cu")
		(net "IOM_B_SLOT_ID_1")
	)
	(segment
		(start 346.468954 -29.46654)
		(end 340.646766 -29.46654)
		(width 0.13335)
		(layer "In2.Cu")
		(net "IOM_B_SLOT_ID_1")
	)
	(segment
		(start 365.37519 -31.080202)
		(end 361.047538 -35.407854)
		(width 0.13335)
		(layer "In2.Cu")
		(net "IOM_B_SLOT_ID_1")
	)
	(segment
		(start 365.949992 -29.550106)
		(end 365.37519 -30.124908)
		(width 0.13335)
		(layer "In2.Cu")
		(net "IOM_B_SLOT_ID_1")
	)
	(segment
		(start 339.932772 -28.752546)
		(end 333.105506 -28.752546)
		(width 0.13335)
		(layer "In2.Cu")
		(net "IOM_B_SLOT_ID_1")
	)
	(segment
		(start 340.646766 -29.46654)
		(end 339.932772 -28.752546)
		(width 0.13335)
		(layer "In2.Cu")
		(net "IOM_B_SLOT_ID_1")
	)
	(segment
		(start 361.047538 -35.407854)
		(end 352.410268 -35.407854)
		(width 0.13335)
		(layer "In2.Cu")
		(net "IOM_B_SLOT_ID_1")
	)
	(segment
		(start 365.37519 -30.124908)
		(end 365.37519 -31.080202)
		(width 0.13335)
		(layer "In2.Cu")
		(net "IOM_B_SLOT_ID_1")
	)
	(segment
		(start 330.090526 -25.737566)
		(end 330.090526 -25.562306)
		(width 0.13335)
		(layer "In2.Cu")
		(net "IOM_B_SLOT_ID_1")
	)
	(segment
		(start 352.410268 -35.407854)
		(end 346.468954 -29.46654)
		(width 0.13335)
		(layer "In2.Cu")
		(net "IOM_B_SLOT_ID_1")
	)
	(segment
		(start 333.105506 -28.752546)
		(end 330.090526 -25.737566)
		(width 0.13335)
		(layer "In2.Cu")
		(net "IOM_B_SLOT_ID_1")
	)
	(segment
		(start 94.07906 -24.36368)
		(end 92.751148 -24.36368)
		(width 0.17145)
		(layer "F.Cu")
		(net "IOM_A_SLOT_ID_1")
	)
	(segment
		(start 95.997776 -24.365966)
		(end 95.99549 -24.36368)
		(width 0.17145)
		(layer "F.Cu")
		(net "IOM_A_SLOT_ID_1")
	)
	(segment
		(start 95.99549 -24.36368)
		(end 94.07906 -24.36368)
		(width 0.17145)
		(layer "F.Cu")
		(net "IOM_A_SLOT_ID_1")
	)
	(via
		(at 94.07906 -24.36368)
		(size 0.6604)
		(drill 0.3302)
		(layers "F.Cu" "B.Cu")
		(net "IOM_A_SLOT_ID_1")
	)
	(via
		(at 95.997776 -24.365966)
		(size 0.5588)
		(drill 0.3048)
		(layers "F.Cu" "B.Cu")
		(net "IOM_A_SLOT_ID_1")
	)
	(segment
		(start 117.9576 -33.655)
		(end 105.28681 -33.655)
		(width 0.13335)
		(layer "In2.Cu")
		(net "IOM_A_SLOT_ID_1")
	)
	(segment
		(start 105.28681 -33.655)
		(end 95.997776 -24.365966)
		(width 0.13335)
		(layer "In2.Cu")
		(net "IOM_A_SLOT_ID_1")
	)
	(segment
		(start 120.524778 -31.087822)
		(end 117.9576 -33.655)
		(width 0.13335)
		(layer "In2.Cu")
		(net "IOM_A_SLOT_ID_1")
	)
	(segment
		(start 120.524778 -30.100778)
		(end 120.524778 -31.087822)
		(width 0.13335)
		(layer "In2.Cu")
		(net "IOM_A_SLOT_ID_1")
	)
	(segment
		(start 119.949976 -29.550106)
		(end 119.974106 -29.550106)
		(width 0.13335)
		(layer "In2.Cu")
		(net "IOM_A_SLOT_ID_1")
	)
	(segment
		(start 119.974106 -29.550106)
		(end 120.524778 -30.100778)
		(width 0.13335)
		(layer "In2.Cu")
		(net "IOM_A_SLOT_ID_1")
	)
	(segment
		(start 253.393956 -252.15596)
		(end 253.393956 -251.133356)
		(width 0.17145)
		(layer "F.Cu")
		(net "IO_EXP6_INT_N")
	)
	(segment
		(start 252.271276 -250.010676)
		(end 252.7046 -250.444)
		(width 0.17145)
		(layer "F.Cu")
		(net "IO_EXP6_INT_N")
	)
	(segment
		(start 252.271276 -249.32386)
		(end 252.271276 -250.010676)
		(width 0.17145)
		(layer "F.Cu")
		(net "IO_EXP6_INT_N")
	)
	(segment
		(start 253.393956 -251.133356)
		(end 252.7046 -250.444)
		(width 0.17145)
		(layer "F.Cu")
		(net "IO_EXP6_INT_N")
	)
	(via
		(at 252.7046 -250.444)
		(size 0.6604)
		(drill 0.3302)
		(layers "F.Cu" "B.Cu")
		(net "IO_EXP6_INT_N")
	)
	(segment
		(start 223.352614 -375.4628)
		(end 223.352614 -373.954294)
		(width 0.17145)
		(layer "F.Cu")
		(net "IO_EXP3_LED_SDA")
	)
	(segment
		(start 223.347534 -376.557794)
		(end 223.347534 -375.46788)
		(width 0.17145)
		(layer "F.Cu")
		(net "IO_EXP3_LED_SDA")
	)
	(segment
		(start 223.347534 -375.46788)
		(end 223.352614 -375.4628)
		(width 0.17145)
		(layer "F.Cu")
		(net "IO_EXP3_LED_SDA")
	)
	(via
		(at 223.352614 -375.4628)
		(size 0.6604)
		(drill 0.3302)
		(layers "F.Cu" "B.Cu")
		(net "IO_EXP3_LED_SDA")
	)
	(segment
		(start 224.002854 -373.954294)
		(end 224.002854 -375.082054)
		(width 0.17145)
		(layer "F.Cu")
		(net "IO_EXP3_LED_SCL")
	)
	(segment
		(start 224.522538 -375.601738)
		(end 224.446338 -375.525538)
		(width 0.17145)
		(layer "F.Cu")
		(net "IO_EXP3_LED_SCL")
	)
	(segment
		(start 224.522538 -376.56008)
		(end 224.522538 -375.601738)
		(width 0.17145)
		(layer "F.Cu")
		(net "IO_EXP3_LED_SCL")
	)
	(segment
		(start 224.002854 -375.082054)
		(end 224.446338 -375.525538)
		(width 0.17145)
		(layer "F.Cu")
		(net "IO_EXP3_LED_SCL")
	)
	(via
		(at 224.446338 -375.525538)
		(size 0.6604)
		(drill 0.3302)
		(layers "F.Cu" "B.Cu")
		(net "IO_EXP3_LED_SCL")
	)
	(segment
		(start 259.8674 -241.554)
		(end 259.8674 -242.824)
		(width 0.17145)
		(layer "F.Cu")
		(net "IO_EXP3_INT_N")
	)
	(segment
		(start 259.8674 -239.6744)
		(end 259.8674 -241.554)
		(width 0.17145)
		(layer "F.Cu")
		(net "IO_EXP3_INT_N")
	)
	(via
		(at 259.8674 -241.554)
		(size 0.6604)
		(drill 0.3302)
		(layers "F.Cu" "B.Cu")
		(net "IO_EXP3_INT_N")
	)
	(segment
		(start 222.702374 -367.939574)
		(end 221.31655 -366.55375)
		(width 0.17145)
		(layer "F.Cu")
		(net "IO_EXP3_HDD_FAULT_INT_N")
	)
	(segment
		(start 220.599 -365.8362)
		(end 221.31655 -366.55375)
		(width 0.17145)
		(layer "F.Cu")
		(net "IO_EXP3_HDD_FAULT_INT_N")
	)
	(segment
		(start 220.599 -365.5695)
		(end 220.599 -365.8362)
		(width 0.17145)
		(layer "F.Cu")
		(net "IO_EXP3_HDD_FAULT_INT_N")
	)
	(segment
		(start 222.702374 -368.315494)
		(end 222.702374 -367.939574)
		(width 0.17145)
		(layer "F.Cu")
		(net "IO_EXP3_HDD_FAULT_INT_N")
	)
	(via
		(at 221.31655 -366.55375)
		(size 0.6604)
		(drill 0.3302)
		(layers "F.Cu" "B.Cu")
		(net "IO_EXP3_HDD_FAULT_INT_N")
	)
	(segment
		(start 224.028 -365.5695)
		(end 224.002854 -365.594646)
		(width 0.17145)
		(layer "F.Cu")
		(net "IO_EXP3_HDD_FAULT_A2")
	)
	(segment
		(start 225.171 -365.5695)
		(end 224.028 -365.5695)
		(width 0.17145)
		(layer "F.Cu")
		(net "IO_EXP3_HDD_FAULT_A2")
	)
	(segment
		(start 224.002854 -365.594646)
		(end 224.002854 -366.5982)
		(width 0.17145)
		(layer "F.Cu")
		(net "IO_EXP3_HDD_FAULT_A2")
	)
	(segment
		(start 224.002854 -368.315494)
		(end 224.002854 -366.5982)
		(width 0.17145)
		(layer "F.Cu")
		(net "IO_EXP3_HDD_FAULT_A2")
	)
	(via
		(at 224.002854 -366.5982)
		(size 0.6604)
		(drill 0.3302)
		(layers "F.Cu" "B.Cu")
		(net "IO_EXP3_HDD_FAULT_A2")
	)
	(segment
		(start 223.352614 -368.315494)
		(end 223.352614 -367.116614)
		(width 0.17145)
		(layer "F.Cu")
		(net "IO_EXP3_HDD_FAULT_A1")
	)
	(segment
		(start 222.885 -365.5695)
		(end 222.885 -366.649)
		(width 0.17145)
		(layer "F.Cu")
		(net "IO_EXP3_HDD_FAULT_A1")
	)
	(segment
		(start 221.742 -365.5695)
		(end 222.885 -365.5695)
		(width 0.17145)
		(layer "F.Cu")
		(net "IO_EXP3_HDD_FAULT_A1")
	)
	(segment
		(start 223.352614 -367.116614)
		(end 222.885 -366.649)
		(width 0.17145)
		(layer "F.Cu")
		(net "IO_EXP3_HDD_FAULT_A1")
	)
	(via
		(at 222.885 -366.649)
		(size 0.6604)
		(drill 0.3302)
		(layers "F.Cu" "B.Cu")
		(net "IO_EXP3_HDD_FAULT_A1")
	)
	(segment
		(start 225.7044 -375.7676)
		(end 225.552 -375.6152)
		(width 0.17145)
		(layer "F.Cu")
		(net "IO_EXP3_HDD_FAULT_A0")
	)
	(segment
		(start 224.653094 -374.716294)
		(end 225.552 -375.6152)
		(width 0.17145)
		(layer "F.Cu")
		(net "IO_EXP3_HDD_FAULT_A0")
	)
	(segment
		(start 226.8347 -376.5677)
		(end 226.822 -376.555)
		(width 0.17145)
		(layer "F.Cu")
		(net "IO_EXP3_HDD_FAULT_A0")
	)
	(segment
		(start 226.822 -376.555)
		(end 225.7044 -376.555)
		(width 0.17145)
		(layer "F.Cu")
		(net "IO_EXP3_HDD_FAULT_A0")
	)
	(segment
		(start 224.653094 -373.954294)
		(end 224.653094 -374.716294)
		(width 0.17145)
		(layer "F.Cu")
		(net "IO_EXP3_HDD_FAULT_A0")
	)
	(segment
		(start 225.7044 -376.555)
		(end 225.7044 -375.7676)
		(width 0.17145)
		(layer "F.Cu")
		(net "IO_EXP3_HDD_FAULT_A0")
	)
	(via
		(at 225.552 -375.6152)
		(size 0.6604)
		(drill 0.3302)
		(layers "F.Cu" "B.Cu")
		(net "IO_EXP3_HDD_FAULT_A0")
	)
	(segment
		(start 336.174334 -21.89607)
		(end 337.291934 -21.89607)
		(width 0.17145)
		(layer "F.Cu")
		(net "IO_EXP11_A2")
	)
	(segment
		(start 337.291934 -21.89607)
		(end 337.352894 -21.95703)
		(width 0.17145)
		(layer "F.Cu")
		(net "IO_EXP11_A2")
	)
	(segment
		(start 337.352894 -24.41829)
		(end 337.352894 -22.987)
		(width 0.17145)
		(layer "F.Cu")
		(net "IO_EXP11_A2")
	)
	(segment
		(start 337.352894 -21.95703)
		(end 337.352894 -22.987)
		(width 0.17145)
		(layer "F.Cu")
		(net "IO_EXP11_A2")
	)
	(via
		(at 337.352894 -22.987)
		(size 0.6604)
		(drill 0.3302)
		(layers "F.Cu" "B.Cu")
		(net "IO_EXP11_A2")
	)
	(segment
		(start 333.774034 -21.88337)
		(end 334.967834 -21.88337)
		(width 0.17145)
		(layer "F.Cu")
		(net "IO_EXP11_A1")
	)
	(segment
		(start 336.702654 -23.46579)
		(end 336.087974 -22.85111)
		(width 0.17145)
		(layer "F.Cu")
		(net "IO_EXP11_A1")
	)
	(segment
		(start 335.132934 -21.89607)
		(end 336.087974 -22.85111)
		(width 0.17145)
		(layer "F.Cu")
		(net "IO_EXP11_A1")
	)
	(segment
		(start 334.980534 -21.89607)
		(end 335.132934 -21.89607)
		(width 0.17145)
		(layer "F.Cu")
		(net "IO_EXP11_A1")
	)
	(segment
		(start 336.702654 -24.41829)
		(end 336.702654 -23.46579)
		(width 0.17145)
		(layer "F.Cu")
		(net "IO_EXP11_A1")
	)
	(segment
		(start 334.967834 -21.88337)
		(end 334.980534 -21.89607)
		(width 0.17145)
		(layer "F.Cu")
		(net "IO_EXP11_A1")
	)
	(via
		(at 336.087974 -22.85111)
		(size 0.6604)
		(drill 0.3302)
		(layers "F.Cu" "B.Cu")
		(net "IO_EXP11_A1")
	)
	(segment
		(start 338.565236 -33.105852)
		(end 339.759036 -33.105852)
		(width 0.17145)
		(layer "F.Cu")
		(net "IO_EXP11_A0")
	)
	(segment
		(start 338.003134 -30.05709)
		(end 338.003134 -31.183326)
		(width 0.17145)
		(layer "F.Cu")
		(net "IO_EXP11_A0")
	)
	(segment
		(start 338.16671 -32.707326)
		(end 338.565236 -33.105852)
		(width 0.17145)
		(layer "F.Cu")
		(net "IO_EXP11_A0")
	)
	(segment
		(start 338.16671 -31.902654)
		(end 338.16671 -32.707326)
		(width 0.17145)
		(layer "F.Cu")
		(net "IO_EXP11_A0")
	)
	(segment
		(start 338.16671 -31.346902)
		(end 338.16671 -31.902654)
		(width 0.17145)
		(layer "F.Cu")
		(net "IO_EXP11_A0")
	)
	(segment
		(start 338.003134 -31.183326)
		(end 338.16671 -31.346902)
		(width 0.17145)
		(layer "F.Cu")
		(net "IO_EXP11_A0")
	)
	(via
		(at 338.16671 -31.902654)
		(size 0.6604)
		(drill 0.3302)
		(layers "F.Cu" "B.Cu")
		(net "IO_EXP11_A0")
	)
	(segment
		(start 81.564988 -29.332936)
		(end 81.109566 -29.788358)
		(width 0.17145)
		(layer "F.Cu")
		(net "IO_EXP10_SDA")
	)
	(segment
		(start 83.159854 -28.906724)
		(end 82.733642 -29.332936)
		(width 0.17145)
		(layer "F.Cu")
		(net "IO_EXP10_SDA")
	)
	(segment
		(start 82.733642 -29.332936)
		(end 81.564988 -29.332936)
		(width 0.17145)
		(layer "F.Cu")
		(net "IO_EXP10_SDA")
	)
	(segment
		(start 83.159854 -27.86761)
		(end 83.159854 -28.906724)
		(width 0.17145)
		(layer "F.Cu")
		(net "IO_EXP10_SDA")
	)
	(segment
		(start 81.109566 -29.788358)
		(end 81.002886 -29.895038)
		(width 0.17145)
		(layer "F.Cu")
		(net "IO_EXP10_SDA")
	)
	(segment
		(start 81.002886 -29.895038)
		(end 81.002886 -30.960822)
		(width 0.17145)
		(layer "F.Cu")
		(net "IO_EXP10_SDA")
	)
	(via
		(at 81.109566 -29.788358)
		(size 0.6604)
		(drill 0.3302)
		(layers "F.Cu" "B.Cu")
		(net "IO_EXP10_SDA")
	)
	(segment
		(start 83.393534 -30.4038)
		(end 83.810094 -29.98724)
		(width 0.17145)
		(layer "F.Cu")
		(net "IO_EXP10_SCL")
	)
	(segment
		(start 83.393534 -30.949646)
		(end 83.393534 -30.4038)
		(width 0.17145)
		(layer "F.Cu")
		(net "IO_EXP10_SCL")
	)
	(segment
		(start 83.810094 -29.98724)
		(end 83.810094 -29.3878)
		(width 0.17145)
		(layer "F.Cu")
		(net "IO_EXP10_SCL")
	)
	(segment
		(start 83.810094 -29.3878)
		(end 83.810094 -27.86761)
		(width 0.17145)
		(layer "F.Cu")
		(net "IO_EXP10_SCL")
	)
	(via
		(at 83.810094 -29.3878)
		(size 0.6604)
		(drill 0.3302)
		(layers "F.Cu" "B.Cu")
		(net "IO_EXP10_SCL")
	)
	(segment
		(start 83.700366 -17.35963)
		(end 83.700366 -18.50263)
		(width 0.17145)
		(layer "F.Cu")
		(net "IO_EXP10_A2")
	)
	(segment
		(start 83.700366 -18.50263)
		(end 83.700366 -19.6342)
		(width 0.17145)
		(layer "F.Cu")
		(net "IO_EXP10_A2")
	)
	(segment
		(start 83.700366 -20.327366)
		(end 83.810094 -20.437094)
		(width 0.17145)
		(layer "F.Cu")
		(net "IO_EXP10_A2")
	)
	(segment
		(start 83.810094 -20.437094)
		(end 83.810094 -22.22881)
		(width 0.17145)
		(layer "F.Cu")
		(net "IO_EXP10_A2")
	)
	(segment
		(start 83.700366 -19.6342)
		(end 83.700366 -20.327366)
		(width 0.17145)
		(layer "F.Cu")
		(net "IO_EXP10_A2")
	)
	(via
		(at 83.700366 -19.6342)
		(size 0.6604)
		(drill 0.3302)
		(layers "F.Cu" "B.Cu")
		(net "IO_EXP10_A2")
	)
	(segment
		(start 81.069434 -18.50517)
		(end 81.069434 -18.737834)
		(width 0.17145)
		(layer "F.Cu")
		(net "IO_EXP10_A1")
	)
	(segment
		(start 82.03311 -19.70151)
		(end 83.159854 -20.828254)
		(width 0.17145)
		(layer "F.Cu")
		(net "IO_EXP10_A1")
	)
	(segment
		(start 81.069434 -18.737834)
		(end 82.03311 -19.70151)
		(width 0.17145)
		(layer "F.Cu")
		(net "IO_EXP10_A1")
	)
	(segment
		(start 81.07807 -18.496534)
		(end 81.069434 -18.50517)
		(width 0.17145)
		(layer "F.Cu")
		(net "IO_EXP10_A1")
	)
	(segment
		(start 83.159854 -20.828254)
		(end 83.159854 -22.22881)
		(width 0.17145)
		(layer "F.Cu")
		(net "IO_EXP10_A1")
	)
	(segment
		(start 81.07807 -17.368266)
		(end 81.07807 -18.496534)
		(width 0.17145)
		(layer "F.Cu")
		(net "IO_EXP10_A1")
	)
	(via
		(at 82.03311 -19.70151)
		(size 0.6604)
		(drill 0.3302)
		(layers "F.Cu" "B.Cu")
		(net "IO_EXP10_A1")
	)
	(segment
		(start 84.770214 -29.26588)
		(end 84.460334 -28.956)
		(width 0.17145)
		(layer "F.Cu")
		(net "IO_EXP10_A0")
	)
	(segment
		(start 85.781134 -30.96387)
		(end 84.587334 -30.96387)
		(width 0.17145)
		(layer "F.Cu")
		(net "IO_EXP10_A0")
	)
	(segment
		(start 84.587334 -30.353)
		(end 84.770214 -30.17012)
		(width 0.17145)
		(layer "F.Cu")
		(net "IO_EXP10_A0")
	)
	(segment
		(start 84.460334 -28.956)
		(end 84.460334 -27.86761)
		(width 0.17145)
		(layer "F.Cu")
		(net "IO_EXP10_A0")
	)
	(segment
		(start 84.587334 -30.96387)
		(end 84.587334 -30.353)
		(width 0.17145)
		(layer "F.Cu")
		(net "IO_EXP10_A0")
	)
	(segment
		(start 84.770214 -29.852874)
		(end 84.770214 -29.26588)
		(width 0.17145)
		(layer "F.Cu")
		(net "IO_EXP10_A0")
	)
	(segment
		(start 84.770214 -30.17012)
		(end 84.770214 -29.852874)
		(width 0.17145)
		(layer "F.Cu")
		(net "IO_EXP10_A0")
	)
	(via
		(at 84.770214 -29.852874)
		(size 0.6604)
		(drill 0.3302)
		(layers "F.Cu" "B.Cu")
		(net "IO_EXP10_A0")
	)
	(segment
		(start 272.64868 -274.65528)
		(end 271.74698 -273.75358)
		(width 0.17145)
		(layer "F.Cu")
		(net "IO_EXP1_HDD_FAULT_INT_N")
	)
	(segment
		(start 271.526 -273.5326)
		(end 271.74698 -273.75358)
		(width 0.17145)
		(layer "F.Cu")
		(net "IO_EXP1_HDD_FAULT_INT_N")
	)
	(segment
		(start 272.64868 -275.5646)
		(end 272.64868 -274.65528)
		(width 0.17145)
		(layer "F.Cu")
		(net "IO_EXP1_HDD_FAULT_INT_N")
	)
	(segment
		(start 271.526 -272.7325)
		(end 271.526 -273.5326)
		(width 0.17145)
		(layer "F.Cu")
		(net "IO_EXP1_HDD_FAULT_INT_N")
	)
	(via
		(at 271.74698 -273.75358)
		(size 0.6604)
		(drill 0.3302)
		(layers "F.Cu" "B.Cu")
		(net "IO_EXP1_HDD_FAULT_INT_N")
	)
	(segment
		(start 260.58368 -274.12188)
		(end 260.223 -273.7612)
		(width 0.17145)
		(layer "F.Cu")
		(net "IO_EXP0_INT_N")
	)
	(segment
		(start 259.969 -273.5072)
		(end 260.223 -273.7612)
		(width 0.17145)
		(layer "F.Cu")
		(net "IO_EXP0_INT_N")
	)
	(segment
		(start 260.58368 -275.3106)
		(end 260.58368 -274.12188)
		(width 0.17145)
		(layer "F.Cu")
		(net "IO_EXP0_INT_N")
	)
	(segment
		(start 259.969 -272.7325)
		(end 259.969 -273.5072)
		(width 0.17145)
		(layer "F.Cu")
		(net "IO_EXP0_INT_N")
	)
	(via
		(at 260.223 -273.7612)
		(size 0.6604)
		(drill 0.3302)
		(layers "F.Cu" "B.Cu")
		(net "IO_EXP0_INT_N")
	)
	(segment
		(start 35.416998 -295.064942)
		(end 35.353498 -295.001442)
		(width 0.17145)
		(layer "F.Cu")
		(net "HDD_PRSNT_0")
	)
	(segment
		(start 35.353498 -291.127942)
		(end 35.310572 -291.085016)
		(width 0.17145)
		(layer "F.Cu")
		(net "HDD_PRSNT_0")
	)
	(segment
		(start 35.353498 -293.540942)
		(end 35.353498 -292.169342)
		(width 0.17145)
		(layer "F.Cu")
		(net "HDD_PRSNT_0")
	)
	(segment
		(start 35.310572 -291.085016)
		(end 30.025086 -291.085016)
		(width 0.17145)
		(layer "F.Cu")
		(net "HDD_PRSNT_0")
	)
	(segment
		(start 35.353498 -292.169342)
		(end 35.353498 -291.127942)
		(width 0.17145)
		(layer "F.Cu")
		(net "HDD_PRSNT_0")
	)
	(segment
		(start 35.353498 -295.001442)
		(end 35.353498 -293.540942)
		(width 0.17145)
		(layer "F.Cu")
		(net "HDD_PRSNT_0")
	)
	(via
		(at 35.353498 -293.540942)
		(size 0.6604)
		(drill 0.3302)
		(layers "F.Cu" "B.Cu")
		(net "HDD_PRSNT_0")
	)
	(segment
		(start 17.145 -241.49177)
		(end 17.299686 -241.337084)
		(width 0.17145)
		(layer "F.Cu")
		(net "FLT_HDD0")
	)
	(segment
		(start 17.299686 -241.337084)
		(end 17.299686 -236.9566)
		(width 0.17145)
		(layer "F.Cu")
		(net "FLT_HDD0")
	)
	(segment
		(start 17.299686 -210.130136)
		(end 17.299686 -236.9566)
		(width 0.17145)
		(layer "F.Cu")
		(net "FLT_HDD0")
	)
	(via
		(at 17.299686 -236.9566)
		(size 0.6604)
		(drill 0.3302)
		(layers "F.Cu" "B.Cu")
		(net "FLT_HDD0")
	)
	(segment
		(start 85.110574 -23.995634)
		(end 85.076538 -24.02967)
		(width 0.17145)
		(layer "F.Cu")
		(net "FAN_0_INS_N")
	)
	(segment
		(start 85.110574 -22.22881)
		(end 85.110574 -23.995634)
		(width 0.17145)
		(layer "F.Cu")
		(net "FAN_0_INS_N")
	)
	(segment
		(start 338.653374 -24.41829)
		(end 338.653374 -22.993604)
		(width 0.17145)
		(layer "F.Cu")
		(net "FAN_0_INS_N")
	)
	(segment
		(start 259.896356 -257.79476)
		(end 259.896356 -255.81356)
		(width 0.17145)
		(layer "F.Cu")
		(net "FAN_0_INS_N")
	)
	(segment
		(start 338.653374 -22.993604)
		(end 338.653374 -21.623782)
		(width 0.17145)
		(layer "F.Cu")
		(net "FAN_0_INS_N")
	)
	(via
		(at 338.653374 -21.623782)
		(size 0.5588)
		(drill 0.3048)
		(layers "F.Cu" "B.Cu")
		(net "FAN_0_INS_N")
	)
	(via
		(at 85.076538 -24.02967)
		(size 0.5588)
		(drill 0.3048)
		(layers "F.Cu" "B.Cu")
		(net "FAN_0_INS_N")
	)
	(via
		(at 321.124326 -249.236992)
		(size 0.5588)
		(drill 0.3048)
		(layers "F.Cu" "B.Cu")
		(net "FAN_0_INS_N")
	)
	(via
		(at 338.653374 -22.993604)
		(size 0.6604)
		(drill 0.3302)
		(layers "F.Cu" "B.Cu")
		(net "FAN_0_INS_N")
	)
	(via
		(at 259.896356 -255.81356)
		(size 0.5588)
		(drill 0.3048)
		(layers "F.Cu" "B.Cu")
		(net "FAN_0_INS_N")
	)
	(segment
		(start 174.883318 -57.507124)
		(end 177.742596 -60.366402)
		(width 0.13335)
		(layer "In2.Cu")
		(net "FAN_0_INS_N")
	)
	(segment
		(start 320.365882 -248.478548)
		(end 317.812674 -248.478548)
		(width 0.13335)
		(layer "In2.Cu")
		(net "FAN_0_INS_N")
	)
	(segment
		(start 261.5946 -0.020828)
		(end 286.19196 -0.020828)
		(width 0.13335)
		(layer "In2.Cu")
		(net "FAN_0_INS_N")
	)
	(segment
		(start 294.928036 -8.756904)
		(end 306.939442 -8.756904)
		(width 0.13335)
		(layer "In2.Cu")
		(net "FAN_0_INS_N")
	)
	(segment
		(start 276.45487 -247.549416)
		(end 271.210786 -252.7935)
		(width 0.13335)
		(layer "In2.Cu")
		(net "FAN_0_INS_N")
	)
	(segment
		(start 248.76887 -88.558116)
		(end 248.76887 -12.846558)
		(width 0.13335)
		(layer "In2.Cu")
		(net "FAN_0_INS_N")
	)
	(segment
		(start 159.94126 -40.759126)
		(end 174.883318 -55.701184)
		(width 0.13335)
		(layer "In2.Cu")
		(net "FAN_0_INS_N")
	)
	(segment
		(start 333.62392 -20.75815)
		(end 334.663288 -21.797518)
		(width 0.13335)
		(layer "In2.Cu")
		(net "FAN_0_INS_N")
	)
	(segment
		(start 174.883318 -55.701184)
		(end 174.883318 -57.507124)
		(width 0.13335)
		(layer "In2.Cu")
		(net "FAN_0_INS_N")
	)
	(segment
		(start 248.76887 -12.846558)
		(end 261.5946 -0.020828)
		(width 0.13335)
		(layer "In2.Cu")
		(net "FAN_0_INS_N")
	)
	(segment
		(start 177.742596 -76.072492)
		(end 189.09411 -87.424006)
		(width 0.13335)
		(layer "In2.Cu")
		(net "FAN_0_INS_N")
	)
	(segment
		(start 86.850728 -23.62962)
		(end 88.097868 -24.87676)
		(width 0.13335)
		(layer "In2.Cu")
		(net "FAN_0_INS_N")
	)
	(segment
		(start 306.939442 -8.756904)
		(end 310.10225 -11.919712)
		(width 0.13335)
		(layer "In2.Cu")
		(net "FAN_0_INS_N")
	)
	(segment
		(start 284.481016 -247.549416)
		(end 276.45487 -247.549416)
		(width 0.13335)
		(layer "In2.Cu")
		(net "FAN_0_INS_N")
	)
	(segment
		(start 312.082688 -20.75815)
		(end 333.62392 -20.75815)
		(width 0.13335)
		(layer "In2.Cu")
		(net "FAN_0_INS_N")
	)
	(segment
		(start 189.09411 -87.424006)
		(end 229.821486 -87.424006)
		(width 0.13335)
		(layer "In2.Cu")
		(net "FAN_0_INS_N")
	)
	(segment
		(start 85.076538 -24.02967)
		(end 85.476588 -23.62962)
		(width 0.13335)
		(layer "In2.Cu")
		(net "FAN_0_INS_N")
	)
	(segment
		(start 321.124326 -249.236992)
		(end 320.365882 -248.478548)
		(width 0.13335)
		(layer "In2.Cu")
		(net "FAN_0_INS_N")
	)
	(segment
		(start 233.827574 -91.430094)
		(end 245.896892 -91.430094)
		(width 0.13335)
		(layer "In2.Cu")
		(net "FAN_0_INS_N")
	)
	(segment
		(start 267.122656 -252.7935)
		(end 264.51814 -255.398016)
		(width 0.13335)
		(layer "In2.Cu")
		(net "FAN_0_INS_N")
	)
	(segment
		(start 334.663288 -21.797518)
		(end 338.479638 -21.797518)
		(width 0.13335)
		(layer "In2.Cu")
		(net "FAN_0_INS_N")
	)
	(segment
		(start 229.821486 -87.424006)
		(end 233.827574 -91.430094)
		(width 0.13335)
		(layer "In2.Cu")
		(net "FAN_0_INS_N")
	)
	(segment
		(start 286.19196 -0.020828)
		(end 294.928036 -8.756904)
		(width 0.13335)
		(layer "In2.Cu")
		(net "FAN_0_INS_N")
	)
	(segment
		(start 296.964862 -235.06557)
		(end 284.481016 -247.549416)
		(width 0.13335)
		(layer "In2.Cu")
		(net "FAN_0_INS_N")
	)
	(segment
		(start 177.742596 -60.366402)
		(end 177.742596 -76.072492)
		(width 0.13335)
		(layer "In2.Cu")
		(net "FAN_0_INS_N")
	)
	(segment
		(start 264.51814 -255.398016)
		(end 260.3119 -255.398016)
		(width 0.13335)
		(layer "In2.Cu")
		(net "FAN_0_INS_N")
	)
	(segment
		(start 85.476588 -23.62962)
		(end 86.850728 -23.62962)
		(width 0.13335)
		(layer "In2.Cu")
		(net "FAN_0_INS_N")
	)
	(segment
		(start 338.479638 -21.797518)
		(end 338.653374 -21.623782)
		(width 0.13335)
		(layer "In2.Cu")
		(net "FAN_0_INS_N")
	)
	(segment
		(start 310.10225 -18.777712)
		(end 312.082688 -20.75815)
		(width 0.13335)
		(layer "In2.Cu")
		(net "FAN_0_INS_N")
	)
	(segment
		(start 317.812674 -248.478548)
		(end 304.399696 -235.06557)
		(width 0.13335)
		(layer "In2.Cu")
		(net "FAN_0_INS_N")
	)
	(segment
		(start 88.097868 -24.87676)
		(end 89.758774 -24.87676)
		(width 0.13335)
		(layer "In2.Cu")
		(net "FAN_0_INS_N")
	)
	(segment
		(start 260.3119 -255.398016)
		(end 259.896356 -255.81356)
		(width 0.13335)
		(layer "In2.Cu")
		(net "FAN_0_INS_N")
	)
	(segment
		(start 271.210786 -252.7935)
		(end 267.122656 -252.7935)
		(width 0.13335)
		(layer "In2.Cu")
		(net "FAN_0_INS_N")
	)
	(segment
		(start 105.64114 -40.759126)
		(end 159.94126 -40.759126)
		(width 0.13335)
		(layer "In2.Cu")
		(net "FAN_0_INS_N")
	)
	(segment
		(start 310.10225 -11.919712)
		(end 310.10225 -18.777712)
		(width 0.13335)
		(layer "In2.Cu")
		(net "FAN_0_INS_N")
	)
	(segment
		(start 245.896892 -91.430094)
		(end 248.76887 -88.558116)
		(width 0.13335)
		(layer "In2.Cu")
		(net "FAN_0_INS_N")
	)
	(segment
		(start 89.758774 -24.87676)
		(end 105.64114 -40.759126)
		(width 0.13335)
		(layer "In2.Cu")
		(net "FAN_0_INS_N")
	)
	(segment
		(start 304.399696 -235.06557)
		(end 296.964862 -235.06557)
		(width 0.13335)
		(layer "In2.Cu")
		(net "FAN_0_INS_N")
	)
	(segment
		(start 335.030826 -43.264836)
		(end 330.5302 -47.765462)
		(width 0.12065)
		(layer "In4.Cu")
		(net "FAN_0_INS_N")
	)
	(segment
		(start 336.929984 -32.73298)
		(end 335.030826 -34.632138)
		(width 0.12065)
		(layer "In4.Cu")
		(net "FAN_0_INS_N")
	)
	(segment
		(start 336.929984 -25.718008)
		(end 336.929984 -32.73298)
		(width 0.12065)
		(layer "In4.Cu")
		(net "FAN_0_INS_N")
	)
	(segment
		(start 335.030826 -34.632138)
		(end 335.030826 -43.264836)
		(width 0.12065)
		(layer "In4.Cu")
		(net "FAN_0_INS_N")
	)
	(segment
		(start 338.653374 -21.623782)
		(end 338.653374 -23.994618)
		(width 0.12065)
		(layer "In4.Cu")
		(net "FAN_0_INS_N")
	)
	(segment
		(start 319.522348 -146.645122)
		(end 317.560198 -148.607272)
		(width 0.12065)
		(layer "In4.Cu")
		(net "FAN_0_INS_N")
	)
	(segment
		(start 318.242696 -221.165928)
		(end 321.124326 -224.047558)
		(width 0.12065)
		(layer "In4.Cu")
		(net "FAN_0_INS_N")
	)
	(segment
		(start 318.242696 -176.480216)
		(end 318.242696 -221.165928)
		(width 0.12065)
		(layer "In4.Cu")
		(net "FAN_0_INS_N")
	)
	(segment
		(start 317.560198 -175.797718)
		(end 318.242696 -176.480216)
		(width 0.12065)
		(layer "In4.Cu")
		(net "FAN_0_INS_N")
	)
	(segment
		(start 327.3679 -69.366384)
		(end 319.522348 -77.211936)
		(width 0.12065)
		(layer "In4.Cu")
		(net "FAN_0_INS_N")
	)
	(segment
		(start 319.522348 -77.211936)
		(end 319.522348 -146.645122)
		(width 0.12065)
		(layer "In4.Cu")
		(net "FAN_0_INS_N")
	)
	(segment
		(start 330.5302 -47.765462)
		(end 330.5302 -64.301116)
		(width 0.12065)
		(layer "In4.Cu")
		(net "FAN_0_INS_N")
	)
	(segment
		(start 330.5302 -64.301116)
		(end 327.3679 -67.463416)
		(width 0.12065)
		(layer "In4.Cu")
		(net "FAN_0_INS_N")
	)
	(segment
		(start 327.3679 -67.463416)
		(end 327.3679 -69.366384)
		(width 0.12065)
		(layer "In4.Cu")
		(net "FAN_0_INS_N")
	)
	(segment
		(start 321.124326 -224.047558)
		(end 321.124326 -249.236992)
		(width 0.12065)
		(layer "In4.Cu")
		(net "FAN_0_INS_N")
	)
	(segment
		(start 338.653374 -23.994618)
		(end 336.929984 -25.718008)
		(width 0.12065)
		(layer "In4.Cu")
		(net "FAN_0_INS_N")
	)
	(segment
		(start 317.560198 -148.607272)
		(end 317.560198 -175.797718)
		(width 0.12065)
		(layer "In4.Cu")
		(net "FAN_0_INS_N")
	)
	(segment
		(start 228.298248 -333.498952)
		(end 238.6076 -323.1896)
		(width 0.13335)
		(layer "In9.Cu")
		(net "FAN_0_INS_N")
	)
	(segment
		(start 222.684086 -377.150884)
		(end 222.684086 -369.95481)
		(width 0.13335)
		(layer "In9.Cu")
		(net "FAN_0_INS_N")
	)
	(segment
		(start 224.5614 -418.498274)
		(end 224.5614 -401.464526)
		(width 0.13335)
		(layer "In9.Cu")
		(net "FAN_0_INS_N")
	)
	(segment
		(start 224.5614 -401.464526)
		(end 221.55785 -398.460976)
		(width 0.13335)
		(layer "In9.Cu")
		(net "FAN_0_INS_N")
	)
	(segment
		(start 251.983494 -266.6238)
		(end 251.983494 -266.623546)
		(width 0.13335)
		(layer "In9.Cu")
		(net "FAN_0_INS_N")
	)
	(segment
		(start 251.9172 -266.956032)
		(end 251.9172 -266.690094)
		(width 0.13335)
		(layer "In9.Cu")
		(net "FAN_0_INS_N")
	)
	(segment
		(start 253.710694 -257.297936)
		(end 255.992122 -255.016508)
		(width 0.13335)
		(layer "In9.Cu")
		(net "FAN_0_INS_N")
	)
	(segment
		(start 227.167186 -419.605206)
		(end 226.886262 -419.88613)
		(width 0.13335)
		(layer "In9.Cu")
		(net "FAN_0_INS_N")
	)
	(segment
		(start 251.9172 -266.690094)
		(end 251.983494 -266.6238)
		(width 0.13335)
		(layer "In9.Cu")
		(net "FAN_0_INS_N")
	)
	(segment
		(start 252.481842 -266.125452)
		(end 253.710694 -264.8966)
		(width 0.13335)
		(layer "In9.Cu")
		(net "FAN_0_INS_N")
	)
	(segment
		(start 251.865892 -267.00734)
		(end 251.9172 -266.956032)
		(width 0.13335)
		(layer "In9.Cu")
		(net "FAN_0_INS_N")
	)
	(segment
		(start 238.6076 -295.514268)
		(end 251.865892 -282.255976)
		(width 0.13335)
		(layer "In9.Cu")
		(net "FAN_0_INS_N")
	)
	(segment
		(start 227.167186 -419.032944)
		(end 227.167186 -419.605206)
		(width 0.13335)
		(layer "In9.Cu")
		(net "FAN_0_INS_N")
	)
	(segment
		(start 251.865892 -282.255976)
		(end 251.865892 -267.00734)
		(width 0.13335)
		(layer "In9.Cu")
		(net "FAN_0_INS_N")
	)
	(segment
		(start 221.55785 -398.460976)
		(end 221.55785 -378.27712)
		(width 0.13335)
		(layer "In9.Cu")
		(net "FAN_0_INS_N")
	)
	(segment
		(start 222.684086 -369.95481)
		(end 228.298248 -364.340648)
		(width 0.13335)
		(layer "In9.Cu")
		(net "FAN_0_INS_N")
	)
	(segment
		(start 258.140708 -255.016508)
		(end 258.93776 -255.81356)
		(width 0.13335)
		(layer "In9.Cu")
		(net "FAN_0_INS_N")
	)
	(segment
		(start 228.000052 -418.200078)
		(end 227.167186 -419.032944)
		(width 0.13335)
		(layer "In9.Cu")
		(net "FAN_0_INS_N")
	)
	(segment
		(start 226.886262 -419.88613)
		(end 225.949256 -419.88613)
		(width 0.13335)
		(layer "In9.Cu")
		(net "FAN_0_INS_N")
	)
	(segment
		(start 252.481588 -266.125452)
		(end 252.481842 -266.125452)
		(width 0.13335)
		(layer "In9.Cu")
		(net "FAN_0_INS_N")
	)
	(segment
		(start 253.710694 -264.8966)
		(end 253.710694 -257.297936)
		(width 0.13335)
		(layer "In9.Cu")
		(net "FAN_0_INS_N")
	)
	(segment
		(start 258.93776 -255.81356)
		(end 259.896356 -255.81356)
		(width 0.13335)
		(layer "In9.Cu")
		(net "FAN_0_INS_N")
	)
	(segment
		(start 228.298248 -364.340648)
		(end 228.298248 -333.498952)
		(width 0.13335)
		(layer "In9.Cu")
		(net "FAN_0_INS_N")
	)
	(segment
		(start 255.992122 -255.016508)
		(end 258.140708 -255.016508)
		(width 0.13335)
		(layer "In9.Cu")
		(net "FAN_0_INS_N")
	)
	(segment
		(start 221.55785 -378.27712)
		(end 222.684086 -377.150884)
		(width 0.13335)
		(layer "In9.Cu")
		(net "FAN_0_INS_N")
	)
	(segment
		(start 251.983494 -266.623546)
		(end 252.481588 -266.125452)
		(width 0.13335)
		(layer "In9.Cu")
		(net "FAN_0_INS_N")
	)
	(segment
		(start 238.6076 -323.1896)
		(end 238.6076 -295.514268)
		(width 0.13335)
		(layer "In9.Cu")
		(net "FAN_0_INS_N")
	)
	(segment
		(start 225.949256 -419.88613)
		(end 224.5614 -418.498274)
		(width 0.13335)
		(layer "In9.Cu")
		(net "FAN_0_INS_N")
	)
	(segment
		(start 18.415 -241.49177)
		(end 18.300446 -241.377216)
		(width 0.17145)
		(layer "F.Cu")
		(net "DRV_ACT_0")
	)
	(segment
		(start 18.300446 -241.377216)
		(end 18.300446 -234.4674)
		(width 0.17145)
		(layer "F.Cu")
		(net "DRV_ACT_0")
	)
	(segment
		(start 18.300446 -210.130136)
		(end 18.300446 -234.4674)
		(width 0.17145)
		(layer "F.Cu")
		(net "DRV_ACT_0")
	)
	(via
		(at 18.300446 -234.4674)
		(size 0.6604)
		(drill 0.3302)
		(layers "F.Cu" "B.Cu")
		(net "DRV_ACT_0")
	)
	(segment
		(start 237.937802 -261.133082)
		(end 237.915196 -261.155688)
		(width 0.17145)
		(layer "F.Cu")
		(net "DRIVE_INSERT_ALERT_A_N")
	)
	(segment
		(start 238.795814 -246.647716)
		(end 239.932718 -247.78462)
		(width 0.17145)
		(layer "F.Cu")
		(net "DRIVE_INSERT_ALERT_A_N")
	)
	(segment
		(start 237.915196 -262.22706)
		(end 237.915196 -262.998204)
		(width 0.17145)
		(layer "F.Cu")
		(net "DRIVE_INSERT_ALERT_A_N")
	)
	(segment
		(start 240.284 -248.7295)
		(end 240.284 -248.135902)
		(width 0.17145)
		(layer "F.Cu")
		(net "DRIVE_INSERT_ALERT_A_N")
	)
	(segment
		(start 237.915196 -261.155688)
		(end 237.915196 -262.22706)
		(width 0.17145)
		(layer "F.Cu")
		(net "DRIVE_INSERT_ALERT_A_N")
	)
	(segment
		(start 240.284 -248.135902)
		(end 239.932718 -247.78462)
		(width 0.17145)
		(layer "F.Cu")
		(net "DRIVE_INSERT_ALERT_A_N")
	)
	(segment
		(start 252.271276 -248.43486)
		(end 251.261626 -248.43486)
		(width 0.17145)
		(layer "F.Cu")
		(net "DRIVE_INSERT_ALERT_A_N")
	)
	(segment
		(start 251.261626 -248.43486)
		(end 250.884436 -248.81205)
		(width 0.17145)
		(layer "F.Cu")
		(net "DRIVE_INSERT_ALERT_A_N")
	)
	(segment
		(start 237.915196 -262.998204)
		(end 237.840012 -263.073388)
		(width 0.17145)
		(layer "F.Cu")
		(net "DRIVE_INSERT_ALERT_A_N")
	)
	(segment
		(start 237.648242 -246.647716)
		(end 238.795814 -246.647716)
		(width 0.17145)
		(layer "F.Cu")
		(net "DRIVE_INSERT_ALERT_A_N")
	)
	(via
		(at 250.884436 -248.81205)
		(size 0.5588)
		(drill 0.3048)
		(layers "F.Cu" "B.Cu")
		(net "DRIVE_INSERT_ALERT_A_N")
	)
	(via
		(at 239.932718 -247.78462)
		(size 0.6604)
		(drill 0.3302)
		(layers "F.Cu" "B.Cu")
		(net "DRIVE_INSERT_ALERT_A_N")
	)
	(via
		(at 237.840012 -263.073388)
		(size 0.5588)
		(drill 0.3048)
		(layers "F.Cu" "B.Cu")
		(net "DRIVE_INSERT_ALERT_A_N")
	)
	(via
		(at 237.648242 -246.647716)
		(size 0.5588)
		(drill 0.3048)
		(layers "F.Cu" "B.Cu")
		(net "DRIVE_INSERT_ALERT_A_N")
	)
	(segment
		(start 247.893332 -263.574276)
		(end 247.893332 -253.052072)
		(width 0.12065)
		(layer "In4.Cu")
		(net "DRIVE_INSERT_ALERT_A_N")
	)
	(segment
		(start 250.884436 -250.060968)
		(end 250.884436 -248.81205)
		(width 0.12065)
		(layer "In4.Cu")
		(net "DRIVE_INSERT_ALERT_A_N")
	)
	(segment
		(start 283.39288 -338.8614)
		(end 271.286478 -338.8614)
		(width 0.12065)
		(layer "In4.Cu")
		(net "DRIVE_INSERT_ALERT_A_N")
	)
	(segment
		(start 284.236668 -339.705188)
		(end 283.39288 -338.8614)
		(width 0.12065)
		(layer "In4.Cu")
		(net "DRIVE_INSERT_ALERT_A_N")
	)
	(segment
		(start 271.286478 -338.8614)
		(end 250.75007 -318.324992)
		(width 0.12065)
		(layer "In4.Cu")
		(net "DRIVE_INSERT_ALERT_A_N")
	)
	(segment
		(start 253.393448 -284.116272)
		(end 253.393448 -269.074392)
		(width 0.12065)
		(layer "In4.Cu")
		(net "DRIVE_INSERT_ALERT_A_N")
	)
	(segment
		(start 250.75007 -318.324992)
		(end 250.75007 -286.75965)
		(width 0.12065)
		(layer "In4.Cu")
		(net "DRIVE_INSERT_ALERT_A_N")
	)
	(segment
		(start 247.893332 -253.052072)
		(end 250.884436 -250.060968)
		(width 0.12065)
		(layer "In4.Cu")
		(net "DRIVE_INSERT_ALERT_A_N")
	)
	(segment
		(start 253.393448 -269.074392)
		(end 247.893332 -263.574276)
		(width 0.12065)
		(layer "In4.Cu")
		(net "DRIVE_INSERT_ALERT_A_N")
	)
	(segment
		(start 250.75007 -286.75965)
		(end 253.393448 -284.116272)
		(width 0.12065)
		(layer "In4.Cu")
		(net "DRIVE_INSERT_ALERT_A_N")
	)
	(segment
		(start 240.2967 -258.85902)
		(end 237.840012 -261.315708)
		(width 0.12065)
		(layer "In7.Cu")
		(net "DRIVE_INSERT_ALERT_A_N")
	)
	(segment
		(start 250.621038 -248.548652)
		(end 240.890552 -248.548652)
		(width 0.12065)
		(layer "In7.Cu")
		(net "DRIVE_INSERT_ALERT_A_N")
	)
	(segment
		(start 250.884436 -248.81205)
		(end 250.621038 -248.548652)
		(width 0.12065)
		(layer "In7.Cu")
		(net "DRIVE_INSERT_ALERT_A_N")
	)
	(segment
		(start 238.989616 -246.647716)
		(end 237.648242 -246.647716)
		(width 0.12065)
		(layer "In7.Cu")
		(net "DRIVE_INSERT_ALERT_A_N")
	)
	(segment
		(start 236.6772 -246.820944)
		(end 236.6772 -248.3358)
		(width 0.12065)
		(layer "In7.Cu")
		(net "DRIVE_INSERT_ALERT_A_N")
	)
	(segment
		(start 240.2967 -257.42646)
		(end 240.2967 -258.85902)
		(width 0.12065)
		(layer "In7.Cu")
		(net "DRIVE_INSERT_ALERT_A_N")
	)
	(segment
		(start 237.648242 -246.647716)
		(end 236.850428 -246.647716)
		(width 0.12065)
		(layer "In7.Cu")
		(net "DRIVE_INSERT_ALERT_A_N")
	)
	(segment
		(start 239.7506 -256.88036)
		(end 240.2967 -257.42646)
		(width 0.12065)
		(layer "In7.Cu")
		(net "DRIVE_INSERT_ALERT_A_N")
	)
	(segment
		(start 236.850428 -246.647716)
		(end 236.6772 -246.820944)
		(width 0.12065)
		(layer "In7.Cu")
		(net "DRIVE_INSERT_ALERT_A_N")
	)
	(segment
		(start 236.6772 -248.3358)
		(end 239.7506 -251.4092)
		(width 0.12065)
		(layer "In7.Cu")
		(net "DRIVE_INSERT_ALERT_A_N")
	)
	(segment
		(start 237.840012 -261.315708)
		(end 237.840012 -263.073388)
		(width 0.12065)
		(layer "In7.Cu")
		(net "DRIVE_INSERT_ALERT_A_N")
	)
	(segment
		(start 240.890552 -248.548652)
		(end 238.989616 -246.647716)
		(width 0.12065)
		(layer "In7.Cu")
		(net "DRIVE_INSERT_ALERT_A_N")
	)
	(segment
		(start 239.7506 -251.4092)
		(end 239.7506 -256.88036)
		(width 0.12065)
		(layer "In7.Cu")
		(net "DRIVE_INSERT_ALERT_A_N")
	)
	(segment
		(start 227.904294 -373.954294)
		(end 227.904294 -375.331482)
		(width 0.17145)
		(layer "F.Cu")
		(net "DRIVE_B_35_FLT_LED")
	)
	(segment
		(start 227.904294 -375.331482)
		(end 228.188012 -375.6152)
		(width 0.17145)
		(layer "F.Cu")
		(net "DRIVE_B_35_FLT_LED")
	)
	(segment
		(start 230.769668 -376.206258)
		(end 228.77907 -376.206258)
		(width 0.17145)
		(layer "F.Cu")
		(net "DRIVE_B_35_FLT_LED")
	)
	(segment
		(start 467.40445 -292.519862)
		(end 467.50859 -292.519862)
		(width 0.17145)
		(layer "F.Cu")
		(net "DRIVE_B_35_FLT_LED")
	)
	(segment
		(start 468.622126 -292.519862)
		(end 469.036908 -292.934644)
		(width 0.17145)
		(layer "F.Cu")
		(net "DRIVE_B_35_FLT_LED")
	)
	(segment
		(start 466.453474 -291.568886)
		(end 467.40445 -292.519862)
		(width 0.17145)
		(layer "F.Cu")
		(net "DRIVE_B_35_FLT_LED")
	)
	(segment
		(start 467.50859 -292.519862)
		(end 468.622126 -292.519862)
		(width 0.17145)
		(layer "F.Cu")
		(net "DRIVE_B_35_FLT_LED")
	)
	(segment
		(start 228.77907 -376.206258)
		(end 228.188012 -375.6152)
		(width 0.17145)
		(layer "F.Cu")
		(net "DRIVE_B_35_FLT_LED")
	)
	(via
		(at 473.612718 -264.397236)
		(size 0.5588)
		(drill 0.3048)
		(layers "F.Cu" "B.Cu")
		(net "DRIVE_B_35_FLT_LED")
	)
	(via
		(at 228.188012 -375.6152)
		(size 0.6604)
		(drill 0.3302)
		(layers "F.Cu" "B.Cu")
		(net "DRIVE_B_35_FLT_LED")
	)
	(via
		(at 244.602 -298.304458)
		(size 0.5588)
		(drill 0.3048)
		(layers "F.Cu" "B.Cu")
		(net "DRIVE_B_35_FLT_LED")
	)
	(via
		(at 467.50859 -292.519862)
		(size 0.5588)
		(drill 0.3048)
		(layers "F.Cu" "B.Cu")
		(net "DRIVE_B_35_FLT_LED")
	)
	(via
		(at 230.769668 -376.206258)
		(size 0.5588)
		(drill 0.3048)
		(layers "F.Cu" "B.Cu")
		(net "DRIVE_B_35_FLT_LED")
	)
	(segment
		(start 262.018018 -295.073578)
		(end 266.511786 -290.57981)
		(width 0.13335)
		(layer "In2.Cu")
		(net "DRIVE_B_35_FLT_LED")
	)
	(segment
		(start 278.123904 -289.869118)
		(end 285.162752 -282.83027)
		(width 0.13335)
		(layer "In2.Cu")
		(net "DRIVE_B_35_FLT_LED")
	)
	(segment
		(start 266.511786 -290.5252)
		(end 266.996926 -290.04006)
		(width 0.13335)
		(layer "In2.Cu")
		(net "DRIVE_B_35_FLT_LED")
	)
	(segment
		(start 266.511786 -290.57981)
		(end 266.511786 -290.5252)
		(width 0.13335)
		(layer "In2.Cu")
		(net "DRIVE_B_35_FLT_LED")
	)
	(segment
		(start 267.222478 -289.869118)
		(end 278.123904 -289.869118)
		(width 0.13335)
		(layer "In2.Cu")
		(net "DRIVE_B_35_FLT_LED")
	)
	(segment
		(start 252.779022 -295.073578)
		(end 262.018018 -295.073578)
		(width 0.13335)
		(layer "In2.Cu")
		(net "DRIVE_B_35_FLT_LED")
	)
	(segment
		(start 326.77862 -263.490202)
		(end 472.705684 -263.490202)
		(width 0.13335)
		(layer "In2.Cu")
		(net "DRIVE_B_35_FLT_LED")
	)
	(segment
		(start 267.051536 -290.04006)
		(end 267.222478 -289.869118)
		(width 0.13335)
		(layer "In2.Cu")
		(net "DRIVE_B_35_FLT_LED")
	)
	(segment
		(start 245.605046 -298.048426)
		(end 249.804174 -298.048426)
		(width 0.13335)
		(layer "In2.Cu")
		(net "DRIVE_B_35_FLT_LED")
	)
	(segment
		(start 244.602 -298.304458)
		(end 245.349014 -298.304458)
		(width 0.13335)
		(layer "In2.Cu")
		(net "DRIVE_B_35_FLT_LED")
	)
	(segment
		(start 472.705684 -263.490202)
		(end 473.612718 -264.397236)
		(width 0.13335)
		(layer "In2.Cu")
		(net "DRIVE_B_35_FLT_LED")
	)
	(segment
		(start 285.162752 -282.83027)
		(end 307.438552 -282.83027)
		(width 0.13335)
		(layer "In2.Cu")
		(net "DRIVE_B_35_FLT_LED")
	)
	(segment
		(start 249.804174 -298.048426)
		(end 252.779022 -295.073578)
		(width 0.13335)
		(layer "In2.Cu")
		(net "DRIVE_B_35_FLT_LED")
	)
	(segment
		(start 266.996926 -290.04006)
		(end 267.051536 -290.04006)
		(width 0.13335)
		(layer "In2.Cu")
		(net "DRIVE_B_35_FLT_LED")
	)
	(segment
		(start 307.438552 -282.83027)
		(end 326.77862 -263.490202)
		(width 0.13335)
		(layer "In2.Cu")
		(net "DRIVE_B_35_FLT_LED")
	)
	(segment
		(start 245.349014 -298.304458)
		(end 245.605046 -298.048426)
		(width 0.13335)
		(layer "In2.Cu")
		(net "DRIVE_B_35_FLT_LED")
	)
	(segment
		(start 473.612718 -273.111976)
		(end 474.599 -274.098258)
		(width 0.12065)
		(layer "In4.Cu")
		(net "DRIVE_B_35_FLT_LED")
	)
	(segment
		(start 244.092984 -298.304458)
		(end 233.954574 -308.442868)
		(width 0.12065)
		(layer "In4.Cu")
		(net "DRIVE_B_35_FLT_LED")
	)
	(segment
		(start 244.602 -298.304458)
		(end 244.092984 -298.304458)
		(width 0.12065)
		(layer "In4.Cu")
		(net "DRIVE_B_35_FLT_LED")
	)
	(segment
		(start 474.599 -274.098258)
		(end 474.599 -281.94)
		(width 0.12065)
		(layer "In4.Cu")
		(net "DRIVE_B_35_FLT_LED")
	)
	(segment
		(start 233.954574 -353.420934)
		(end 234.812078 -354.278438)
		(width 0.12065)
		(layer "In4.Cu")
		(net "DRIVE_B_35_FLT_LED")
	)
	(segment
		(start 233.954574 -308.442868)
		(end 233.954574 -353.420934)
		(width 0.12065)
		(layer "In4.Cu")
		(net "DRIVE_B_35_FLT_LED")
	)
	(segment
		(start 234.812078 -372.163848)
		(end 230.769668 -376.206258)
		(width 0.12065)
		(layer "In4.Cu")
		(net "DRIVE_B_35_FLT_LED")
	)
	(segment
		(start 474.599 -281.94)
		(end 467.50859 -289.03041)
		(width 0.12065)
		(layer "In4.Cu")
		(net "DRIVE_B_35_FLT_LED")
	)
	(segment
		(start 234.812078 -354.278438)
		(end 234.812078 -372.163848)
		(width 0.12065)
		(layer "In4.Cu")
		(net "DRIVE_B_35_FLT_LED")
	)
	(segment
		(start 467.50859 -289.03041)
		(end 467.50859 -292.519862)
		(width 0.12065)
		(layer "In4.Cu")
		(net "DRIVE_B_35_FLT_LED")
	)
	(segment
		(start 473.612718 -264.397236)
		(end 473.612718 -273.111976)
		(width 0.12065)
		(layer "In4.Cu")
		(net "DRIVE_B_35_FLT_LED")
	)
	(segment
		(start 467.3346 -288.76498)
		(end 467.3346 -291.559996)
		(width 0.17145)
		(layer "F.Cu")
		(net "DRIVE_B_35_ACT")
	)
	(segment
		(start 472.609418 -292.487604)
		(end 472.609418 -292.940232)
		(width 0.17145)
		(layer "F.Cu")
		(net "DRIVE_B_35_ACT")
	)
	(segment
		(start 467.3346 -291.559996)
		(end 467.773004 -291.9984)
		(width 0.17145)
		(layer "F.Cu")
		(net "DRIVE_B_35_ACT")
	)
	(segment
		(start 472.120214 -291.9984)
		(end 472.609418 -292.487604)
		(width 0.17145)
		(layer "F.Cu")
		(net "DRIVE_B_35_ACT")
	)
	(segment
		(start 466.3948 -287.02)
		(end 466.3948 -287.82518)
		(width 0.17145)
		(layer "F.Cu")
		(net "DRIVE_B_35_ACT")
	)
	(segment
		(start 466.3948 -287.82518)
		(end 467.3346 -288.76498)
		(width 0.17145)
		(layer "F.Cu")
		(net "DRIVE_B_35_ACT")
	)
	(segment
		(start 467.773004 -291.9984)
		(end 472.120214 -291.9984)
		(width 0.17145)
		(layer "F.Cu")
		(net "DRIVE_B_35_ACT")
	)
	(via
		(at 467.868 -341.5538)
		(size 0.5588)
		(drill 0.3048)
		(layers "F.Cu" "B.Cu")
		(net "DRIVE_B_35_ACT")
	)
	(via
		(at 466.3948 -287.02)
		(size 0.5588)
		(drill 0.3048)
		(layers "F.Cu" "B.Cu")
		(net "DRIVE_B_35_ACT")
	)
	(segment
		(start 228.6762 -397.401034)
		(end 228.6762 -402.136864)
		(width 0.13335)
		(layer "In2.Cu")
		(net "DRIVE_B_35_ACT")
	)
	(segment
		(start 225.934524 -393.07135)
		(end 226.459034 -393.59586)
		(width 0.13335)
		(layer "In2.Cu")
		(net "DRIVE_B_35_ACT")
	)
	(segment
		(start 269.770352 -360.150664)
		(end 259.390642 -349.770954)
		(width 0.13335)
		(layer "In2.Cu")
		(net "DRIVE_B_35_ACT")
	)
	(segment
		(start 467.868 -341.5538)
		(end 296.49801 -341.5538)
		(width 0.13335)
		(layer "In2.Cu")
		(net "DRIVE_B_35_ACT")
	)
	(segment
		(start 290.598352 -356.916228)
		(end 287.363916 -360.150664)
		(width 0.13335)
		(layer "In2.Cu")
		(net "DRIVE_B_35_ACT")
	)
	(segment
		(start 259.390642 -349.770954)
		(end 240.067846 -349.770954)
		(width 0.13335)
		(layer "In2.Cu")
		(net "DRIVE_B_35_ACT")
	)
	(segment
		(start 240.067846 -349.770954)
		(end 228.235256 -361.603544)
		(width 0.13335)
		(layer "In2.Cu")
		(net "DRIVE_B_35_ACT")
	)
	(segment
		(start 290.598352 -347.453458)
		(end 290.598352 -356.916228)
		(width 0.13335)
		(layer "In2.Cu")
		(net "DRIVE_B_35_ACT")
	)
	(segment
		(start 225.93427 -393.07135)
		(end 225.934524 -393.07135)
		(width 0.13335)
		(layer "In2.Cu")
		(net "DRIVE_B_35_ACT")
	)
	(segment
		(start 225.68535 -392.82243)
		(end 225.93427 -393.07135)
		(width 0.13335)
		(layer "In2.Cu")
		(net "DRIVE_B_35_ACT")
	)
	(segment
		(start 296.49801 -341.5538)
		(end 290.598352 -347.453458)
		(width 0.13335)
		(layer "In2.Cu")
		(net "DRIVE_B_35_ACT")
	)
	(segment
		(start 287.363916 -360.150664)
		(end 269.770352 -360.150664)
		(width 0.13335)
		(layer "In2.Cu")
		(net "DRIVE_B_35_ACT")
	)
	(segment
		(start 226.459034 -393.59586)
		(end 226.459034 -395.183868)
		(width 0.13335)
		(layer "In2.Cu")
		(net "DRIVE_B_35_ACT")
	)
	(segment
		(start 228.235256 -361.603544)
		(end 228.235256 -380.441454)
		(width 0.13335)
		(layer "In2.Cu")
		(net "DRIVE_B_35_ACT")
	)
	(segment
		(start 228.6762 -402.136864)
		(end 229.80015 -403.260814)
		(width 0.13335)
		(layer "In2.Cu")
		(net "DRIVE_B_35_ACT")
	)
	(segment
		(start 229.80015 -403.260814)
		(end 229.80015 -405.900128)
		(width 0.13335)
		(layer "In2.Cu")
		(net "DRIVE_B_35_ACT")
	)
	(segment
		(start 228.235256 -380.441454)
		(end 225.68535 -382.99136)
		(width 0.13335)
		(layer "In2.Cu")
		(net "DRIVE_B_35_ACT")
	)
	(segment
		(start 225.68535 -382.99136)
		(end 225.68535 -392.82243)
		(width 0.13335)
		(layer "In2.Cu")
		(net "DRIVE_B_35_ACT")
	)
	(segment
		(start 226.459034 -395.183868)
		(end 228.6762 -397.401034)
		(width 0.13335)
		(layer "In2.Cu")
		(net "DRIVE_B_35_ACT")
	)
	(segment
		(start 465.765896 -287.648904)
		(end 465.765896 -293.72814)
		(width 0.12065)
		(layer "In4.Cu")
		(net "DRIVE_B_35_ACT")
	)
	(segment
		(start 465.765896 -293.72814)
		(end 467.868 -295.830244)
		(width 0.12065)
		(layer "In4.Cu")
		(net "DRIVE_B_35_ACT")
	)
	(segment
		(start 466.3948 -287.02)
		(end 465.765896 -287.648904)
		(width 0.12065)
		(layer "In4.Cu")
		(net "DRIVE_B_35_ACT")
	)
	(segment
		(start 467.868 -295.830244)
		(end 467.868 -341.5538)
		(width 0.12065)
		(layer "In4.Cu")
		(net "DRIVE_B_35_ACT")
	)
	(segment
		(start 230.820468 -375.266458)
		(end 228.987858 -375.266458)
		(width 0.17145)
		(layer "F.Cu")
		(net "DRIVE_B_34_FLT_LED")
	)
	(segment
		(start 438.852564 -290.951412)
		(end 440.294014 -290.951412)
		(width 0.17145)
		(layer "F.Cu")
		(net "DRIVE_B_34_FLT_LED")
	)
	(segment
		(start 440.294014 -290.951412)
		(end 440.294014 -290.16198)
		(width 0.17145)
		(layer "F.Cu")
		(net "DRIVE_B_34_FLT_LED")
	)
	(segment
		(start 228.554534 -374.833134)
		(end 228.554534 -373.954294)
		(width 0.17145)
		(layer "F.Cu")
		(net "DRIVE_B_34_FLT_LED")
	)
	(segment
		(start 439.196734 -292.889432)
		(end 438.775602 -292.4683)
		(width 0.17145)
		(layer "F.Cu")
		(net "DRIVE_B_34_FLT_LED")
	)
	(segment
		(start 228.987858 -375.266458)
		(end 228.554534 -374.833134)
		(width 0.17145)
		(layer "F.Cu")
		(net "DRIVE_B_34_FLT_LED")
	)
	(segment
		(start 440.294014 -290.16198)
		(end 440.123072 -289.991038)
		(width 0.17145)
		(layer "F.Cu")
		(net "DRIVE_B_34_FLT_LED")
	)
	(segment
		(start 438.775602 -292.4683)
		(end 438.775602 -291.028374)
		(width 0.17145)
		(layer "F.Cu")
		(net "DRIVE_B_34_FLT_LED")
	)
	(segment
		(start 438.775602 -291.028374)
		(end 438.852564 -290.951412)
		(width 0.17145)
		(layer "F.Cu")
		(net "DRIVE_B_34_FLT_LED")
	)
	(via
		(at 230.820468 -375.266458)
		(size 0.5588)
		(drill 0.3048)
		(layers "F.Cu" "B.Cu")
		(net "DRIVE_B_34_FLT_LED")
	)
	(via
		(at 438.775602 -291.028374)
		(size 0.6604)
		(drill 0.3302)
		(layers "F.Cu" "B.Cu")
		(net "DRIVE_B_34_FLT_LED")
	)
	(via
		(at 243.299234 -297.489626)
		(size 0.5588)
		(drill 0.3048)
		(layers "F.Cu" "B.Cu")
		(net "DRIVE_B_34_FLT_LED")
	)
	(via
		(at 429.709834 -262.931402)
		(size 0.5588)
		(drill 0.3048)
		(layers "F.Cu" "B.Cu")
		(net "DRIVE_B_34_FLT_LED")
	)
	(via
		(at 440.123072 -289.991038)
		(size 0.5588)
		(drill 0.3048)
		(layers "F.Cu" "B.Cu")
		(net "DRIVE_B_34_FLT_LED")
	)
	(segment
		(start 326.546972 -262.931402)
		(end 307.206904 -282.27147)
		(width 0.13335)
		(layer "In2.Cu")
		(net "DRIVE_B_34_FLT_LED")
	)
	(segment
		(start 278.080978 -289.310318)
		(end 266.99083 -289.310318)
		(width 0.13335)
		(layer "In2.Cu")
		(net "DRIVE_B_34_FLT_LED")
	)
	(segment
		(start 261.78637 -294.514778)
		(end 252.547374 -294.514778)
		(width 0.13335)
		(layer "In2.Cu")
		(net "DRIVE_B_34_FLT_LED")
	)
	(segment
		(start 307.206904 -282.27147)
		(end 285.119826 -282.27147)
		(width 0.13335)
		(layer "In2.Cu")
		(net "DRIVE_B_34_FLT_LED")
	)
	(segment
		(start 249.572526 -297.489626)
		(end 243.299234 -297.489626)
		(width 0.13335)
		(layer "In2.Cu")
		(net "DRIVE_B_34_FLT_LED")
	)
	(segment
		(start 285.119826 -282.27147)
		(end 278.080978 -289.310318)
		(width 0.13335)
		(layer "In2.Cu")
		(net "DRIVE_B_34_FLT_LED")
	)
	(segment
		(start 252.547374 -294.514778)
		(end 249.572526 -297.489626)
		(width 0.13335)
		(layer "In2.Cu")
		(net "DRIVE_B_34_FLT_LED")
	)
	(segment
		(start 266.99083 -289.310318)
		(end 261.78637 -294.514778)
		(width 0.13335)
		(layer "In2.Cu")
		(net "DRIVE_B_34_FLT_LED")
	)
	(segment
		(start 429.709834 -262.931402)
		(end 326.546972 -262.931402)
		(width 0.13335)
		(layer "In2.Cu")
		(net "DRIVE_B_34_FLT_LED")
	)
	(segment
		(start 233.395774 -307.393086)
		(end 233.395774 -353.652582)
		(width 0.12065)
		(layer "In4.Cu")
		(net "DRIVE_B_34_FLT_LED")
	)
	(segment
		(start 438.534048 -271.755616)
		(end 429.709834 -262.931402)
		(width 0.12065)
		(layer "In4.Cu")
		(net "DRIVE_B_34_FLT_LED")
	)
	(segment
		(start 233.395774 -353.652582)
		(end 234.253278 -354.510086)
		(width 0.12065)
		(layer "In4.Cu")
		(net "DRIVE_B_34_FLT_LED")
	)
	(segment
		(start 243.299234 -297.489626)
		(end 233.395774 -307.393086)
		(width 0.12065)
		(layer "In4.Cu")
		(net "DRIVE_B_34_FLT_LED")
	)
	(segment
		(start 234.253278 -354.510086)
		(end 234.253278 -371.833648)
		(width 0.12065)
		(layer "In4.Cu")
		(net "DRIVE_B_34_FLT_LED")
	)
	(segment
		(start 438.534048 -288.402014)
		(end 438.534048 -271.755616)
		(width 0.12065)
		(layer "In4.Cu")
		(net "DRIVE_B_34_FLT_LED")
	)
	(segment
		(start 234.253278 -371.833648)
		(end 230.820468 -375.266458)
		(width 0.12065)
		(layer "In4.Cu")
		(net "DRIVE_B_34_FLT_LED")
	)
	(segment
		(start 440.123072 -289.991038)
		(end 438.534048 -288.402014)
		(width 0.12065)
		(layer "In4.Cu")
		(net "DRIVE_B_34_FLT_LED")
	)
	(segment
		(start 438.780174 -284.60192)
		(end 438.869836 -284.512258)
		(width 0.17145)
		(layer "F.Cu")
		(net "DRIVE_B_34_ACT")
	)
	(segment
		(start 438.869836 -284.512258)
		(end 440.24423 -284.512258)
		(width 0.17145)
		(layer "F.Cu")
		(net "DRIVE_B_34_ACT")
	)
	(segment
		(start 440.24423 -284.512258)
		(end 440.24423 -283.337762)
		(width 0.17145)
		(layer "F.Cu")
		(net "DRIVE_B_34_ACT")
	)
	(segment
		(start 439.160412 -286.49549)
		(end 438.780174 -286.115252)
		(width 0.17145)
		(layer "F.Cu")
		(net "DRIVE_B_34_ACT")
	)
	(segment
		(start 438.780174 -286.115252)
		(end 438.780174 -284.60192)
		(width 0.17145)
		(layer "F.Cu")
		(net "DRIVE_B_34_ACT")
	)
	(via
		(at 441.96 -342.1126)
		(size 0.5588)
		(drill 0.3048)
		(layers "F.Cu" "B.Cu")
		(net "DRIVE_B_34_ACT")
	)
	(via
		(at 440.24423 -283.337762)
		(size 0.5588)
		(drill 0.3048)
		(layers "F.Cu" "B.Cu")
		(net "DRIVE_B_34_ACT")
	)
	(via
		(at 438.780174 -284.60192)
		(size 0.6604)
		(drill 0.3302)
		(layers "F.Cu" "B.Cu")
		(net "DRIVE_B_34_ACT")
	)
	(segment
		(start 269.538704 -360.709464)
		(end 287.667446 -360.709464)
		(width 0.13335)
		(layer "In2.Cu")
		(net "DRIVE_B_34_ACT")
	)
	(segment
		(start 226.884484 -395.007592)
		(end 226.884484 -393.419584)
		(width 0.13335)
		(layer "In2.Cu")
		(net "DRIVE_B_34_ACT")
	)
	(segment
		(start 226.1108 -392.6459)
		(end 226.1108 -383.167636)
		(width 0.13335)
		(layer "In2.Cu")
		(net "DRIVE_B_34_ACT")
	)
	(segment
		(start 229.235 -397.358108)
		(end 226.884484 -395.007592)
		(width 0.13335)
		(layer "In2.Cu")
		(net "DRIVE_B_34_ACT")
	)
	(segment
		(start 229.80015 -407.000202)
		(end 230.594916 -406.205436)
		(width 0.13335)
		(layer "In2.Cu")
		(net "DRIVE_B_34_ACT")
	)
	(segment
		(start 230.594916 -403.069044)
		(end 229.235 -401.709128)
		(width 0.13335)
		(layer "In2.Cu")
		(net "DRIVE_B_34_ACT")
	)
	(segment
		(start 296.729658 -342.1126)
		(end 441.96 -342.1126)
		(width 0.13335)
		(layer "In2.Cu")
		(net "DRIVE_B_34_ACT")
	)
	(segment
		(start 287.667446 -360.709464)
		(end 291.185854 -357.191056)
		(width 0.13335)
		(layer "In2.Cu")
		(net "DRIVE_B_34_ACT")
	)
	(segment
		(start 226.884484 -393.419584)
		(end 226.1108 -392.6459)
		(width 0.13335)
		(layer "In2.Cu")
		(net "DRIVE_B_34_ACT")
	)
	(segment
		(start 226.1108 -383.167636)
		(end 228.660706 -380.61773)
		(width 0.13335)
		(layer "In2.Cu")
		(net "DRIVE_B_34_ACT")
	)
	(segment
		(start 259.158994 -350.329754)
		(end 269.538704 -360.709464)
		(width 0.13335)
		(layer "In2.Cu")
		(net "DRIVE_B_34_ACT")
	)
	(segment
		(start 240.110772 -350.329754)
		(end 259.158994 -350.329754)
		(width 0.13335)
		(layer "In2.Cu")
		(net "DRIVE_B_34_ACT")
	)
	(segment
		(start 229.235 -401.709128)
		(end 229.235 -397.358108)
		(width 0.13335)
		(layer "In2.Cu")
		(net "DRIVE_B_34_ACT")
	)
	(segment
		(start 230.594916 -406.205436)
		(end 230.594916 -403.069044)
		(width 0.13335)
		(layer "In2.Cu")
		(net "DRIVE_B_34_ACT")
	)
	(segment
		(start 291.185854 -357.191056)
		(end 291.185854 -347.656404)
		(width 0.13335)
		(layer "In2.Cu")
		(net "DRIVE_B_34_ACT")
	)
	(segment
		(start 228.660706 -361.77982)
		(end 240.110772 -350.329754)
		(width 0.13335)
		(layer "In2.Cu")
		(net "DRIVE_B_34_ACT")
	)
	(segment
		(start 291.185854 -347.656404)
		(end 296.729658 -342.1126)
		(width 0.13335)
		(layer "In2.Cu")
		(net "DRIVE_B_34_ACT")
	)
	(segment
		(start 228.660706 -380.61773)
		(end 228.660706 -361.77982)
		(width 0.13335)
		(layer "In2.Cu")
		(net "DRIVE_B_34_ACT")
	)
	(segment
		(start 441.966604 -342.105996)
		(end 441.966604 -287.482534)
		(width 0.12065)
		(layer "In4.Cu")
		(net "DRIVE_B_34_ACT")
	)
	(segment
		(start 441.96 -342.1126)
		(end 441.966604 -342.105996)
		(width 0.12065)
		(layer "In4.Cu")
		(net "DRIVE_B_34_ACT")
	)
	(segment
		(start 441.966604 -287.482534)
		(end 440.24423 -285.76016)
		(width 0.12065)
		(layer "In4.Cu")
		(net "DRIVE_B_34_ACT")
	)
	(segment
		(start 440.24423 -285.76016)
		(end 440.24423 -283.337762)
		(width 0.12065)
		(layer "In4.Cu")
		(net "DRIVE_B_34_ACT")
	)
	(segment
		(start 412.512002 -286.530034)
		(end 412.512002 -287.355788)
		(width 0.17145)
		(layer "F.Cu")
		(net "DRIVE_B_33_FLT_LED")
	)
	(segment
		(start 229.422706 -372.658894)
		(end 229.204774 -372.876826)
		(width 0.17145)
		(layer "F.Cu")
		(net "DRIVE_B_33_FLT_LED")
	)
	(segment
		(start 229.997 -372.658894)
		(end 229.422706 -372.658894)
		(width 0.17145)
		(layer "F.Cu")
		(net "DRIVE_B_33_FLT_LED")
	)
	(segment
		(start 411.339284 -289.196018)
		(end 411.339284 -288.528506)
		(width 0.17145)
		(layer "F.Cu")
		(net "DRIVE_B_33_FLT_LED")
	)
	(segment
		(start 412.512002 -287.355788)
		(end 412.250636 -287.617154)
		(width 0.17145)
		(layer "F.Cu")
		(net "DRIVE_B_33_FLT_LED")
	)
	(segment
		(start 411.339284 -288.528506)
		(end 412.250636 -287.617154)
		(width 0.17145)
		(layer "F.Cu")
		(net "DRIVE_B_33_FLT_LED")
	)
	(segment
		(start 229.204774 -372.876826)
		(end 229.204774 -373.954294)
		(width 0.17145)
		(layer "F.Cu")
		(net "DRIVE_B_33_FLT_LED")
	)
	(segment
		(start 411.494986 -286.530034)
		(end 412.512002 -286.530034)
		(width 0.17145)
		(layer "F.Cu")
		(net "DRIVE_B_33_FLT_LED")
	)
	(via
		(at 245.744238 -296.875708)
		(size 0.5588)
		(drill 0.3048)
		(layers "F.Cu" "B.Cu")
		(net "DRIVE_B_33_FLT_LED")
	)
	(via
		(at 229.997 -372.658894)
		(size 0.5588)
		(drill 0.3048)
		(layers "F.Cu" "B.Cu")
		(net "DRIVE_B_33_FLT_LED")
	)
	(via
		(at 411.494986 -262.364728)
		(size 0.5588)
		(drill 0.3048)
		(layers "F.Cu" "B.Cu")
		(net "DRIVE_B_33_FLT_LED")
	)
	(via
		(at 412.250636 -287.617154)
		(size 0.6604)
		(drill 0.3302)
		(layers "F.Cu" "B.Cu")
		(net "DRIVE_B_33_FLT_LED")
	)
	(via
		(at 411.494986 -286.530034)
		(size 0.5588)
		(drill 0.3048)
		(layers "F.Cu" "B.Cu")
		(net "DRIVE_B_33_FLT_LED")
	)
	(segment
		(start 252.194568 -293.955978)
		(end 261.533132 -293.955978)
		(width 0.13335)
		(layer "In2.Cu")
		(net "DRIVE_B_33_FLT_LED")
	)
	(segment
		(start 245.744238 -296.875708)
		(end 249.274838 -296.875708)
		(width 0.13335)
		(layer "In2.Cu")
		(net "DRIVE_B_33_FLT_LED")
	)
	(segment
		(start 278.038052 -288.751518)
		(end 285.0769 -281.71267)
		(width 0.13335)
		(layer "In2.Cu")
		(net "DRIVE_B_33_FLT_LED")
	)
	(segment
		(start 249.274838 -296.875708)
		(end 252.194568 -293.955978)
		(width 0.13335)
		(layer "In2.Cu")
		(net "DRIVE_B_33_FLT_LED")
	)
	(segment
		(start 306.975256 -281.71267)
		(end 326.33666 -262.351266)
		(width 0.13335)
		(layer "In2.Cu")
		(net "DRIVE_B_33_FLT_LED")
	)
	(segment
		(start 326.33666 -262.351266)
		(end 411.481524 -262.351266)
		(width 0.13335)
		(layer "In2.Cu")
		(net "DRIVE_B_33_FLT_LED")
	)
	(segment
		(start 285.0769 -281.71267)
		(end 306.975256 -281.71267)
		(width 0.13335)
		(layer "In2.Cu")
		(net "DRIVE_B_33_FLT_LED")
	)
	(segment
		(start 411.481524 -262.351266)
		(end 411.494986 -262.364728)
		(width 0.13335)
		(layer "In2.Cu")
		(net "DRIVE_B_33_FLT_LED")
	)
	(segment
		(start 266.737592 -288.751518)
		(end 278.038052 -288.751518)
		(width 0.13335)
		(layer "In2.Cu")
		(net "DRIVE_B_33_FLT_LED")
	)
	(segment
		(start 261.533132 -293.955978)
		(end 266.737592 -288.751518)
		(width 0.13335)
		(layer "In2.Cu")
		(net "DRIVE_B_33_FLT_LED")
	)
	(segment
		(start 231.356154 -372.658894)
		(end 229.997 -372.658894)
		(width 0.12065)
		(layer "In4.Cu")
		(net "DRIVE_B_33_FLT_LED")
	)
	(segment
		(start 245.744238 -296.875708)
		(end 243.026692 -296.875708)
		(width 0.12065)
		(layer "In4.Cu")
		(net "DRIVE_B_33_FLT_LED")
	)
	(segment
		(start 233.694478 -354.741734)
		(end 233.694478 -370.32057)
		(width 0.12065)
		(layer "In4.Cu")
		(net "DRIVE_B_33_FLT_LED")
	)
	(segment
		(start 411.494986 -286.530034)
		(end 411.494986 -262.364728)
		(width 0.12065)
		(layer "In4.Cu")
		(net "DRIVE_B_33_FLT_LED")
	)
	(segment
		(start 243.026692 -296.875708)
		(end 232.836974 -307.065426)
		(width 0.12065)
		(layer "In4.Cu")
		(net "DRIVE_B_33_FLT_LED")
	)
	(segment
		(start 233.694478 -370.32057)
		(end 231.356154 -372.658894)
		(width 0.12065)
		(layer "In4.Cu")
		(net "DRIVE_B_33_FLT_LED")
	)
	(segment
		(start 232.836974 -353.88423)
		(end 233.694478 -354.741734)
		(width 0.12065)
		(layer "In4.Cu")
		(net "DRIVE_B_33_FLT_LED")
	)
	(segment
		(start 232.836974 -307.065426)
		(end 232.836974 -353.88423)
		(width 0.12065)
		(layer "In4.Cu")
		(net "DRIVE_B_33_FLT_LED")
	)
	(segment
		(start 411.493208 -283.070046)
		(end 411.304232 -282.88107)
		(width 0.17145)
		(layer "F.Cu")
		(net "DRIVE_B_33_ACT")
	)
	(segment
		(start 411.304232 -281.356054)
		(end 411.54477 -281.115516)
		(width 0.17145)
		(layer "F.Cu")
		(net "DRIVE_B_33_ACT")
	)
	(segment
		(start 412.571692 -282.247086)
		(end 412.546292 -282.272486)
		(width 0.17145)
		(layer "F.Cu")
		(net "DRIVE_B_33_ACT")
	)
	(segment
		(start 411.304232 -282.88107)
		(end 411.304232 -281.356054)
		(width 0.17145)
		(layer "F.Cu")
		(net "DRIVE_B_33_ACT")
	)
	(segment
		(start 411.54477 -281.115516)
		(end 412.571692 -281.115516)
		(width 0.17145)
		(layer "F.Cu")
		(net "DRIVE_B_33_ACT")
	)
	(segment
		(start 412.571692 -281.115516)
		(end 412.571692 -282.247086)
		(width 0.17145)
		(layer "F.Cu")
		(net "DRIVE_B_33_ACT")
	)
	(via
		(at 231.417876 -402.824442)
		(size 0.5588)
		(drill 0.3048)
		(layers "F.Cu" "B.Cu")
		(net "DRIVE_B_33_ACT")
	)
	(via
		(at 412.623 -342.6714)
		(size 0.5588)
		(drill 0.3048)
		(layers "F.Cu" "B.Cu")
		(net "DRIVE_B_33_ACT")
	)
	(via
		(at 412.546292 -282.272486)
		(size 0.5588)
		(drill 0.3048)
		(layers "F.Cu" "B.Cu")
		(net "DRIVE_B_33_ACT")
	)
	(via
		(at 411.304232 -281.356054)
		(size 0.6604)
		(drill 0.3302)
		(layers "F.Cu" "B.Cu")
		(net "DRIVE_B_33_ACT")
	)
	(segment
		(start 227.551488 -382.706372)
		(end 227.551488 -392.161522)
		(width 0.13335)
		(layer "In2.Cu")
		(net "DRIVE_B_33_ACT")
	)
	(segment
		(start 287.970976 -361.268264)
		(end 269.307056 -361.268264)
		(width 0.13335)
		(layer "In2.Cu")
		(net "DRIVE_B_33_ACT")
	)
	(segment
		(start 227.309934 -392.403076)
		(end 227.309934 -394.831316)
		(width 0.13335)
		(layer "In2.Cu")
		(net "DRIVE_B_33_ACT")
	)
	(segment
		(start 227.309934 -394.831316)
		(end 229.7938 -397.315182)
		(width 0.13335)
		(layer "In2.Cu")
		(net "DRIVE_B_33_ACT")
	)
	(segment
		(start 227.551488 -392.161522)
		(end 227.309934 -392.403076)
		(width 0.13335)
		(layer "In2.Cu")
		(net "DRIVE_B_33_ACT")
	)
	(segment
		(start 291.744654 -347.888052)
		(end 291.744654 -357.494586)
		(width 0.13335)
		(layer "In2.Cu")
		(net "DRIVE_B_33_ACT")
	)
	(segment
		(start 269.307056 -361.268264)
		(end 258.927346 -350.888554)
		(width 0.13335)
		(layer "In2.Cu")
		(net "DRIVE_B_33_ACT")
	)
	(segment
		(start 296.961306 -342.6714)
		(end 291.744654 -347.888052)
		(width 0.13335)
		(layer "In2.Cu")
		(net "DRIVE_B_33_ACT")
	)
	(segment
		(start 240.34242 -350.888554)
		(end 231.838246 -359.392728)
		(width 0.13335)
		(layer "In2.Cu")
		(net "DRIVE_B_33_ACT")
	)
	(segment
		(start 229.7938 -397.315182)
		(end 229.7938 -401.200366)
		(width 0.13335)
		(layer "In2.Cu")
		(net "DRIVE_B_33_ACT")
	)
	(segment
		(start 231.838246 -359.392728)
		(end 231.838246 -378.419614)
		(width 0.13335)
		(layer "In2.Cu")
		(net "DRIVE_B_33_ACT")
	)
	(segment
		(start 258.927346 -350.888554)
		(end 240.34242 -350.888554)
		(width 0.13335)
		(layer "In2.Cu")
		(net "DRIVE_B_33_ACT")
	)
	(segment
		(start 231.838246 -378.419614)
		(end 227.551488 -382.706372)
		(width 0.13335)
		(layer "In2.Cu")
		(net "DRIVE_B_33_ACT")
	)
	(segment
		(start 291.744654 -357.494586)
		(end 287.970976 -361.268264)
		(width 0.13335)
		(layer "In2.Cu")
		(net "DRIVE_B_33_ACT")
	)
	(segment
		(start 229.7938 -401.200366)
		(end 231.417876 -402.824442)
		(width 0.13335)
		(layer "In2.Cu")
		(net "DRIVE_B_33_ACT")
	)
	(segment
		(start 412.623 -342.6714)
		(end 296.961306 -342.6714)
		(width 0.13335)
		(layer "In2.Cu")
		(net "DRIVE_B_33_ACT")
	)
	(segment
		(start 412.623 -342.6714)
		(end 412.546292 -342.594692)
		(width 0.12065)
		(layer "In4.Cu")
		(net "DRIVE_B_33_ACT")
	)
	(segment
		(start 412.546292 -342.594692)
		(end 412.546292 -282.272486)
		(width 0.12065)
		(layer "In4.Cu")
		(net "DRIVE_B_33_ACT")
	)
	(segment
		(start 229.80015 -408.399996)
		(end 230.630222 -407.569924)
		(width 0.12065)
		(layer "In7.Cu")
		(net "DRIVE_B_33_ACT")
	)
	(segment
		(start 231.417876 -403.765766)
		(end 231.417876 -402.824442)
		(width 0.12065)
		(layer "In7.Cu")
		(net "DRIVE_B_33_ACT")
	)
	(segment
		(start 230.630222 -407.569924)
		(end 230.630222 -404.55342)
		(width 0.12065)
		(layer "In7.Cu")
		(net "DRIVE_B_33_ACT")
	)
	(segment
		(start 230.630222 -404.55342)
		(end 231.417876 -403.765766)
		(width 0.12065)
		(layer "In7.Cu")
		(net "DRIVE_B_33_ACT")
	)
	(segment
		(start 377.401582 -290.591748)
		(end 376.158252 -290.591748)
		(width 0.17145)
		(layer "F.Cu")
		(net "DRIVE_B_32_FLT_LED")
	)
	(segment
		(start 376.324622 -292.002464)
		(end 376.324622 -292.940232)
		(width 0.17145)
		(layer "F.Cu")
		(net "DRIVE_B_32_FLT_LED")
	)
	(segment
		(start 231.14 -372.0846)
		(end 231.14 -373.4054)
		(width 0.17145)
		(layer "F.Cu")
		(net "DRIVE_B_32_FLT_LED")
	)
	(segment
		(start 377.401582 -289.653726)
		(end 377.401582 -290.591748)
		(width 0.17145)
		(layer "F.Cu")
		(net "DRIVE_B_32_FLT_LED")
	)
	(segment
		(start 376.158252 -290.591748)
		(end 376.0724 -290.6776)
		(width 0.17145)
		(layer "F.Cu")
		(net "DRIVE_B_32_FLT_LED")
	)
	(segment
		(start 375.9962 -290.7538)
		(end 375.9962 -291.674042)
		(width 0.17145)
		(layer "F.Cu")
		(net "DRIVE_B_32_FLT_LED")
	)
	(segment
		(start 375.9962 -291.674042)
		(end 376.324622 -292.002464)
		(width 0.17145)
		(layer "F.Cu")
		(net "DRIVE_B_32_FLT_LED")
	)
	(segment
		(start 231.14 -373.4054)
		(end 230.591106 -373.954294)
		(width 0.17145)
		(layer "F.Cu")
		(net "DRIVE_B_32_FLT_LED")
	)
	(segment
		(start 230.591106 -373.954294)
		(end 229.855014 -373.954294)
		(width 0.17145)
		(layer "F.Cu")
		(net "DRIVE_B_32_FLT_LED")
	)
	(segment
		(start 376.0724 -290.6776)
		(end 375.9962 -290.7538)
		(width 0.17145)
		(layer "F.Cu")
		(net "DRIVE_B_32_FLT_LED")
	)
	(via
		(at 376.0724 -290.6776)
		(size 0.6604)
		(drill 0.3302)
		(layers "F.Cu" "B.Cu")
		(net "DRIVE_B_32_FLT_LED")
	)
	(via
		(at 376.308366 -261.747)
		(size 0.5588)
		(drill 0.3048)
		(layers "F.Cu" "B.Cu")
		(net "DRIVE_B_32_FLT_LED")
	)
	(via
		(at 244.587014 -296.145966)
		(size 0.5588)
		(drill 0.3048)
		(layers "F.Cu" "B.Cu")
		(net "DRIVE_B_32_FLT_LED")
	)
	(via
		(at 231.14 -372.0846)
		(size 0.5588)
		(drill 0.3048)
		(layers "F.Cu" "B.Cu")
		(net "DRIVE_B_32_FLT_LED")
	)
	(via
		(at 377.401582 -289.653726)
		(size 0.5588)
		(drill 0.3048)
		(layers "F.Cu" "B.Cu")
		(net "DRIVE_B_32_FLT_LED")
	)
	(segment
		(start 249.214132 -296.145966)
		(end 251.96292 -293.397178)
		(width 0.13335)
		(layer "In2.Cu")
		(net "DRIVE_B_32_FLT_LED")
	)
	(segment
		(start 326.12965 -261.767574)
		(end 376.287792 -261.767574)
		(width 0.13335)
		(layer "In2.Cu")
		(net "DRIVE_B_32_FLT_LED")
	)
	(segment
		(start 306.743354 -281.15387)
		(end 326.12965 -261.767574)
		(width 0.13335)
		(layer "In2.Cu")
		(net "DRIVE_B_32_FLT_LED")
	)
	(segment
		(start 376.287792 -261.767574)
		(end 376.308366 -261.747)
		(width 0.13335)
		(layer "In2.Cu")
		(net "DRIVE_B_32_FLT_LED")
	)
	(segment
		(start 261.301484 -293.397178)
		(end 266.505944 -288.192718)
		(width 0.13335)
		(layer "In2.Cu")
		(net "DRIVE_B_32_FLT_LED")
	)
	(segment
		(start 251.96292 -293.397178)
		(end 261.301484 -293.397178)
		(width 0.13335)
		(layer "In2.Cu")
		(net "DRIVE_B_32_FLT_LED")
	)
	(segment
		(start 285.033974 -281.15387)
		(end 306.743354 -281.15387)
		(width 0.13335)
		(layer "In2.Cu")
		(net "DRIVE_B_32_FLT_LED")
	)
	(segment
		(start 277.995126 -288.192718)
		(end 285.033974 -281.15387)
		(width 0.13335)
		(layer "In2.Cu")
		(net "DRIVE_B_32_FLT_LED")
	)
	(segment
		(start 266.505944 -288.192718)
		(end 277.995126 -288.192718)
		(width 0.13335)
		(layer "In2.Cu")
		(net "DRIVE_B_32_FLT_LED")
	)
	(segment
		(start 244.587014 -296.145966)
		(end 249.214132 -296.145966)
		(width 0.13335)
		(layer "In2.Cu")
		(net "DRIVE_B_32_FLT_LED")
	)
	(segment
		(start 376.308366 -288.56051)
		(end 377.401582 -289.653726)
		(width 0.12065)
		(layer "In4.Cu")
		(net "DRIVE_B_32_FLT_LED")
	)
	(segment
		(start 244.587014 -296.145966)
		(end 242.816634 -296.145966)
		(width 0.12065)
		(layer "In4.Cu")
		(net "DRIVE_B_32_FLT_LED")
	)
	(segment
		(start 233.135678 -370.088922)
		(end 231.14 -372.0846)
		(width 0.12065)
		(layer "In4.Cu")
		(net "DRIVE_B_32_FLT_LED")
	)
	(segment
		(start 376.308366 -261.747)
		(end 376.308366 -288.56051)
		(width 0.12065)
		(layer "In4.Cu")
		(net "DRIVE_B_32_FLT_LED")
	)
	(segment
		(start 242.816634 -296.145966)
		(end 232.278174 -306.684426)
		(width 0.12065)
		(layer "In4.Cu")
		(net "DRIVE_B_32_FLT_LED")
	)
	(segment
		(start 232.278174 -306.684426)
		(end 232.278174 -354.115878)
		(width 0.12065)
		(layer "In4.Cu")
		(net "DRIVE_B_32_FLT_LED")
	)
	(segment
		(start 233.135678 -354.973382)
		(end 233.135678 -370.088922)
		(width 0.12065)
		(layer "In4.Cu")
		(net "DRIVE_B_32_FLT_LED")
	)
	(segment
		(start 232.278174 -354.115878)
		(end 233.135678 -354.973382)
		(width 0.12065)
		(layer "In4.Cu")
		(net "DRIVE_B_32_FLT_LED")
	)
	(segment
		(start 375.8438 -284.008576)
		(end 375.876312 -283.976064)
		(width 0.17145)
		(layer "F.Cu")
		(net "DRIVE_B_32_ACT")
	)
	(segment
		(start 375.8438 -285.79953)
		(end 375.8438 -284.008576)
		(width 0.17145)
		(layer "F.Cu")
		(net "DRIVE_B_32_ACT")
	)
	(segment
		(start 377.344432 -283.957522)
		(end 377.344432 -282.861512)
		(width 0.17145)
		(layer "F.Cu")
		(net "DRIVE_B_32_ACT")
	)
	(segment
		(start 376.261884 -286.217614)
		(end 375.8438 -285.79953)
		(width 0.17145)
		(layer "F.Cu")
		(net "DRIVE_B_32_ACT")
	)
	(segment
		(start 375.876312 -283.976064)
		(end 375.894854 -283.957522)
		(width 0.17145)
		(layer "F.Cu")
		(net "DRIVE_B_32_ACT")
	)
	(segment
		(start 375.894854 -283.957522)
		(end 377.344432 -283.957522)
		(width 0.17145)
		(layer "F.Cu")
		(net "DRIVE_B_32_ACT")
	)
	(via
		(at 377.344432 -282.861512)
		(size 0.5588)
		(drill 0.3048)
		(layers "F.Cu" "B.Cu")
		(net "DRIVE_B_32_ACT")
	)
	(via
		(at 375.876312 -283.976064)
		(size 0.6604)
		(drill 0.3302)
		(layers "F.Cu" "B.Cu")
		(net "DRIVE_B_32_ACT")
	)
	(via
		(at 231.57434 -401.92325)
		(size 0.5588)
		(drill 0.3048)
		(layers "F.Cu" "B.Cu")
		(net "DRIVE_B_32_ACT")
	)
	(via
		(at 378.882148 -343.2302)
		(size 0.5588)
		(drill 0.3048)
		(layers "F.Cu" "B.Cu")
		(net "DRIVE_B_32_ACT")
	)
	(segment
		(start 258.695698 -351.447354)
		(end 240.574068 -351.447354)
		(width 0.13335)
		(layer "In2.Cu")
		(net "DRIVE_B_32_ACT")
	)
	(segment
		(start 297.192954 -343.2302)
		(end 292.303454 -348.1197)
		(width 0.13335)
		(layer "In2.Cu")
		(net "DRIVE_B_32_ACT")
	)
	(segment
		(start 288.274506 -361.827064)
		(end 269.075408 -361.827064)
		(width 0.13335)
		(layer "In2.Cu")
		(net "DRIVE_B_32_ACT")
	)
	(segment
		(start 378.882148 -343.2302)
		(end 297.192954 -343.2302)
		(width 0.13335)
		(layer "In2.Cu")
		(net "DRIVE_B_32_ACT")
	)
	(segment
		(start 230.3526 -397.272256)
		(end 230.3526 -400.70151)
		(width 0.13335)
		(layer "In2.Cu")
		(net "DRIVE_B_32_ACT")
	)
	(segment
		(start 269.075408 -361.827064)
		(end 258.695698 -351.447354)
		(width 0.13335)
		(layer "In2.Cu")
		(net "DRIVE_B_32_ACT")
	)
	(segment
		(start 292.303454 -357.798116)
		(end 288.274506 -361.827064)
		(width 0.13335)
		(layer "In2.Cu")
		(net "DRIVE_B_32_ACT")
	)
	(segment
		(start 227.976938 -392.338052)
		(end 227.735384 -392.579606)
		(width 0.13335)
		(layer "In2.Cu")
		(net "DRIVE_B_32_ACT")
	)
	(segment
		(start 232.397046 -359.624376)
		(end 232.397046 -378.46254)
		(width 0.13335)
		(layer "In2.Cu")
		(net "DRIVE_B_32_ACT")
	)
	(segment
		(start 227.735384 -392.579606)
		(end 227.735384 -394.65504)
		(width 0.13335)
		(layer "In2.Cu")
		(net "DRIVE_B_32_ACT")
	)
	(segment
		(start 232.397046 -378.46254)
		(end 227.976938 -382.882648)
		(width 0.13335)
		(layer "In2.Cu")
		(net "DRIVE_B_32_ACT")
	)
	(segment
		(start 227.976938 -382.882648)
		(end 227.976938 -392.338052)
		(width 0.13335)
		(layer "In2.Cu")
		(net "DRIVE_B_32_ACT")
	)
	(segment
		(start 230.3526 -400.70151)
		(end 231.57434 -401.92325)
		(width 0.13335)
		(layer "In2.Cu")
		(net "DRIVE_B_32_ACT")
	)
	(segment
		(start 227.735384 -394.65504)
		(end 230.3526 -397.272256)
		(width 0.13335)
		(layer "In2.Cu")
		(net "DRIVE_B_32_ACT")
	)
	(segment
		(start 240.574068 -351.447354)
		(end 232.397046 -359.624376)
		(width 0.13335)
		(layer "In2.Cu")
		(net "DRIVE_B_32_ACT")
	)
	(segment
		(start 292.303454 -348.1197)
		(end 292.303454 -357.798116)
		(width 0.13335)
		(layer "In2.Cu")
		(net "DRIVE_B_32_ACT")
	)
	(segment
		(start 378.882148 -289.442652)
		(end 378.882148 -343.2302)
		(width 0.12065)
		(layer "In4.Cu")
		(net "DRIVE_B_32_ACT")
	)
	(segment
		(start 377.344432 -282.861512)
		(end 377.344432 -287.904936)
		(width 0.12065)
		(layer "In4.Cu")
		(net "DRIVE_B_32_ACT")
	)
	(segment
		(start 377.344432 -287.904936)
		(end 378.882148 -289.442652)
		(width 0.12065)
		(layer "In4.Cu")
		(net "DRIVE_B_32_ACT")
	)
	(segment
		(start 229.1334 -404.36419)
		(end 231.57434 -401.92325)
		(width 0.12065)
		(layer "In7.Cu")
		(net "DRIVE_B_32_ACT")
	)
	(segment
		(start 229.1334 -408.83332)
		(end 229.1334 -404.36419)
		(width 0.12065)
		(layer "In7.Cu")
		(net "DRIVE_B_32_ACT")
	)
	(segment
		(start 229.80015 -409.50007)
		(end 229.1334 -408.83332)
		(width 0.12065)
		(layer "In7.Cu")
		(net "DRIVE_B_32_ACT")
	)
	(segment
		(start 344.1954 -291.4396)
		(end 344.0938 -291.5412)
		(width 0.17145)
		(layer "F.Cu")
		(net "DRIVE_B_31_FLT_LED")
	)
	(segment
		(start 230.9876 -370.6368)
		(end 229.5652 -370.6368)
		(width 0.17145)
		(layer "F.Cu")
		(net "DRIVE_B_31_FLT_LED")
	)
	(segment
		(start 229.5652 -370.6368)
		(end 229.204774 -370.276374)
		(width 0.17145)
		(layer "F.Cu")
		(net "DRIVE_B_31_FLT_LED")
	)
	(segment
		(start 345.748102 -290.789868)
		(end 345.500452 -290.542218)
		(width 0.17145)
		(layer "F.Cu")
		(net "DRIVE_B_31_FLT_LED")
	)
	(segment
		(start 345.748102 -291.356542)
		(end 345.748102 -290.789868)
		(width 0.17145)
		(layer "F.Cu")
		(net "DRIVE_B_31_FLT_LED")
	)
	(segment
		(start 344.0938 -291.5412)
		(end 344.0938 -292.35527)
		(width 0.17145)
		(layer "F.Cu")
		(net "DRIVE_B_31_FLT_LED")
	)
	(segment
		(start 344.0938 -292.35527)
		(end 344.657426 -292.918896)
		(width 0.17145)
		(layer "F.Cu")
		(net "DRIVE_B_31_FLT_LED")
	)
	(segment
		(start 344.278458 -291.356542)
		(end 344.1954 -291.4396)
		(width 0.17145)
		(layer "F.Cu")
		(net "DRIVE_B_31_FLT_LED")
	)
	(segment
		(start 229.204774 -370.276374)
		(end 229.204774 -368.315494)
		(width 0.17145)
		(layer "F.Cu")
		(net "DRIVE_B_31_FLT_LED")
	)
	(segment
		(start 345.748102 -291.356542)
		(end 344.278458 -291.356542)
		(width 0.17145)
		(layer "F.Cu")
		(net "DRIVE_B_31_FLT_LED")
	)
	(via
		(at 345.500452 -290.542218)
		(size 0.5588)
		(drill 0.3048)
		(layers "F.Cu" "B.Cu")
		(net "DRIVE_B_31_FLT_LED")
	)
	(via
		(at 243.55298 -295.558718)
		(size 0.5588)
		(drill 0.3048)
		(layers "F.Cu" "B.Cu")
		(net "DRIVE_B_31_FLT_LED")
	)
	(via
		(at 230.9876 -370.6368)
		(size 0.5588)
		(drill 0.3048)
		(layers "F.Cu" "B.Cu")
		(net "DRIVE_B_31_FLT_LED")
	)
	(via
		(at 344.1954 -291.4396)
		(size 0.6604)
		(drill 0.3302)
		(layers "F.Cu" "B.Cu")
		(net "DRIVE_B_31_FLT_LED")
	)
	(via
		(at 346.849954 -261.1755)
		(size 0.5588)
		(drill 0.3048)
		(layers "F.Cu" "B.Cu")
		(net "DRIVE_B_31_FLT_LED")
	)
	(segment
		(start 243.55298 -295.558718)
		(end 245.311422 -295.558718)
		(width 0.13335)
		(layer "In2.Cu")
		(net "DRIVE_B_31_FLT_LED")
	)
	(segment
		(start 266.274296 -287.633918)
		(end 277.763478 -287.633918)
		(width 0.13335)
		(layer "In2.Cu")
		(net "DRIVE_B_31_FLT_LED")
	)
	(segment
		(start 245.5926 -295.27754)
		(end 249.29211 -295.27754)
		(width 0.13335)
		(layer "In2.Cu")
		(net "DRIVE_B_31_FLT_LED")
	)
	(segment
		(start 325.807832 -261.179056)
		(end 346.846398 -261.179056)
		(width 0.13335)
		(layer "In2.Cu")
		(net "DRIVE_B_31_FLT_LED")
	)
	(segment
		(start 284.802326 -280.59507)
		(end 306.391818 -280.59507)
		(width 0.13335)
		(layer "In2.Cu")
		(net "DRIVE_B_31_FLT_LED")
	)
	(segment
		(start 261.069836 -292.838378)
		(end 266.274296 -287.633918)
		(width 0.13335)
		(layer "In2.Cu")
		(net "DRIVE_B_31_FLT_LED")
	)
	(segment
		(start 251.731272 -292.838378)
		(end 261.069836 -292.838378)
		(width 0.13335)
		(layer "In2.Cu")
		(net "DRIVE_B_31_FLT_LED")
	)
	(segment
		(start 277.763478 -287.633918)
		(end 284.802326 -280.59507)
		(width 0.13335)
		(layer "In2.Cu")
		(net "DRIVE_B_31_FLT_LED")
	)
	(segment
		(start 249.29211 -295.27754)
		(end 251.731272 -292.838378)
		(width 0.13335)
		(layer "In2.Cu")
		(net "DRIVE_B_31_FLT_LED")
	)
	(segment
		(start 306.391818 -280.59507)
		(end 325.807832 -261.179056)
		(width 0.13335)
		(layer "In2.Cu")
		(net "DRIVE_B_31_FLT_LED")
	)
	(segment
		(start 346.846398 -261.179056)
		(end 346.849954 -261.1755)
		(width 0.13335)
		(layer "In2.Cu")
		(net "DRIVE_B_31_FLT_LED")
	)
	(segment
		(start 245.311422 -295.558718)
		(end 245.5926 -295.27754)
		(width 0.13335)
		(layer "In2.Cu")
		(net "DRIVE_B_31_FLT_LED")
	)
	(segment
		(start 344.948256 -279.991058)
		(end 344.948256 -289.990022)
		(width 0.12065)
		(layer "In4.Cu")
		(net "DRIVE_B_31_FLT_LED")
	)
	(segment
		(start 232.576878 -369.047522)
		(end 230.9876 -370.6368)
		(width 0.12065)
		(layer "In4.Cu")
		(net "DRIVE_B_31_FLT_LED")
	)
	(segment
		(start 346.849954 -261.1755)
		(end 346.849954 -266.30503)
		(width 0.12065)
		(layer "In4.Cu")
		(net "DRIVE_B_31_FLT_LED")
	)
	(segment
		(start 347.244162 -266.699238)
		(end 347.244162 -277.695152)
		(width 0.12065)
		(layer "In4.Cu")
		(net "DRIVE_B_31_FLT_LED")
	)
	(segment
		(start 344.948256 -289.990022)
		(end 345.500452 -290.542218)
		(width 0.12065)
		(layer "In4.Cu")
		(net "DRIVE_B_31_FLT_LED")
	)
	(segment
		(start 231.719374 -306.252626)
		(end 231.719374 -354.347526)
		(width 0.12065)
		(layer "In4.Cu")
		(net "DRIVE_B_31_FLT_LED")
	)
	(segment
		(start 243.55298 -295.558718)
		(end 242.413282 -295.558718)
		(width 0.12065)
		(layer "In4.Cu")
		(net "DRIVE_B_31_FLT_LED")
	)
	(segment
		(start 242.413282 -295.558718)
		(end 231.719374 -306.252626)
		(width 0.12065)
		(layer "In4.Cu")
		(net "DRIVE_B_31_FLT_LED")
	)
	(segment
		(start 232.576878 -355.20503)
		(end 232.576878 -369.047522)
		(width 0.12065)
		(layer "In4.Cu")
		(net "DRIVE_B_31_FLT_LED")
	)
	(segment
		(start 346.849954 -266.30503)
		(end 347.244162 -266.699238)
		(width 0.12065)
		(layer "In4.Cu")
		(net "DRIVE_B_31_FLT_LED")
	)
	(segment
		(start 347.244162 -277.695152)
		(end 344.948256 -279.991058)
		(width 0.12065)
		(layer "In4.Cu")
		(net "DRIVE_B_31_FLT_LED")
	)
	(segment
		(start 231.719374 -354.347526)
		(end 232.576878 -355.20503)
		(width 0.12065)
		(layer "In4.Cu")
		(net "DRIVE_B_31_FLT_LED")
	)
	(segment
		(start 344.858594 -287.44037)
		(end 344.586306 -287.168082)
		(width 0.17145)
		(layer "F.Cu")
		(net "DRIVE_B_31_ACT")
	)
	(segment
		(start 345.923616 -285.33471)
		(end 345.923616 -283.31033)
		(width 0.17145)
		(layer "F.Cu")
		(net "DRIVE_B_31_ACT")
	)
	(segment
		(start 344.586306 -285.345632)
		(end 344.597228 -285.33471)
		(width 0.17145)
		(layer "F.Cu")
		(net "DRIVE_B_31_ACT")
	)
	(segment
		(start 344.586306 -287.168082)
		(end 344.586306 -285.345632)
		(width 0.17145)
		(layer "F.Cu")
		(net "DRIVE_B_31_ACT")
	)
	(segment
		(start 344.597228 -285.33471)
		(end 345.923616 -285.33471)
		(width 0.17145)
		(layer "F.Cu")
		(net "DRIVE_B_31_ACT")
	)
	(segment
		(start 345.923616 -283.31033)
		(end 345.712796 -283.09951)
		(width 0.17145)
		(layer "F.Cu")
		(net "DRIVE_B_31_ACT")
	)
	(via
		(at 346.849954 -343.789)
		(size 0.5588)
		(drill 0.3048)
		(layers "F.Cu" "B.Cu")
		(net "DRIVE_B_31_ACT")
	)
	(via
		(at 344.586306 -285.345632)
		(size 0.6604)
		(drill 0.3302)
		(layers "F.Cu" "B.Cu")
		(net "DRIVE_B_31_ACT")
	)
	(via
		(at 231.550464 -400.507708)
		(size 0.5588)
		(drill 0.3048)
		(layers "F.Cu" "B.Cu")
		(net "DRIVE_B_31_ACT")
	)
	(via
		(at 345.712796 -283.09951)
		(size 0.5588)
		(drill 0.3048)
		(layers "F.Cu" "B.Cu")
		(net "DRIVE_B_31_ACT")
	)
	(segment
		(start 229.80015 -410.600144)
		(end 230.77678 -409.623514)
		(width 0.17145)
		(layer "B.Cu")
		(net "DRIVE_B_31_ACT")
	)
	(segment
		(start 230.77678 -401.281392)
		(end 231.550464 -400.507708)
		(width 0.17145)
		(layer "B.Cu")
		(net "DRIVE_B_31_ACT")
	)
	(segment
		(start 230.77678 -409.623514)
		(end 230.77678 -401.281392)
		(width 0.17145)
		(layer "B.Cu")
		(net "DRIVE_B_31_ACT")
	)
	(segment
		(start 228.160834 -394.290042)
		(end 230.9114 -397.040608)
		(width 0.13335)
		(layer "In2.Cu")
		(net "DRIVE_B_31_ACT")
	)
	(segment
		(start 292.862254 -358.131364)
		(end 288.607754 -362.385864)
		(width 0.13335)
		(layer "In2.Cu")
		(net "DRIVE_B_31_ACT")
	)
	(segment
		(start 229.074218 -387.500114)
		(end 229.098602 -387.524498)
		(width 0.13335)
		(layer "In2.Cu")
		(net "DRIVE_B_31_ACT")
	)
	(segment
		(start 229.098602 -387.937502)
		(end 229.074218 -387.961886)
		(width 0.13335)
		(layer "In2.Cu")
		(net "DRIVE_B_31_ACT")
	)
	(segment
		(start 232.955846 -378.694188)
		(end 229.074218 -382.575816)
		(width 0.13335)
		(layer "In2.Cu")
		(net "DRIVE_B_31_ACT")
	)
	(segment
		(start 268.84376 -362.385864)
		(end 258.46405 -352.006154)
		(width 0.13335)
		(layer "In2.Cu")
		(net "DRIVE_B_31_ACT")
	)
	(segment
		(start 346.849954 -343.789)
		(end 297.425364 -343.789)
		(width 0.13335)
		(layer "In2.Cu")
		(net "DRIVE_B_31_ACT")
	)
	(segment
		(start 229.074218 -391.842498)
		(end 228.160834 -392.755882)
		(width 0.13335)
		(layer "In2.Cu")
		(net "DRIVE_B_31_ACT")
	)
	(segment
		(start 297.425364 -343.789)
		(end 292.862254 -348.35211)
		(width 0.13335)
		(layer "In2.Cu")
		(net "DRIVE_B_31_ACT")
	)
	(segment
		(start 230.9114 -399.868644)
		(end 231.550464 -400.507708)
		(width 0.13335)
		(layer "In2.Cu")
		(net "DRIVE_B_31_ACT")
	)
	(segment
		(start 232.955846 -359.856024)
		(end 232.955846 -378.694188)
		(width 0.13335)
		(layer "In2.Cu")
		(net "DRIVE_B_31_ACT")
	)
	(segment
		(start 258.46405 -352.006154)
		(end 240.805716 -352.006154)
		(width 0.13335)
		(layer "In2.Cu")
		(net "DRIVE_B_31_ACT")
	)
	(segment
		(start 240.805716 -352.006154)
		(end 232.955846 -359.856024)
		(width 0.13335)
		(layer "In2.Cu")
		(net "DRIVE_B_31_ACT")
	)
	(segment
		(start 288.607754 -362.385864)
		(end 268.84376 -362.385864)
		(width 0.13335)
		(layer "In2.Cu")
		(net "DRIVE_B_31_ACT")
	)
	(segment
		(start 229.074218 -387.961886)
		(end 229.074218 -391.842498)
		(width 0.13335)
		(layer "In2.Cu")
		(net "DRIVE_B_31_ACT")
	)
	(segment
		(start 229.098602 -387.524498)
		(end 229.098602 -387.937502)
		(width 0.13335)
		(layer "In2.Cu")
		(net "DRIVE_B_31_ACT")
	)
	(segment
		(start 229.074218 -382.575816)
		(end 229.074218 -387.500114)
		(width 0.13335)
		(layer "In2.Cu")
		(net "DRIVE_B_31_ACT")
	)
	(segment
		(start 230.9114 -397.040608)
		(end 230.9114 -399.868644)
		(width 0.13335)
		(layer "In2.Cu")
		(net "DRIVE_B_31_ACT")
	)
	(segment
		(start 228.160834 -392.755882)
		(end 228.160834 -394.290042)
		(width 0.13335)
		(layer "In2.Cu")
		(net "DRIVE_B_31_ACT")
	)
	(segment
		(start 292.862254 -348.35211)
		(end 292.862254 -358.131364)
		(width 0.13335)
		(layer "In2.Cu")
		(net "DRIVE_B_31_ACT")
	)
	(segment
		(start 345.507056 -289.302952)
		(end 346.077794 -289.87369)
		(width 0.12065)
		(layer "In4.Cu")
		(net "DRIVE_B_31_ACT")
	)
	(segment
		(start 346.849954 -297.634152)
		(end 346.849954 -343.789)
		(width 0.12065)
		(layer "In4.Cu")
		(net "DRIVE_B_31_ACT")
	)
	(segment
		(start 345.507056 -283.30525)
		(end 345.507056 -289.302952)
		(width 0.12065)
		(layer "In4.Cu")
		(net "DRIVE_B_31_ACT")
	)
	(segment
		(start 346.077794 -296.861992)
		(end 346.849954 -297.634152)
		(width 0.12065)
		(layer "In4.Cu")
		(net "DRIVE_B_31_ACT")
	)
	(segment
		(start 345.712796 -283.09951)
		(end 345.507056 -283.30525)
		(width 0.12065)
		(layer "In4.Cu")
		(net "DRIVE_B_31_ACT")
	)
	(segment
		(start 346.077794 -289.87369)
		(end 346.077794 -296.861992)
		(width 0.12065)
		(layer "In4.Cu")
		(net "DRIVE_B_31_ACT")
	)
	(segment
		(start 310.063642 -291.22624)
		(end 310.332882 -290.957)
		(width 0.17145)
		(layer "F.Cu")
		(net "DRIVE_B_30_FLT_LED")
	)
	(segment
		(start 310.063642 -292.644576)
		(end 310.063642 -291.22624)
		(width 0.17145)
		(layer "F.Cu")
		(net "DRIVE_B_30_FLT_LED")
	)
	(segment
		(start 311.454038 -290.118292)
		(end 311.454038 -290.91255)
		(width 0.17145)
		(layer "F.Cu")
		(net "DRIVE_B_30_FLT_LED")
	)
	(segment
		(start 230.2764 -371.2464)
		(end 229.3366 -371.2464)
		(width 0.17145)
		(layer "F.Cu")
		(net "DRIVE_B_30_FLT_LED")
	)
	(segment
		(start 310.38038 -292.961314)
		(end 310.063642 -292.644576)
		(width 0.17145)
		(layer "F.Cu")
		(net "DRIVE_B_30_FLT_LED")
	)
	(segment
		(start 310.332882 -290.957)
		(end 311.409588 -290.957)
		(width 0.17145)
		(layer "F.Cu")
		(net "DRIVE_B_30_FLT_LED")
	)
	(segment
		(start 311.409588 -290.957)
		(end 311.454038 -290.91255)
		(width 0.17145)
		(layer "F.Cu")
		(net "DRIVE_B_30_FLT_LED")
	)
	(segment
		(start 311.828942 -289.743388)
		(end 311.454038 -290.118292)
		(width 0.17145)
		(layer "F.Cu")
		(net "DRIVE_B_30_FLT_LED")
	)
	(segment
		(start 313.141868 -289.743388)
		(end 311.828942 -289.743388)
		(width 0.17145)
		(layer "F.Cu")
		(net "DRIVE_B_30_FLT_LED")
	)
	(segment
		(start 229.3366 -371.2464)
		(end 228.554534 -370.464334)
		(width 0.17145)
		(layer "F.Cu")
		(net "DRIVE_B_30_FLT_LED")
	)
	(segment
		(start 228.554534 -370.464334)
		(end 228.554534 -368.315494)
		(width 0.17145)
		(layer "F.Cu")
		(net "DRIVE_B_30_FLT_LED")
	)
	(via
		(at 310.063642 -291.22624)
		(size 0.6604)
		(drill 0.3302)
		(layers "F.Cu" "B.Cu")
		(net "DRIVE_B_30_FLT_LED")
	)
	(via
		(at 244.992398 -294.71874)
		(size 0.5588)
		(drill 0.3048)
		(layers "F.Cu" "B.Cu")
		(net "DRIVE_B_30_FLT_LED")
	)
	(via
		(at 230.2764 -371.2464)
		(size 0.5588)
		(drill 0.3048)
		(layers "F.Cu" "B.Cu")
		(net "DRIVE_B_30_FLT_LED")
	)
	(via
		(at 313.141868 -289.743388)
		(size 0.5588)
		(drill 0.3048)
		(layers "F.Cu" "B.Cu")
		(net "DRIVE_B_30_FLT_LED")
	)
	(via
		(at 318.1096 -267.7414)
		(size 0.5588)
		(drill 0.3048)
		(layers "F.Cu" "B.Cu")
		(net "DRIVE_B_30_FLT_LED")
	)
	(segment
		(start 251.499624 -292.279578)
		(end 260.838188 -292.279578)
		(width 0.13335)
		(layer "In2.Cu")
		(net "DRIVE_B_30_FLT_LED")
	)
	(segment
		(start 284.570678 -280.03627)
		(end 305.81473 -280.03627)
		(width 0.13335)
		(layer "In2.Cu")
		(net "DRIVE_B_30_FLT_LED")
	)
	(segment
		(start 244.992398 -294.71874)
		(end 249.060462 -294.71874)
		(width 0.13335)
		(layer "In2.Cu")
		(net "DRIVE_B_30_FLT_LED")
	)
	(segment
		(start 266.042648 -287.075118)
		(end 277.53183 -287.075118)
		(width 0.13335)
		(layer "In2.Cu")
		(net "DRIVE_B_30_FLT_LED")
	)
	(segment
		(start 249.060462 -294.71874)
		(end 251.499624 -292.279578)
		(width 0.13335)
		(layer "In2.Cu")
		(net "DRIVE_B_30_FLT_LED")
	)
	(segment
		(start 277.53183 -287.075118)
		(end 284.570678 -280.03627)
		(width 0.13335)
		(layer "In2.Cu")
		(net "DRIVE_B_30_FLT_LED")
	)
	(segment
		(start 305.81473 -280.03627)
		(end 318.1096 -267.7414)
		(width 0.13335)
		(layer "In2.Cu")
		(net "DRIVE_B_30_FLT_LED")
	)
	(segment
		(start 260.838188 -292.279578)
		(end 266.042648 -287.075118)
		(width 0.13335)
		(layer "In2.Cu")
		(net "DRIVE_B_30_FLT_LED")
	)
	(segment
		(start 232.018078 -355.436678)
		(end 232.018078 -368.815874)
		(width 0.12065)
		(layer "In4.Cu")
		(net "DRIVE_B_30_FLT_LED")
	)
	(segment
		(start 232.018078 -368.815874)
		(end 230.2764 -370.557552)
		(width 0.12065)
		(layer "In4.Cu")
		(net "DRIVE_B_30_FLT_LED")
	)
	(segment
		(start 313.141868 -289.743388)
		(end 313.141868 -272.709132)
		(width 0.12065)
		(layer "In4.Cu")
		(net "DRIVE_B_30_FLT_LED")
	)
	(segment
		(start 242.36426 -294.71874)
		(end 231.160574 -305.922426)
		(width 0.12065)
		(layer "In4.Cu")
		(net "DRIVE_B_30_FLT_LED")
	)
	(segment
		(start 313.141868 -272.709132)
		(end 318.1096 -267.7414)
		(width 0.12065)
		(layer "In4.Cu")
		(net "DRIVE_B_30_FLT_LED")
	)
	(segment
		(start 231.160574 -305.922426)
		(end 231.160574 -354.579174)
		(width 0.12065)
		(layer "In4.Cu")
		(net "DRIVE_B_30_FLT_LED")
	)
	(segment
		(start 231.160574 -354.579174)
		(end 232.018078 -355.436678)
		(width 0.12065)
		(layer "In4.Cu")
		(net "DRIVE_B_30_FLT_LED")
	)
	(segment
		(start 244.992398 -294.71874)
		(end 242.36426 -294.71874)
		(width 0.12065)
		(layer "In4.Cu")
		(net "DRIVE_B_30_FLT_LED")
	)
	(segment
		(start 230.2764 -370.557552)
		(end 230.2764 -371.2464)
		(width 0.12065)
		(layer "In4.Cu")
		(net "DRIVE_B_30_FLT_LED")
	)
	(segment
		(start 313.5884 -292.581076)
		(end 313.5884 -291.197792)
		(width 0.17145)
		(layer "F.Cu")
		(net "DRIVE_B_30_ACT")
	)
	(segment
		(start 313.96178 -292.954456)
		(end 313.5884 -292.581076)
		(width 0.17145)
		(layer "F.Cu")
		(net "DRIVE_B_30_ACT")
	)
	(segment
		(start 313.5884 -291.197792)
		(end 313.68873 -291.097462)
		(width 0.17145)
		(layer "F.Cu")
		(net "DRIVE_B_30_ACT")
	)
	(segment
		(start 313.85129 -290.934902)
		(end 315.039756 -290.934902)
		(width 0.17145)
		(layer "F.Cu")
		(net "DRIVE_B_30_ACT")
	)
	(segment
		(start 313.68873 -291.097462)
		(end 313.85129 -290.934902)
		(width 0.17145)
		(layer "F.Cu")
		(net "DRIVE_B_30_ACT")
	)
	(segment
		(start 315.039756 -290.934902)
		(end 315.039756 -289.494214)
		(width 0.17145)
		(layer "F.Cu")
		(net "DRIVE_B_30_ACT")
	)
	(via
		(at 315.039756 -289.494214)
		(size 0.5588)
		(drill 0.3048)
		(layers "F.Cu" "B.Cu")
		(net "DRIVE_B_30_ACT")
	)
	(via
		(at 313.68873 -291.097462)
		(size 0.6604)
		(drill 0.3302)
		(layers "F.Cu" "B.Cu")
		(net "DRIVE_B_30_ACT")
	)
	(via
		(at 315.030104 -344.6018)
		(size 0.5588)
		(drill 0.3048)
		(layers "F.Cu" "B.Cu")
		(net "DRIVE_B_30_ACT")
	)
	(via
		(at 231.525064 -399.593308)
		(size 0.5588)
		(drill 0.3048)
		(layers "F.Cu" "B.Cu")
		(net "DRIVE_B_30_ACT")
	)
	(segment
		(start 228.976682 -410.993082)
		(end 228.976682 -402.14169)
		(width 0.17145)
		(layer "B.Cu")
		(net "DRIVE_B_30_ACT")
	)
	(segment
		(start 229.80015 -412.000192)
		(end 229.80015 -411.81655)
		(width 0.17145)
		(layer "B.Cu")
		(net "DRIVE_B_30_ACT")
	)
	(segment
		(start 229.80015 -411.81655)
		(end 228.976682 -410.993082)
		(width 0.17145)
		(layer "B.Cu")
		(net "DRIVE_B_30_ACT")
	)
	(segment
		(start 228.976682 -402.14169)
		(end 231.525064 -399.593308)
		(width 0.17145)
		(layer "B.Cu")
		(net "DRIVE_B_30_ACT")
	)
	(segment
		(start 258.232402 -352.564954)
		(end 268.612112 -362.944664)
		(width 0.13335)
		(layer "In2.Cu")
		(net "DRIVE_B_30_ACT")
	)
	(segment
		(start 231.525064 -396.863824)
		(end 228.586284 -393.925044)
		(width 0.13335)
		(layer "In2.Cu")
		(net "DRIVE_B_30_ACT")
	)
	(segment
		(start 241.037364 -352.564954)
		(end 258.232402 -352.564954)
		(width 0.13335)
		(layer "In2.Cu")
		(net "DRIVE_B_30_ACT")
	)
	(segment
		(start 228.586284 -393.925044)
		(end 228.586284 -392.932158)
		(width 0.13335)
		(layer "In2.Cu")
		(net "DRIVE_B_30_ACT")
	)
	(segment
		(start 229.625144 -391.893298)
		(end 229.625398 -391.893298)
		(width 0.13335)
		(layer "In2.Cu")
		(net "DRIVE_B_30_ACT")
	)
	(segment
		(start 228.586284 -392.932158)
		(end 229.625144 -391.893298)
		(width 0.13335)
		(layer "In2.Cu")
		(net "DRIVE_B_30_ACT")
	)
	(segment
		(start 297.403012 -344.6018)
		(end 315.030104 -344.6018)
		(width 0.13335)
		(layer "In2.Cu")
		(net "DRIVE_B_30_ACT")
	)
	(segment
		(start 233.514646 -360.087672)
		(end 241.037364 -352.564954)
		(width 0.13335)
		(layer "In2.Cu")
		(net "DRIVE_B_30_ACT")
	)
	(segment
		(start 231.525064 -399.593308)
		(end 231.525064 -396.863824)
		(width 0.13335)
		(layer "In2.Cu")
		(net "DRIVE_B_30_ACT")
	)
	(segment
		(start 229.625398 -391.893298)
		(end 229.633018 -391.885678)
		(width 0.13335)
		(layer "In2.Cu")
		(net "DRIVE_B_30_ACT")
	)
	(segment
		(start 293.421054 -358.363012)
		(end 293.421054 -348.583758)
		(width 0.13335)
		(layer "In2.Cu")
		(net "DRIVE_B_30_ACT")
	)
	(segment
		(start 229.633018 -391.885678)
		(end 229.633018 -382.807464)
		(width 0.13335)
		(layer "In2.Cu")
		(net "DRIVE_B_30_ACT")
	)
	(segment
		(start 229.633018 -382.807464)
		(end 233.514646 -378.925836)
		(width 0.13335)
		(layer "In2.Cu")
		(net "DRIVE_B_30_ACT")
	)
	(segment
		(start 268.612112 -362.944664)
		(end 288.839402 -362.944664)
		(width 0.13335)
		(layer "In2.Cu")
		(net "DRIVE_B_30_ACT")
	)
	(segment
		(start 293.421054 -348.583758)
		(end 297.403012 -344.6018)
		(width 0.13335)
		(layer "In2.Cu")
		(net "DRIVE_B_30_ACT")
	)
	(segment
		(start 233.514646 -378.925836)
		(end 233.514646 -360.087672)
		(width 0.13335)
		(layer "In2.Cu")
		(net "DRIVE_B_30_ACT")
	)
	(segment
		(start 288.839402 -362.944664)
		(end 293.421054 -358.363012)
		(width 0.13335)
		(layer "In2.Cu")
		(net "DRIVE_B_30_ACT")
	)
	(segment
		(start 315.039756 -289.494214)
		(end 315.030104 -289.503866)
		(width 0.12065)
		(layer "In4.Cu")
		(net "DRIVE_B_30_ACT")
	)
	(segment
		(start 315.030104 -289.503866)
		(end 315.030104 -344.6018)
		(width 0.12065)
		(layer "In4.Cu")
		(net "DRIVE_B_30_ACT")
	)
	(segment
		(start 162.969956 -301.245778)
		(end 164.370004 -301.245778)
		(width 0.17145)
		(layer "F.Cu")
		(net "DRIVE_B_29_FLT_LED")
	)
	(segment
		(start 163.295076 -302.93056)
		(end 162.911282 -302.546766)
		(width 0.17145)
		(layer "F.Cu")
		(net "DRIVE_B_29_FLT_LED")
	)
	(segment
		(start 227.904294 -369.859306)
		(end 225.50755 -372.25605)
		(width 0.17145)
		(layer "F.Cu")
		(net "DRIVE_B_29_FLT_LED")
	)
	(segment
		(start 208.110328 -374.311672)
		(end 203.401168 -374.311672)
		(width 0.17145)
		(layer "F.Cu")
		(net "DRIVE_B_29_FLT_LED")
	)
	(segment
		(start 162.911282 -302.546766)
		(end 162.911282 -301.304452)
		(width 0.17145)
		(layer "F.Cu")
		(net "DRIVE_B_29_FLT_LED")
	)
	(segment
		(start 208.113376 -374.308624)
		(end 208.110328 -374.311672)
		(width 0.17145)
		(layer "F.Cu")
		(net "DRIVE_B_29_FLT_LED")
	)
	(segment
		(start 210.207606 -372.25605)
		(end 210.163156 -372.3005)
		(width 0.17145)
		(layer "F.Cu")
		(net "DRIVE_B_29_FLT_LED")
	)
	(segment
		(start 227.904294 -368.315494)
		(end 227.904294 -369.859306)
		(width 0.17145)
		(layer "F.Cu")
		(net "DRIVE_B_29_FLT_LED")
	)
	(segment
		(start 210.163156 -372.3005)
		(end 210.15833 -372.3005)
		(width 0.17145)
		(layer "F.Cu")
		(net "DRIVE_B_29_FLT_LED")
	)
	(segment
		(start 162.911282 -301.304452)
		(end 162.969956 -301.245778)
		(width 0.17145)
		(layer "F.Cu")
		(net "DRIVE_B_29_FLT_LED")
	)
	(segment
		(start 164.370004 -301.245778)
		(end 164.370004 -302.136302)
		(width 0.17145)
		(layer "F.Cu")
		(net "DRIVE_B_29_FLT_LED")
	)
	(segment
		(start 210.15833 -372.3005)
		(end 208.150206 -374.308624)
		(width 0.17145)
		(layer "F.Cu")
		(net "DRIVE_B_29_FLT_LED")
	)
	(segment
		(start 203.401168 -374.311672)
		(end 202.399392 -373.309896)
		(width 0.17145)
		(layer "F.Cu")
		(net "DRIVE_B_29_FLT_LED")
	)
	(segment
		(start 225.50755 -372.25605)
		(end 210.207606 -372.25605)
		(width 0.17145)
		(layer "F.Cu")
		(net "DRIVE_B_29_FLT_LED")
	)
	(segment
		(start 208.150206 -374.308624)
		(end 208.113376 -374.308624)
		(width 0.17145)
		(layer "F.Cu")
		(net "DRIVE_B_29_FLT_LED")
	)
	(via
		(at 162.911282 -301.304452)
		(size 0.6604)
		(drill 0.3302)
		(layers "F.Cu" "B.Cu")
		(net "DRIVE_B_29_FLT_LED")
	)
	(via
		(at 164.370004 -302.136302)
		(size 0.5588)
		(drill 0.3048)
		(layers "F.Cu" "B.Cu")
		(net "DRIVE_B_29_FLT_LED")
	)
	(via
		(at 202.399392 -373.309896)
		(size 0.5588)
		(drill 0.3048)
		(layers "F.Cu" "B.Cu")
		(net "DRIVE_B_29_FLT_LED")
	)
	(segment
		(start 182.289196 -328.633836)
		(end 196.79666 -343.1413)
		(width 0.12065)
		(layer "In4.Cu")
		(net "DRIVE_B_29_FLT_LED")
	)
	(segment
		(start 202.137772 -373.048276)
		(end 202.399392 -373.309896)
		(width 0.12065)
		(layer "In4.Cu")
		(net "DRIVE_B_29_FLT_LED")
	)
	(segment
		(start 196.79666 -343.1413)
		(end 197.4977 -343.1413)
		(width 0.12065)
		(layer "In4.Cu")
		(net "DRIVE_B_29_FLT_LED")
	)
	(segment
		(start 164.370004 -302.136302)
		(end 182.289196 -320.055494)
		(width 0.12065)
		(layer "In4.Cu")
		(net "DRIVE_B_29_FLT_LED")
	)
	(segment
		(start 182.289196 -320.055494)
		(end 182.289196 -328.633836)
		(width 0.12065)
		(layer "In4.Cu")
		(net "DRIVE_B_29_FLT_LED")
	)
	(segment
		(start 197.4977 -343.1413)
		(end 202.137772 -347.781372)
		(width 0.12065)
		(layer "In4.Cu")
		(net "DRIVE_B_29_FLT_LED")
	)
	(segment
		(start 202.137772 -347.781372)
		(end 202.137772 -373.048276)
		(width 0.12065)
		(layer "In4.Cu")
		(net "DRIVE_B_29_FLT_LED")
	)
	(segment
		(start 163.319206 -297.281346)
		(end 164.519864 -296.080688)
		(width 0.17145)
		(layer "F.Cu")
		(net "DRIVE_B_29_ACT")
	)
	(segment
		(start 164.519864 -294.84574)
		(end 164.519864 -293.1541)
		(width 0.17145)
		(layer "F.Cu")
		(net "DRIVE_B_29_ACT")
	)
	(segment
		(start 164.519864 -296.080688)
		(end 164.519864 -294.84574)
		(width 0.17145)
		(layer "F.Cu")
		(net "DRIVE_B_29_ACT")
	)
	(segment
		(start 163.319206 -297.791886)
		(end 163.319206 -297.281346)
		(width 0.17145)
		(layer "F.Cu")
		(net "DRIVE_B_29_ACT")
	)
	(via
		(at 227.6094 -356.0064)
		(size 0.5588)
		(drill 0.3048)
		(layers "F.Cu" "B.Cu")
		(net "DRIVE_B_29_ACT")
	)
	(via
		(at 170.942 -343.9414)
		(size 0.5588)
		(drill 0.3048)
		(layers "F.Cu" "B.Cu")
		(net "DRIVE_B_29_ACT")
	)
	(via
		(at 227.847652 -400.7104)
		(size 0.5588)
		(drill 0.3048)
		(layers "F.Cu" "B.Cu")
		(net "DRIVE_B_29_ACT")
	)
	(via
		(at 164.519864 -296.080688)
		(size 0.6604)
		(drill 0.3302)
		(layers "F.Cu" "B.Cu")
		(net "DRIVE_B_29_ACT")
	)
	(via
		(at 164.519864 -293.1541)
		(size 0.5588)
		(drill 0.3048)
		(layers "F.Cu" "B.Cu")
		(net "DRIVE_B_29_ACT")
	)
	(segment
		(start 218.511628 -354.334572)
		(end 225.937572 -354.334572)
		(width 0.13335)
		(layer "In2.Cu")
		(net "DRIVE_B_29_ACT")
	)
	(segment
		(start 225.937572 -354.334572)
		(end 227.6094 -356.0064)
		(width 0.13335)
		(layer "In2.Cu")
		(net "DRIVE_B_29_ACT")
	)
	(segment
		(start 229.80015 -413.100012)
		(end 229.0318 -412.331662)
		(width 0.13335)
		(layer "In2.Cu")
		(net "DRIVE_B_29_ACT")
	)
	(segment
		(start 170.942 -343.9414)
		(end 208.118456 -343.9414)
		(width 0.13335)
		(layer "In2.Cu")
		(net "DRIVE_B_29_ACT")
	)
	(segment
		(start 229.0318 -403.671024)
		(end 227.847652 -402.486876)
		(width 0.13335)
		(layer "In2.Cu")
		(net "DRIVE_B_29_ACT")
	)
	(segment
		(start 229.0318 -412.331662)
		(end 229.0318 -403.671024)
		(width 0.13335)
		(layer "In2.Cu")
		(net "DRIVE_B_29_ACT")
	)
	(segment
		(start 208.118456 -343.9414)
		(end 218.511628 -354.334572)
		(width 0.13335)
		(layer "In2.Cu")
		(net "DRIVE_B_29_ACT")
	)
	(segment
		(start 227.847652 -402.486876)
		(end 227.847652 -400.7104)
		(width 0.13335)
		(layer "In2.Cu")
		(net "DRIVE_B_29_ACT")
	)
	(segment
		(start 164.519864 -297.252136)
		(end 163.195 -298.577)
		(width 0.12065)
		(layer "In4.Cu")
		(net "DRIVE_B_29_ACT")
	)
	(segment
		(start 227.3808 -399.51406)
		(end 228.24694 -398.64792)
		(width 0.12065)
		(layer "In4.Cu")
		(net "DRIVE_B_29_ACT")
	)
	(segment
		(start 228.24694 -398.64792)
		(end 228.24694 -392.27506)
		(width 0.12065)
		(layer "In4.Cu")
		(net "DRIVE_B_29_ACT")
	)
	(segment
		(start 227.00107 -376.846084)
		(end 227.00107 -368.848386)
		(width 0.12065)
		(layer "In4.Cu")
		(net "DRIVE_B_29_ACT")
	)
	(segment
		(start 228.24694 -392.27506)
		(end 229.610158 -390.911842)
		(width 0.12065)
		(layer "In4.Cu")
		(net "DRIVE_B_29_ACT")
	)
	(segment
		(start 227.00107 -368.848386)
		(end 229.224078 -366.625378)
		(width 0.12065)
		(layer "In4.Cu")
		(net "DRIVE_B_29_ACT")
	)
	(segment
		(start 227.847652 -400.7104)
		(end 227.3808 -400.243548)
		(width 0.12065)
		(layer "In4.Cu")
		(net "DRIVE_B_29_ACT")
	)
	(segment
		(start 227.3808 -400.243548)
		(end 227.3808 -399.51406)
		(width 0.12065)
		(layer "In4.Cu")
		(net "DRIVE_B_29_ACT")
	)
	(segment
		(start 229.610158 -390.911842)
		(end 229.610158 -379.455172)
		(width 0.12065)
		(layer "In4.Cu")
		(net "DRIVE_B_29_ACT")
	)
	(segment
		(start 229.224078 -366.625378)
		(end 229.224078 -357.621078)
		(width 0.12065)
		(layer "In4.Cu")
		(net "DRIVE_B_29_ACT")
	)
	(segment
		(start 164.519864 -293.1541)
		(end 164.519864 -297.252136)
		(width 0.12065)
		(layer "In4.Cu")
		(net "DRIVE_B_29_ACT")
	)
	(segment
		(start 229.610158 -379.455172)
		(end 227.00107 -376.846084)
		(width 0.12065)
		(layer "In4.Cu")
		(net "DRIVE_B_29_ACT")
	)
	(segment
		(start 163.195 -306.451)
		(end 170.942 -314.198)
		(width 0.12065)
		(layer "In4.Cu")
		(net "DRIVE_B_29_ACT")
	)
	(segment
		(start 229.224078 -357.621078)
		(end 227.6094 -356.0064)
		(width 0.12065)
		(layer "In4.Cu")
		(net "DRIVE_B_29_ACT")
	)
	(segment
		(start 163.195 -298.577)
		(end 163.195 -306.451)
		(width 0.12065)
		(layer "In4.Cu")
		(net "DRIVE_B_29_ACT")
	)
	(segment
		(start 170.942 -314.198)
		(end 170.942 -343.9414)
		(width 0.12065)
		(layer "In4.Cu")
		(net "DRIVE_B_29_ACT")
	)
	(segment
		(start 225.17735 -371.69725)
		(end 225.193606 -371.69725)
		(width 0.17145)
		(layer "F.Cu")
		(net "DRIVE_B_28_FLT_LED")
	)
	(segment
		(start 203.317348 -373.184674)
		(end 203.885546 -373.752872)
		(width 0.17145)
		(layer "F.Cu")
		(net "DRIVE_B_28_FLT_LED")
	)
	(segment
		(start 203.885546 -373.752872)
		(end 207.978502 -373.752872)
		(width 0.17145)
		(layer "F.Cu")
		(net "DRIVE_B_28_FLT_LED")
	)
	(segment
		(start 131.404868 -301.155354)
		(end 132.550408 -301.155354)
		(width 0.17145)
		(layer "F.Cu")
		(net "DRIVE_B_28_FLT_LED")
	)
	(segment
		(start 131.404868 -302.612044)
		(end 131.404868 -301.155354)
		(width 0.17145)
		(layer "F.Cu")
		(net "DRIVE_B_28_FLT_LED")
	)
	(segment
		(start 227.254054 -369.636802)
		(end 227.254054 -368.315494)
		(width 0.17145)
		(layer "F.Cu")
		(net "DRIVE_B_28_FLT_LED")
	)
	(segment
		(start 207.978502 -373.752872)
		(end 209.945224 -371.78615)
		(width 0.17145)
		(layer "F.Cu")
		(net "DRIVE_B_28_FLT_LED")
	)
	(segment
		(start 132.550408 -301.155354)
		(end 132.808218 -301.413164)
		(width 0.17145)
		(layer "F.Cu")
		(net "DRIVE_B_28_FLT_LED")
	)
	(segment
		(start 209.945224 -371.78615)
		(end 209.95005 -371.78615)
		(width 0.17145)
		(layer "F.Cu")
		(net "DRIVE_B_28_FLT_LED")
	)
	(segment
		(start 225.1329 -371.7417)
		(end 225.17735 -371.69725)
		(width 0.17145)
		(layer "F.Cu")
		(net "DRIVE_B_28_FLT_LED")
	)
	(segment
		(start 225.193606 -371.69725)
		(end 227.254054 -369.636802)
		(width 0.17145)
		(layer "F.Cu")
		(net "DRIVE_B_28_FLT_LED")
	)
	(segment
		(start 209.95005 -371.78615)
		(end 209.9945 -371.7417)
		(width 0.17145)
		(layer "F.Cu")
		(net "DRIVE_B_28_FLT_LED")
	)
	(segment
		(start 132.808218 -301.413164)
		(end 132.808218 -302.332136)
		(width 0.17145)
		(layer "F.Cu")
		(net "DRIVE_B_28_FLT_LED")
	)
	(segment
		(start 209.9945 -371.7417)
		(end 225.1329 -371.7417)
		(width 0.17145)
		(layer "F.Cu")
		(net "DRIVE_B_28_FLT_LED")
	)
	(segment
		(start 131.734052 -302.941228)
		(end 131.404868 -302.612044)
		(width 0.17145)
		(layer "F.Cu")
		(net "DRIVE_B_28_FLT_LED")
	)
	(via
		(at 132.808218 -312.698638)
		(size 0.5588)
		(drill 0.3048)
		(layers "F.Cu" "B.Cu")
		(net "DRIVE_B_28_FLT_LED")
	)
	(via
		(at 131.404868 -301.155354)
		(size 0.6604)
		(drill 0.3302)
		(layers "F.Cu" "B.Cu")
		(net "DRIVE_B_28_FLT_LED")
	)
	(via
		(at 203.317348 -373.184674)
		(size 0.5588)
		(drill 0.3048)
		(layers "F.Cu" "B.Cu")
		(net "DRIVE_B_28_FLT_LED")
	)
	(via
		(at 132.808218 -302.332136)
		(size 0.5588)
		(drill 0.3048)
		(layers "F.Cu" "B.Cu")
		(net "DRIVE_B_28_FLT_LED")
	)
	(via
		(at 182.993284 -321.926458)
		(size 0.5588)
		(drill 0.3048)
		(layers "F.Cu" "B.Cu")
		(net "DRIVE_B_28_FLT_LED")
	)
	(segment
		(start 132.808218 -312.698638)
		(end 166.32809 -312.698638)
		(width 0.13335)
		(layer "In2.Cu")
		(net "DRIVE_B_28_FLT_LED")
	)
	(segment
		(start 175.55591 -321.926458)
		(end 182.993284 -321.926458)
		(width 0.13335)
		(layer "In2.Cu")
		(net "DRIVE_B_28_FLT_LED")
	)
	(segment
		(start 166.32809 -312.698638)
		(end 175.55591 -321.926458)
		(width 0.13335)
		(layer "In2.Cu")
		(net "DRIVE_B_28_FLT_LED")
	)
	(segment
		(start 202.696572 -347.549724)
		(end 202.696572 -372.563898)
		(width 0.12065)
		(layer "In4.Cu")
		(net "DRIVE_B_28_FLT_LED")
	)
	(segment
		(start 202.696572 -372.563898)
		(end 203.317348 -373.184674)
		(width 0.12065)
		(layer "In4.Cu")
		(net "DRIVE_B_28_FLT_LED")
	)
	(segment
		(start 197.028308 -342.582246)
		(end 197.729094 -342.582246)
		(width 0.12065)
		(layer "In4.Cu")
		(net "DRIVE_B_28_FLT_LED")
	)
	(segment
		(start 132.808218 -312.698638)
		(end 132.808218 -302.332136)
		(width 0.12065)
		(layer "In4.Cu")
		(net "DRIVE_B_28_FLT_LED")
	)
	(segment
		(start 197.729094 -342.582246)
		(end 202.696572 -347.549724)
		(width 0.12065)
		(layer "In4.Cu")
		(net "DRIVE_B_28_FLT_LED")
	)
	(segment
		(start 182.993284 -328.547222)
		(end 197.028308 -342.582246)
		(width 0.12065)
		(layer "In4.Cu")
		(net "DRIVE_B_28_FLT_LED")
	)
	(segment
		(start 182.993284 -321.926458)
		(end 182.993284 -328.547222)
		(width 0.12065)
		(layer "In4.Cu")
		(net "DRIVE_B_28_FLT_LED")
	)
	(segment
		(start 132.842254 -294.908732)
		(end 133.306312 -294.444674)
		(width 0.17145)
		(layer "F.Cu")
		(net "DRIVE_B_28_ACT")
	)
	(segment
		(start 131.768342 -296.497248)
		(end 131.81965 -296.44594)
		(width 0.17145)
		(layer "F.Cu")
		(net "DRIVE_B_28_ACT")
	)
	(segment
		(start 131.768342 -297.844464)
		(end 131.768342 -296.497248)
		(width 0.17145)
		(layer "F.Cu")
		(net "DRIVE_B_28_ACT")
	)
	(segment
		(start 132.842254 -295.423336)
		(end 132.842254 -294.908732)
		(width 0.17145)
		(layer "F.Cu")
		(net "DRIVE_B_28_ACT")
	)
	(segment
		(start 131.81965 -296.44594)
		(end 132.842254 -295.423336)
		(width 0.17145)
		(layer "F.Cu")
		(net "DRIVE_B_28_ACT")
	)
	(via
		(at 227.6348 -356.9462)
		(size 0.5588)
		(drill 0.3048)
		(layers "F.Cu" "B.Cu")
		(net "DRIVE_B_28_ACT")
	)
	(via
		(at 131.81965 -296.44594)
		(size 0.6604)
		(drill 0.3302)
		(layers "F.Cu" "B.Cu")
		(net "DRIVE_B_28_ACT")
	)
	(via
		(at 133.306312 -294.444674)
		(size 0.5588)
		(drill 0.3048)
		(layers "F.Cu" "B.Cu")
		(net "DRIVE_B_28_ACT")
	)
	(via
		(at 131.672838 -345.44)
		(size 0.5588)
		(drill 0.3048)
		(layers "F.Cu" "B.Cu")
		(net "DRIVE_B_28_ACT")
	)
	(segment
		(start 134.874 -345.44)
		(end 136.017 -346.583)
		(width 0.13335)
		(layer "In2.Cu")
		(net "DRIVE_B_28_ACT")
	)
	(segment
		(start 225.581972 -354.893372)
		(end 227.6348 -356.9462)
		(width 0.13335)
		(layer "In2.Cu")
		(net "DRIVE_B_28_ACT")
	)
	(segment
		(start 131.672838 -345.44)
		(end 134.874 -345.44)
		(width 0.13335)
		(layer "In2.Cu")
		(net "DRIVE_B_28_ACT")
	)
	(segment
		(start 209.969608 -346.583)
		(end 218.27998 -354.893372)
		(width 0.13335)
		(layer "In2.Cu")
		(net "DRIVE_B_28_ACT")
	)
	(segment
		(start 136.017 -346.583)
		(end 209.969608 -346.583)
		(width 0.13335)
		(layer "In2.Cu")
		(net "DRIVE_B_28_ACT")
	)
	(segment
		(start 218.27998 -354.893372)
		(end 225.581972 -354.893372)
		(width 0.13335)
		(layer "In2.Cu")
		(net "DRIVE_B_28_ACT")
	)
	(segment
		(start 131.673346 -345.439492)
		(end 131.672838 -345.44)
		(width 0.12065)
		(layer "In4.Cu")
		(net "DRIVE_B_28_ACT")
	)
	(segment
		(start 228.0412 -378.676662)
		(end 226.44227 -377.077732)
		(width 0.12065)
		(layer "In4.Cu")
		(net "DRIVE_B_28_ACT")
	)
	(segment
		(start 133.306312 -294.444674)
		(end 134.36981 -295.508172)
		(width 0.12065)
		(layer "In4.Cu")
		(net "DRIVE_B_28_ACT")
	)
	(segment
		(start 131.673346 -316.074806)
		(end 131.673346 -345.439492)
		(width 0.12065)
		(layer "In4.Cu")
		(net "DRIVE_B_28_ACT")
	)
	(segment
		(start 134.36981 -313.378342)
		(end 131.673346 -316.074806)
		(width 0.12065)
		(layer "In4.Cu")
		(net "DRIVE_B_28_ACT")
	)
	(segment
		(start 228.665278 -357.976678)
		(end 227.6348 -356.9462)
		(width 0.12065)
		(layer "In4.Cu")
		(net "DRIVE_B_28_ACT")
	)
	(segment
		(start 134.36981 -295.508172)
		(end 134.36981 -313.378342)
		(width 0.12065)
		(layer "In4.Cu")
		(net "DRIVE_B_28_ACT")
	)
	(segment
		(start 228.0412 -391.690352)
		(end 228.0412 -378.676662)
		(width 0.12065)
		(layer "In4.Cu")
		(net "DRIVE_B_28_ACT")
	)
	(segment
		(start 226.822 -398.9451)
		(end 227.64496 -398.12214)
		(width 0.12065)
		(layer "In4.Cu")
		(net "DRIVE_B_28_ACT")
	)
	(segment
		(start 229.80015 -414.200086)
		(end 229.116382 -413.516318)
		(width 0.12065)
		(layer "In4.Cu")
		(net "DRIVE_B_28_ACT")
	)
	(segment
		(start 227.64496 -392.086592)
		(end 228.0412 -391.690352)
		(width 0.12065)
		(layer "In4.Cu")
		(net "DRIVE_B_28_ACT")
	)
	(segment
		(start 226.44227 -377.077732)
		(end 226.44227 -368.616738)
		(width 0.12065)
		(layer "In4.Cu")
		(net "DRIVE_B_28_ACT")
	)
	(segment
		(start 228.665278 -366.39373)
		(end 228.665278 -357.976678)
		(width 0.12065)
		(layer "In4.Cu")
		(net "DRIVE_B_28_ACT")
	)
	(segment
		(start 226.44227 -368.616738)
		(end 228.665278 -366.39373)
		(width 0.12065)
		(layer "In4.Cu")
		(net "DRIVE_B_28_ACT")
	)
	(segment
		(start 229.116382 -402.869908)
		(end 226.822 -400.575526)
		(width 0.12065)
		(layer "In4.Cu")
		(net "DRIVE_B_28_ACT")
	)
	(segment
		(start 229.116382 -413.516318)
		(end 229.116382 -402.869908)
		(width 0.12065)
		(layer "In4.Cu")
		(net "DRIVE_B_28_ACT")
	)
	(segment
		(start 226.822 -400.575526)
		(end 226.822 -398.9451)
		(width 0.12065)
		(layer "In4.Cu")
		(net "DRIVE_B_28_ACT")
	)
	(segment
		(start 227.64496 -398.12214)
		(end 227.64496 -392.086592)
		(width 0.12065)
		(layer "In4.Cu")
		(net "DRIVE_B_28_ACT")
	)
	(segment
		(start 99.816158 -302.56226)
		(end 99.816158 -301.23003)
		(width 0.17145)
		(layer "F.Cu")
		(net "DRIVE_B_27_FLT_LED")
	)
	(segment
		(start 99.816158 -301.23003)
		(end 100.053394 -300.992794)
		(width 0.17145)
		(layer "F.Cu")
		(net "DRIVE_B_27_FLT_LED")
	)
	(segment
		(start 224.9805 -371.1829)
		(end 226.603814 -369.559586)
		(width 0.17145)
		(layer "F.Cu")
		(net "DRIVE_B_27_FLT_LED")
	)
	(segment
		(start 209.6389 -371.1829)
		(end 224.9805 -371.1829)
		(width 0.17145)
		(layer "F.Cu")
		(net "DRIVE_B_27_FLT_LED")
	)
	(segment
		(start 101.321362 -300.992794)
		(end 101.321362 -301.823882)
		(width 0.17145)
		(layer "F.Cu")
		(net "DRIVE_B_27_FLT_LED")
	)
	(segment
		(start 203.4286 -372.169436)
		(end 204.453236 -373.194072)
		(width 0.17145)
		(layer "F.Cu")
		(net "DRIVE_B_27_FLT_LED")
	)
	(segment
		(start 100.205794 -302.951896)
		(end 99.816158 -302.56226)
		(width 0.17145)
		(layer "F.Cu")
		(net "DRIVE_B_27_FLT_LED")
	)
	(segment
		(start 101.321362 -301.823882)
		(end 101.225858 -301.919386)
		(width 0.17145)
		(layer "F.Cu")
		(net "DRIVE_B_27_FLT_LED")
	)
	(segment
		(start 204.453236 -373.194072)
		(end 207.627728 -373.194072)
		(width 0.17145)
		(layer "F.Cu")
		(net "DRIVE_B_27_FLT_LED")
	)
	(segment
		(start 226.603814 -369.559586)
		(end 226.603814 -368.315494)
		(width 0.17145)
		(layer "F.Cu")
		(net "DRIVE_B_27_FLT_LED")
	)
	(segment
		(start 100.053394 -300.992794)
		(end 101.321362 -300.992794)
		(width 0.17145)
		(layer "F.Cu")
		(net "DRIVE_B_27_FLT_LED")
	)
	(segment
		(start 207.627728 -373.194072)
		(end 209.6389 -371.1829)
		(width 0.17145)
		(layer "F.Cu")
		(net "DRIVE_B_27_FLT_LED")
	)
	(via
		(at 101.225858 -313.267344)
		(size 0.5588)
		(drill 0.3048)
		(layers "F.Cu" "B.Cu")
		(net "DRIVE_B_27_FLT_LED")
	)
	(via
		(at 203.4286 -372.169436)
		(size 0.5588)
		(drill 0.3048)
		(layers "F.Cu" "B.Cu")
		(net "DRIVE_B_27_FLT_LED")
	)
	(via
		(at 99.816158 -301.23003)
		(size 0.6604)
		(drill 0.3302)
		(layers "F.Cu" "B.Cu")
		(net "DRIVE_B_27_FLT_LED")
	)
	(via
		(at 101.225858 -301.919386)
		(size 0.5588)
		(drill 0.3048)
		(layers "F.Cu" "B.Cu")
		(net "DRIVE_B_27_FLT_LED")
	)
	(via
		(at 183.58866 -322.721478)
		(size 0.5588)
		(drill 0.3048)
		(layers "F.Cu" "B.Cu")
		(net "DRIVE_B_27_FLT_LED")
	)
	(segment
		(start 166.106348 -313.267344)
		(end 175.560482 -322.721478)
		(width 0.13335)
		(layer "In2.Cu")
		(net "DRIVE_B_27_FLT_LED")
	)
	(segment
		(start 101.225858 -313.267344)
		(end 166.106348 -313.267344)
		(width 0.13335)
		(layer "In2.Cu")
		(net "DRIVE_B_27_FLT_LED")
	)
	(segment
		(start 175.560482 -322.721478)
		(end 183.58866 -322.721478)
		(width 0.13335)
		(layer "In2.Cu")
		(net "DRIVE_B_27_FLT_LED")
	)
	(segment
		(start 183.58866 -322.721478)
		(end 183.58866 -328.351896)
		(width 0.12065)
		(layer "In4.Cu")
		(net "DRIVE_B_27_FLT_LED")
	)
	(segment
		(start 183.58866 -328.351896)
		(end 197.26021 -342.023446)
		(width 0.12065)
		(layer "In4.Cu")
		(net "DRIVE_B_27_FLT_LED")
	)
	(segment
		(start 101.225858 -301.919386)
		(end 101.225858 -313.267344)
		(width 0.12065)
		(layer "In4.Cu")
		(net "DRIVE_B_27_FLT_LED")
	)
	(segment
		(start 197.26021 -342.023446)
		(end 197.960742 -342.023446)
		(width 0.12065)
		(layer "In4.Cu")
		(net "DRIVE_B_27_FLT_LED")
	)
	(segment
		(start 197.960742 -342.023446)
		(end 203.255372 -347.318076)
		(width 0.12065)
		(layer "In4.Cu")
		(net "DRIVE_B_27_FLT_LED")
	)
	(segment
		(start 203.255372 -347.318076)
		(end 203.255372 -371.996208)
		(width 0.12065)
		(layer "In4.Cu")
		(net "DRIVE_B_27_FLT_LED")
	)
	(segment
		(start 203.255372 -371.996208)
		(end 203.4286 -372.169436)
		(width 0.12065)
		(layer "In4.Cu")
		(net "DRIVE_B_27_FLT_LED")
	)
	(segment
		(start 99.751896 -296.195242)
		(end 98.823018 -297.12412)
		(width 0.17145)
		(layer "F.Cu")
		(net "DRIVE_B_27_ACT")
	)
	(segment
		(start 100.179124 -297.57243)
		(end 100.179124 -296.375074)
		(width 0.17145)
		(layer "F.Cu")
		(net "DRIVE_B_27_ACT")
	)
	(segment
		(start 98.715576 -297.231562)
		(end 97.330514 -297.231562)
		(width 0.17145)
		(layer "F.Cu")
		(net "DRIVE_B_27_ACT")
	)
	(segment
		(start 100.179124 -296.375074)
		(end 99.999292 -296.195242)
		(width 0.17145)
		(layer "F.Cu")
		(net "DRIVE_B_27_ACT")
	)
	(segment
		(start 99.999292 -296.195242)
		(end 99.751896 -296.195242)
		(width 0.17145)
		(layer "F.Cu")
		(net "DRIVE_B_27_ACT")
	)
	(segment
		(start 98.823018 -297.12412)
		(end 98.715576 -297.231562)
		(width 0.17145)
		(layer "F.Cu")
		(net "DRIVE_B_27_ACT")
	)
	(via
		(at 105.517188 -343.408)
		(size 0.5588)
		(drill 0.3048)
		(layers "F.Cu" "B.Cu")
		(net "DRIVE_B_27_ACT")
	)
	(via
		(at 97.330514 -297.231562)
		(size 0.5588)
		(drill 0.3048)
		(layers "F.Cu" "B.Cu")
		(net "DRIVE_B_27_ACT")
	)
	(via
		(at 99.999292 -296.195242)
		(size 0.6604)
		(drill 0.3302)
		(layers "F.Cu" "B.Cu")
		(net "DRIVE_B_27_ACT")
	)
	(via
		(at 227.9396 -399.796)
		(size 0.5588)
		(drill 0.3048)
		(layers "F.Cu" "B.Cu")
		(net "DRIVE_B_27_ACT")
	)
	(via
		(at 227.6348 -355.0666)
		(size 0.5588)
		(drill 0.3048)
		(layers "F.Cu" "B.Cu")
		(net "DRIVE_B_27_ACT")
	)
	(segment
		(start 129.780538 -344.837004)
		(end 138.306556 -344.837004)
		(width 0.13335)
		(layer "In2.Cu")
		(net "DRIVE_B_27_ACT")
	)
	(segment
		(start 139.442952 -345.9734)
		(end 167.304466 -345.9734)
		(width 0.13335)
		(layer "In2.Cu")
		(net "DRIVE_B_27_ACT")
	)
	(segment
		(start 169.895266 -343.3826)
		(end 208.350104 -343.3826)
		(width 0.13335)
		(layer "In2.Cu")
		(net "DRIVE_B_27_ACT")
	)
	(segment
		(start 105.517188 -343.408)
		(end 128.351534 -343.408)
		(width 0.13335)
		(layer "In2.Cu")
		(net "DRIVE_B_27_ACT")
	)
	(segment
		(start 226.314 -353.7458)
		(end 227.6348 -355.0666)
		(width 0.13335)
		(layer "In2.Cu")
		(net "DRIVE_B_27_ACT")
	)
	(segment
		(start 167.304466 -345.9734)
		(end 169.895266 -343.3826)
		(width 0.13335)
		(layer "In2.Cu")
		(net "DRIVE_B_27_ACT")
	)
	(segment
		(start 218.713304 -353.7458)
		(end 226.314 -353.7458)
		(width 0.13335)
		(layer "In2.Cu")
		(net "DRIVE_B_27_ACT")
	)
	(segment
		(start 128.351534 -343.408)
		(end 129.780538 -344.837004)
		(width 0.13335)
		(layer "In2.Cu")
		(net "DRIVE_B_27_ACT")
	)
	(segment
		(start 138.306556 -344.837004)
		(end 139.442952 -345.9734)
		(width 0.13335)
		(layer "In2.Cu")
		(net "DRIVE_B_27_ACT")
	)
	(segment
		(start 208.350104 -343.3826)
		(end 218.713304 -353.7458)
		(width 0.13335)
		(layer "In2.Cu")
		(net "DRIVE_B_27_ACT")
	)
	(segment
		(start 227.55987 -369.080034)
		(end 229.782878 -366.857026)
		(width 0.12065)
		(layer "In4.Cu")
		(net "DRIVE_B_27_ACT")
	)
	(segment
		(start 228.80574 -392.506708)
		(end 230.168958 -391.14349)
		(width 0.12065)
		(layer "In4.Cu")
		(net "DRIVE_B_27_ACT")
	)
	(segment
		(start 100.61829 -302.63338)
		(end 100.61829 -314.813442)
		(width 0.12065)
		(layer "In4.Cu")
		(net "DRIVE_B_27_ACT")
	)
	(segment
		(start 229.782878 -366.857026)
		(end 229.782878 -357.214678)
		(width 0.12065)
		(layer "In4.Cu")
		(net "DRIVE_B_27_ACT")
	)
	(segment
		(start 228.80574 -398.92986)
		(end 228.80574 -392.506708)
		(width 0.12065)
		(layer "In4.Cu")
		(net "DRIVE_B_27_ACT")
	)
	(segment
		(start 105.517188 -319.71234)
		(end 105.517188 -343.408)
		(width 0.12065)
		(layer "In4.Cu")
		(net "DRIVE_B_27_ACT")
	)
	(segment
		(start 98.657664 -298.558712)
		(end 98.657664 -300.672754)
		(width 0.12065)
		(layer "In4.Cu")
		(net "DRIVE_B_27_ACT")
	)
	(segment
		(start 98.657664 -300.672754)
		(end 100.61829 -302.63338)
		(width 0.12065)
		(layer "In4.Cu")
		(net "DRIVE_B_27_ACT")
	)
	(segment
		(start 230.168958 -391.14349)
		(end 230.168958 -379.223524)
		(width 0.12065)
		(layer "In4.Cu")
		(net "DRIVE_B_27_ACT")
	)
	(segment
		(start 229.782878 -357.214678)
		(end 227.6348 -355.0666)
		(width 0.12065)
		(layer "In4.Cu")
		(net "DRIVE_B_27_ACT")
	)
	(segment
		(start 100.61829 -314.813442)
		(end 105.517188 -319.71234)
		(width 0.12065)
		(layer "In4.Cu")
		(net "DRIVE_B_27_ACT")
	)
	(segment
		(start 227.55987 -376.614436)
		(end 227.55987 -369.080034)
		(width 0.12065)
		(layer "In4.Cu")
		(net "DRIVE_B_27_ACT")
	)
	(segment
		(start 97.330514 -297.231562)
		(end 98.657664 -298.558712)
		(width 0.12065)
		(layer "In4.Cu")
		(net "DRIVE_B_27_ACT")
	)
	(segment
		(start 227.9396 -399.796)
		(end 228.80574 -398.92986)
		(width 0.12065)
		(layer "In4.Cu")
		(net "DRIVE_B_27_ACT")
	)
	(segment
		(start 230.168958 -379.223524)
		(end 227.55987 -376.614436)
		(width 0.12065)
		(layer "In4.Cu")
		(net "DRIVE_B_27_ACT")
	)
	(segment
		(start 230.5812 -414.819084)
		(end 230.5812 -402.4376)
		(width 0.13335)
		(layer "In9.Cu")
		(net "DRIVE_B_27_ACT")
	)
	(segment
		(start 229.80015 -415.600134)
		(end 230.5812 -414.819084)
		(width 0.13335)
		(layer "In9.Cu")
		(net "DRIVE_B_27_ACT")
	)
	(segment
		(start 230.5812 -402.4376)
		(end 227.9396 -399.796)
		(width 0.13335)
		(layer "In9.Cu")
		(net "DRIVE_B_27_ACT")
	)
	(segment
		(start 68.193412 -302.478948)
		(end 68.193412 -301.374048)
		(width 0.17145)
		(layer "F.Cu")
		(net "DRIVE_B_26_FLT_LED")
	)
	(segment
		(start 225.953574 -369.397026)
		(end 224.7265 -370.6241)
		(width 0.17145)
		(layer "F.Cu")
		(net "DRIVE_B_26_FLT_LED")
	)
	(segment
		(start 203.817982 -371.772688)
		(end 203.817982 -371.251226)
		(width 0.17145)
		(layer "F.Cu")
		(net "DRIVE_B_26_FLT_LED")
	)
	(segment
		(start 209.3849 -370.6241)
		(end 207.373728 -372.635272)
		(width 0.17145)
		(layer "F.Cu")
		(net "DRIVE_B_26_FLT_LED")
	)
	(segment
		(start 224.7265 -370.6241)
		(end 209.3849 -370.6241)
		(width 0.17145)
		(layer "F.Cu")
		(net "DRIVE_B_26_FLT_LED")
	)
	(segment
		(start 68.66636 -302.951896)
		(end 68.193412 -302.478948)
		(width 0.17145)
		(layer "F.Cu")
		(net "DRIVE_B_26_FLT_LED")
	)
	(segment
		(start 69.760084 -300.816772)
		(end 69.403722 -300.46041)
		(width 0.17145)
		(layer "F.Cu")
		(net "DRIVE_B_26_FLT_LED")
	)
	(segment
		(start 69.760084 -301.29988)
		(end 69.760084 -300.816772)
		(width 0.17145)
		(layer "F.Cu")
		(net "DRIVE_B_26_FLT_LED")
	)
	(segment
		(start 204.680566 -372.635272)
		(end 203.817982 -371.772688)
		(width 0.17145)
		(layer "F.Cu")
		(net "DRIVE_B_26_FLT_LED")
	)
	(segment
		(start 207.373728 -372.635272)
		(end 204.680566 -372.635272)
		(width 0.17145)
		(layer "F.Cu")
		(net "DRIVE_B_26_FLT_LED")
	)
	(segment
		(start 68.26758 -301.29988)
		(end 69.760084 -301.29988)
		(width 0.17145)
		(layer "F.Cu")
		(net "DRIVE_B_26_FLT_LED")
	)
	(segment
		(start 225.953574 -368.315494)
		(end 225.953574 -369.397026)
		(width 0.17145)
		(layer "F.Cu")
		(net "DRIVE_B_26_FLT_LED")
	)
	(segment
		(start 68.193412 -301.374048)
		(end 68.26758 -301.29988)
		(width 0.17145)
		(layer "F.Cu")
		(net "DRIVE_B_26_FLT_LED")
	)
	(via
		(at 68.193412 -301.374048)
		(size 0.6604)
		(drill 0.3302)
		(layers "F.Cu" "B.Cu")
		(net "DRIVE_B_26_FLT_LED")
	)
	(via
		(at 184.322212 -323.290946)
		(size 0.5588)
		(drill 0.3048)
		(layers "F.Cu" "B.Cu")
		(net "DRIVE_B_26_FLT_LED")
	)
	(via
		(at 69.403722 -300.46041)
		(size 0.5588)
		(drill 0.3048)
		(layers "F.Cu" "B.Cu")
		(net "DRIVE_B_26_FLT_LED")
	)
	(via
		(at 70.1294 -312.1914)
		(size 0.5588)
		(drill 0.3048)
		(layers "F.Cu" "B.Cu")
		(net "DRIVE_B_26_FLT_LED")
	)
	(via
		(at 203.817982 -371.251226)
		(size 0.5588)
		(drill 0.3048)
		(layers "F.Cu" "B.Cu")
		(net "DRIVE_B_26_FLT_LED")
	)
	(segment
		(start 70.1294 -312.1914)
		(end 71.764144 -313.826144)
		(width 0.13335)
		(layer "In2.Cu")
		(net "DRIVE_B_26_FLT_LED")
	)
	(segment
		(start 165.820344 -313.826144)
		(end 175.285146 -323.290946)
		(width 0.13335)
		(layer "In2.Cu")
		(net "DRIVE_B_26_FLT_LED")
	)
	(segment
		(start 175.285146 -323.290946)
		(end 184.322212 -323.290946)
		(width 0.13335)
		(layer "In2.Cu")
		(net "DRIVE_B_26_FLT_LED")
	)
	(segment
		(start 71.764144 -313.826144)
		(end 165.820344 -313.826144)
		(width 0.13335)
		(layer "In2.Cu")
		(net "DRIVE_B_26_FLT_LED")
	)
	(segment
		(start 203.814172 -347.086428)
		(end 203.814172 -371.247416)
		(width 0.12065)
		(layer "In4.Cu")
		(net "DRIVE_B_26_FLT_LED")
	)
	(segment
		(start 184.34431 -328.316844)
		(end 197.492112 -341.464646)
		(width 0.12065)
		(layer "In4.Cu")
		(net "DRIVE_B_26_FLT_LED")
	)
	(segment
		(start 198.19239 -341.464646)
		(end 203.814172 -347.086428)
		(width 0.12065)
		(layer "In4.Cu")
		(net "DRIVE_B_26_FLT_LED")
	)
	(segment
		(start 197.492112 -341.464646)
		(end 198.19239 -341.464646)
		(width 0.12065)
		(layer "In4.Cu")
		(net "DRIVE_B_26_FLT_LED")
	)
	(segment
		(start 203.814172 -371.247416)
		(end 203.817982 -371.251226)
		(width 0.12065)
		(layer "In4.Cu")
		(net "DRIVE_B_26_FLT_LED")
	)
	(segment
		(start 69.403722 -311.465722)
		(end 70.1294 -312.1914)
		(width 0.12065)
		(layer "In4.Cu")
		(net "DRIVE_B_26_FLT_LED")
	)
	(segment
		(start 184.322212 -323.290946)
		(end 184.34431 -323.313044)
		(width 0.12065)
		(layer "In4.Cu")
		(net "DRIVE_B_26_FLT_LED")
	)
	(segment
		(start 184.34431 -323.313044)
		(end 184.34431 -328.316844)
		(width 0.12065)
		(layer "In4.Cu")
		(net "DRIVE_B_26_FLT_LED")
	)
	(segment
		(start 69.403722 -300.46041)
		(end 69.403722 -311.465722)
		(width 0.12065)
		(layer "In4.Cu")
		(net "DRIVE_B_26_FLT_LED")
	)
	(segment
		(start 69.869304 -294.191182)
		(end 69.872098 -294.193976)
		(width 0.17145)
		(layer "F.Cu")
		(net "DRIVE_B_26_ACT")
	)
	(segment
		(start 69.872098 -294.193976)
		(end 69.872098 -295.460674)
		(width 0.17145)
		(layer "F.Cu")
		(net "DRIVE_B_26_ACT")
	)
	(segment
		(start 69.872098 -296.02049)
		(end 69.872098 -295.460674)
		(width 0.17145)
		(layer "F.Cu")
		(net "DRIVE_B_26_ACT")
	)
	(segment
		(start 69.94779 -292.759384)
		(end 69.869304 -292.83787)
		(width 0.17145)
		(layer "F.Cu")
		(net "DRIVE_B_26_ACT")
	)
	(segment
		(start 69.869304 -292.83787)
		(end 69.869304 -294.191182)
		(width 0.17145)
		(layer "F.Cu")
		(net "DRIVE_B_26_ACT")
	)
	(segment
		(start 68.62572 -297.266868)
		(end 69.872098 -296.02049)
		(width 0.17145)
		(layer "F.Cu")
		(net "DRIVE_B_26_ACT")
	)
	(via
		(at 72.6694 -342.813386)
		(size 0.5588)
		(drill 0.3048)
		(layers "F.Cu" "B.Cu")
		(net "DRIVE_B_26_ACT")
	)
	(via
		(at 69.872098 -295.460674)
		(size 0.6604)
		(drill 0.3302)
		(layers "F.Cu" "B.Cu")
		(net "DRIVE_B_26_ACT")
	)
	(via
		(at 227.6094 -354.0252)
		(size 0.5588)
		(drill 0.3048)
		(layers "F.Cu" "B.Cu")
		(net "DRIVE_B_26_ACT")
	)
	(via
		(at 69.94779 -292.759384)
		(size 0.5588)
		(drill 0.3048)
		(layers "F.Cu" "B.Cu")
		(net "DRIVE_B_26_ACT")
	)
	(segment
		(start 218.944952 -353.187)
		(end 226.7712 -353.187)
		(width 0.13335)
		(layer "In2.Cu")
		(net "DRIVE_B_26_ACT")
	)
	(segment
		(start 208.581752 -342.8238)
		(end 218.944952 -353.187)
		(width 0.13335)
		(layer "In2.Cu")
		(net "DRIVE_B_26_ACT")
	)
	(segment
		(start 169.663618 -342.8238)
		(end 208.581752 -342.8238)
		(width 0.13335)
		(layer "In2.Cu")
		(net "DRIVE_B_26_ACT")
	)
	(segment
		(start 167.072818 -345.4146)
		(end 169.663618 -342.8238)
		(width 0.13335)
		(layer "In2.Cu")
		(net "DRIVE_B_26_ACT")
	)
	(segment
		(start 226.7712 -353.187)
		(end 227.6094 -354.0252)
		(width 0.13335)
		(layer "In2.Cu")
		(net "DRIVE_B_26_ACT")
	)
	(segment
		(start 139.6746 -345.4146)
		(end 167.072818 -345.4146)
		(width 0.13335)
		(layer "In2.Cu")
		(net "DRIVE_B_26_ACT")
	)
	(segment
		(start 130.012186 -344.278204)
		(end 138.538204 -344.278204)
		(width 0.13335)
		(layer "In2.Cu")
		(net "DRIVE_B_26_ACT")
	)
	(segment
		(start 128.547368 -342.813386)
		(end 130.012186 -344.278204)
		(width 0.13335)
		(layer "In2.Cu")
		(net "DRIVE_B_26_ACT")
	)
	(segment
		(start 72.6694 -342.813386)
		(end 128.547368 -342.813386)
		(width 0.13335)
		(layer "In2.Cu")
		(net "DRIVE_B_26_ACT")
	)
	(segment
		(start 138.538204 -344.278204)
		(end 139.6746 -345.4146)
		(width 0.13335)
		(layer "In2.Cu")
		(net "DRIVE_B_26_ACT")
	)
	(segment
		(start 230.727758 -415.772346)
		(end 230.727758 -378.991876)
		(width 0.12065)
		(layer "In4.Cu")
		(net "DRIVE_B_26_ACT")
	)
	(segment
		(start 72.6186 -342.762586)
		(end 72.6694 -342.813386)
		(width 0.12065)
		(layer "In4.Cu")
		(net "DRIVE_B_26_ACT")
	)
	(segment
		(start 230.727758 -378.991876)
		(end 228.11867 -376.382788)
		(width 0.12065)
		(layer "In4.Cu")
		(net "DRIVE_B_26_ACT")
	)
	(segment
		(start 229.80015 -416.699954)
		(end 230.727758 -415.772346)
		(width 0.12065)
		(layer "In4.Cu")
		(net "DRIVE_B_26_ACT")
	)
	(segment
		(start 228.11867 -376.382788)
		(end 228.11867 -369.311682)
		(width 0.12065)
		(layer "In4.Cu")
		(net "DRIVE_B_26_ACT")
	)
	(segment
		(start 228.11867 -369.311682)
		(end 230.341678 -367.088674)
		(width 0.12065)
		(layer "In4.Cu")
		(net "DRIVE_B_26_ACT")
	)
	(segment
		(start 69.94779 -292.759384)
		(end 69.94779 -295.625266)
		(width 0.12065)
		(layer "In4.Cu")
		(net "DRIVE_B_26_ACT")
	)
	(segment
		(start 71.297038 -296.974514)
		(end 71.297038 -305.231038)
		(width 0.12065)
		(layer "In4.Cu")
		(net "DRIVE_B_26_ACT")
	)
	(segment
		(start 230.341678 -356.757478)
		(end 227.6094 -354.0252)
		(width 0.12065)
		(layer "In4.Cu")
		(net "DRIVE_B_26_ACT")
	)
	(segment
		(start 230.341678 -367.088674)
		(end 230.341678 -356.757478)
		(width 0.12065)
		(layer "In4.Cu")
		(net "DRIVE_B_26_ACT")
	)
	(segment
		(start 69.94779 -295.625266)
		(end 71.297038 -296.974514)
		(width 0.12065)
		(layer "In4.Cu")
		(net "DRIVE_B_26_ACT")
	)
	(segment
		(start 72.6186 -306.5526)
		(end 72.6186 -342.762586)
		(width 0.12065)
		(layer "In4.Cu")
		(net "DRIVE_B_26_ACT")
	)
	(segment
		(start 71.297038 -305.231038)
		(end 72.6186 -306.5526)
		(width 0.12065)
		(layer "In4.Cu")
		(net "DRIVE_B_26_ACT")
	)
	(segment
		(start 36.643056 -301.374048)
		(end 36.717224 -301.29988)
		(width 0.17145)
		(layer "F.Cu")
		(net "DRIVE_B_25_FLT_LED")
	)
	(segment
		(start 209.0801 -370.0653)
		(end 224.4471 -370.0653)
		(width 0.17145)
		(layer "F.Cu")
		(net "DRIVE_B_25_FLT_LED")
	)
	(segment
		(start 36.643056 -302.478948)
		(end 36.643056 -301.374048)
		(width 0.17145)
		(layer "F.Cu")
		(net "DRIVE_B_25_FLT_LED")
	)
	(segment
		(start 36.717224 -301.29988)
		(end 38.209728 -301.29988)
		(width 0.17145)
		(layer "F.Cu")
		(net "DRIVE_B_25_FLT_LED")
	)
	(segment
		(start 225.303334 -369.209066)
		(end 225.303334 -368.315494)
		(width 0.17145)
		(layer "F.Cu")
		(net "DRIVE_B_25_FLT_LED")
	)
	(segment
		(start 204.868272 -371.92585)
		(end 207.21955 -371.92585)
		(width 0.17145)
		(layer "F.Cu")
		(net "DRIVE_B_25_FLT_LED")
	)
	(segment
		(start 37.116004 -302.951896)
		(end 36.643056 -302.478948)
		(width 0.17145)
		(layer "F.Cu")
		(net "DRIVE_B_25_FLT_LED")
	)
	(segment
		(start 38.209728 -300.961552)
		(end 37.670994 -300.422818)
		(width 0.17145)
		(layer "F.Cu")
		(net "DRIVE_B_25_FLT_LED")
	)
	(segment
		(start 207.21955 -371.92585)
		(end 209.0801 -370.0653)
		(width 0.17145)
		(layer "F.Cu")
		(net "DRIVE_B_25_FLT_LED")
	)
	(segment
		(start 224.4471 -370.0653)
		(end 225.303334 -369.209066)
		(width 0.17145)
		(layer "F.Cu")
		(net "DRIVE_B_25_FLT_LED")
	)
	(segment
		(start 38.209728 -301.29988)
		(end 38.209728 -300.961552)
		(width 0.17145)
		(layer "F.Cu")
		(net "DRIVE_B_25_FLT_LED")
	)
	(via
		(at 37.6682 -312.1152)
		(size 0.5588)
		(drill 0.3048)
		(layers "F.Cu" "B.Cu")
		(net "DRIVE_B_25_FLT_LED")
	)
	(via
		(at 37.670994 -300.422818)
		(size 0.5588)
		(drill 0.3048)
		(layers "F.Cu" "B.Cu")
		(net "DRIVE_B_25_FLT_LED")
	)
	(via
		(at 184.956196 -324.005194)
		(size 0.5588)
		(drill 0.3048)
		(layers "F.Cu" "B.Cu")
		(net "DRIVE_B_25_FLT_LED")
	)
	(via
		(at 36.643056 -301.374048)
		(size 0.6604)
		(drill 0.3302)
		(layers "F.Cu" "B.Cu")
		(net "DRIVE_B_25_FLT_LED")
	)
	(via
		(at 204.868272 -371.92585)
		(size 0.5588)
		(drill 0.3048)
		(layers "F.Cu" "B.Cu")
		(net "DRIVE_B_25_FLT_LED")
	)
	(segment
		(start 70.773544 -314.384944)
		(end 68.6308 -312.2422)
		(width 0.13335)
		(layer "In2.Cu")
		(net "DRIVE_B_25_FLT_LED")
	)
	(segment
		(start 37.7952 -312.2422)
		(end 37.6682 -312.1152)
		(width 0.13335)
		(layer "In2.Cu")
		(net "DRIVE_B_25_FLT_LED")
	)
	(segment
		(start 184.956196 -324.005194)
		(end 175.135794 -324.005194)
		(width 0.13335)
		(layer "In2.Cu")
		(net "DRIVE_B_25_FLT_LED")
	)
	(segment
		(start 165.515544 -314.384944)
		(end 70.773544 -314.384944)
		(width 0.13335)
		(layer "In2.Cu")
		(net "DRIVE_B_25_FLT_LED")
	)
	(segment
		(start 68.6308 -312.2422)
		(end 37.7952 -312.2422)
		(width 0.13335)
		(layer "In2.Cu")
		(net "DRIVE_B_25_FLT_LED")
	)
	(segment
		(start 175.135794 -324.005194)
		(end 165.515544 -314.384944)
		(width 0.13335)
		(layer "In2.Cu")
		(net "DRIVE_B_25_FLT_LED")
	)
	(segment
		(start 197.724014 -340.905846)
		(end 198.424038 -340.905846)
		(width 0.12065)
		(layer "In4.Cu")
		(net "DRIVE_B_25_FLT_LED")
	)
	(segment
		(start 184.956196 -328.138028)
		(end 197.724014 -340.905846)
		(width 0.12065)
		(layer "In4.Cu")
		(net "DRIVE_B_25_FLT_LED")
	)
	(segment
		(start 184.956196 -324.005194)
		(end 184.956196 -328.138028)
		(width 0.12065)
		(layer "In4.Cu")
		(net "DRIVE_B_25_FLT_LED")
	)
	(segment
		(start 204.372972 -346.85478)
		(end 204.372972 -371.43055)
		(width 0.12065)
		(layer "In4.Cu")
		(net "DRIVE_B_25_FLT_LED")
	)
	(segment
		(start 198.424038 -340.905846)
		(end 204.372972 -346.85478)
		(width 0.12065)
		(layer "In4.Cu")
		(net "DRIVE_B_25_FLT_LED")
	)
	(segment
		(start 204.372972 -371.43055)
		(end 204.868272 -371.92585)
		(width 0.12065)
		(layer "In4.Cu")
		(net "DRIVE_B_25_FLT_LED")
	)
	(segment
		(start 37.670994 -312.112406)
		(end 37.6682 -312.1152)
		(width 0.12065)
		(layer "In4.Cu")
		(net "DRIVE_B_25_FLT_LED")
	)
	(segment
		(start 37.670994 -300.422818)
		(end 37.670994 -312.112406)
		(width 0.12065)
		(layer "In4.Cu")
		(net "DRIVE_B_25_FLT_LED")
	)
	(segment
		(start 38.320726 -295.458388)
		(end 38.320726 -296.021506)
		(width 0.17145)
		(layer "F.Cu")
		(net "DRIVE_B_25_ACT")
	)
	(segment
		(start 38.320726 -296.021506)
		(end 37.075364 -297.266868)
		(width 0.17145)
		(layer "F.Cu")
		(net "DRIVE_B_25_ACT")
	)
	(segment
		(start 38.318948 -294.191182)
		(end 38.320726 -294.19296)
		(width 0.17145)
		(layer "F.Cu")
		(net "DRIVE_B_25_ACT")
	)
	(segment
		(start 38.318948 -294.191182)
		(end 38.318948 -292.791642)
		(width 0.17145)
		(layer "F.Cu")
		(net "DRIVE_B_25_ACT")
	)
	(segment
		(start 38.320726 -294.19296)
		(end 38.320726 -295.458388)
		(width 0.17145)
		(layer "F.Cu")
		(net "DRIVE_B_25_ACT")
	)
	(via
		(at 41.529 -341.6808)
		(size 0.5588)
		(drill 0.3048)
		(layers "F.Cu" "B.Cu")
		(net "DRIVE_B_25_ACT")
	)
	(via
		(at 38.320726 -295.458388)
		(size 0.6604)
		(drill 0.3302)
		(layers "F.Cu" "B.Cu")
		(net "DRIVE_B_25_ACT")
	)
	(via
		(at 38.318948 -292.791642)
		(size 0.5588)
		(drill 0.3048)
		(layers "F.Cu" "B.Cu")
		(net "DRIVE_B_25_ACT")
	)
	(via
		(at 234.710986 -418.5158)
		(size 0.5588)
		(drill 0.3048)
		(layers "F.Cu" "B.Cu")
		(net "DRIVE_B_25_ACT")
	)
	(via
		(at 227.6348 -352.044)
		(size 0.5588)
		(drill 0.3048)
		(layers "F.Cu" "B.Cu")
		(net "DRIVE_B_25_ACT")
	)
	(segment
		(start 229.80015 -417.800028)
		(end 230.632 -418.631878)
		(width 0.17145)
		(layer "B.Cu")
		(net "DRIVE_B_25_ACT")
	)
	(segment
		(start 230.632 -418.631878)
		(end 230.632 -419.453568)
		(width 0.17145)
		(layer "B.Cu")
		(net "DRIVE_B_25_ACT")
	)
	(segment
		(start 233.161586 -420.0652)
		(end 234.710986 -418.5158)
		(width 0.17145)
		(layer "B.Cu")
		(net "DRIVE_B_25_ACT")
	)
	(segment
		(start 231.243632 -420.0652)
		(end 233.161586 -420.0652)
		(width 0.17145)
		(layer "B.Cu")
		(net "DRIVE_B_25_ACT")
	)
	(segment
		(start 230.632 -419.453568)
		(end 231.243632 -420.0652)
		(width 0.17145)
		(layer "B.Cu")
		(net "DRIVE_B_25_ACT")
	)
	(segment
		(start 209.0928 -341.7062)
		(end 219.4306 -352.044)
		(width 0.13335)
		(layer "In2.Cu")
		(net "DRIVE_B_25_ACT")
	)
	(segment
		(start 219.4306 -352.044)
		(end 227.6348 -352.044)
		(width 0.13335)
		(layer "In2.Cu")
		(net "DRIVE_B_25_ACT")
	)
	(segment
		(start 169.200322 -341.7062)
		(end 209.0928 -341.7062)
		(width 0.13335)
		(layer "In2.Cu")
		(net "DRIVE_B_25_ACT")
	)
	(segment
		(start 129.010664 -341.695786)
		(end 130.475482 -343.160604)
		(width 0.13335)
		(layer "In2.Cu")
		(net "DRIVE_B_25_ACT")
	)
	(segment
		(start 41.543986 -341.695786)
		(end 129.010664 -341.695786)
		(width 0.13335)
		(layer "In2.Cu")
		(net "DRIVE_B_25_ACT")
	)
	(segment
		(start 130.475482 -343.160604)
		(end 139.053316 -343.160604)
		(width 0.13335)
		(layer "In2.Cu")
		(net "DRIVE_B_25_ACT")
	)
	(segment
		(start 41.529 -341.6808)
		(end 41.543986 -341.695786)
		(width 0.13335)
		(layer "In2.Cu")
		(net "DRIVE_B_25_ACT")
	)
	(segment
		(start 166.609522 -344.297)
		(end 169.200322 -341.7062)
		(width 0.13335)
		(layer "In2.Cu")
		(net "DRIVE_B_25_ACT")
	)
	(segment
		(start 139.053316 -343.160604)
		(end 139.235434 -343.342722)
		(width 0.13335)
		(layer "In2.Cu")
		(net "DRIVE_B_25_ACT")
	)
	(segment
		(start 140.189458 -344.297)
		(end 166.609522 -344.297)
		(width 0.13335)
		(layer "In2.Cu")
		(net "DRIVE_B_25_ACT")
	)
	(segment
		(start 139.235434 -343.342722)
		(end 139.235434 -343.342976)
		(width 0.13335)
		(layer "In2.Cu")
		(net "DRIVE_B_25_ACT")
	)
	(segment
		(start 139.235434 -343.342976)
		(end 140.189458 -344.297)
		(width 0.13335)
		(layer "In2.Cu")
		(net "DRIVE_B_25_ACT")
	)
	(segment
		(start 231.845358 -378.52858)
		(end 229.23627 -375.919492)
		(width 0.12065)
		(layer "In4.Cu")
		(net "DRIVE_B_25_ACT")
	)
	(segment
		(start 231.459278 -355.868478)
		(end 227.6348 -352.044)
		(width 0.12065)
		(layer "In4.Cu")
		(net "DRIVE_B_25_ACT")
	)
	(segment
		(start 231.459278 -367.55197)
		(end 231.459278 -355.868478)
		(width 0.12065)
		(layer "In4.Cu")
		(net "DRIVE_B_25_ACT")
	)
	(segment
		(start 229.23627 -375.919492)
		(end 229.23627 -369.774978)
		(width 0.12065)
		(layer "In4.Cu")
		(net "DRIVE_B_25_ACT")
	)
	(segment
		(start 42.164 -341.0458)
		(end 41.529 -341.6808)
		(width 0.12065)
		(layer "In4.Cu")
		(net "DRIVE_B_25_ACT")
	)
	(segment
		(start 229.23627 -369.774978)
		(end 231.459278 -367.55197)
		(width 0.12065)
		(layer "In4.Cu")
		(net "DRIVE_B_25_ACT")
	)
	(segment
		(start 38.318948 -307.558948)
		(end 42.164 -311.404)
		(width 0.12065)
		(layer "In4.Cu")
		(net "DRIVE_B_25_ACT")
	)
	(segment
		(start 234.710986 -393.378436)
		(end 231.845358 -390.512808)
		(width 0.12065)
		(layer "In4.Cu")
		(net "DRIVE_B_25_ACT")
	)
	(segment
		(start 42.164 -311.404)
		(end 42.164 -341.0458)
		(width 0.12065)
		(layer "In4.Cu")
		(net "DRIVE_B_25_ACT")
	)
	(segment
		(start 38.318948 -292.791642)
		(end 38.318948 -307.558948)
		(width 0.12065)
		(layer "In4.Cu")
		(net "DRIVE_B_25_ACT")
	)
	(segment
		(start 234.710986 -418.5158)
		(end 234.710986 -393.378436)
		(width 0.12065)
		(layer "In4.Cu")
		(net "DRIVE_B_25_ACT")
	)
	(segment
		(start 231.845358 -390.512808)
		(end 231.845358 -378.52858)
		(width 0.12065)
		(layer "In4.Cu")
		(net "DRIVE_B_25_ACT")
	)
	(segment
		(start 224.19945 -369.55095)
		(end 208.866994 -369.55095)
		(width 0.17145)
		(layer "F.Cu")
		(net "DRIVE_B_24_FLT_LED")
	)
	(segment
		(start 5.705856 -291.042344)
		(end 5.6134 -291.1348)
		(width 0.17145)
		(layer "F.Cu")
		(net "DRIVE_B_24_FLT_LED")
	)
	(segment
		(start 224.653094 -368.315494)
		(end 224.653094 -369.097306)
		(width 0.17145)
		(layer "F.Cu")
		(net "DRIVE_B_24_FLT_LED")
	)
	(segment
		(start 208.866994 -369.55095)
		(end 207.45196 -370.965984)
		(width 0.17145)
		(layer "F.Cu")
		(net "DRIVE_B_24_FLT_LED")
	)
	(segment
		(start 5.6134 -291.1348)
		(end 5.574284 -291.173916)
		(width 0.17145)
		(layer "F.Cu")
		(net "DRIVE_B_24_FLT_LED")
	)
	(segment
		(start 224.653094 -369.097306)
		(end 224.19945 -369.55095)
		(width 0.17145)
		(layer "F.Cu")
		(net "DRIVE_B_24_FLT_LED")
	)
	(segment
		(start 6.889242 -289.921188)
		(end 6.889242 -291.042344)
		(width 0.17145)
		(layer "F.Cu")
		(net "DRIVE_B_24_FLT_LED")
	)
	(segment
		(start 6.88086 -289.912806)
		(end 6.889242 -289.921188)
		(width 0.17145)
		(layer "F.Cu")
		(net "DRIVE_B_24_FLT_LED")
	)
	(segment
		(start 5.574284 -292.684962)
		(end 5.815076 -292.925754)
		(width 0.17145)
		(layer "F.Cu")
		(net "DRIVE_B_24_FLT_LED")
	)
	(segment
		(start 5.574284 -291.173916)
		(end 5.574284 -292.684962)
		(width 0.17145)
		(layer "F.Cu")
		(net "DRIVE_B_24_FLT_LED")
	)
	(segment
		(start 6.889242 -291.042344)
		(end 5.705856 -291.042344)
		(width 0.17145)
		(layer "F.Cu")
		(net "DRIVE_B_24_FLT_LED")
	)
	(segment
		(start 207.45196 -370.965984)
		(end 204.965808 -370.965984)
		(width 0.17145)
		(layer "F.Cu")
		(net "DRIVE_B_24_FLT_LED")
	)
	(via
		(at 9.45515 -312.4454)
		(size 0.5588)
		(drill 0.3048)
		(layers "F.Cu" "B.Cu")
		(net "DRIVE_B_24_FLT_LED")
	)
	(via
		(at 185.801 -324.563994)
		(size 0.5588)
		(drill 0.3048)
		(layers "F.Cu" "B.Cu")
		(net "DRIVE_B_24_FLT_LED")
	)
	(via
		(at 5.6134 -291.1348)
		(size 0.6604)
		(drill 0.3302)
		(layers "F.Cu" "B.Cu")
		(net "DRIVE_B_24_FLT_LED")
	)
	(via
		(at 6.88086 -289.912806)
		(size 0.5588)
		(drill 0.3048)
		(layers "F.Cu" "B.Cu")
		(net "DRIVE_B_24_FLT_LED")
	)
	(via
		(at 204.965808 -370.965984)
		(size 0.5588)
		(drill 0.3048)
		(layers "F.Cu" "B.Cu")
		(net "DRIVE_B_24_FLT_LED")
	)
	(segment
		(start 10.11555 -313.1058)
		(end 68.0466 -313.1058)
		(width 0.13335)
		(layer "In2.Cu")
		(net "DRIVE_B_24_FLT_LED")
	)
	(segment
		(start 70.011544 -315.070744)
		(end 165.388544 -315.070744)
		(width 0.13335)
		(layer "In2.Cu")
		(net "DRIVE_B_24_FLT_LED")
	)
	(segment
		(start 174.881794 -324.563994)
		(end 185.801 -324.563994)
		(width 0.13335)
		(layer "In2.Cu")
		(net "DRIVE_B_24_FLT_LED")
	)
	(segment
		(start 9.45515 -312.4454)
		(end 10.11555 -313.1058)
		(width 0.13335)
		(layer "In2.Cu")
		(net "DRIVE_B_24_FLT_LED")
	)
	(segment
		(start 165.388544 -315.070744)
		(end 174.881794 -324.563994)
		(width 0.13335)
		(layer "In2.Cu")
		(net "DRIVE_B_24_FLT_LED")
	)
	(segment
		(start 68.0466 -313.1058)
		(end 70.011544 -315.070744)
		(width 0.13335)
		(layer "In2.Cu")
		(net "DRIVE_B_24_FLT_LED")
	)
	(segment
		(start 197.955916 -340.347046)
		(end 198.655686 -340.347046)
		(width 0.12065)
		(layer "In4.Cu")
		(net "DRIVE_B_24_FLT_LED")
	)
	(segment
		(start 185.801 -324.563994)
		(end 185.801 -328.19213)
		(width 0.12065)
		(layer "In4.Cu")
		(net "DRIVE_B_24_FLT_LED")
	)
	(segment
		(start 204.9272 -346.61856)
		(end 204.9272 -370.927376)
		(width 0.12065)
		(layer "In4.Cu")
		(net "DRIVE_B_24_FLT_LED")
	)
	(segment
		(start 6.88086 -289.912806)
		(end 6.88086 -298.286932)
		(width 0.12065)
		(layer "In4.Cu")
		(net "DRIVE_B_24_FLT_LED")
	)
	(segment
		(start 6.88086 -298.286932)
		(end 9.45515 -300.861222)
		(width 0.12065)
		(layer "In4.Cu")
		(net "DRIVE_B_24_FLT_LED")
	)
	(segment
		(start 204.9272 -370.927376)
		(end 204.965808 -370.965984)
		(width 0.12065)
		(layer "In4.Cu")
		(net "DRIVE_B_24_FLT_LED")
	)
	(segment
		(start 198.655686 -340.347046)
		(end 204.9272 -346.61856)
		(width 0.12065)
		(layer "In4.Cu")
		(net "DRIVE_B_24_FLT_LED")
	)
	(segment
		(start 185.801 -328.19213)
		(end 197.955916 -340.347046)
		(width 0.12065)
		(layer "In4.Cu")
		(net "DRIVE_B_24_FLT_LED")
	)
	(segment
		(start 9.45515 -300.861222)
		(end 9.45515 -312.4454)
		(width 0.12065)
		(layer "In4.Cu")
		(net "DRIVE_B_24_FLT_LED")
	)
	(segment
		(start 5.493004 -284.7086)
		(end 5.461 -284.740604)
		(width 0.17145)
		(layer "F.Cu")
		(net "DRIVE_B_24_ACT")
	)
	(segment
		(start 6.796024 -284.60319)
		(end 6.787642 -284.594808)
		(width 0.17145)
		(layer "F.Cu")
		(net "DRIVE_B_24_ACT")
	)
	(segment
		(start 5.461 -286.12592)
		(end 5.82168 -286.4866)
		(width 0.17145)
		(layer "F.Cu")
		(net "DRIVE_B_24_ACT")
	)
	(segment
		(start 5.461 -284.740604)
		(end 5.461 -286.12592)
		(width 0.17145)
		(layer "F.Cu")
		(net "DRIVE_B_24_ACT")
	)
	(segment
		(start 5.598414 -284.60319)
		(end 5.493004 -284.7086)
		(width 0.17145)
		(layer "F.Cu")
		(net "DRIVE_B_24_ACT")
	)
	(segment
		(start 6.787642 -284.594808)
		(end 6.787642 -283.473652)
		(width 0.17145)
		(layer "F.Cu")
		(net "DRIVE_B_24_ACT")
	)
	(segment
		(start 6.796024 -284.60319)
		(end 5.598414 -284.60319)
		(width 0.17145)
		(layer "F.Cu")
		(net "DRIVE_B_24_ACT")
	)
	(via
		(at 10.510774 -339.234018)
		(size 0.5588)
		(drill 0.3048)
		(layers "F.Cu" "B.Cu")
		(net "DRIVE_B_24_ACT")
	)
	(via
		(at 5.493004 -284.7086)
		(size 0.6604)
		(drill 0.3302)
		(layers "F.Cu" "B.Cu")
		(net "DRIVE_B_24_ACT")
	)
	(via
		(at 227.5586 -353.0854)
		(size 0.5588)
		(drill 0.3048)
		(layers "F.Cu" "B.Cu")
		(net "DRIVE_B_24_ACT")
	)
	(via
		(at 6.787642 -283.473652)
		(size 0.5588)
		(drill 0.3048)
		(layers "F.Cu" "B.Cu")
		(net "DRIVE_B_24_ACT")
	)
	(segment
		(start 13.531342 -342.254586)
		(end 128.779016 -342.254586)
		(width 0.13335)
		(layer "In2.Cu")
		(net "DRIVE_B_24_ACT")
	)
	(segment
		(start 166.84117 -344.8558)
		(end 169.43197 -342.265)
		(width 0.13335)
		(layer "In2.Cu")
		(net "DRIVE_B_24_ACT")
	)
	(segment
		(start 226.972622 -352.701098)
		(end 226.975924 -352.7044)
		(width 0.13335)
		(layer "In2.Cu")
		(net "DRIVE_B_24_ACT")
	)
	(segment
		(start 227.1776 -352.7044)
		(end 227.5586 -353.0854)
		(width 0.13335)
		(layer "In2.Cu")
		(net "DRIVE_B_24_ACT")
	)
	(segment
		(start 139.95781 -344.8558)
		(end 166.84117 -344.8558)
		(width 0.13335)
		(layer "In2.Cu")
		(net "DRIVE_B_24_ACT")
	)
	(segment
		(start 208.8134 -342.265)
		(end 219.249498 -352.701098)
		(width 0.13335)
		(layer "In2.Cu")
		(net "DRIVE_B_24_ACT")
	)
	(segment
		(start 138.821414 -343.719404)
		(end 139.95781 -344.8558)
		(width 0.13335)
		(layer "In2.Cu")
		(net "DRIVE_B_24_ACT")
	)
	(segment
		(start 169.43197 -342.265)
		(end 208.8134 -342.265)
		(width 0.13335)
		(layer "In2.Cu")
		(net "DRIVE_B_24_ACT")
	)
	(segment
		(start 130.243834 -343.719404)
		(end 138.821414 -343.719404)
		(width 0.13335)
		(layer "In2.Cu")
		(net "DRIVE_B_24_ACT")
	)
	(segment
		(start 226.975924 -352.7044)
		(end 227.1776 -352.7044)
		(width 0.13335)
		(layer "In2.Cu")
		(net "DRIVE_B_24_ACT")
	)
	(segment
		(start 128.779016 -342.254586)
		(end 130.243834 -343.719404)
		(width 0.13335)
		(layer "In2.Cu")
		(net "DRIVE_B_24_ACT")
	)
	(segment
		(start 10.510774 -339.234018)
		(end 13.531342 -342.254586)
		(width 0.13335)
		(layer "In2.Cu")
		(net "DRIVE_B_24_ACT")
	)
	(segment
		(start 219.249498 -352.701098)
		(end 226.972622 -352.701098)
		(width 0.13335)
		(layer "In2.Cu")
		(net "DRIVE_B_24_ACT")
	)
	(segment
		(start 228.67747 -369.54333)
		(end 230.900478 -367.320322)
		(width 0.12065)
		(layer "In4.Cu")
		(net "DRIVE_B_24_ACT")
	)
	(segment
		(start 231.286558 -378.760228)
		(end 228.67747 -376.15114)
		(width 0.12065)
		(layer "In4.Cu")
		(net "DRIVE_B_24_ACT")
	)
	(segment
		(start 8.685784 -301.382684)
		(end 6.0198 -298.7167)
		(width 0.12065)
		(layer "In4.Cu")
		(net "DRIVE_B_24_ACT")
	)
	(segment
		(start 228.67747 -376.15114)
		(end 228.67747 -369.54333)
		(width 0.12065)
		(layer "In4.Cu")
		(net "DRIVE_B_24_ACT")
	)
	(segment
		(start 8.685784 -337.409028)
		(end 8.685784 -301.382684)
		(width 0.12065)
		(layer "In4.Cu")
		(net "DRIVE_B_24_ACT")
	)
	(segment
		(start 232.5243 -392.5189)
		(end 231.286558 -391.281158)
		(width 0.12065)
		(layer "In4.Cu")
		(net "DRIVE_B_24_ACT")
	)
	(segment
		(start 6.0198 -298.7167)
		(end 6.0198 -284.241494)
		(width 0.12065)
		(layer "In4.Cu")
		(net "DRIVE_B_24_ACT")
	)
	(segment
		(start 232.5243 -419.42766)
		(end 232.5243 -392.5189)
		(width 0.12065)
		(layer "In4.Cu")
		(net "DRIVE_B_24_ACT")
	)
	(segment
		(start 230.563674 -419.9636)
		(end 231.98836 -419.9636)
		(width 0.12065)
		(layer "In4.Cu")
		(net "DRIVE_B_24_ACT")
	)
	(segment
		(start 6.0198 -284.241494)
		(end 6.787642 -283.473652)
		(width 0.12065)
		(layer "In4.Cu")
		(net "DRIVE_B_24_ACT")
	)
	(segment
		(start 230.900478 -356.427278)
		(end 227.5586 -353.0854)
		(width 0.12065)
		(layer "In4.Cu")
		(net "DRIVE_B_24_ACT")
	)
	(segment
		(start 230.900478 -367.320322)
		(end 230.900478 -356.427278)
		(width 0.12065)
		(layer "In4.Cu")
		(net "DRIVE_B_24_ACT")
	)
	(segment
		(start 10.510774 -339.234018)
		(end 8.685784 -337.409028)
		(width 0.12065)
		(layer "In4.Cu")
		(net "DRIVE_B_24_ACT")
	)
	(segment
		(start 231.286558 -391.281158)
		(end 231.286558 -378.760228)
		(width 0.12065)
		(layer "In4.Cu")
		(net "DRIVE_B_24_ACT")
	)
	(segment
		(start 231.98836 -419.9636)
		(end 232.5243 -419.42766)
		(width 0.12065)
		(layer "In4.Cu")
		(net "DRIVE_B_24_ACT")
	)
	(segment
		(start 229.80015 -419.200076)
		(end 230.563674 -419.9636)
		(width 0.12065)
		(layer "In4.Cu")
		(net "DRIVE_B_24_ACT")
	)
	(segment
		(start 228.34092 -232.024428)
		(end 228.34092 -234.1626)
		(width 0.17145)
		(layer "F.Cu")
		(net "DRIVE_A_9_PWR")
	)
	(segment
		(start 228.210872 -231.89438)
		(end 228.34092 -232.024428)
		(width 0.17145)
		(layer "F.Cu")
		(net "DRIVE_A_9_PWR")
	)
	(segment
		(start 430.438052 -271.1704)
		(end 430.438052 -270.1544)
		(width 0.17145)
		(layer "F.Cu")
		(net "DRIVE_A_9_PWR")
	)
	(segment
		(start 430.438052 -272.141442)
		(end 430.438052 -271.1704)
		(width 0.17145)
		(layer "F.Cu")
		(net "DRIVE_A_9_PWR")
	)
	(via
		(at 416.469576 -225.99777)
		(size 0.5588)
		(drill 0.3048)
		(layers "F.Cu" "B.Cu")
		(net "DRIVE_A_9_PWR")
	)
	(via
		(at 228.210872 -231.89438)
		(size 0.5588)
		(drill 0.3048)
		(layers "F.Cu" "B.Cu")
		(net "DRIVE_A_9_PWR")
	)
	(via
		(at 430.438052 -270.1544)
		(size 0.5588)
		(drill 0.3048)
		(layers "F.Cu" "B.Cu")
		(net "DRIVE_A_9_PWR")
	)
	(via
		(at 430.438052 -271.1704)
		(size 0.6604)
		(drill 0.3302)
		(layers "F.Cu" "B.Cu")
		(net "DRIVE_A_9_PWR")
	)
	(segment
		(start 229.199186 -231.89438)
		(end 228.210872 -231.89438)
		(width 0.13335)
		(layer "In2.Cu")
		(net "DRIVE_A_9_PWR")
	)
	(segment
		(start 232.385362 -225.640138)
		(end 230.386636 -227.638864)
		(width 0.13335)
		(layer "In2.Cu")
		(net "DRIVE_A_9_PWR")
	)
	(segment
		(start 366.4966 -223.0628)
		(end 327.189592 -223.0628)
		(width 0.13335)
		(layer "In2.Cu")
		(net "DRIVE_A_9_PWR")
	)
	(segment
		(start 317.46571 -213.338918)
		(end 278.779224 -213.338918)
		(width 0.13335)
		(layer "In2.Cu")
		(net "DRIVE_A_9_PWR")
	)
	(segment
		(start 327.189592 -223.0628)
		(end 317.46571 -213.338918)
		(width 0.13335)
		(layer "In2.Cu")
		(net "DRIVE_A_9_PWR")
	)
	(segment
		(start 266.478004 -225.640138)
		(end 232.385362 -225.640138)
		(width 0.13335)
		(layer "In2.Cu")
		(net "DRIVE_A_9_PWR")
	)
	(segment
		(start 278.779224 -213.338918)
		(end 266.478004 -225.640138)
		(width 0.13335)
		(layer "In2.Cu")
		(net "DRIVE_A_9_PWR")
	)
	(segment
		(start 230.386636 -227.638864)
		(end 230.386636 -230.70693)
		(width 0.13335)
		(layer "In2.Cu")
		(net "DRIVE_A_9_PWR")
	)
	(segment
		(start 416.469576 -225.99777)
		(end 415.592006 -225.1202)
		(width 0.13335)
		(layer "In2.Cu")
		(net "DRIVE_A_9_PWR")
	)
	(segment
		(start 368.554 -225.1202)
		(end 366.4966 -223.0628)
		(width 0.13335)
		(layer "In2.Cu")
		(net "DRIVE_A_9_PWR")
	)
	(segment
		(start 230.386636 -230.70693)
		(end 229.199186 -231.89438)
		(width 0.13335)
		(layer "In2.Cu")
		(net "DRIVE_A_9_PWR")
	)
	(segment
		(start 415.592006 -225.1202)
		(end 368.554 -225.1202)
		(width 0.13335)
		(layer "In2.Cu")
		(net "DRIVE_A_9_PWR")
	)
	(segment
		(start 429.34001 -270.1544)
		(end 430.438052 -270.1544)
		(width 0.12065)
		(layer "In4.Cu")
		(net "DRIVE_A_9_PWR")
	)
	(segment
		(start 416.469576 -225.99777)
		(end 421.5384 -231.066594)
		(width 0.12065)
		(layer "In4.Cu")
		(net "DRIVE_A_9_PWR")
	)
	(segment
		(start 421.5384 -262.35279)
		(end 429.34001 -270.1544)
		(width 0.12065)
		(layer "In4.Cu")
		(net "DRIVE_A_9_PWR")
	)
	(segment
		(start 421.5384 -231.066594)
		(end 421.5384 -262.35279)
		(width 0.12065)
		(layer "In4.Cu")
		(net "DRIVE_A_9_PWR")
	)
	(segment
		(start 227.743766 -249.50039)
		(end 228.08311 -249.50039)
		(width 0.17145)
		(layer "F.Cu")
		(net "DRIVE_A_9_INS")
	)
	(segment
		(start 228.08311 -249.50039)
		(end 228.97592 -250.3932)
		(width 0.17145)
		(layer "F.Cu")
		(net "DRIVE_A_9_INS")
	)
	(segment
		(start 228.97592 -250.3932)
		(end 228.97592 -251.8156)
		(width 0.17145)
		(layer "F.Cu")
		(net "DRIVE_A_9_INS")
	)
	(segment
		(start 414.817052 -295.064942)
		(end 414.817052 -296.080942)
		(width 0.17145)
		(layer "F.Cu")
		(net "DRIVE_A_9_INS")
	)
	(via
		(at 415.6456 -235.1532)
		(size 0.5588)
		(drill 0.3048)
		(layers "F.Cu" "B.Cu")
		(net "DRIVE_A_9_INS")
	)
	(via
		(at 414.817052 -296.080942)
		(size 0.5588)
		(drill 0.3048)
		(layers "F.Cu" "B.Cu")
		(net "DRIVE_A_9_INS")
	)
	(via
		(at 227.743766 -249.50039)
		(size 0.5588)
		(drill 0.3048)
		(layers "F.Cu" "B.Cu")
		(net "DRIVE_A_9_INS")
	)
	(via
		(at 228.97592 -250.3932)
		(size 0.6604)
		(drill 0.3302)
		(layers "F.Cu" "B.Cu")
		(net "DRIVE_A_9_INS")
	)
	(segment
		(start 263.825228 -242.671854)
		(end 252.824742 -242.671854)
		(width 0.13335)
		(layer "In2.Cu")
		(net "DRIVE_A_9_INS")
	)
	(segment
		(start 245.68912 -249.807476)
		(end 245.02618 -249.807476)
		(width 0.13335)
		(layer "In2.Cu")
		(net "DRIVE_A_9_INS")
	)
	(segment
		(start 284.058106 -234.430062)
		(end 273.593052 -234.430062)
		(width 0.13335)
		(layer "In2.Cu")
		(net "DRIVE_A_9_INS")
	)
	(segment
		(start 271.676368 -236.346746)
		(end 270.150336 -236.346746)
		(width 0.13335)
		(layer "In2.Cu")
		(net "DRIVE_A_9_INS")
	)
	(segment
		(start 323.735192 -235.1532)
		(end 313.791854 -225.209862)
		(width 0.13335)
		(layer "In2.Cu")
		(net "DRIVE_A_9_INS")
	)
	(segment
		(start 415.6456 -235.1532)
		(end 323.735192 -235.1532)
		(width 0.13335)
		(layer "In2.Cu")
		(net "DRIVE_A_9_INS")
	)
	(segment
		(start 237.529878 -250.122944)
		(end 236.630464 -251.022358)
		(width 0.13335)
		(layer "In2.Cu")
		(net "DRIVE_A_9_INS")
	)
	(segment
		(start 252.824742 -242.671854)
		(end 245.68912 -249.807476)
		(width 0.13335)
		(layer "In2.Cu")
		(net "DRIVE_A_9_INS")
	)
	(segment
		(start 273.593052 -234.430062)
		(end 271.676368 -236.346746)
		(width 0.13335)
		(layer "In2.Cu")
		(net "DRIVE_A_9_INS")
	)
	(segment
		(start 313.791854 -225.209862)
		(end 293.278306 -225.209862)
		(width 0.13335)
		(layer "In2.Cu")
		(net "DRIVE_A_9_INS")
	)
	(segment
		(start 245.02618 -249.807476)
		(end 244.710712 -250.122944)
		(width 0.13335)
		(layer "In2.Cu")
		(net "DRIVE_A_9_INS")
	)
	(segment
		(start 270.150336 -236.346746)
		(end 263.825228 -242.671854)
		(width 0.13335)
		(layer "In2.Cu")
		(net "DRIVE_A_9_INS")
	)
	(segment
		(start 244.710712 -250.122944)
		(end 237.529878 -250.122944)
		(width 0.13335)
		(layer "In2.Cu")
		(net "DRIVE_A_9_INS")
	)
	(segment
		(start 293.278306 -225.209862)
		(end 284.058106 -234.430062)
		(width 0.13335)
		(layer "In2.Cu")
		(net "DRIVE_A_9_INS")
	)
	(segment
		(start 229.265734 -251.022358)
		(end 227.743766 -249.50039)
		(width 0.13335)
		(layer "In2.Cu")
		(net "DRIVE_A_9_INS")
	)
	(segment
		(start 236.630464 -251.022358)
		(end 229.265734 -251.022358)
		(width 0.13335)
		(layer "In2.Cu")
		(net "DRIVE_A_9_INS")
	)
	(segment
		(start 415.6456 -235.1532)
		(end 415.6456 -276.1996)
		(width 0.12065)
		(layer "In4.Cu")
		(net "DRIVE_A_9_INS")
	)
	(segment
		(start 414.817052 -277.028148)
		(end 414.817052 -296.080942)
		(width 0.12065)
		(layer "In4.Cu")
		(net "DRIVE_A_9_INS")
	)
	(segment
		(start 415.6456 -276.1996)
		(end 414.817052 -277.028148)
		(width 0.12065)
		(layer "In4.Cu")
		(net "DRIVE_A_9_INS")
	)
	(segment
		(start 406.608534 -246.025416)
		(end 406.955498 -246.37238)
		(width 0.17145)
		(layer "F.Cu")
		(net "DRIVE_A_9_FLT_LED")
	)
	(segment
		(start 408.1272 -245.335806)
		(end 406.608534 -245.335806)
		(width 0.17145)
		(layer "F.Cu")
		(net "DRIVE_A_9_FLT_LED")
	)
	(segment
		(start 406.608534 -245.335806)
		(end 406.608534 -246.025416)
		(width 0.17145)
		(layer "F.Cu")
		(net "DRIVE_A_9_FLT_LED")
	)
	(segment
		(start 267.73632 -283.8958)
		(end 267.08608 -283.24556)
		(width 0.17145)
		(layer "F.Cu")
		(net "DRIVE_A_9_FLT_LED")
	)
	(segment
		(start 267.08608 -283.24556)
		(end 267.08608 -280.9494)
		(width 0.17145)
		(layer "F.Cu")
		(net "DRIVE_A_9_FLT_LED")
	)
	(segment
		(start 408.178 -245.285006)
		(end 408.1272 -245.335806)
		(width 0.17145)
		(layer "F.Cu")
		(net "DRIVE_A_9_FLT_LED")
	)
	(segment
		(start 408.178 -244.26545)
		(end 408.178 -245.285006)
		(width 0.17145)
		(layer "F.Cu")
		(net "DRIVE_A_9_FLT_LED")
	)
	(segment
		(start 407.696162 -243.783612)
		(end 408.178 -244.26545)
		(width 0.17145)
		(layer "F.Cu")
		(net "DRIVE_A_9_FLT_LED")
	)
	(via
		(at 267.73632 -283.8958)
		(size 0.5588)
		(drill 0.3048)
		(layers "F.Cu" "B.Cu")
		(net "DRIVE_A_9_FLT_LED")
	)
	(via
		(at 407.0096 -258.918964)
		(size 0.5588)
		(drill 0.3048)
		(layers "F.Cu" "B.Cu")
		(net "DRIVE_A_9_FLT_LED")
	)
	(via
		(at 406.955498 -246.37238)
		(size 0.5588)
		(drill 0.3048)
		(layers "F.Cu" "B.Cu")
		(net "DRIVE_A_9_FLT_LED")
	)
	(via
		(at 408.1272 -245.335806)
		(size 0.6604)
		(drill 0.3302)
		(layers "F.Cu" "B.Cu")
		(net "DRIVE_A_9_FLT_LED")
	)
	(segment
		(start 276.097238 -278.365204)
		(end 279.513284 -278.365204)
		(width 0.13335)
		(layer "In2.Cu")
		(net "DRIVE_A_9_FLT_LED")
	)
	(segment
		(start 308.424834 -274.574)
		(end 324.07987 -258.918964)
		(width 0.13335)
		(layer "In2.Cu")
		(net "DRIVE_A_9_FLT_LED")
	)
	(segment
		(start 270.566642 -283.8958)
		(end 276.097238 -278.365204)
		(width 0.13335)
		(layer "In2.Cu")
		(net "DRIVE_A_9_FLT_LED")
	)
	(segment
		(start 267.73632 -283.8958)
		(end 270.566642 -283.8958)
		(width 0.13335)
		(layer "In2.Cu")
		(net "DRIVE_A_9_FLT_LED")
	)
	(segment
		(start 283.304488 -274.574)
		(end 308.424834 -274.574)
		(width 0.13335)
		(layer "In2.Cu")
		(net "DRIVE_A_9_FLT_LED")
	)
	(segment
		(start 279.513284 -278.365204)
		(end 283.304488 -274.574)
		(width 0.13335)
		(layer "In2.Cu")
		(net "DRIVE_A_9_FLT_LED")
	)
	(segment
		(start 324.07987 -258.918964)
		(end 407.0096 -258.918964)
		(width 0.13335)
		(layer "In2.Cu")
		(net "DRIVE_A_9_FLT_LED")
	)
	(segment
		(start 407.011378 -246.42826)
		(end 407.011378 -258.917186)
		(width 0.12065)
		(layer "In4.Cu")
		(net "DRIVE_A_9_FLT_LED")
	)
	(segment
		(start 407.011378 -258.917186)
		(end 407.0096 -258.918964)
		(width 0.12065)
		(layer "In4.Cu")
		(net "DRIVE_A_9_FLT_LED")
	)
	(segment
		(start 406.955498 -246.37238)
		(end 407.011378 -246.42826)
		(width 0.12065)
		(layer "In4.Cu")
		(net "DRIVE_A_9_FLT_LED")
	)
	(segment
		(start 404.091394 -243.773198)
		(end 404.393908 -244.075712)
		(width 0.17145)
		(layer "F.Cu")
		(net "DRIVE_A_9_ACT")
	)
	(segment
		(start 404.349204 -245.315486)
		(end 404.393908 -245.270782)
		(width 0.17145)
		(layer "F.Cu")
		(net "DRIVE_A_9_ACT")
	)
	(segment
		(start 403.01672 -245.315486)
		(end 404.349204 -245.315486)
		(width 0.17145)
		(layer "F.Cu")
		(net "DRIVE_A_9_ACT")
	)
	(segment
		(start 403.308566 -246.174514)
		(end 403.01672 -245.882668)
		(width 0.17145)
		(layer "F.Cu")
		(net "DRIVE_A_9_ACT")
	)
	(segment
		(start 300.736 -320.0654)
		(end 296.545 -320.0654)
		(width 0.17145)
		(layer "F.Cu")
		(net "DRIVE_A_9_ACT")
	)
	(segment
		(start 404.393908 -244.075712)
		(end 404.393908 -245.270782)
		(width 0.17145)
		(layer "F.Cu")
		(net "DRIVE_A_9_ACT")
	)
	(segment
		(start 296.545 -320.0654)
		(end 295.9354 -320.675)
		(width 0.17145)
		(layer "F.Cu")
		(net "DRIVE_A_9_ACT")
	)
	(segment
		(start 403.01672 -245.882668)
		(end 403.01672 -245.315486)
		(width 0.17145)
		(layer "F.Cu")
		(net "DRIVE_A_9_ACT")
	)
	(segment
		(start 282.606496 -320.675)
		(end 281.836622 -319.905126)
		(width 0.17145)
		(layer "F.Cu")
		(net "DRIVE_A_9_ACT")
	)
	(segment
		(start 295.9354 -320.675)
		(end 282.606496 -320.675)
		(width 0.17145)
		(layer "F.Cu")
		(net "DRIVE_A_9_ACT")
	)
	(via
		(at 409.8036 -314.071)
		(size 0.5588)
		(drill 0.3048)
		(layers "F.Cu" "B.Cu")
		(net "DRIVE_A_9_ACT")
	)
	(via
		(at 404.393908 -245.270782)
		(size 0.6604)
		(drill 0.3302)
		(layers "F.Cu" "B.Cu")
		(net "DRIVE_A_9_ACT")
	)
	(via
		(at 300.736 -320.0654)
		(size 0.5588)
		(drill 0.3048)
		(layers "F.Cu" "B.Cu")
		(net "DRIVE_A_9_ACT")
	)
	(via
		(at 403.308566 -246.174514)
		(size 0.5588)
		(drill 0.3048)
		(layers "F.Cu" "B.Cu")
		(net "DRIVE_A_9_ACT")
	)
	(segment
		(start 319.3796 -320.0654)
		(end 300.736 -320.0654)
		(width 0.13335)
		(layer "In2.Cu")
		(net "DRIVE_A_9_ACT")
	)
	(segment
		(start 325.675498 -313.769502)
		(end 319.3796 -320.0654)
		(width 0.13335)
		(layer "In2.Cu")
		(net "DRIVE_A_9_ACT")
	)
	(segment
		(start 409.8036 -314.071)
		(end 409.502102 -313.769502)
		(width 0.13335)
		(layer "In2.Cu")
		(net "DRIVE_A_9_ACT")
	)
	(segment
		(start 409.502102 -313.769502)
		(end 325.675498 -313.769502)
		(width 0.13335)
		(layer "In2.Cu")
		(net "DRIVE_A_9_ACT")
	)
	(segment
		(start 403.308566 -272.854166)
		(end 409.8036 -279.3492)
		(width 0.12065)
		(layer "In4.Cu")
		(net "DRIVE_A_9_ACT")
	)
	(segment
		(start 403.308566 -246.174514)
		(end 403.308566 -272.854166)
		(width 0.12065)
		(layer "In4.Cu")
		(net "DRIVE_A_9_ACT")
	)
	(segment
		(start 409.8036 -279.3492)
		(end 409.8036 -314.071)
		(width 0.12065)
		(layer "In4.Cu")
		(net "DRIVE_A_9_ACT")
	)
	(segment
		(start 398.88795 -271.1704)
		(end 398.88795 -269.748)
		(width 0.17145)
		(layer "F.Cu")
		(net "DRIVE_A_8_PWR")
	)
	(segment
		(start 227.69068 -234.1626)
		(end 227.69068 -232.844848)
		(width 0.17145)
		(layer "F.Cu")
		(net "DRIVE_A_8_PWR")
	)
	(segment
		(start 398.88795 -272.141442)
		(end 398.88795 -271.1704)
		(width 0.17145)
		(layer "F.Cu")
		(net "DRIVE_A_8_PWR")
	)
	(via
		(at 398.88795 -269.748)
		(size 0.5588)
		(drill 0.3048)
		(layers "F.Cu" "B.Cu")
		(net "DRIVE_A_8_PWR")
	)
	(via
		(at 398.907 -225.6536)
		(size 0.5588)
		(drill 0.3048)
		(layers "F.Cu" "B.Cu")
		(net "DRIVE_A_8_PWR")
	)
	(via
		(at 227.69068 -232.844848)
		(size 0.5588)
		(drill 0.3048)
		(layers "F.Cu" "B.Cu")
		(net "DRIVE_A_8_PWR")
	)
	(via
		(at 398.88795 -271.1704)
		(size 0.6604)
		(drill 0.3302)
		(layers "F.Cu" "B.Cu")
		(net "DRIVE_A_8_PWR")
	)
	(segment
		(start 368.2746 -225.6536)
		(end 366.2426 -223.6216)
		(width 0.13335)
		(layer "In2.Cu")
		(net "DRIVE_A_8_PWR")
	)
	(segment
		(start 230.945436 -230.938578)
		(end 229.039166 -232.844848)
		(width 0.13335)
		(layer "In2.Cu")
		(net "DRIVE_A_8_PWR")
	)
	(segment
		(start 232.66019 -226.198938)
		(end 230.945436 -227.913692)
		(width 0.13335)
		(layer "In2.Cu")
		(net "DRIVE_A_8_PWR")
	)
	(segment
		(start 279.010872 -213.897718)
		(end 266.709652 -226.198938)
		(width 0.13335)
		(layer "In2.Cu")
		(net "DRIVE_A_8_PWR")
	)
	(segment
		(start 266.709652 -226.198938)
		(end 232.66019 -226.198938)
		(width 0.13335)
		(layer "In2.Cu")
		(net "DRIVE_A_8_PWR")
	)
	(segment
		(start 398.907 -225.6536)
		(end 368.2746 -225.6536)
		(width 0.13335)
		(layer "In2.Cu")
		(net "DRIVE_A_8_PWR")
	)
	(segment
		(start 317.234062 -213.897718)
		(end 279.010872 -213.897718)
		(width 0.13335)
		(layer "In2.Cu")
		(net "DRIVE_A_8_PWR")
	)
	(segment
		(start 326.957944 -223.6216)
		(end 317.234062 -213.897718)
		(width 0.13335)
		(layer "In2.Cu")
		(net "DRIVE_A_8_PWR")
	)
	(segment
		(start 366.2426 -223.6216)
		(end 326.957944 -223.6216)
		(width 0.13335)
		(layer "In2.Cu")
		(net "DRIVE_A_8_PWR")
	)
	(segment
		(start 230.945436 -227.913692)
		(end 230.945436 -230.938578)
		(width 0.13335)
		(layer "In2.Cu")
		(net "DRIVE_A_8_PWR")
	)
	(segment
		(start 229.039166 -232.844848)
		(end 227.69068 -232.844848)
		(width 0.13335)
		(layer "In2.Cu")
		(net "DRIVE_A_8_PWR")
	)
	(segment
		(start 398.88795 -269.748)
		(end 398.88795 -225.67265)
		(width 0.12065)
		(layer "In4.Cu")
		(net "DRIVE_A_8_PWR")
	)
	(segment
		(start 398.88795 -225.67265)
		(end 398.907 -225.6536)
		(width 0.12065)
		(layer "In4.Cu")
		(net "DRIVE_A_8_PWR")
	)
	(segment
		(start 227.486464 -250.426728)
		(end 227.693728 -250.426728)
		(width 0.17145)
		(layer "F.Cu")
		(net "DRIVE_A_8_INS")
	)
	(segment
		(start 380.6698 -295.0718)
		(end 380.6698 -296.1132)
		(width 0.17145)
		(layer "F.Cu")
		(net "DRIVE_A_8_INS")
	)
	(segment
		(start 227.693728 -250.426728)
		(end 228.32568 -251.05868)
		(width 0.17145)
		(layer "F.Cu")
		(net "DRIVE_A_8_INS")
	)
	(segment
		(start 228.32568 -251.05868)
		(end 228.32568 -251.8156)
		(width 0.17145)
		(layer "F.Cu")
		(net "DRIVE_A_8_INS")
	)
	(segment
		(start 381.212852 -296.656252)
		(end 382.0668 -297.5102)
		(width 0.17145)
		(layer "F.Cu")
		(net "DRIVE_A_8_INS")
	)
	(segment
		(start 380.6698 -296.1132)
		(end 381.212852 -296.656252)
		(width 0.17145)
		(layer "F.Cu")
		(net "DRIVE_A_8_INS")
	)
	(via
		(at 381.212852 -296.656252)
		(size 0.6604)
		(drill 0.3302)
		(layers "F.Cu" "B.Cu")
		(net "DRIVE_A_8_INS")
	)
	(via
		(at 227.486464 -250.426728)
		(size 0.5588)
		(drill 0.3048)
		(layers "F.Cu" "B.Cu")
		(net "DRIVE_A_8_INS")
	)
	(via
		(at 382.0668 -297.5102)
		(size 0.5588)
		(drill 0.3048)
		(layers "F.Cu" "B.Cu")
		(net "DRIVE_A_8_INS")
	)
	(via
		(at 386.3848 -235.712)
		(size 0.5588)
		(drill 0.3048)
		(layers "F.Cu" "B.Cu")
		(net "DRIVE_A_8_INS")
	)
	(segment
		(start 386.3848 -235.712)
		(end 323.503544 -235.712)
		(width 0.13335)
		(layer "In2.Cu")
		(net "DRIVE_A_8_INS")
	)
	(segment
		(start 270.381984 -236.905546)
		(end 264.056876 -243.230654)
		(width 0.13335)
		(layer "In2.Cu")
		(net "DRIVE_A_8_INS")
	)
	(segment
		(start 245.257828 -250.366276)
		(end 244.037104 -251.587)
		(width 0.13335)
		(layer "In2.Cu")
		(net "DRIVE_A_8_INS")
	)
	(segment
		(start 284.451298 -234.988862)
		(end 273.8247 -234.988862)
		(width 0.13335)
		(layer "In2.Cu")
		(net "DRIVE_A_8_INS")
	)
	(segment
		(start 273.8247 -234.988862)
		(end 271.908016 -236.905546)
		(width 0.13335)
		(layer "In2.Cu")
		(net "DRIVE_A_8_INS")
	)
	(segment
		(start 228.646736 -251.587)
		(end 227.486464 -250.426728)
		(width 0.13335)
		(layer "In2.Cu")
		(net "DRIVE_A_8_INS")
	)
	(segment
		(start 314.109862 -226.318318)
		(end 293.121842 -226.318318)
		(width 0.13335)
		(layer "In2.Cu")
		(net "DRIVE_A_8_INS")
	)
	(segment
		(start 244.037104 -251.587)
		(end 228.646736 -251.587)
		(width 0.13335)
		(layer "In2.Cu")
		(net "DRIVE_A_8_INS")
	)
	(segment
		(start 245.920768 -250.366276)
		(end 245.257828 -250.366276)
		(width 0.13335)
		(layer "In2.Cu")
		(net "DRIVE_A_8_INS")
	)
	(segment
		(start 271.908016 -236.905546)
		(end 270.381984 -236.905546)
		(width 0.13335)
		(layer "In2.Cu")
		(net "DRIVE_A_8_INS")
	)
	(segment
		(start 253.05639 -243.230654)
		(end 245.920768 -250.366276)
		(width 0.13335)
		(layer "In2.Cu")
		(net "DRIVE_A_8_INS")
	)
	(segment
		(start 323.503544 -235.712)
		(end 314.109862 -226.318318)
		(width 0.13335)
		(layer "In2.Cu")
		(net "DRIVE_A_8_INS")
	)
	(segment
		(start 264.056876 -243.230654)
		(end 253.05639 -243.230654)
		(width 0.13335)
		(layer "In2.Cu")
		(net "DRIVE_A_8_INS")
	)
	(segment
		(start 293.121842 -226.318318)
		(end 284.451298 -234.988862)
		(width 0.13335)
		(layer "In2.Cu")
		(net "DRIVE_A_8_INS")
	)
	(segment
		(start 382.0668 -297.5102)
		(end 382.8796 -296.6974)
		(width 0.12065)
		(layer "In4.Cu")
		(net "DRIVE_A_8_INS")
	)
	(segment
		(start 382.8796 -246.7864)
		(end 382.8796 -239.2172)
		(width 0.12065)
		(layer "In4.Cu")
		(net "DRIVE_A_8_INS")
	)
	(segment
		(start 382.8796 -280.2636)
		(end 381.635 -279.019)
		(width 0.12065)
		(layer "In4.Cu")
		(net "DRIVE_A_8_INS")
	)
	(segment
		(start 381.635 -279.019)
		(end 381.635 -248.031)
		(width 0.12065)
		(layer "In4.Cu")
		(net "DRIVE_A_8_INS")
	)
	(segment
		(start 382.8796 -296.6974)
		(end 382.8796 -280.2636)
		(width 0.12065)
		(layer "In4.Cu")
		(net "DRIVE_A_8_INS")
	)
	(segment
		(start 382.8796 -239.2172)
		(end 386.3848 -235.712)
		(width 0.12065)
		(layer "In4.Cu")
		(net "DRIVE_A_8_INS")
	)
	(segment
		(start 381.635 -248.031)
		(end 382.8796 -246.7864)
		(width 0.12065)
		(layer "In4.Cu")
		(net "DRIVE_A_8_INS")
	)
	(segment
		(start 375.405396 -246.391176)
		(end 375.033032 -246.018812)
		(width 0.17145)
		(layer "F.Cu")
		(net "DRIVE_A_8_FLT_LED")
	)
	(segment
		(start 267.73632 -280.9494)
		(end 267.73632 -282.9306)
		(width 0.17145)
		(layer "F.Cu")
		(net "DRIVE_A_8_FLT_LED")
	)
	(segment
		(start 375.665238 -245.55704)
		(end 375.412 -245.303802)
		(width 0.17145)
		(layer "F.Cu")
		(net "DRIVE_A_8_FLT_LED")
	)
	(segment
		(start 376.629422 -244.23497)
		(end 376.629422 -245.55704)
		(width 0.17145)
		(layer "F.Cu")
		(net "DRIVE_A_8_FLT_LED")
	)
	(segment
		(start 375.412 -245.303802)
		(end 375.033032 -245.303802)
		(width 0.17145)
		(layer "F.Cu")
		(net "DRIVE_A_8_FLT_LED")
	)
	(segment
		(start 375.033032 -246.018812)
		(end 375.033032 -245.303802)
		(width 0.17145)
		(layer "F.Cu")
		(net "DRIVE_A_8_FLT_LED")
	)
	(segment
		(start 376.14606 -243.751608)
		(end 376.629422 -244.23497)
		(width 0.17145)
		(layer "F.Cu")
		(net "DRIVE_A_8_FLT_LED")
	)
	(segment
		(start 376.629422 -245.55704)
		(end 375.665238 -245.55704)
		(width 0.17145)
		(layer "F.Cu")
		(net "DRIVE_A_8_FLT_LED")
	)
	(via
		(at 376.629422 -245.55704)
		(size 0.6604)
		(drill 0.3302)
		(layers "F.Cu" "B.Cu")
		(net "DRIVE_A_8_FLT_LED")
	)
	(via
		(at 267.73632 -282.9306)
		(size 0.5588)
		(drill 0.3048)
		(layers "F.Cu" "B.Cu")
		(net "DRIVE_A_8_FLT_LED")
	)
	(via
		(at 375.461276 -258.360164)
		(size 0.5588)
		(drill 0.3048)
		(layers "F.Cu" "B.Cu")
		(net "DRIVE_A_8_FLT_LED")
	)
	(via
		(at 375.405396 -246.391176)
		(size 0.5588)
		(drill 0.3048)
		(layers "F.Cu" "B.Cu")
		(net "DRIVE_A_8_FLT_LED")
	)
	(segment
		(start 375.454672 -258.35356)
		(end 375.461276 -258.360164)
		(width 0.13335)
		(layer "In2.Cu")
		(net "DRIVE_A_8_FLT_LED")
	)
	(segment
		(start 270.918178 -282.9306)
		(end 276.478492 -277.370286)
		(width 0.13335)
		(layer "In2.Cu")
		(net "DRIVE_A_8_FLT_LED")
	)
	(segment
		(start 323.854826 -258.35356)
		(end 375.454672 -258.35356)
		(width 0.13335)
		(layer "In2.Cu")
		(net "DRIVE_A_8_FLT_LED")
	)
	(segment
		(start 278.49195 -277.370286)
		(end 282.74899 -273.113246)
		(width 0.13335)
		(layer "In2.Cu")
		(net "DRIVE_A_8_FLT_LED")
	)
	(segment
		(start 282.74899 -273.113246)
		(end 309.09514 -273.113246)
		(width 0.13335)
		(layer "In2.Cu")
		(net "DRIVE_A_8_FLT_LED")
	)
	(segment
		(start 309.09514 -273.113246)
		(end 323.854826 -258.35356)
		(width 0.13335)
		(layer "In2.Cu")
		(net "DRIVE_A_8_FLT_LED")
	)
	(segment
		(start 276.478492 -277.370286)
		(end 278.49195 -277.370286)
		(width 0.13335)
		(layer "In2.Cu")
		(net "DRIVE_A_8_FLT_LED")
	)
	(segment
		(start 267.73632 -282.9306)
		(end 270.918178 -282.9306)
		(width 0.13335)
		(layer "In2.Cu")
		(net "DRIVE_A_8_FLT_LED")
	)
	(segment
		(start 375.4628 -258.35864)
		(end 375.461276 -258.360164)
		(width 0.12065)
		(layer "In4.Cu")
		(net "DRIVE_A_8_FLT_LED")
	)
	(segment
		(start 375.405396 -246.391176)
		(end 375.4628 -246.44858)
		(width 0.12065)
		(layer "In4.Cu")
		(net "DRIVE_A_8_FLT_LED")
	)
	(segment
		(start 375.4628 -246.44858)
		(end 375.4628 -258.35864)
		(width 0.12065)
		(layer "In4.Cu")
		(net "DRIVE_A_8_FLT_LED")
	)
	(segment
		(start 371.466618 -245.901464)
		(end 371.758464 -246.19331)
		(width 0.17145)
		(layer "F.Cu")
		(net "DRIVE_A_8_ACT")
	)
	(segment
		(start 372.541292 -243.741194)
		(end 372.843806 -244.043708)
		(width 0.17145)
		(layer "F.Cu")
		(net "DRIVE_A_8_ACT")
	)
	(segment
		(start 371.466618 -245.334282)
		(end 371.466618 -245.901464)
		(width 0.17145)
		(layer "F.Cu")
		(net "DRIVE_A_8_ACT")
	)
	(segment
		(start 372.799102 -245.334282)
		(end 371.466618 -245.334282)
		(width 0.17145)
		(layer "F.Cu")
		(net "DRIVE_A_8_ACT")
	)
	(segment
		(start 372.843806 -245.289578)
		(end 372.799102 -245.334282)
		(width 0.17145)
		(layer "F.Cu")
		(net "DRIVE_A_8_ACT")
	)
	(segment
		(start 372.843806 -244.043708)
		(end 372.843806 -245.289578)
		(width 0.17145)
		(layer "F.Cu")
		(net "DRIVE_A_8_ACT")
	)
	(via
		(at 374.2944 -315.665358)
		(size 0.5588)
		(drill 0.3048)
		(layers "F.Cu" "B.Cu")
		(net "DRIVE_A_8_ACT")
	)
	(via
		(at 371.758464 -246.19331)
		(size 0.5588)
		(drill 0.3048)
		(layers "F.Cu" "B.Cu")
		(net "DRIVE_A_8_ACT")
	)
	(via
		(at 372.843806 -245.289578)
		(size 0.6604)
		(drill 0.3302)
		(layers "F.Cu" "B.Cu")
		(net "DRIVE_A_8_ACT")
	)
	(segment
		(start 374.2944 -315.665358)
		(end 372.957344 -314.328302)
		(width 0.13335)
		(layer "In2.Cu")
		(net "DRIVE_A_8_ACT")
	)
	(segment
		(start 372.957344 -314.328302)
		(end 326.05345 -314.328302)
		(width 0.13335)
		(layer "In2.Cu")
		(net "DRIVE_A_8_ACT")
	)
	(segment
		(start 284.133544 -320.802)
		(end 283.23667 -319.905126)
		(width 0.13335)
		(layer "In2.Cu")
		(net "DRIVE_A_8_ACT")
	)
	(segment
		(start 319.579752 -320.802)
		(end 284.133544 -320.802)
		(width 0.13335)
		(layer "In2.Cu")
		(net "DRIVE_A_8_ACT")
	)
	(segment
		(start 326.05345 -314.328302)
		(end 319.579752 -320.802)
		(width 0.13335)
		(layer "In2.Cu")
		(net "DRIVE_A_8_ACT")
	)
	(segment
		(start 371.758464 -267.048234)
		(end 371.758464 -246.19331)
		(width 0.12065)
		(layer "In4.Cu")
		(net "DRIVE_A_8_ACT")
	)
	(segment
		(start 374.2944 -269.58417)
		(end 371.758464 -267.048234)
		(width 0.12065)
		(layer "In4.Cu")
		(net "DRIVE_A_8_ACT")
	)
	(segment
		(start 374.2944 -315.665358)
		(end 374.2944 -269.58417)
		(width 0.12065)
		(layer "In4.Cu")
		(net "DRIVE_A_8_ACT")
	)
	(segment
		(start 367.338102 -270.9418)
		(end 367.338102 -269.8242)
		(width 0.17145)
		(layer "F.Cu")
		(net "DRIVE_A_7_PWR")
	)
	(segment
		(start 228.34092 -236.170724)
		(end 228.34092 -239.8014)
		(width 0.17145)
		(layer "F.Cu")
		(net "DRIVE_A_7_PWR")
	)
	(segment
		(start 367.338102 -272.141442)
		(end 367.338102 -270.9418)
		(width 0.17145)
		(layer "F.Cu")
		(net "DRIVE_A_7_PWR")
	)
	(segment
		(start 227.756466 -235.58627)
		(end 228.34092 -236.170724)
		(width 0.17145)
		(layer "F.Cu")
		(net "DRIVE_A_7_PWR")
	)
	(via
		(at 364.5662 -224.2058)
		(size 0.5588)
		(drill 0.3048)
		(layers "F.Cu" "B.Cu")
		(net "DRIVE_A_7_PWR")
	)
	(via
		(at 227.756466 -235.58627)
		(size 0.5588)
		(drill 0.3048)
		(layers "F.Cu" "B.Cu")
		(net "DRIVE_A_7_PWR")
	)
	(via
		(at 367.338102 -270.9418)
		(size 0.6604)
		(drill 0.3302)
		(layers "F.Cu" "B.Cu")
		(net "DRIVE_A_7_PWR")
	)
	(via
		(at 367.338102 -269.8242)
		(size 0.5588)
		(drill 0.3048)
		(layers "F.Cu" "B.Cu")
		(net "DRIVE_A_7_PWR")
	)
	(segment
		(start 317.002414 -214.456518)
		(end 279.24252 -214.456518)
		(width 0.13335)
		(layer "In2.Cu")
		(net "DRIVE_A_7_PWR")
	)
	(segment
		(start 227.756466 -235.077)
		(end 227.756466 -235.58627)
		(width 0.13335)
		(layer "In2.Cu")
		(net "DRIVE_A_7_PWR")
	)
	(segment
		(start 231.504236 -231.32923)
		(end 227.756466 -235.077)
		(width 0.13335)
		(layer "In2.Cu")
		(net "DRIVE_A_7_PWR")
	)
	(segment
		(start 231.504236 -228.231192)
		(end 231.504236 -231.32923)
		(width 0.13335)
		(layer "In2.Cu")
		(net "DRIVE_A_7_PWR")
	)
	(segment
		(start 364.5662 -224.2058)
		(end 326.751696 -224.2058)
		(width 0.13335)
		(layer "In2.Cu")
		(net "DRIVE_A_7_PWR")
	)
	(segment
		(start 266.9413 -226.757738)
		(end 232.97769 -226.757738)
		(width 0.13335)
		(layer "In2.Cu")
		(net "DRIVE_A_7_PWR")
	)
	(segment
		(start 279.24252 -214.456518)
		(end 266.9413 -226.757738)
		(width 0.13335)
		(layer "In2.Cu")
		(net "DRIVE_A_7_PWR")
	)
	(segment
		(start 232.97769 -226.757738)
		(end 231.504236 -228.231192)
		(width 0.13335)
		(layer "In2.Cu")
		(net "DRIVE_A_7_PWR")
	)
	(segment
		(start 326.751696 -224.2058)
		(end 317.002414 -214.456518)
		(width 0.13335)
		(layer "In2.Cu")
		(net "DRIVE_A_7_PWR")
	)
	(segment
		(start 367.338102 -241.023902)
		(end 367.338102 -269.8242)
		(width 0.12065)
		(layer "In4.Cu")
		(net "DRIVE_A_7_PWR")
	)
	(segment
		(start 364.5662 -238.252)
		(end 367.338102 -241.023902)
		(width 0.12065)
		(layer "In4.Cu")
		(net "DRIVE_A_7_PWR")
	)
	(segment
		(start 364.5662 -224.2058)
		(end 364.5662 -238.252)
		(width 0.12065)
		(layer "In4.Cu")
		(net "DRIVE_A_7_PWR")
	)
	(segment
		(start 227.678234 -254.536448)
		(end 228.97592 -255.834134)
		(width 0.17145)
		(layer "F.Cu")
		(net "DRIVE_A_7_INS")
	)
	(segment
		(start 348.996 -295.0718)
		(end 348.996 -296.5958)
		(width 0.17145)
		(layer "F.Cu")
		(net "DRIVE_A_7_INS")
	)
	(segment
		(start 348.996 -296.5958)
		(end 349.424498 -297.024298)
		(width 0.17145)
		(layer "F.Cu")
		(net "DRIVE_A_7_INS")
	)
	(segment
		(start 350.825308 -297.024298)
		(end 349.475298 -297.024298)
		(width 0.17145)
		(layer "F.Cu")
		(net "DRIVE_A_7_INS")
	)
	(segment
		(start 351.510346 -296.33926)
		(end 350.825308 -297.024298)
		(width 0.17145)
		(layer "F.Cu")
		(net "DRIVE_A_7_INS")
	)
	(segment
		(start 349.424498 -297.024298)
		(end 349.475298 -297.024298)
		(width 0.17145)
		(layer "F.Cu")
		(net "DRIVE_A_7_INS")
	)
	(segment
		(start 228.97592 -255.834134)
		(end 228.97592 -257.4544)
		(width 0.17145)
		(layer "F.Cu")
		(net "DRIVE_A_7_INS")
	)
	(via
		(at 351.510346 -296.33926)
		(size 0.5588)
		(drill 0.3048)
		(layers "F.Cu" "B.Cu")
		(net "DRIVE_A_7_INS")
	)
	(via
		(at 349.475298 -297.024298)
		(size 0.6604)
		(drill 0.3302)
		(layers "F.Cu" "B.Cu")
		(net "DRIVE_A_7_INS")
	)
	(via
		(at 227.678234 -254.536448)
		(size 0.5588)
		(drill 0.3048)
		(layers "F.Cu" "B.Cu")
		(net "DRIVE_A_7_INS")
	)
	(via
		(at 350.5962 -236.2708)
		(size 0.5588)
		(drill 0.3048)
		(layers "F.Cu" "B.Cu")
		(net "DRIVE_A_7_INS")
	)
	(segment
		(start 245.489476 -250.925076)
		(end 246.228616 -250.925076)
		(width 0.13335)
		(layer "In2.Cu")
		(net "DRIVE_A_7_INS")
	)
	(segment
		(start 313.878214 -226.877118)
		(end 323.271896 -236.2708)
		(width 0.13335)
		(layer "In2.Cu")
		(net "DRIVE_A_7_INS")
	)
	(segment
		(start 260.5024 -243.7892)
		(end 267.16101 -243.7892)
		(width 0.13335)
		(layer "In2.Cu")
		(net "DRIVE_A_7_INS")
	)
	(segment
		(start 275.402548 -235.547662)
		(end 284.682946 -235.547662)
		(width 0.13335)
		(layer "In2.Cu")
		(net "DRIVE_A_7_INS")
	)
	(segment
		(start 246.228616 -250.925076)
		(end 251.423932 -245.72976)
		(width 0.13335)
		(layer "In2.Cu")
		(net "DRIVE_A_7_INS")
	)
	(segment
		(start 267.16101 -243.7892)
		(end 275.402548 -235.547662)
		(width 0.13335)
		(layer "In2.Cu")
		(net "DRIVE_A_7_INS")
	)
	(segment
		(start 323.271896 -236.2708)
		(end 350.5962 -236.2708)
		(width 0.13335)
		(layer "In2.Cu")
		(net "DRIVE_A_7_INS")
	)
	(segment
		(start 284.682946 -235.547662)
		(end 293.35349 -226.877118)
		(width 0.13335)
		(layer "In2.Cu")
		(net "DRIVE_A_7_INS")
	)
	(segment
		(start 293.35349 -226.877118)
		(end 313.878214 -226.877118)
		(width 0.13335)
		(layer "In2.Cu")
		(net "DRIVE_A_7_INS")
	)
	(segment
		(start 251.423932 -245.72976)
		(end 258.56184 -245.72976)
		(width 0.13335)
		(layer "In2.Cu")
		(net "DRIVE_A_7_INS")
	)
	(segment
		(start 227.678234 -254.536448)
		(end 229.98303 -252.231652)
		(width 0.13335)
		(layer "In2.Cu")
		(net "DRIVE_A_7_INS")
	)
	(segment
		(start 258.56184 -245.72976)
		(end 260.5024 -243.7892)
		(width 0.13335)
		(layer "In2.Cu")
		(net "DRIVE_A_7_INS")
	)
	(segment
		(start 229.98303 -252.231652)
		(end 244.1829 -252.231652)
		(width 0.13335)
		(layer "In2.Cu")
		(net "DRIVE_A_7_INS")
	)
	(segment
		(start 244.1829 -252.231652)
		(end 245.489476 -250.925076)
		(width 0.13335)
		(layer "In2.Cu")
		(net "DRIVE_A_7_INS")
	)
	(segment
		(start 350.5962 -283.8704)
		(end 351.5106 -284.7848)
		(width 0.12065)
		(layer "In4.Cu")
		(net "DRIVE_A_7_INS")
	)
	(segment
		(start 350.5962 -236.2708)
		(end 350.5962 -283.8704)
		(width 0.12065)
		(layer "In4.Cu")
		(net "DRIVE_A_7_INS")
	)
	(segment
		(start 351.5106 -284.7848)
		(end 351.5106 -296.339006)
		(width 0.12065)
		(layer "In4.Cu")
		(net "DRIVE_A_7_INS")
	)
	(segment
		(start 351.5106 -296.339006)
		(end 351.510346 -296.33926)
		(width 0.12065)
		(layer "In4.Cu")
		(net "DRIVE_A_7_INS")
	)
	(segment
		(start 344.354658 -245.5672)
		(end 345.029282 -245.5672)
		(width 0.17145)
		(layer "F.Cu")
		(net "DRIVE_A_7_FLT_LED")
	)
	(segment
		(start 344.076528 -245.28907)
		(end 344.354658 -245.5672)
		(width 0.17145)
		(layer "F.Cu")
		(net "DRIVE_A_7_FLT_LED")
	)
	(segment
		(start 343.483184 -245.28907)
		(end 344.076528 -245.28907)
		(width 0.17145)
		(layer "F.Cu")
		(net "DRIVE_A_7_FLT_LED")
	)
	(segment
		(start 267.08608 -278.57196)
		(end 267.08608 -275.3106)
		(width 0.17145)
		(layer "F.Cu")
		(net "DRIVE_A_7_FLT_LED")
	)
	(segment
		(start 344.596212 -243.762276)
		(end 345.079574 -244.245638)
		(width 0.17145)
		(layer "F.Cu")
		(net "DRIVE_A_7_FLT_LED")
	)
	(segment
		(start 343.483184 -245.97868)
		(end 343.855548 -246.351044)
		(width 0.17145)
		(layer "F.Cu")
		(net "DRIVE_A_7_FLT_LED")
	)
	(segment
		(start 266.43584 -279.2222)
		(end 267.08608 -278.57196)
		(width 0.17145)
		(layer "F.Cu")
		(net "DRIVE_A_7_FLT_LED")
	)
	(segment
		(start 343.483184 -245.28907)
		(end 343.483184 -245.97868)
		(width 0.17145)
		(layer "F.Cu")
		(net "DRIVE_A_7_FLT_LED")
	)
	(segment
		(start 345.079574 -244.245638)
		(end 345.079574 -245.516908)
		(width 0.17145)
		(layer "F.Cu")
		(net "DRIVE_A_7_FLT_LED")
	)
	(segment
		(start 345.029282 -245.5672)
		(end 345.079574 -245.516908)
		(width 0.17145)
		(layer "F.Cu")
		(net "DRIVE_A_7_FLT_LED")
	)
	(via
		(at 345.079574 -245.516908)
		(size 0.6604)
		(drill 0.3302)
		(layers "F.Cu" "B.Cu")
		(net "DRIVE_A_7_FLT_LED")
	)
	(via
		(at 342.856566 -257.76936)
		(size 0.5588)
		(drill 0.3048)
		(layers "F.Cu" "B.Cu")
		(net "DRIVE_A_7_FLT_LED")
	)
	(via
		(at 266.43584 -279.2222)
		(size 0.5588)
		(drill 0.3048)
		(layers "F.Cu" "B.Cu")
		(net "DRIVE_A_7_FLT_LED")
	)
	(via
		(at 343.855548 -246.351044)
		(size 0.5588)
		(drill 0.3048)
		(layers "F.Cu" "B.Cu")
		(net "DRIVE_A_7_FLT_LED")
	)
	(segment
		(start 282.517342 -272.554446)
		(end 308.863492 -272.554446)
		(width 0.13335)
		(layer "In2.Cu")
		(net "DRIVE_A_7_FLT_LED")
	)
	(segment
		(start 278.260302 -276.811486)
		(end 282.517342 -272.554446)
		(width 0.13335)
		(layer "In2.Cu")
		(net "DRIVE_A_7_FLT_LED")
	)
	(segment
		(start 323.648578 -257.76936)
		(end 342.856566 -257.76936)
		(width 0.13335)
		(layer "In2.Cu")
		(net "DRIVE_A_7_FLT_LED")
	)
	(segment
		(start 266.43584 -279.2222)
		(end 268.846554 -276.811486)
		(width 0.13335)
		(layer "In2.Cu")
		(net "DRIVE_A_7_FLT_LED")
	)
	(segment
		(start 268.846554 -276.811486)
		(end 278.260302 -276.811486)
		(width 0.13335)
		(layer "In2.Cu")
		(net "DRIVE_A_7_FLT_LED")
	)
	(segment
		(start 308.863492 -272.554446)
		(end 323.648578 -257.76936)
		(width 0.13335)
		(layer "In2.Cu")
		(net "DRIVE_A_7_FLT_LED")
	)
	(segment
		(start 343.8906 -246.386096)
		(end 343.8906 -256.735326)
		(width 0.12065)
		(layer "In4.Cu")
		(net "DRIVE_A_7_FLT_LED")
	)
	(segment
		(start 343.8906 -256.735326)
		(end 342.856566 -257.76936)
		(width 0.12065)
		(layer "In4.Cu")
		(net "DRIVE_A_7_FLT_LED")
	)
	(segment
		(start 343.855548 -246.351044)
		(end 343.8906 -246.386096)
		(width 0.12065)
		(layer "In4.Cu")
		(net "DRIVE_A_7_FLT_LED")
	)
	(segment
		(start 282.83662 -321.97802)
		(end 283.4132 -322.5546)
		(width 0.17145)
		(layer "F.Cu")
		(net "DRIVE_A_7_ACT")
	)
	(segment
		(start 339.91677 -245.80977)
		(end 340.208616 -246.101616)
		(width 0.17145)
		(layer "F.Cu")
		(net "DRIVE_A_7_ACT")
	)
	(segment
		(start 341.293958 -244.054376)
		(end 341.293958 -245.274846)
		(width 0.17145)
		(layer "F.Cu")
		(net "DRIVE_A_7_ACT")
	)
	(segment
		(start 283.4132 -322.5546)
		(end 299.1104 -322.5546)
		(width 0.17145)
		(layer "F.Cu")
		(net "DRIVE_A_7_ACT")
	)
	(segment
		(start 282.83662 -321.705224)
		(end 282.83662 -321.97802)
		(width 0.17145)
		(layer "F.Cu")
		(net "DRIVE_A_7_ACT")
	)
	(segment
		(start 341.293958 -245.274846)
		(end 341.249254 -245.31955)
		(width 0.17145)
		(layer "F.Cu")
		(net "DRIVE_A_7_ACT")
	)
	(segment
		(start 340.208616 -246.101616)
		(end 340.208616 -246.2784)
		(width 0.17145)
		(layer "F.Cu")
		(net "DRIVE_A_7_ACT")
	)
	(segment
		(start 339.91677 -245.31955)
		(end 339.91677 -245.80977)
		(width 0.17145)
		(layer "F.Cu")
		(net "DRIVE_A_7_ACT")
	)
	(segment
		(start 341.249254 -245.31955)
		(end 339.91677 -245.31955)
		(width 0.17145)
		(layer "F.Cu")
		(net "DRIVE_A_7_ACT")
	)
	(segment
		(start 299.1104 -322.5546)
		(end 300.0756 -321.5894)
		(width 0.17145)
		(layer "F.Cu")
		(net "DRIVE_A_7_ACT")
	)
	(segment
		(start 340.991444 -243.751862)
		(end 341.293958 -244.054376)
		(width 0.17145)
		(layer "F.Cu")
		(net "DRIVE_A_7_ACT")
	)
	(via
		(at 300.0756 -321.5894)
		(size 0.5588)
		(drill 0.3048)
		(layers "F.Cu" "B.Cu")
		(net "DRIVE_A_7_ACT")
	)
	(via
		(at 344.356182 -315.4426)
		(size 0.5588)
		(drill 0.3048)
		(layers "F.Cu" "B.Cu")
		(net "DRIVE_A_7_ACT")
	)
	(via
		(at 341.293958 -245.274846)
		(size 0.6604)
		(drill 0.3302)
		(layers "F.Cu" "B.Cu")
		(net "DRIVE_A_7_ACT")
	)
	(via
		(at 340.208616 -246.2784)
		(size 0.5588)
		(drill 0.3048)
		(layers "F.Cu" "B.Cu")
		(net "DRIVE_A_7_ACT")
	)
	(segment
		(start 326.285098 -314.887102)
		(end 319.5828 -321.5894)
		(width 0.13335)
		(layer "In2.Cu")
		(net "DRIVE_A_7_ACT")
	)
	(segment
		(start 319.5828 -321.5894)
		(end 300.0756 -321.5894)
		(width 0.13335)
		(layer "In2.Cu")
		(net "DRIVE_A_7_ACT")
	)
	(segment
		(start 343.800684 -314.887102)
		(end 326.285098 -314.887102)
		(width 0.13335)
		(layer "In2.Cu")
		(net "DRIVE_A_7_ACT")
	)
	(segment
		(start 344.356182 -315.4426)
		(end 343.800684 -314.887102)
		(width 0.13335)
		(layer "In2.Cu")
		(net "DRIVE_A_7_ACT")
	)
	(segment
		(start 344.356182 -279.792684)
		(end 344.356182 -315.4426)
		(width 0.12065)
		(layer "In4.Cu")
		(net "DRIVE_A_7_ACT")
	)
	(segment
		(start 346.685362 -266.930886)
		(end 346.685362 -277.463504)
		(width 0.12065)
		(layer "In4.Cu")
		(net "DRIVE_A_7_ACT")
	)
	(segment
		(start 346.685362 -277.463504)
		(end 344.356182 -279.792684)
		(width 0.12065)
		(layer "In4.Cu")
		(net "DRIVE_A_7_ACT")
	)
	(segment
		(start 340.208616 -260.45414)
		(end 346.685362 -266.930886)
		(width 0.12065)
		(layer "In4.Cu")
		(net "DRIVE_A_7_ACT")
	)
	(segment
		(start 340.208616 -246.2784)
		(end 340.208616 -260.45414)
		(width 0.12065)
		(layer "In4.Cu")
		(net "DRIVE_A_7_ACT")
	)
	(segment
		(start 228.99116 -239.8014)
		(end 228.99116 -238.178848)
		(width 0.17145)
		(layer "F.Cu")
		(net "DRIVE_A_6_PWR")
	)
	(segment
		(start 334.6196 -272.1483)
		(end 334.6196 -271.272)
		(width 0.17145)
		(layer "F.Cu")
		(net "DRIVE_A_6_PWR")
	)
	(via
		(at 228.99116 -238.178848)
		(size 0.5588)
		(drill 0.3048)
		(layers "F.Cu" "B.Cu")
		(net "DRIVE_A_6_PWR")
	)
	(via
		(at 333.442818 -224.92589)
		(size 0.5588)
		(drill 0.3048)
		(layers "F.Cu" "B.Cu")
		(net "DRIVE_A_6_PWR")
	)
	(via
		(at 334.6196 -271.272)
		(size 0.5588)
		(drill 0.3048)
		(layers "F.Cu" "B.Cu")
		(net "DRIVE_A_6_PWR")
	)
	(segment
		(start 233.06151 -234.728004)
		(end 233.06151 -228.96449)
		(width 0.13335)
		(layer "In2.Cu")
		(net "DRIVE_A_6_PWR")
	)
	(segment
		(start 233.06151 -228.96449)
		(end 234.709462 -227.316538)
		(width 0.13335)
		(layer "In2.Cu")
		(net "DRIVE_A_6_PWR")
	)
	(segment
		(start 316.770766 -215.015318)
		(end 326.681338 -224.92589)
		(width 0.13335)
		(layer "In2.Cu")
		(net "DRIVE_A_6_PWR")
	)
	(segment
		(start 229.610666 -238.178848)
		(end 233.06151 -234.728004)
		(width 0.13335)
		(layer "In2.Cu")
		(net "DRIVE_A_6_PWR")
	)
	(segment
		(start 326.681338 -224.92589)
		(end 333.442818 -224.92589)
		(width 0.13335)
		(layer "In2.Cu")
		(net "DRIVE_A_6_PWR")
	)
	(segment
		(start 279.474168 -215.015318)
		(end 316.770766 -215.015318)
		(width 0.13335)
		(layer "In2.Cu")
		(net "DRIVE_A_6_PWR")
	)
	(segment
		(start 228.99116 -238.178848)
		(end 229.610666 -238.178848)
		(width 0.13335)
		(layer "In2.Cu")
		(net "DRIVE_A_6_PWR")
	)
	(segment
		(start 267.172948 -227.316538)
		(end 279.474168 -215.015318)
		(width 0.13335)
		(layer "In2.Cu")
		(net "DRIVE_A_6_PWR")
	)
	(segment
		(start 234.709462 -227.316538)
		(end 267.172948 -227.316538)
		(width 0.13335)
		(layer "In2.Cu")
		(net "DRIVE_A_6_PWR")
	)
	(segment
		(start 333.442818 -269.536418)
		(end 333.442818 -224.92589)
		(width 0.12065)
		(layer "In4.Cu")
		(net "DRIVE_A_6_PWR")
	)
	(segment
		(start 334.6196 -270.7132)
		(end 333.442818 -269.536418)
		(width 0.12065)
		(layer "In4.Cu")
		(net "DRIVE_A_6_PWR")
	)
	(segment
		(start 334.6196 -271.272)
		(end 334.6196 -270.7132)
		(width 0.12065)
		(layer "In4.Cu")
		(net "DRIVE_A_6_PWR")
	)
	(segment
		(start 229.62616 -254.981202)
		(end 229.62616 -257.4544)
		(width 0.17145)
		(layer "F.Cu")
		(net "DRIVE_A_6_INS")
	)
	(segment
		(start 229.474268 -254.82931)
		(end 229.62616 -254.981202)
		(width 0.17145)
		(layer "F.Cu")
		(net "DRIVE_A_6_INS")
	)
	(segment
		(start 317.4492 -295.0972)
		(end 317.4492 -296.4434)
		(width 0.17145)
		(layer "F.Cu")
		(net "DRIVE_A_6_INS")
	)
	(segment
		(start 317.9318 -296.926)
		(end 317.767462 -296.761662)
		(width 0.17145)
		(layer "F.Cu")
		(net "DRIVE_A_6_INS")
	)
	(segment
		(start 317.4492 -296.4434)
		(end 317.767462 -296.761662)
		(width 0.17145)
		(layer "F.Cu")
		(net "DRIVE_A_6_INS")
	)
	(segment
		(start 320.1162 -296.926)
		(end 317.9318 -296.926)
		(width 0.17145)
		(layer "F.Cu")
		(net "DRIVE_A_6_INS")
	)
	(via
		(at 317.767462 -296.761662)
		(size 0.6604)
		(drill 0.3302)
		(layers "F.Cu" "B.Cu")
		(net "DRIVE_A_6_INS")
	)
	(via
		(at 320.1162 -296.926)
		(size 0.5588)
		(drill 0.3048)
		(layers "F.Cu" "B.Cu")
		(net "DRIVE_A_6_INS")
	)
	(via
		(at 229.474268 -254.82931)
		(size 0.5588)
		(drill 0.3048)
		(layers "F.Cu" "B.Cu")
		(net "DRIVE_A_6_INS")
	)
	(via
		(at 319.991232 -235.52404)
		(size 0.5588)
		(drill 0.3048)
		(layers "F.Cu" "B.Cu")
		(net "DRIVE_A_6_INS")
	)
	(segment
		(start 233.758486 -252.791976)
		(end 234.48772 -253.52121)
		(width 0.13335)
		(layer "In2.Cu")
		(net "DRIVE_A_6_INS")
	)
	(segment
		(start 251.65558 -246.28856)
		(end 259.32384 -246.28856)
		(width 0.13335)
		(layer "In2.Cu")
		(net "DRIVE_A_6_INS")
	)
	(segment
		(start 240.431066 -252.791976)
		(end 244.413024 -252.791976)
		(width 0.13335)
		(layer "In2.Cu")
		(net "DRIVE_A_6_INS")
	)
	(segment
		(start 234.48772 -253.52121)
		(end 239.701832 -253.52121)
		(width 0.13335)
		(layer "In2.Cu")
		(net "DRIVE_A_6_INS")
	)
	(segment
		(start 239.701832 -253.52121)
		(end 240.431066 -252.791976)
		(width 0.13335)
		(layer "In2.Cu")
		(net "DRIVE_A_6_INS")
	)
	(segment
		(start 231.511602 -252.791976)
		(end 233.758486 -252.791976)
		(width 0.13335)
		(layer "In2.Cu")
		(net "DRIVE_A_6_INS")
	)
	(segment
		(start 229.474268 -254.82931)
		(end 231.511602 -252.791976)
		(width 0.13335)
		(layer "In2.Cu")
		(net "DRIVE_A_6_INS")
	)
	(segment
		(start 259.32384 -246.28856)
		(end 260.52272 -245.08968)
		(width 0.13335)
		(layer "In2.Cu")
		(net "DRIVE_A_6_INS")
	)
	(segment
		(start 311.90311 -227.435918)
		(end 319.991232 -235.52404)
		(width 0.13335)
		(layer "In2.Cu")
		(net "DRIVE_A_6_INS")
	)
	(segment
		(start 249.014234 -250.600718)
		(end 249.014234 -248.929906)
		(width 0.13335)
		(layer "In2.Cu")
		(net "DRIVE_A_6_INS")
	)
	(segment
		(start 249.014234 -248.929906)
		(end 251.65558 -246.28856)
		(width 0.13335)
		(layer "In2.Cu")
		(net "DRIVE_A_6_INS")
	)
	(segment
		(start 276.959822 -236.106462)
		(end 284.914594 -236.106462)
		(width 0.13335)
		(layer "In2.Cu")
		(net "DRIVE_A_6_INS")
	)
	(segment
		(start 244.413024 -252.791976)
		(end 245.7196 -251.4854)
		(width 0.13335)
		(layer "In2.Cu")
		(net "DRIVE_A_6_INS")
	)
	(segment
		(start 260.52272 -245.08968)
		(end 267.976604 -245.08968)
		(width 0.13335)
		(layer "In2.Cu")
		(net "DRIVE_A_6_INS")
	)
	(segment
		(start 284.914594 -236.106462)
		(end 293.585138 -227.435918)
		(width 0.13335)
		(layer "In2.Cu")
		(net "DRIVE_A_6_INS")
	)
	(segment
		(start 293.585138 -227.435918)
		(end 311.90311 -227.435918)
		(width 0.13335)
		(layer "In2.Cu")
		(net "DRIVE_A_6_INS")
	)
	(segment
		(start 248.129552 -251.4854)
		(end 249.014234 -250.600718)
		(width 0.13335)
		(layer "In2.Cu")
		(net "DRIVE_A_6_INS")
	)
	(segment
		(start 245.7196 -251.4854)
		(end 248.129552 -251.4854)
		(width 0.13335)
		(layer "In2.Cu")
		(net "DRIVE_A_6_INS")
	)
	(segment
		(start 267.976604 -245.08968)
		(end 276.959822 -236.106462)
		(width 0.13335)
		(layer "In2.Cu")
		(net "DRIVE_A_6_INS")
	)
	(segment
		(start 319.278 -266.1158)
		(end 319.278 -296.0878)
		(width 0.12065)
		(layer "In4.Cu")
		(net "DRIVE_A_6_INS")
	)
	(segment
		(start 319.278 -296.0878)
		(end 320.1162 -296.926)
		(width 0.12065)
		(layer "In4.Cu")
		(net "DRIVE_A_6_INS")
	)
	(segment
		(start 319.991232 -265.402568)
		(end 319.278 -266.1158)
		(width 0.12065)
		(layer "In4.Cu")
		(net "DRIVE_A_6_INS")
	)
	(segment
		(start 319.991232 -235.52404)
		(end 319.991232 -265.402568)
		(width 0.12065)
		(layer "In4.Cu")
		(net "DRIVE_A_6_INS")
	)
	(segment
		(start 266.43584 -275.3106)
		(end 266.43584 -277.2918)
		(width 0.17145)
		(layer "F.Cu")
		(net "DRIVE_A_6_FLT_LED")
	)
	(segment
		(start 319.861184 -245.365016)
		(end 319.9384 -245.2878)
		(width 0.17145)
		(layer "F.Cu")
		(net "DRIVE_A_6_FLT_LED")
	)
	(segment
		(start 320.01206 -245.21414)
		(end 320.01206 -244.12575)
		(width 0.17145)
		(layer "F.Cu")
		(net "DRIVE_A_6_FLT_LED")
	)
	(segment
		(start 319.9384 -245.2878)
		(end 320.01206 -245.21414)
		(width 0.17145)
		(layer "F.Cu")
		(net "DRIVE_A_6_FLT_LED")
	)
	(segment
		(start 320.01206 -244.12575)
		(end 319.584324 -243.698014)
		(width 0.17145)
		(layer "F.Cu")
		(net "DRIVE_A_6_FLT_LED")
	)
	(segment
		(start 318.50965 -245.365016)
		(end 318.50965 -246.417338)
		(width 0.17145)
		(layer "F.Cu")
		(net "DRIVE_A_6_FLT_LED")
	)
	(segment
		(start 318.50965 -245.365016)
		(end 319.861184 -245.365016)
		(width 0.17145)
		(layer "F.Cu")
		(net "DRIVE_A_6_FLT_LED")
	)
	(via
		(at 266.43584 -277.2918)
		(size 0.5588)
		(drill 0.3048)
		(layers "F.Cu" "B.Cu")
		(net "DRIVE_A_6_FLT_LED")
	)
	(via
		(at 319.9384 -245.2878)
		(size 0.6604)
		(drill 0.3302)
		(layers "F.Cu" "B.Cu")
		(net "DRIVE_A_6_FLT_LED")
	)
	(via
		(at 318.50965 -246.417338)
		(size 0.5588)
		(drill 0.3048)
		(layers "F.Cu" "B.Cu")
		(net "DRIVE_A_6_FLT_LED")
	)
	(via
		(at 319.060068 -261.446264)
		(size 0.5588)
		(drill 0.3048)
		(layers "F.Cu" "B.Cu")
		(net "DRIVE_A_6_FLT_LED")
	)
	(segment
		(start 266.43584 -277.2918)
		(end 267.474954 -276.252686)
		(width 0.13335)
		(layer "In2.Cu")
		(net "DRIVE_A_6_FLT_LED")
	)
	(segment
		(start 308.510686 -271.995646)
		(end 319.060068 -261.446264)
		(width 0.13335)
		(layer "In2.Cu")
		(net "DRIVE_A_6_FLT_LED")
	)
	(segment
		(start 267.474954 -276.252686)
		(end 278.028654 -276.252686)
		(width 0.13335)
		(layer "In2.Cu")
		(net "DRIVE_A_6_FLT_LED")
	)
	(segment
		(start 278.028654 -276.252686)
		(end 282.285694 -271.995646)
		(width 0.13335)
		(layer "In2.Cu")
		(net "DRIVE_A_6_FLT_LED")
	)
	(segment
		(start 282.285694 -271.995646)
		(end 308.510686 -271.995646)
		(width 0.13335)
		(layer "In2.Cu")
		(net "DRIVE_A_6_FLT_LED")
	)
	(segment
		(start 319.060068 -246.967756)
		(end 318.50965 -246.417338)
		(width 0.12065)
		(layer "In4.Cu")
		(net "DRIVE_A_6_FLT_LED")
	)
	(segment
		(start 319.060068 -261.446264)
		(end 319.060068 -246.967756)
		(width 0.12065)
		(layer "In4.Cu")
		(net "DRIVE_A_6_FLT_LED")
	)
	(segment
		(start 318.347852 -249.119136)
		(end 317.622936 -249.119136)
		(width 0.17145)
		(layer "F.Cu")
		(net "DRIVE_A_6_ACT")
	)
	(segment
		(start 317.622936 -249.119136)
		(end 314.915804 -246.412004)
		(width 0.17145)
		(layer "F.Cu")
		(net "DRIVE_A_6_ACT")
	)
	(segment
		(start 316.324996 -245.3259)
		(end 316.324996 -244.022626)
		(width 0.17145)
		(layer "F.Cu")
		(net "DRIVE_A_6_ACT")
	)
	(segment
		(start 314.915804 -246.412004)
		(end 314.915804 -245.357142)
		(width 0.17145)
		(layer "F.Cu")
		(net "DRIVE_A_6_ACT")
	)
	(segment
		(start 316.324996 -244.022626)
		(end 316.000638 -243.698268)
		(width 0.17145)
		(layer "F.Cu")
		(net "DRIVE_A_6_ACT")
	)
	(segment
		(start 316.293754 -245.357142)
		(end 316.324996 -245.3259)
		(width 0.17145)
		(layer "F.Cu")
		(net "DRIVE_A_6_ACT")
	)
	(segment
		(start 314.915804 -245.357142)
		(end 316.293754 -245.357142)
		(width 0.17145)
		(layer "F.Cu")
		(net "DRIVE_A_6_ACT")
	)
	(via
		(at 316.293754 -245.357142)
		(size 0.6604)
		(drill 0.3302)
		(layers "F.Cu" "B.Cu")
		(net "DRIVE_A_6_ACT")
	)
	(via
		(at 318.347852 -249.119136)
		(size 0.5588)
		(drill 0.3048)
		(layers "F.Cu" "B.Cu")
		(net "DRIVE_A_6_ACT")
	)
	(via
		(at 318.7192 -322.4784)
		(size 0.5588)
		(drill 0.3048)
		(layers "F.Cu" "B.Cu")
		(net "DRIVE_A_6_ACT")
	)
	(segment
		(start 284.861 -322.6562)
		(end 284.236668 -322.031868)
		(width 0.13335)
		(layer "In2.Cu")
		(net "DRIVE_A_6_ACT")
	)
	(segment
		(start 284.236668 -322.031868)
		(end 284.236668 -321.705224)
		(width 0.13335)
		(layer "In2.Cu")
		(net "DRIVE_A_6_ACT")
	)
	(segment
		(start 318.5414 -322.6562)
		(end 284.861 -322.6562)
		(width 0.13335)
		(layer "In2.Cu")
		(net "DRIVE_A_6_ACT")
	)
	(segment
		(start 318.7192 -322.4784)
		(end 318.5414 -322.6562)
		(width 0.13335)
		(layer "In2.Cu")
		(net "DRIVE_A_6_ACT")
	)
	(segment
		(start 318.347852 -265.266424)
		(end 318.7192 -265.637772)
		(width 0.12065)
		(layer "In4.Cu")
		(net "DRIVE_A_6_ACT")
	)
	(segment
		(start 318.7192 -265.637772)
		(end 318.7192 -322.4784)
		(width 0.12065)
		(layer "In4.Cu")
		(net "DRIVE_A_6_ACT")
	)
	(segment
		(start 318.347852 -249.119136)
		(end 318.347852 -265.266424)
		(width 0.12065)
		(layer "In4.Cu")
		(net "DRIVE_A_6_ACT")
	)
	(segment
		(start 227.254054 -248.222262)
		(end 227.254054 -245.526814)
		(width 0.17145)
		(layer "F.Cu")
		(net "DRIVE_A_5_PWR")
	)
	(segment
		(start 228.7524 -244.028468)
		(end 228.7524 -241.6048)
		(width 0.17145)
		(layer "F.Cu")
		(net "DRIVE_A_5_PWR")
	)
	(segment
		(start 227.254054 -245.526814)
		(end 228.7016 -244.079268)
		(width 0.17145)
		(layer "F.Cu")
		(net "DRIVE_A_5_PWR")
	)
	(segment
		(start 229.6414 -240.7158)
		(end 229.6414 -239.8014)
		(width 0.17145)
		(layer "F.Cu")
		(net "DRIVE_A_5_PWR")
	)
	(segment
		(start 228.7016 -244.079268)
		(end 228.7524 -244.028468)
		(width 0.17145)
		(layer "F.Cu")
		(net "DRIVE_A_5_PWR")
	)
	(segment
		(start 228.7524 -241.6048)
		(end 229.6414 -240.7158)
		(width 0.17145)
		(layer "F.Cu")
		(net "DRIVE_A_5_PWR")
	)
	(segment
		(start 227.542598 -248.510806)
		(end 227.254054 -248.222262)
		(width 0.17145)
		(layer "F.Cu")
		(net "DRIVE_A_5_PWR")
	)
	(segment
		(start 181.1909 -274.821142)
		(end 182.0164 -274.821142)
		(width 0.17145)
		(layer "F.Cu")
		(net "DRIVE_A_5_PWR")
	)
	(via
		(at 227.542598 -248.510806)
		(size 0.5588)
		(drill 0.3048)
		(layers "F.Cu" "B.Cu")
		(net "DRIVE_A_5_PWR")
	)
	(via
		(at 182.0164 -274.821142)
		(size 0.5588)
		(drill 0.3048)
		(layers "F.Cu" "B.Cu")
		(net "DRIVE_A_5_PWR")
	)
	(via
		(at 171.2722 -254.41148)
		(size 0.5588)
		(drill 0.3048)
		(layers "F.Cu" "B.Cu")
		(net "DRIVE_A_5_PWR")
	)
	(via
		(at 228.7016 -244.079268)
		(size 0.6604)
		(drill 0.3302)
		(layers "F.Cu" "B.Cu")
		(net "DRIVE_A_5_PWR")
	)
	(segment
		(start 171.444666 -254.583946)
		(end 171.2722 -254.41148)
		(width 0.13335)
		(layer "In2.Cu")
		(net "DRIVE_A_5_PWR")
	)
	(segment
		(start 227.542598 -248.510806)
		(end 227.002594 -248.510806)
		(width 0.13335)
		(layer "In2.Cu")
		(net "DRIVE_A_5_PWR")
	)
	(segment
		(start 227.002594 -248.510806)
		(end 220.9292 -254.5842)
		(width 0.13335)
		(layer "In2.Cu")
		(net "DRIVE_A_5_PWR")
	)
	(segment
		(start 199.817228 -254.583946)
		(end 171.444666 -254.583946)
		(width 0.13335)
		(layer "In2.Cu")
		(net "DRIVE_A_5_PWR")
	)
	(segment
		(start 220.9292 -254.5842)
		(end 199.817482 -254.5842)
		(width 0.13335)
		(layer "In2.Cu")
		(net "DRIVE_A_5_PWR")
	)
	(segment
		(start 199.817482 -254.5842)
		(end 199.817228 -254.583946)
		(width 0.13335)
		(layer "In2.Cu")
		(net "DRIVE_A_5_PWR")
	)
	(segment
		(start 182.0164 -274.821142)
		(end 182.0164 -270.45539)
		(width 0.12065)
		(layer "In4.Cu")
		(net "DRIVE_A_5_PWR")
	)
	(segment
		(start 171.2722 -259.71119)
		(end 171.2722 -254.41148)
		(width 0.12065)
		(layer "In4.Cu")
		(net "DRIVE_A_5_PWR")
	)
	(segment
		(start 182.0164 -270.45539)
		(end 171.2722 -259.71119)
		(width 0.12065)
		(layer "In4.Cu")
		(net "DRIVE_A_5_PWR")
	)
	(segment
		(start 229.064058 -259.758942)
		(end 230.2764 -258.5466)
		(width 0.17145)
		(layer "F.Cu")
		(net "DRIVE_A_5_INS")
	)
	(segment
		(start 230.2764 -258.5466)
		(end 230.2764 -257.4544)
		(width 0.17145)
		(layer "F.Cu")
		(net "DRIVE_A_5_INS")
	)
	(segment
		(start 229.83825 -266.998958)
		(end 229.83825 -265.83386)
		(width 0.17145)
		(layer "F.Cu")
		(net "DRIVE_A_5_INS")
	)
	(segment
		(start 229.064058 -265.059668)
		(end 229.064058 -259.758942)
		(width 0.17145)
		(layer "F.Cu")
		(net "DRIVE_A_5_INS")
	)
	(segment
		(start 229.83825 -265.83386)
		(end 229.064058 -265.059668)
		(width 0.17145)
		(layer "F.Cu")
		(net "DRIVE_A_5_INS")
	)
	(segment
		(start 191.135 -295.529)
		(end 191.135 -296.545)
		(width 0.17145)
		(layer "F.Cu")
		(net "DRIVE_A_5_INS")
	)
	(via
		(at 229.83825 -265.83386)
		(size 0.6604)
		(drill 0.3302)
		(layers "F.Cu" "B.Cu")
		(net "DRIVE_A_5_INS")
	)
	(via
		(at 191.135 -296.545)
		(size 0.5588)
		(drill 0.3048)
		(layers "F.Cu" "B.Cu")
		(net "DRIVE_A_5_INS")
	)
	(via
		(at 192.913 -268.2494)
		(size 0.5588)
		(drill 0.3048)
		(layers "F.Cu" "B.Cu")
		(net "DRIVE_A_5_INS")
	)
	(via
		(at 229.83825 -266.998958)
		(size 0.5588)
		(drill 0.3048)
		(layers "F.Cu" "B.Cu")
		(net "DRIVE_A_5_INS")
	)
	(segment
		(start 228.384608 -268.4526)
		(end 229.83825 -266.998958)
		(width 0.13335)
		(layer "In2.Cu")
		(net "DRIVE_A_5_INS")
	)
	(segment
		(start 192.913 -268.2494)
		(end 193.1162 -268.4526)
		(width 0.13335)
		(layer "In2.Cu")
		(net "DRIVE_A_5_INS")
	)
	(segment
		(start 193.1162 -268.4526)
		(end 228.384608 -268.4526)
		(width 0.13335)
		(layer "In2.Cu")
		(net "DRIVE_A_5_INS")
	)
	(segment
		(start 191.135 -270.0274)
		(end 192.913 -268.2494)
		(width 0.12065)
		(layer "In4.Cu")
		(net "DRIVE_A_5_INS")
	)
	(segment
		(start 191.135 -296.545)
		(end 191.135 -270.0274)
		(width 0.12065)
		(layer "In4.Cu")
		(net "DRIVE_A_5_INS")
	)
	(segment
		(start 265.7856 -277.60676)
		(end 265.7856 -275.3106)
		(width 0.17145)
		(layer "F.Cu")
		(net "DRIVE_A_5_FLT_LED")
	)
	(segment
		(start 266.43584 -278.257)
		(end 265.7856 -277.60676)
		(width 0.17145)
		(layer "F.Cu")
		(net "DRIVE_A_5_FLT_LED")
	)
	(segment
		(start 161.878772 -189.261242)
		(end 161.880804 -189.25921)
		(width 0.17145)
		(layer "F.Cu")
		(net "DRIVE_A_5_FLT_LED")
	)
	(segment
		(start 161.878772 -190.410846)
		(end 161.878772 -189.261242)
		(width 0.17145)
		(layer "F.Cu")
		(net "DRIVE_A_5_FLT_LED")
	)
	(segment
		(start 161.880804 -189.25921)
		(end 161.880804 -187.913264)
		(width 0.17145)
		(layer "F.Cu")
		(net "DRIVE_A_5_FLT_LED")
	)
	(segment
		(start 161.880804 -187.913264)
		(end 163.289488 -187.913264)
		(width 0.17145)
		(layer "F.Cu")
		(net "DRIVE_A_5_FLT_LED")
	)
	(segment
		(start 163.289488 -187.913264)
		(end 163.298886 -187.922662)
		(width 0.17145)
		(layer "F.Cu")
		(net "DRIVE_A_5_FLT_LED")
	)
	(via
		(at 160.681162 -288.60115)
		(size 0.5588)
		(drill 0.3048)
		(layers "F.Cu" "B.Cu")
		(net "DRIVE_A_5_FLT_LED")
	)
	(via
		(at 161.878772 -190.410846)
		(size 0.5588)
		(drill 0.3048)
		(layers "F.Cu" "B.Cu")
		(net "DRIVE_A_5_FLT_LED")
	)
	(via
		(at 161.878772 -189.261242)
		(size 0.6604)
		(drill 0.3302)
		(layers "F.Cu" "B.Cu")
		(net "DRIVE_A_5_FLT_LED")
	)
	(via
		(at 266.43584 -278.257)
		(size 0.5588)
		(drill 0.3048)
		(layers "F.Cu" "B.Cu")
		(net "DRIVE_A_5_FLT_LED")
	)
	(segment
		(start 202.766422 -285.788862)
		(end 176.93513 -285.788862)
		(width 0.13335)
		(layer "In2.Cu")
		(net "DRIVE_A_5_FLT_LED")
	)
	(segment
		(start 264.0584 -280.7462)
		(end 257.462274 -280.7462)
		(width 0.13335)
		(layer "In2.Cu")
		(net "DRIVE_A_5_FLT_LED")
	)
	(segment
		(start 176.93513 -285.788862)
		(end 174.122842 -288.60115)
		(width 0.13335)
		(layer "In2.Cu")
		(net "DRIVE_A_5_FLT_LED")
	)
	(segment
		(start 257.462274 -280.7462)
		(end 248.361962 -289.846512)
		(width 0.13335)
		(layer "In2.Cu")
		(net "DRIVE_A_5_FLT_LED")
	)
	(segment
		(start 266.43584 -278.36876)
		(end 264.0584 -280.7462)
		(width 0.13335)
		(layer "In2.Cu")
		(net "DRIVE_A_5_FLT_LED")
	)
	(segment
		(start 248.361962 -289.846512)
		(end 206.824072 -289.846512)
		(width 0.13335)
		(layer "In2.Cu")
		(net "DRIVE_A_5_FLT_LED")
	)
	(segment
		(start 266.43584 -278.257)
		(end 266.43584 -278.36876)
		(width 0.13335)
		(layer "In2.Cu")
		(net "DRIVE_A_5_FLT_LED")
	)
	(segment
		(start 206.824072 -289.846512)
		(end 202.766422 -285.788862)
		(width 0.13335)
		(layer "In2.Cu")
		(net "DRIVE_A_5_FLT_LED")
	)
	(segment
		(start 174.122842 -288.60115)
		(end 160.681162 -288.60115)
		(width 0.13335)
		(layer "In2.Cu")
		(net "DRIVE_A_5_FLT_LED")
	)
	(segment
		(start 165.3032 -236.6391)
		(end 165.3032 -257.9116)
		(width 0.12065)
		(layer "In4.Cu")
		(net "DRIVE_A_5_FLT_LED")
	)
	(segment
		(start 161.878772 -195.90385)
		(end 167.0304 -201.055478)
		(width 0.12065)
		(layer "In4.Cu")
		(net "DRIVE_A_5_FLT_LED")
	)
	(segment
		(start 160.681162 -262.533638)
		(end 160.681162 -288.60115)
		(width 0.12065)
		(layer "In4.Cu")
		(net "DRIVE_A_5_FLT_LED")
	)
	(segment
		(start 167.0304 -201.055478)
		(end 167.0304 -234.9119)
		(width 0.12065)
		(layer "In4.Cu")
		(net "DRIVE_A_5_FLT_LED")
	)
	(segment
		(start 167.0304 -234.9119)
		(end 165.3032 -236.6391)
		(width 0.12065)
		(layer "In4.Cu")
		(net "DRIVE_A_5_FLT_LED")
	)
	(segment
		(start 165.3032 -257.9116)
		(end 160.681162 -262.533638)
		(width 0.12065)
		(layer "In4.Cu")
		(net "DRIVE_A_5_FLT_LED")
	)
	(segment
		(start 161.878772 -190.410846)
		(end 161.878772 -195.90385)
		(width 0.12065)
		(layer "In4.Cu")
		(net "DRIVE_A_5_FLT_LED")
	)
	(segment
		(start 163.29787 -184.132982)
		(end 163.29787 -183.638444)
		(width 0.17145)
		(layer "F.Cu")
		(net "DRIVE_A_5_ACT")
	)
	(segment
		(start 164.390578 -181.406038)
		(end 164.390578 -180.22697)
		(width 0.17145)
		(layer "F.Cu")
		(net "DRIVE_A_5_ACT")
	)
	(segment
		(start 164.390578 -182.545736)
		(end 164.390578 -181.406038)
		(width 0.17145)
		(layer "F.Cu")
		(net "DRIVE_A_5_ACT")
	)
	(segment
		(start 163.29787 -183.638444)
		(end 164.390578 -182.545736)
		(width 0.17145)
		(layer "F.Cu")
		(net "DRIVE_A_5_ACT")
	)
	(via
		(at 164.390578 -182.545736)
		(size 0.6604)
		(drill 0.3302)
		(layers "F.Cu" "B.Cu")
		(net "DRIVE_A_5_ACT")
	)
	(via
		(at 164.390578 -180.22697)
		(size 0.5588)
		(drill 0.3048)
		(layers "F.Cu" "B.Cu")
		(net "DRIVE_A_5_ACT")
	)
	(via
		(at 168.656 -324.6374)
		(size 0.5588)
		(drill 0.3048)
		(layers "F.Cu" "B.Cu")
		(net "DRIVE_A_5_ACT")
	)
	(segment
		(start 280.962354 -322.6308)
		(end 276.3012 -322.6308)
		(width 0.13335)
		(layer "In2.Cu")
		(net "DRIVE_A_5_ACT")
	)
	(segment
		(start 190.463932 -321.7672)
		(end 187.060332 -325.1708)
		(width 0.13335)
		(layer "In2.Cu")
		(net "DRIVE_A_5_ACT")
	)
	(segment
		(start 169.1894 -325.1708)
		(end 168.656 -324.6374)
		(width 0.13335)
		(layer "In2.Cu")
		(net "DRIVE_A_5_ACT")
	)
	(segment
		(start 281.836622 -323.505068)
		(end 280.962354 -322.6308)
		(width 0.13335)
		(layer "In2.Cu")
		(net "DRIVE_A_5_ACT")
	)
	(segment
		(start 187.060332 -325.1708)
		(end 169.1894 -325.1708)
		(width 0.13335)
		(layer "In2.Cu")
		(net "DRIVE_A_5_ACT")
	)
	(segment
		(start 276.3012 -322.6308)
		(end 275.4376 -321.7672)
		(width 0.13335)
		(layer "In2.Cu")
		(net "DRIVE_A_5_ACT")
	)
	(segment
		(start 275.4376 -321.7672)
		(end 190.463932 -321.7672)
		(width 0.13335)
		(layer "In2.Cu")
		(net "DRIVE_A_5_ACT")
	)
	(segment
		(start 169.5196 -234.188)
		(end 169.5196 -260.0198)
		(width 0.12065)
		(layer "In4.Cu")
		(net "DRIVE_A_5_ACT")
	)
	(segment
		(start 168.7068 -233.3752)
		(end 169.5196 -234.188)
		(width 0.12065)
		(layer "In4.Cu")
		(net "DRIVE_A_5_ACT")
	)
	(segment
		(start 169.5196 -260.0198)
		(end 161.239962 -268.299438)
		(width 0.12065)
		(layer "In4.Cu")
		(net "DRIVE_A_5_ACT")
	)
	(segment
		(start 161.239962 -268.299438)
		(end 161.239962 -290.95446)
		(width 0.12065)
		(layer "In4.Cu")
		(net "DRIVE_A_5_ACT")
	)
	(segment
		(start 168.656 -319.633854)
		(end 168.656 -324.6374)
		(width 0.12065)
		(layer "In4.Cu")
		(net "DRIVE_A_5_ACT")
	)
	(segment
		(start 161.239962 -290.95446)
		(end 158.409894 -293.784528)
		(width 0.12065)
		(layer "In4.Cu")
		(net "DRIVE_A_5_ACT")
	)
	(segment
		(start 164.390578 -196.044312)
		(end 168.7068 -200.360534)
		(width 0.12065)
		(layer "In4.Cu")
		(net "DRIVE_A_5_ACT")
	)
	(segment
		(start 158.409894 -309.387748)
		(end 168.656 -319.633854)
		(width 0.12065)
		(layer "In4.Cu")
		(net "DRIVE_A_5_ACT")
	)
	(segment
		(start 158.409894 -293.784528)
		(end 158.409894 -309.387748)
		(width 0.12065)
		(layer "In4.Cu")
		(net "DRIVE_A_5_ACT")
	)
	(segment
		(start 164.390578 -180.22697)
		(end 164.390578 -196.044312)
		(width 0.12065)
		(layer "In4.Cu")
		(net "DRIVE_A_5_ACT")
	)
	(segment
		(start 168.7068 -200.360534)
		(end 168.7068 -233.3752)
		(width 0.12065)
		(layer "In4.Cu")
		(net "DRIVE_A_5_ACT")
	)
	(segment
		(start 227.842064 -247.353582)
		(end 227.842064 -246.443754)
		(width 0.17145)
		(layer "F.Cu")
		(net "DRIVE_A_4_PWR")
	)
	(segment
		(start 230.29164 -240.90376)
		(end 230.29164 -239.8014)
		(width 0.17145)
		(layer "F.Cu")
		(net "DRIVE_A_4_PWR")
	)
	(segment
		(start 227.842064 -246.443754)
		(end 229.327964 -244.957854)
		(width 0.17145)
		(layer "F.Cu")
		(net "DRIVE_A_4_PWR")
	)
	(segment
		(start 228.248718 -247.760236)
		(end 227.842064 -247.353582)
		(width 0.17145)
		(layer "F.Cu")
		(net "DRIVE_A_4_PWR")
	)
	(segment
		(start 149.640798 -274.871942)
		(end 150.466298 -274.871942)
		(width 0.17145)
		(layer "F.Cu")
		(net "DRIVE_A_4_PWR")
	)
	(segment
		(start 229.327964 -244.957854)
		(end 229.327964 -241.867436)
		(width 0.17145)
		(layer "F.Cu")
		(net "DRIVE_A_4_PWR")
	)
	(segment
		(start 229.327964 -241.867436)
		(end 230.29164 -240.90376)
		(width 0.17145)
		(layer "F.Cu")
		(net "DRIVE_A_4_PWR")
	)
	(via
		(at 145.1356 -254.0254)
		(size 0.5588)
		(drill 0.3048)
		(layers "F.Cu" "B.Cu")
		(net "DRIVE_A_4_PWR")
	)
	(via
		(at 229.327964 -244.957854)
		(size 0.6604)
		(drill 0.3302)
		(layers "F.Cu" "B.Cu")
		(net "DRIVE_A_4_PWR")
	)
	(via
		(at 150.466298 -274.871942)
		(size 0.5588)
		(drill 0.3048)
		(layers "F.Cu" "B.Cu")
		(net "DRIVE_A_4_PWR")
	)
	(via
		(at 228.248718 -247.760236)
		(size 0.5588)
		(drill 0.3048)
		(layers "F.Cu" "B.Cu")
		(net "DRIVE_A_4_PWR")
	)
	(segment
		(start 145.3134 -253.8476)
		(end 145.1356 -254.0254)
		(width 0.13335)
		(layer "In2.Cu")
		(net "DRIVE_A_4_PWR")
	)
	(segment
		(start 228.248718 -247.760236)
		(end 226.962716 -247.760236)
		(width 0.13335)
		(layer "In2.Cu")
		(net "DRIVE_A_4_PWR")
	)
	(segment
		(start 200.048876 -254.025146)
		(end 171.676314 -254.025146)
		(width 0.13335)
		(layer "In2.Cu")
		(net "DRIVE_A_4_PWR")
	)
	(segment
		(start 226.962716 -247.760236)
		(end 220.697552 -254.0254)
		(width 0.13335)
		(layer "In2.Cu")
		(net "DRIVE_A_4_PWR")
	)
	(segment
		(start 220.697552 -254.0254)
		(end 200.04913 -254.0254)
		(width 0.13335)
		(layer "In2.Cu")
		(net "DRIVE_A_4_PWR")
	)
	(segment
		(start 171.676314 -254.025146)
		(end 171.498768 -253.8476)
		(width 0.13335)
		(layer "In2.Cu")
		(net "DRIVE_A_4_PWR")
	)
	(segment
		(start 171.498768 -253.8476)
		(end 145.3134 -253.8476)
		(width 0.13335)
		(layer "In2.Cu")
		(net "DRIVE_A_4_PWR")
	)
	(segment
		(start 200.04913 -254.0254)
		(end 200.048876 -254.025146)
		(width 0.13335)
		(layer "In2.Cu")
		(net "DRIVE_A_4_PWR")
	)
	(segment
		(start 145.1102 -254.0508)
		(end 145.1356 -254.0254)
		(width 0.12065)
		(layer "In4.Cu")
		(net "DRIVE_A_4_PWR")
	)
	(segment
		(start 145.1102 -269.515844)
		(end 145.1102 -254.0508)
		(width 0.12065)
		(layer "In4.Cu")
		(net "DRIVE_A_4_PWR")
	)
	(segment
		(start 150.466298 -274.871942)
		(end 145.1102 -269.515844)
		(width 0.12065)
		(layer "In4.Cu")
		(net "DRIVE_A_4_PWR")
	)
	(segment
		(start 229.622858 -259.962142)
		(end 229.622858 -264.62228)
		(width 0.17145)
		(layer "F.Cu")
		(net "DRIVE_A_4_INS")
	)
	(segment
		(start 163.140898 -295.064942)
		(end 163.140898 -293.998142)
		(width 0.17145)
		(layer "F.Cu")
		(net "DRIVE_A_4_INS")
	)
	(segment
		(start 229.622858 -264.62228)
		(end 231.238298 -266.23772)
		(width 0.17145)
		(layer "F.Cu")
		(net "DRIVE_A_4_INS")
	)
	(segment
		(start 230.92664 -257.4544)
		(end 230.92664 -258.65836)
		(width 0.17145)
		(layer "F.Cu")
		(net "DRIVE_A_4_INS")
	)
	(segment
		(start 231.238298 -268.057376)
		(end 231.238298 -266.998958)
		(width 0.17145)
		(layer "F.Cu")
		(net "DRIVE_A_4_INS")
	)
	(segment
		(start 163.140898 -293.998142)
		(end 163.307268 -293.831772)
		(width 0.17145)
		(layer "F.Cu")
		(net "DRIVE_A_4_INS")
	)
	(segment
		(start 231.238298 -266.23772)
		(end 231.238298 -266.998958)
		(width 0.17145)
		(layer "F.Cu")
		(net "DRIVE_A_4_INS")
	)
	(segment
		(start 230.92664 -258.65836)
		(end 229.622858 -259.962142)
		(width 0.17145)
		(layer "F.Cu")
		(net "DRIVE_A_4_INS")
	)
	(via
		(at 163.8808 -271.2212)
		(size 0.5588)
		(drill 0.3048)
		(layers "F.Cu" "B.Cu")
		(net "DRIVE_A_4_INS")
	)
	(via
		(at 231.238298 -268.057376)
		(size 0.5588)
		(drill 0.3048)
		(layers "F.Cu" "B.Cu")
		(net "DRIVE_A_4_INS")
	)
	(via
		(at 163.307268 -293.831772)
		(size 0.5588)
		(drill 0.3048)
		(layers "F.Cu" "B.Cu")
		(net "DRIVE_A_4_INS")
	)
	(via
		(at 231.238298 -266.998958)
		(size 0.6604)
		(drill 0.3302)
		(layers "F.Cu" "B.Cu")
		(net "DRIVE_A_4_INS")
	)
	(segment
		(start 182.500778 -266.39647)
		(end 172.704506 -276.192742)
		(width 0.13335)
		(layer "In2.Cu")
		(net "DRIVE_A_4_INS")
	)
	(segment
		(start 231.238298 -268.057376)
		(end 230.208074 -269.0876)
		(width 0.13335)
		(layer "In2.Cu")
		(net "DRIVE_A_4_INS")
	)
	(segment
		(start 230.208074 -269.0876)
		(end 189.988444 -269.0876)
		(width 0.13335)
		(layer "In2.Cu")
		(net "DRIVE_A_4_INS")
	)
	(segment
		(start 172.704506 -276.192742)
		(end 168.852088 -276.192742)
		(width 0.13335)
		(layer "In2.Cu")
		(net "DRIVE_A_4_INS")
	)
	(segment
		(start 163.8808 -271.221454)
		(end 163.8808 -271.2212)
		(width 0.13335)
		(layer "In2.Cu")
		(net "DRIVE_A_4_INS")
	)
	(segment
		(start 189.988444 -269.0876)
		(end 187.297314 -266.39647)
		(width 0.13335)
		(layer "In2.Cu")
		(net "DRIVE_A_4_INS")
	)
	(segment
		(start 187.297314 -266.39647)
		(end 182.500778 -266.39647)
		(width 0.13335)
		(layer "In2.Cu")
		(net "DRIVE_A_4_INS")
	)
	(segment
		(start 168.852088 -276.192742)
		(end 163.8808 -271.221454)
		(width 0.13335)
		(layer "In2.Cu")
		(net "DRIVE_A_4_INS")
	)
	(segment
		(start 163.8808 -271.2212)
		(end 163.8808 -293.25824)
		(width 0.12065)
		(layer "In4.Cu")
		(net "DRIVE_A_4_INS")
	)
	(segment
		(start 163.8808 -293.25824)
		(end 163.307268 -293.831772)
		(width 0.12065)
		(layer "In4.Cu")
		(net "DRIVE_A_4_INS")
	)
	(segment
		(start 264.48512 -279.527)
		(end 264.48512 -279.27808)
		(width 0.17145)
		(layer "F.Cu")
		(net "DRIVE_A_4_FLT_LED")
	)
	(segment
		(start 265.13536 -278.62784)
		(end 265.13536 -275.3106)
		(width 0.17145)
		(layer "F.Cu")
		(net "DRIVE_A_4_FLT_LED")
	)
	(segment
		(start 130.272536 -187.936378)
		(end 130.272536 -189.282324)
		(width 0.17145)
		(layer "F.Cu")
		(net "DRIVE_A_4_FLT_LED")
	)
	(segment
		(start 131.69265 -187.943744)
		(end 131.683252 -187.934346)
		(width 0.17145)
		(layer "F.Cu")
		(net "DRIVE_A_4_FLT_LED")
	)
	(segment
		(start 131.683252 -187.934346)
		(end 130.274568 -187.934346)
		(width 0.17145)
		(layer "F.Cu")
		(net "DRIVE_A_4_FLT_LED")
	)
	(segment
		(start 264.48512 -279.27808)
		(end 265.13536 -278.62784)
		(width 0.17145)
		(layer "F.Cu")
		(net "DRIVE_A_4_FLT_LED")
	)
	(segment
		(start 130.274568 -187.934346)
		(end 130.272536 -187.936378)
		(width 0.17145)
		(layer "F.Cu")
		(net "DRIVE_A_4_FLT_LED")
	)
	(segment
		(start 130.272536 -189.282324)
		(end 130.272536 -190.431928)
		(width 0.17145)
		(layer "F.Cu")
		(net "DRIVE_A_4_FLT_LED")
	)
	(via
		(at 129.295398 -288.7218)
		(size 0.5588)
		(drill 0.3048)
		(layers "F.Cu" "B.Cu")
		(net "DRIVE_A_4_FLT_LED")
	)
	(via
		(at 130.272536 -190.431928)
		(size 0.5588)
		(drill 0.3048)
		(layers "F.Cu" "B.Cu")
		(net "DRIVE_A_4_FLT_LED")
	)
	(via
		(at 264.48512 -279.527)
		(size 0.5588)
		(drill 0.3048)
		(layers "F.Cu" "B.Cu")
		(net "DRIVE_A_4_FLT_LED")
	)
	(via
		(at 130.272536 -189.282324)
		(size 0.6604)
		(drill 0.3302)
		(layers "F.Cu" "B.Cu")
		(net "DRIVE_A_4_FLT_LED")
	)
	(segment
		(start 177.427128 -284.506416)
		(end 173.891194 -288.04235)
		(width 0.13335)
		(layer "In2.Cu")
		(net "DRIVE_A_4_FLT_LED")
	)
	(segment
		(start 202.274424 -284.506416)
		(end 177.427128 -284.506416)
		(width 0.13335)
		(layer "In2.Cu")
		(net "DRIVE_A_4_FLT_LED")
	)
	(segment
		(start 173.891194 -288.04235)
		(end 154.696668 -288.04235)
		(width 0.13335)
		(layer "In2.Cu")
		(net "DRIVE_A_4_FLT_LED")
	)
	(segment
		(start 264.48512 -279.527)
		(end 263.82472 -280.1874)
		(width 0.13335)
		(layer "In2.Cu")
		(net "DRIVE_A_4_FLT_LED")
	)
	(segment
		(start 257.230626 -280.1874)
		(end 248.130568 -289.287458)
		(width 0.13335)
		(layer "In2.Cu")
		(net "DRIVE_A_4_FLT_LED")
	)
	(segment
		(start 263.82472 -280.1874)
		(end 257.230626 -280.1874)
		(width 0.13335)
		(layer "In2.Cu")
		(net "DRIVE_A_4_FLT_LED")
	)
	(segment
		(start 248.130568 -289.287458)
		(end 207.055466 -289.287458)
		(width 0.13335)
		(layer "In2.Cu")
		(net "DRIVE_A_4_FLT_LED")
	)
	(segment
		(start 154.017218 -288.7218)
		(end 129.295398 -288.7218)
		(width 0.13335)
		(layer "In2.Cu")
		(net "DRIVE_A_4_FLT_LED")
	)
	(segment
		(start 154.696668 -288.04235)
		(end 154.017218 -288.7218)
		(width 0.13335)
		(layer "In2.Cu")
		(net "DRIVE_A_4_FLT_LED")
	)
	(segment
		(start 207.055466 -289.287458)
		(end 202.274424 -284.506416)
		(width 0.13335)
		(layer "In2.Cu")
		(net "DRIVE_A_4_FLT_LED")
	)
	(segment
		(start 127.311404 -190.431928)
		(end 111.37265 -206.370682)
		(width 0.12065)
		(layer "In4.Cu")
		(net "DRIVE_A_4_FLT_LED")
	)
	(segment
		(start 130.272536 -190.431928)
		(end 127.311404 -190.431928)
		(width 0.12065)
		(layer "In4.Cu")
		(net "DRIVE_A_4_FLT_LED")
	)
	(segment
		(start 115.5827 -231.659938)
		(end 115.5827 -252.803406)
		(width 0.12065)
		(layer "In4.Cu")
		(net "DRIVE_A_4_FLT_LED")
	)
	(segment
		(start 111.37265 -206.370682)
		(end 111.37265 -227.449888)
		(width 0.12065)
		(layer "In4.Cu")
		(net "DRIVE_A_4_FLT_LED")
	)
	(segment
		(start 129.295398 -266.516104)
		(end 129.295398 -288.7218)
		(width 0.12065)
		(layer "In4.Cu")
		(net "DRIVE_A_4_FLT_LED")
	)
	(segment
		(start 111.37265 -227.449888)
		(end 115.5827 -231.659938)
		(width 0.12065)
		(layer "In4.Cu")
		(net "DRIVE_A_4_FLT_LED")
	)
	(segment
		(start 115.5827 -252.803406)
		(end 129.295398 -266.516104)
		(width 0.12065)
		(layer "In4.Cu")
		(net "DRIVE_A_4_FLT_LED")
	)
	(segment
		(start 131.691634 -183.700166)
		(end 132.784342 -182.607458)
		(width 0.17145)
		(layer "F.Cu")
		(net "DRIVE_A_4_ACT")
	)
	(segment
		(start 131.691634 -184.154064)
		(end 131.691634 -183.700166)
		(width 0.17145)
		(layer "F.Cu")
		(net "DRIVE_A_4_ACT")
	)
	(segment
		(start 132.784342 -181.42712)
		(end 132.784342 -180.248052)
		(width 0.17145)
		(layer "F.Cu")
		(net "DRIVE_A_4_ACT")
	)
	(segment
		(start 132.784342 -182.607458)
		(end 132.784342 -182.566818)
		(width 0.17145)
		(layer "F.Cu")
		(net "DRIVE_A_4_ACT")
	)
	(segment
		(start 132.784342 -182.566818)
		(end 132.784342 -181.42712)
		(width 0.17145)
		(layer "F.Cu")
		(net "DRIVE_A_4_ACT")
	)
	(via
		(at 132.784342 -180.248052)
		(size 0.5588)
		(drill 0.3048)
		(layers "F.Cu" "B.Cu")
		(net "DRIVE_A_4_ACT")
	)
	(via
		(at 132.784342 -182.566818)
		(size 0.6604)
		(drill 0.3302)
		(layers "F.Cu" "B.Cu")
		(net "DRIVE_A_4_ACT")
	)
	(via
		(at 132.2324 -336.3214)
		(size 0.5588)
		(drill 0.3048)
		(layers "F.Cu" "B.Cu")
		(net "DRIVE_A_4_ACT")
	)
	(segment
		(start 283.23667 -323.505068)
		(end 282.358338 -324.3834)
		(width 0.13335)
		(layer "In2.Cu")
		(net "DRIVE_A_4_ACT")
	)
	(segment
		(start 190.64478 -322.3768)
		(end 187.24118 -325.7804)
		(width 0.13335)
		(layer "In2.Cu")
		(net "DRIVE_A_4_ACT")
	)
	(segment
		(start 282.358338 -324.3834)
		(end 276.7838 -324.3834)
		(width 0.13335)
		(layer "In2.Cu")
		(net "DRIVE_A_4_ACT")
	)
	(segment
		(start 143.996664 -336.949796)
		(end 143.368268 -336.3214)
		(width 0.13335)
		(layer "In2.Cu")
		(net "DRIVE_A_4_ACT")
	)
	(segment
		(start 163.360608 -336.949796)
		(end 143.996664 -336.949796)
		(width 0.13335)
		(layer "In2.Cu")
		(net "DRIVE_A_4_ACT")
	)
	(segment
		(start 276.7838 -324.3834)
		(end 274.7772 -322.3768)
		(width 0.13335)
		(layer "In2.Cu")
		(net "DRIVE_A_4_ACT")
	)
	(segment
		(start 187.24118 -325.7804)
		(end 174.530004 -325.7804)
		(width 0.13335)
		(layer "In2.Cu")
		(net "DRIVE_A_4_ACT")
	)
	(segment
		(start 274.7772 -322.3768)
		(end 190.64478 -322.3768)
		(width 0.13335)
		(layer "In2.Cu")
		(net "DRIVE_A_4_ACT")
	)
	(segment
		(start 174.530004 -325.7804)
		(end 163.360608 -336.949796)
		(width 0.13335)
		(layer "In2.Cu")
		(net "DRIVE_A_4_ACT")
	)
	(segment
		(start 143.368268 -336.3214)
		(end 132.2324 -336.3214)
		(width 0.13335)
		(layer "In2.Cu")
		(net "DRIVE_A_4_ACT")
	)
	(segment
		(start 132.2324 -316.3062)
		(end 132.2324 -336.3214)
		(width 0.12065)
		(layer "In4.Cu")
		(net "DRIVE_A_4_ACT")
	)
	(segment
		(start 144.000474 -228.611938)
		(end 135.381746 -237.230666)
		(width 0.12065)
		(layer "In4.Cu")
		(net "DRIVE_A_4_ACT")
	)
	(segment
		(start 144.000474 -195.462906)
		(end 144.000474 -228.611938)
		(width 0.12065)
		(layer "In4.Cu")
		(net "DRIVE_A_4_ACT")
	)
	(segment
		(start 132.784342 -180.248052)
		(end 132.784342 -184.246774)
		(width 0.12065)
		(layer "In4.Cu")
		(net "DRIVE_A_4_ACT")
	)
	(segment
		(start 135.1788 -313.3598)
		(end 132.2324 -316.3062)
		(width 0.12065)
		(layer "In4.Cu")
		(net "DRIVE_A_4_ACT")
	)
	(segment
		(start 135.381746 -284.948376)
		(end 134.53872 -285.791402)
		(width 0.12065)
		(layer "In4.Cu")
		(net "DRIVE_A_4_ACT")
	)
	(segment
		(start 135.1788 -294.941244)
		(end 135.1788 -313.3598)
		(width 0.12065)
		(layer "In4.Cu")
		(net "DRIVE_A_4_ACT")
	)
	(segment
		(start 134.53872 -294.301164)
		(end 135.1788 -294.941244)
		(width 0.12065)
		(layer "In4.Cu")
		(net "DRIVE_A_4_ACT")
	)
	(segment
		(start 135.381746 -237.230666)
		(end 135.381746 -284.948376)
		(width 0.12065)
		(layer "In4.Cu")
		(net "DRIVE_A_4_ACT")
	)
	(segment
		(start 134.53872 -285.791402)
		(end 134.53872 -294.301164)
		(width 0.12065)
		(layer "In4.Cu")
		(net "DRIVE_A_4_ACT")
	)
	(segment
		(start 132.784342 -184.246774)
		(end 144.000474 -195.462906)
		(width 0.12065)
		(layer "In4.Cu")
		(net "DRIVE_A_4_ACT")
	)
	(segment
		(start 262.46836 -240.333022)
		(end 263.130538 -240.9952)
		(width 0.17145)
		(layer "F.Cu")
		(net "DRIVE_A_35_PWR")
	)
	(segment
		(start 467.619334 -39.832788)
		(end 467.619334 -38.853872)
		(width 0.17145)
		(layer "F.Cu")
		(net "DRIVE_A_35_PWR")
	)
	(segment
		(start 467.619334 -41.077134)
		(end 467.618318 -41.07815)
		(width 0.17145)
		(layer "F.Cu")
		(net "DRIVE_A_35_PWR")
	)
	(segment
		(start 467.619334 -39.832788)
		(end 467.619334 -41.077134)
		(width 0.17145)
		(layer "F.Cu")
		(net "DRIVE_A_35_PWR")
	)
	(segment
		(start 262.46836 -239.6744)
		(end 262.46836 -240.333022)
		(width 0.17145)
		(layer "F.Cu")
		(net "DRIVE_A_35_PWR")
	)
	(via
		(at 467.619334 -39.832788)
		(size 0.6604)
		(drill 0.3302)
		(layers "F.Cu" "B.Cu")
		(net "DRIVE_A_35_PWR")
	)
	(via
		(at 411.933898 -232.945432)
		(size 0.5588)
		(drill 0.3048)
		(layers "F.Cu" "B.Cu")
		(net "DRIVE_A_35_PWR")
	)
	(via
		(at 263.130538 -240.9952)
		(size 0.5588)
		(drill 0.3048)
		(layers "F.Cu" "B.Cu")
		(net "DRIVE_A_35_PWR")
	)
	(via
		(at 467.619334 -38.853872)
		(size 0.5588)
		(drill 0.3048)
		(layers "F.Cu" "B.Cu")
		(net "DRIVE_A_35_PWR")
	)
	(segment
		(start 283.299154 -232.51287)
		(end 273.1389 -232.51287)
		(width 0.13335)
		(layer "In2.Cu")
		(net "DRIVE_A_35_PWR")
	)
	(segment
		(start 324.455536 -233.426)
		(end 314.535566 -223.50603)
		(width 0.13335)
		(layer "In2.Cu")
		(net "DRIVE_A_35_PWR")
	)
	(segment
		(start 314.535566 -223.50603)
		(end 292.305994 -223.50603)
		(width 0.13335)
		(layer "In2.Cu")
		(net "DRIVE_A_35_PWR")
	)
	(segment
		(start 273.1389 -232.51287)
		(end 270.981424 -234.670346)
		(width 0.13335)
		(layer "In2.Cu")
		(net "DRIVE_A_35_PWR")
	)
	(segment
		(start 292.305994 -223.50603)
		(end 283.299154 -232.51287)
		(width 0.13335)
		(layer "In2.Cu")
		(net "DRIVE_A_35_PWR")
	)
	(segment
		(start 269.455392 -234.670346)
		(end 263.130538 -240.9952)
		(width 0.13335)
		(layer "In2.Cu")
		(net "DRIVE_A_35_PWR")
	)
	(segment
		(start 411.933898 -232.945432)
		(end 411.45333 -233.426)
		(width 0.13335)
		(layer "In2.Cu")
		(net "DRIVE_A_35_PWR")
	)
	(segment
		(start 270.981424 -234.670346)
		(end 269.455392 -234.670346)
		(width 0.13335)
		(layer "In2.Cu")
		(net "DRIVE_A_35_PWR")
	)
	(segment
		(start 411.45333 -233.426)
		(end 324.455536 -233.426)
		(width 0.13335)
		(layer "In2.Cu")
		(net "DRIVE_A_35_PWR")
	)
	(segment
		(start 416.61842 -114.013234)
		(end 416.61842 -109.00918)
		(width 0.12065)
		(layer "In4.Cu")
		(net "DRIVE_A_35_PWR")
	)
	(segment
		(start 409.23845 -174.196248)
		(end 416.27806 -167.156638)
		(width 0.12065)
		(layer "In4.Cu")
		(net "DRIVE_A_35_PWR")
	)
	(segment
		(start 416.61842 -109.00918)
		(end 466.6488 -58.9788)
		(width 0.12065)
		(layer "In4.Cu")
		(net "DRIVE_A_35_PWR")
	)
	(segment
		(start 411.933898 -232.945432)
		(end 409.23845 -230.249984)
		(width 0.12065)
		(layer "In4.Cu")
		(net "DRIVE_A_35_PWR")
	)
	(segment
		(start 412.445454 -151.468836)
		(end 412.445454 -118.1862)
		(width 0.12065)
		(layer "In4.Cu")
		(net "DRIVE_A_35_PWR")
	)
	(segment
		(start 416.27806 -167.156638)
		(end 416.27806 -155.301442)
		(width 0.12065)
		(layer "In4.Cu")
		(net "DRIVE_A_35_PWR")
	)
	(segment
		(start 412.445454 -118.1862)
		(end 416.61842 -114.013234)
		(width 0.12065)
		(layer "In4.Cu")
		(net "DRIVE_A_35_PWR")
	)
	(segment
		(start 466.6488 -39.824406)
		(end 467.619334 -38.853872)
		(width 0.12065)
		(layer "In4.Cu")
		(net "DRIVE_A_35_PWR")
	)
	(segment
		(start 409.23845 -230.249984)
		(end 409.23845 -174.196248)
		(width 0.12065)
		(layer "In4.Cu")
		(net "DRIVE_A_35_PWR")
	)
	(segment
		(start 466.6488 -58.9788)
		(end 466.6488 -39.824406)
		(width 0.12065)
		(layer "In4.Cu")
		(net "DRIVE_A_35_PWR")
	)
	(segment
		(start 416.27806 -155.301442)
		(end 412.445454 -151.468836)
		(width 0.12065)
		(layer "In4.Cu")
		(net "DRIVE_A_35_PWR")
	)
	(segment
		(start 473.873576 -46.924976)
		(end 473.65285 -46.70425)
		(width 0.17145)
		(layer "F.Cu")
		(net "DRIVE_A_35_INS")
	)
	(segment
		(start 256.645156 -254.44196)
		(end 257.295396 -253.79172)
		(width 0.17145)
		(layer "F.Cu")
		(net "DRIVE_A_35_INS")
	)
	(segment
		(start 473.65285 -45.77715)
		(end 473.65285 -46.242478)
		(width 0.17145)
		(layer "F.Cu")
		(net "DRIVE_A_35_INS")
	)
	(segment
		(start 473.65285 -46.70425)
		(end 473.65285 -46.242478)
		(width 0.17145)
		(layer "F.Cu")
		(net "DRIVE_A_35_INS")
	)
	(segment
		(start 257.295396 -253.79172)
		(end 257.295396 -252.15596)
		(width 0.17145)
		(layer "F.Cu")
		(net "DRIVE_A_35_INS")
	)
	(segment
		(start 474.853 -45.500036)
		(end 473.929964 -45.500036)
		(width 0.17145)
		(layer "F.Cu")
		(net "DRIVE_A_35_INS")
	)
	(segment
		(start 473.929964 -45.500036)
		(end 473.65285 -45.77715)
		(width 0.17145)
		(layer "F.Cu")
		(net "DRIVE_A_35_INS")
	)
	(segment
		(start 474.853 -46.924976)
		(end 473.873576 -46.924976)
		(width 0.17145)
		(layer "F.Cu")
		(net "DRIVE_A_35_INS")
	)
	(via
		(at 256.645156 -254.44196)
		(size 0.5588)
		(drill 0.3048)
		(layers "F.Cu" "B.Cu")
		(net "DRIVE_A_35_INS")
	)
	(via
		(at 474.853 -45.500036)
		(size 0.5588)
		(drill 0.3048)
		(layers "F.Cu" "B.Cu")
		(net "DRIVE_A_35_INS")
	)
	(via
		(at 473.65285 -46.242478)
		(size 0.6604)
		(drill 0.3302)
		(layers "F.Cu" "B.Cu")
		(net "DRIVE_A_35_INS")
	)
	(via
		(at 413.789876 -247.695466)
		(size 0.5588)
		(drill 0.3048)
		(layers "F.Cu" "B.Cu")
		(net "DRIVE_A_35_INS")
	)
	(segment
		(start 284.1498 -246.382032)
		(end 276.169628 -246.382032)
		(width 0.13335)
		(layer "In2.Cu")
		(net "DRIVE_A_35_INS")
	)
	(segment
		(start 317.965582 -247.324372)
		(end 304.782728 -234.141518)
		(width 0.13335)
		(layer "In2.Cu")
		(net "DRIVE_A_35_INS")
	)
	(segment
		(start 412.285942 -249.1994)
		(end 327.9902 -249.1994)
		(width 0.13335)
		(layer "In2.Cu")
		(net "DRIVE_A_35_INS")
	)
	(segment
		(start 327.9902 -249.1994)
		(end 326.115172 -247.324372)
		(width 0.13335)
		(layer "In2.Cu")
		(net "DRIVE_A_35_INS")
	)
	(segment
		(start 296.390314 -234.141518)
		(end 284.1498 -246.382032)
		(width 0.13335)
		(layer "In2.Cu")
		(net "DRIVE_A_35_INS")
	)
	(segment
		(start 261.345934 -253.831852)
		(end 257.255264 -253.831852)
		(width 0.13335)
		(layer "In2.Cu")
		(net "DRIVE_A_35_INS")
	)
	(segment
		(start 413.789876 -247.695466)
		(end 412.285942 -249.1994)
		(width 0.13335)
		(layer "In2.Cu")
		(net "DRIVE_A_35_INS")
	)
	(segment
		(start 304.782728 -234.141518)
		(end 296.390314 -234.141518)
		(width 0.13335)
		(layer "In2.Cu")
		(net "DRIVE_A_35_INS")
	)
	(segment
		(start 257.255264 -253.831852)
		(end 256.645156 -254.44196)
		(width 0.13335)
		(layer "In2.Cu")
		(net "DRIVE_A_35_INS")
	)
	(segment
		(start 263.301988 -251.875798)
		(end 261.345934 -253.831852)
		(width 0.13335)
		(layer "In2.Cu")
		(net "DRIVE_A_35_INS")
	)
	(segment
		(start 270.675862 -251.875798)
		(end 263.301988 -251.875798)
		(width 0.13335)
		(layer "In2.Cu")
		(net "DRIVE_A_35_INS")
	)
	(segment
		(start 276.169628 -246.382032)
		(end 270.675862 -251.875798)
		(width 0.13335)
		(layer "In2.Cu")
		(net "DRIVE_A_35_INS")
	)
	(segment
		(start 326.115172 -247.324372)
		(end 317.965582 -247.324372)
		(width 0.13335)
		(layer "In2.Cu")
		(net "DRIVE_A_35_INS")
	)
	(segment
		(start 472.694 -47.659036)
		(end 472.694 -55.753)
		(width 0.12065)
		(layer "In4.Cu")
		(net "DRIVE_A_35_INS")
	)
	(segment
		(start 416.69081 -167.81399)
		(end 409.8544 -174.6504)
		(width 0.12065)
		(layer "In4.Cu")
		(net "DRIVE_A_35_INS")
	)
	(segment
		(start 409.8544 -174.6504)
		(end 409.8544 -228.4984)
		(width 0.12065)
		(layer "In4.Cu")
		(net "DRIVE_A_35_INS")
	)
	(segment
		(start 454.279 -74.168)
		(end 454.279 -76.9366)
		(width 0.12065)
		(layer "In4.Cu")
		(net "DRIVE_A_35_INS")
	)
	(segment
		(start 412.858204 -118.357396)
		(end 412.858204 -151.29764)
		(width 0.12065)
		(layer "In4.Cu")
		(net "DRIVE_A_35_INS")
	)
	(segment
		(start 414.258252 -232.902252)
		(end 414.258252 -247.22709)
		(width 0.12065)
		(layer "In4.Cu")
		(net "DRIVE_A_35_INS")
	)
	(segment
		(start 454.279 -76.9366)
		(end 412.858204 -118.357396)
		(width 0.12065)
		(layer "In4.Cu")
		(net "DRIVE_A_35_INS")
	)
	(segment
		(start 416.69081 -155.130246)
		(end 416.69081 -167.81399)
		(width 0.12065)
		(layer "In4.Cu")
		(net "DRIVE_A_35_INS")
	)
	(segment
		(start 472.694 -55.753)
		(end 454.279 -74.168)
		(width 0.12065)
		(layer "In4.Cu")
		(net "DRIVE_A_35_INS")
	)
	(segment
		(start 474.853 -45.500036)
		(end 472.694 -47.659036)
		(width 0.12065)
		(layer "In4.Cu")
		(net "DRIVE_A_35_INS")
	)
	(segment
		(start 412.858204 -151.29764)
		(end 416.69081 -155.130246)
		(width 0.12065)
		(layer "In4.Cu")
		(net "DRIVE_A_35_INS")
	)
	(segment
		(start 409.8544 -228.4984)
		(end 414.258252 -232.902252)
		(width 0.12065)
		(layer "In4.Cu")
		(net "DRIVE_A_35_INS")
	)
	(segment
		(start 414.258252 -247.22709)
		(end 413.789876 -247.695466)
		(width 0.12065)
		(layer "In4.Cu")
		(net "DRIVE_A_35_INS")
	)
	(segment
		(start 288.7726 -281.2034)
		(end 288.7726 -282.827476)
		(width 0.17145)
		(layer "F.Cu")
		(net "DRIVE_A_35_FLT_LED")
	)
	(segment
		(start 217.800174 -1.450086)
		(end 217.800174 -0.175514)
		(width 0.17145)
		(layer "F.Cu")
		(net "DRIVE_A_35_FLT_LED")
	)
	(segment
		(start 217.800174 -0.175514)
		(end 217.808302 -0.167386)
		(width 0.17145)
		(layer "F.Cu")
		(net "DRIVE_A_35_FLT_LED")
	)
	(segment
		(start 288.7726 -282.827476)
		(end 288.545778 -283.054298)
		(width 0.17145)
		(layer "F.Cu")
		(net "DRIVE_A_35_FLT_LED")
	)
	(segment
		(start 288.545778 -285.323534)
		(end 288.908744 -285.6865)
		(width 0.17145)
		(layer "F.Cu")
		(net "DRIVE_A_35_FLT_LED")
	)
	(segment
		(start 288.545778 -283.054298)
		(end 288.545778 -285.323534)
		(width 0.17145)
		(layer "F.Cu")
		(net "DRIVE_A_35_FLT_LED")
	)
	(via
		(at 217.808302 -0.167386)
		(size 0.5588)
		(drill 0.3048)
		(layers "F.Cu" "B.Cu")
		(net "DRIVE_A_35_FLT_LED")
	)
	(via
		(at 288.908744 -285.6865)
		(size 0.5588)
		(drill 0.3048)
		(layers "F.Cu" "B.Cu")
		(net "DRIVE_A_35_FLT_LED")
	)
	(via
		(at 288.545778 -283.054298)
		(size 0.6604)
		(drill 0.3302)
		(layers "F.Cu" "B.Cu")
		(net "DRIVE_A_35_FLT_LED")
	)
	(segment
		(start 311.1881 -129.396744)
		(end 295.45407 -113.662714)
		(width 0.12065)
		(layer "In4.Cu")
		(net "DRIVE_A_35_FLT_LED")
	)
	(segment
		(start 296.620946 -59.149996)
		(end 296.620946 -29.954982)
		(width 0.12065)
		(layer "In4.Cu")
		(net "DRIVE_A_35_FLT_LED")
	)
	(segment
		(start 288.908744 -285.6865)
		(end 291.1475 -285.6865)
		(width 0.12065)
		(layer "In4.Cu")
		(net "DRIVE_A_35_FLT_LED")
	)
	(segment
		(start 291.465 -280.924)
		(end 298.463716 -273.925284)
		(width 0.12065)
		(layer "In4.Cu")
		(net "DRIVE_A_35_FLT_LED")
	)
	(segment
		(start 296.660062 26.133044)
		(end 289.986212 32.806894)
		(width 0.12065)
		(layer "In4.Cu")
		(net "DRIVE_A_35_FLT_LED")
	)
	(segment
		(start 296.660062 -29.954982)
		(end 296.660062 26.133044)
		(width 0.12065)
		(layer "In4.Cu")
		(net "DRIVE_A_35_FLT_LED")
	)
	(segment
		(start 219.281248 -0.167386)
		(end 217.808302 -0.167386)
		(width 0.12065)
		(layer "In4.Cu")
		(net "DRIVE_A_35_FLT_LED")
	)
	(segment
		(start 295.45407 -60.316872)
		(end 296.620946 -59.149996)
		(width 0.12065)
		(layer "In4.Cu")
		(net "DRIVE_A_35_FLT_LED")
	)
	(segment
		(start 295.45407 -113.662714)
		(end 295.45407 -60.316872)
		(width 0.12065)
		(layer "In4.Cu")
		(net "DRIVE_A_35_FLT_LED")
	)
	(segment
		(start 235.568744 32.806894)
		(end 222.763588 20.001738)
		(width 0.12065)
		(layer "In4.Cu")
		(net "DRIVE_A_35_FLT_LED")
	)
	(segment
		(start 298.463716 -272.728436)
		(end 311.1881 -260.004052)
		(width 0.12065)
		(layer "In4.Cu")
		(net "DRIVE_A_35_FLT_LED")
	)
	(segment
		(start 291.1475 -285.6865)
		(end 291.465 -285.369)
		(width 0.12065)
		(layer "In4.Cu")
		(net "DRIVE_A_35_FLT_LED")
	)
	(segment
		(start 289.986212 32.806894)
		(end 235.568744 32.806894)
		(width 0.12065)
		(layer "In4.Cu")
		(net "DRIVE_A_35_FLT_LED")
	)
	(segment
		(start 296.620946 -29.954982)
		(end 296.660062 -29.954982)
		(width 0.12065)
		(layer "In4.Cu")
		(net "DRIVE_A_35_FLT_LED")
	)
	(segment
		(start 298.463716 -273.925284)
		(end 298.463716 -272.728436)
		(width 0.12065)
		(layer "In4.Cu")
		(net "DRIVE_A_35_FLT_LED")
	)
	(segment
		(start 311.1881 -260.004052)
		(end 311.1881 -129.396744)
		(width 0.12065)
		(layer "In4.Cu")
		(net "DRIVE_A_35_FLT_LED")
	)
	(segment
		(start 291.465 -285.369)
		(end 291.465 -280.924)
		(width 0.12065)
		(layer "In4.Cu")
		(net "DRIVE_A_35_FLT_LED")
	)
	(segment
		(start 222.763588 20.001738)
		(end 222.763588 3.314954)
		(width 0.12065)
		(layer "In4.Cu")
		(net "DRIVE_A_35_FLT_LED")
	)
	(segment
		(start 222.763588 3.314954)
		(end 219.281248 -0.167386)
		(width 0.12065)
		(layer "In4.Cu")
		(net "DRIVE_A_35_FLT_LED")
	)
	(segment
		(start 225.133154 0.94869)
		(end 224.947226 1.134618)
		(width 0.17145)
		(layer "F.Cu")
		(net "DRIVE_A_35_ACT")
	)
	(segment
		(start 224.947226 1.134618)
		(end 220.659198 1.134618)
		(width 0.17145)
		(layer "F.Cu")
		(net "DRIVE_A_35_ACT")
	)
	(segment
		(start 218.800172 -0.724408)
		(end 218.800172 -1.450086)
		(width 0.17145)
		(layer "F.Cu")
		(net "DRIVE_A_35_ACT")
	)
	(segment
		(start 220.659198 1.134618)
		(end 218.800172 -0.724408)
		(width 0.17145)
		(layer "F.Cu")
		(net "DRIVE_A_35_ACT")
	)
	(via
		(at 225.133154 0.94869)
		(size 0.5588)
		(drill 0.3048)
		(layers "F.Cu" "B.Cu")
		(net "DRIVE_A_35_ACT")
	)
	(via
		(at 201.234802 -297.246294)
		(size 0.6604)
		(drill 0.3048)
		(layers "F.Cu" "B.Cu")
		(net "DRIVE_A_35_ACT")
	)
	(segment
		(start 252.701552 -301.3964)
		(end 259.178552 -301.3964)
		(width 0.13335)
		(layer "In2.Cu")
		(net "DRIVE_A_35_ACT")
	)
	(segment
		(start 276.3774 -295.5798)
		(end 281.911298 -295.5798)
		(width 0.13335)
		(layer "In2.Cu")
		(net "DRIVE_A_35_ACT")
	)
	(segment
		(start 281.911298 -295.5798)
		(end 282.83662 -296.505122)
		(width 0.13335)
		(layer "In2.Cu")
		(net "DRIVE_A_35_ACT")
	)
	(segment
		(start 259.178552 -301.3964)
		(end 265.348974 -295.225978)
		(width 0.13335)
		(layer "In2.Cu")
		(net "DRIVE_A_35_ACT")
	)
	(segment
		(start 251.967492 -302.13046)
		(end 252.701552 -301.3964)
		(width 0.13335)
		(layer "In2.Cu")
		(net "DRIVE_A_35_ACT")
	)
	(segment
		(start 210.434428 -302.13046)
		(end 251.967492 -302.13046)
		(width 0.13335)
		(layer "In2.Cu")
		(net "DRIVE_A_35_ACT")
	)
	(segment
		(start 201.234802 -297.246294)
		(end 201.235056 -297.24604)
		(width 0.13335)
		(layer "In2.Cu")
		(net "DRIVE_A_35_ACT")
	)
	(segment
		(start 205.550008 -297.24604)
		(end 210.434428 -302.13046)
		(width 0.13335)
		(layer "In2.Cu")
		(net "DRIVE_A_35_ACT")
	)
	(segment
		(start 201.235056 -297.24604)
		(end 205.550008 -297.24604)
		(width 0.13335)
		(layer "In2.Cu")
		(net "DRIVE_A_35_ACT")
	)
	(segment
		(start 276.023578 -295.225978)
		(end 276.3774 -295.5798)
		(width 0.13335)
		(layer "In2.Cu")
		(net "DRIVE_A_35_ACT")
	)
	(segment
		(start 265.348974 -295.225978)
		(end 276.023578 -295.225978)
		(width 0.13335)
		(layer "In2.Cu")
		(net "DRIVE_A_35_ACT")
	)
	(segment
		(start 212.615272 -122.034554)
		(end 212.615272 -80.155288)
		(width 0.12065)
		(layer "In4.Cu")
		(net "DRIVE_A_35_ACT")
	)
	(segment
		(start 217.30843 -70.660768)
		(end 220.236034 -67.733164)
		(width 0.12065)
		(layer "In4.Cu")
		(net "DRIVE_A_35_ACT")
	)
	(segment
		(start 220.236034 -67.733164)
		(end 220.236034 -63.33236)
		(width 0.12065)
		(layer "In4.Cu")
		(net "DRIVE_A_35_ACT")
	)
	(segment
		(start 225.018854 0.94869)
		(end 225.133154 0.94869)
		(width 0.12065)
		(layer "In4.Cu")
		(net "DRIVE_A_35_ACT")
	)
	(segment
		(start 220.236034 -63.33236)
		(end 220.261434 -63.30696)
		(width 0.12065)
		(layer "In4.Cu")
		(net "DRIVE_A_35_ACT")
	)
	(segment
		(start 208.087468 -280.003758)
		(end 208.087468 -203.637388)
		(width 0.12065)
		(layer "In4.Cu")
		(net "DRIVE_A_35_ACT")
	)
	(segment
		(start 212.615272 -80.155288)
		(end 217.30843 -75.46213)
		(width 0.12065)
		(layer "In4.Cu")
		(net "DRIVE_A_35_ACT")
	)
	(segment
		(start 216.120218 -195.604638)
		(end 216.120218 -146.215608)
		(width 0.12065)
		(layer "In4.Cu")
		(net "DRIVE_A_35_ACT")
	)
	(segment
		(start 201.234802 -286.856424)
		(end 208.087468 -280.003758)
		(width 0.12065)
		(layer "In4.Cu")
		(net "DRIVE_A_35_ACT")
	)
	(segment
		(start 208.087468 -203.637388)
		(end 216.120218 -195.604638)
		(width 0.12065)
		(layer "In4.Cu")
		(net "DRIVE_A_35_ACT")
	)
	(segment
		(start 212.075776 -13.783818)
		(end 215.342978 -10.516616)
		(width 0.12065)
		(layer "In4.Cu")
		(net "DRIVE_A_35_ACT")
	)
	(segment
		(start 215.342978 -8.727186)
		(end 225.018854 0.94869)
		(width 0.12065)
		(layer "In4.Cu")
		(net "DRIVE_A_35_ACT")
	)
	(segment
		(start 220.261434 -57.320942)
		(end 212.075776 -49.135284)
		(width 0.12065)
		(layer "In4.Cu")
		(net "DRIVE_A_35_ACT")
	)
	(segment
		(start 217.30843 -75.46213)
		(end 217.30843 -70.660768)
		(width 0.12065)
		(layer "In4.Cu")
		(net "DRIVE_A_35_ACT")
	)
	(segment
		(start 212.075776 -49.135284)
		(end 212.075776 -13.783818)
		(width 0.12065)
		(layer "In4.Cu")
		(net "DRIVE_A_35_ACT")
	)
	(segment
		(start 216.120218 -146.215608)
		(end 214.811102 -144.906492)
		(width 0.12065)
		(layer "In4.Cu")
		(net "DRIVE_A_35_ACT")
	)
	(segment
		(start 215.342978 -10.516616)
		(end 215.342978 -8.727186)
		(width 0.12065)
		(layer "In4.Cu")
		(net "DRIVE_A_35_ACT")
	)
	(segment
		(start 220.261434 -63.30696)
		(end 220.261434 -57.320942)
		(width 0.12065)
		(layer "In4.Cu")
		(net "DRIVE_A_35_ACT")
	)
	(segment
		(start 214.811102 -144.906492)
		(end 214.811102 -124.230384)
		(width 0.12065)
		(layer "In4.Cu")
		(net "DRIVE_A_35_ACT")
	)
	(segment
		(start 214.811102 -124.230384)
		(end 212.615272 -122.034554)
		(width 0.12065)
		(layer "In4.Cu")
		(net "DRIVE_A_35_ACT")
	)
	(segment
		(start 201.234802 -297.246294)
		(end 201.234802 -286.856424)
		(width 0.12065)
		(layer "In4.Cu")
		(net "DRIVE_A_35_ACT")
	)
	(segment
		(start 263.1186 -239.6744)
		(end 263.1186 -237.358682)
		(width 0.17145)
		(layer "F.Cu")
		(net "DRIVE_A_34_PWR")
	)
	(segment
		(start 464.232752 -42.141394)
		(end 463.271616 -42.141394)
		(width 0.17145)
		(layer "F.Cu")
		(net "DRIVE_A_34_PWR")
	)
	(segment
		(start 461.9879 -42.141394)
		(end 463.271616 -42.141394)
		(width 0.17145)
		(layer "F.Cu")
		(net "DRIVE_A_34_PWR")
	)
	(segment
		(start 263.1186 -237.358682)
		(end 263.419082 -237.0582)
		(width 0.17145)
		(layer "F.Cu")
		(net "DRIVE_A_34_PWR")
	)
	(segment
		(start 464.260184 -42.168826)
		(end 464.232752 -42.141394)
		(width 0.17145)
		(layer "F.Cu")
		(net "DRIVE_A_34_PWR")
	)
	(via
		(at 464.260184 -42.168826)
		(size 0.5588)
		(drill 0.3048)
		(layers "F.Cu" "B.Cu")
		(net "DRIVE_A_34_PWR")
	)
	(via
		(at 263.419082 -237.0582)
		(size 0.5588)
		(drill 0.3048)
		(layers "F.Cu" "B.Cu")
		(net "DRIVE_A_34_PWR")
	)
	(via
		(at 463.271616 -42.141394)
		(size 0.6604)
		(drill 0.3302)
		(layers "F.Cu" "B.Cu")
		(net "DRIVE_A_34_PWR")
	)
	(via
		(at 411.0228 -232.8672)
		(size 0.5588)
		(drill 0.3048)
		(layers "F.Cu" "B.Cu")
		(net "DRIVE_A_34_PWR")
	)
	(segment
		(start 267.670788 -234.111546)
		(end 264.724134 -237.0582)
		(width 0.13335)
		(layer "In2.Cu")
		(net "DRIVE_A_34_PWR")
	)
	(segment
		(start 270.749776 -234.111546)
		(end 267.670788 -234.111546)
		(width 0.13335)
		(layer "In2.Cu")
		(net "DRIVE_A_34_PWR")
	)
	(segment
		(start 272.907252 -231.95407)
		(end 270.749776 -234.111546)
		(width 0.13335)
		(layer "In2.Cu")
		(net "DRIVE_A_34_PWR")
	)
	(segment
		(start 264.724134 -237.0582)
		(end 263.419082 -237.0582)
		(width 0.13335)
		(layer "In2.Cu")
		(net "DRIVE_A_34_PWR")
	)
	(segment
		(start 314.767214 -222.94723)
		(end 292.074346 -222.94723)
		(width 0.13335)
		(layer "In2.Cu")
		(net "DRIVE_A_34_PWR")
	)
	(segment
		(start 283.067506 -231.95407)
		(end 272.907252 -231.95407)
		(width 0.13335)
		(layer "In2.Cu")
		(net "DRIVE_A_34_PWR")
	)
	(segment
		(start 324.687184 -232.8672)
		(end 314.767214 -222.94723)
		(width 0.13335)
		(layer "In2.Cu")
		(net "DRIVE_A_34_PWR")
	)
	(segment
		(start 292.074346 -222.94723)
		(end 283.067506 -231.95407)
		(width 0.13335)
		(layer "In2.Cu")
		(net "DRIVE_A_34_PWR")
	)
	(segment
		(start 411.0228 -232.8672)
		(end 324.687184 -232.8672)
		(width 0.13335)
		(layer "In2.Cu")
		(net "DRIVE_A_34_PWR")
	)
	(segment
		(start 411.0228 -232.8672)
		(end 408.499564 -230.343964)
		(width 0.12065)
		(layer "In4.Cu")
		(net "DRIVE_A_34_PWR")
	)
	(segment
		(start 415.787078 -102.017322)
		(end 464.260184 -53.544216)
		(width 0.12065)
		(layer "In4.Cu")
		(net "DRIVE_A_34_PWR")
	)
	(segment
		(start 408.499564 -230.343964)
		(end 408.499564 -174.024036)
		(width 0.12065)
		(layer "In4.Cu")
		(net "DRIVE_A_34_PWR")
	)
	(segment
		(start 412.032704 -118.015004)
		(end 415.787078 -114.26063)
		(width 0.12065)
		(layer "In4.Cu")
		(net "DRIVE_A_34_PWR")
	)
	(segment
		(start 413.819848 -168.703752)
		(end 413.819848 -153.427176)
		(width 0.12065)
		(layer "In4.Cu")
		(net "DRIVE_A_34_PWR")
	)
	(segment
		(start 415.787078 -114.26063)
		(end 415.787078 -102.017322)
		(width 0.12065)
		(layer "In4.Cu")
		(net "DRIVE_A_34_PWR")
	)
	(segment
		(start 464.260184 -53.544216)
		(end 464.260184 -42.168826)
		(width 0.12065)
		(layer "In4.Cu")
		(net "DRIVE_A_34_PWR")
	)
	(segment
		(start 408.499564 -174.024036)
		(end 413.819848 -168.703752)
		(width 0.12065)
		(layer "In4.Cu")
		(net "DRIVE_A_34_PWR")
	)
	(segment
		(start 413.819848 -153.427176)
		(end 412.032704 -151.640032)
		(width 0.12065)
		(layer "In4.Cu")
		(net "DRIVE_A_34_PWR")
	)
	(segment
		(start 412.032704 -151.640032)
		(end 412.032704 -118.015004)
		(width 0.12065)
		(layer "In4.Cu")
		(net "DRIVE_A_34_PWR")
	)
	(segment
		(start 443.8777 -65.039494)
		(end 443.8777 -66.3194)
		(width 0.17145)
		(layer "F.Cu")
		(net "DRIVE_A_34_INS")
	)
	(segment
		(start 256.645156 -252.15596)
		(end 256.645156 -253.47676)
		(width 0.17145)
		(layer "F.Cu")
		(net "DRIVE_A_34_INS")
	)
	(segment
		(start 443.8777 -66.3194)
		(end 443.8777 -67.31)
		(width 0.17145)
		(layer "F.Cu")
		(net "DRIVE_A_34_INS")
	)
	(via
		(at 443.8777 -67.31)
		(size 0.5588)
		(drill 0.3048)
		(layers "F.Cu" "B.Cu")
		(net "DRIVE_A_34_INS")
	)
	(via
		(at 256.645156 -253.47676)
		(size 0.5588)
		(drill 0.3048)
		(layers "F.Cu" "B.Cu")
		(net "DRIVE_A_34_INS")
	)
	(via
		(at 443.8777 -66.3194)
		(size 0.6604)
		(drill 0.3302)
		(layers "F.Cu" "B.Cu")
		(net "DRIVE_A_34_INS")
	)
	(via
		(at 410.335476 -247.187466)
		(size 0.5588)
		(drill 0.3048)
		(layers "F.Cu" "B.Cu")
		(net "DRIVE_A_34_INS")
	)
	(segment
		(start 326.34682 -246.765572)
		(end 320.365628 -246.765572)
		(width 0.13335)
		(layer "In2.Cu")
		(net "DRIVE_A_34_INS")
	)
	(segment
		(start 307.182774 -233.582718)
		(end 296.158666 -233.582718)
		(width 0.13335)
		(layer "In2.Cu")
		(net "DRIVE_A_34_INS")
	)
	(segment
		(start 296.158666 -233.582718)
		(end 283.918152 -245.823232)
		(width 0.13335)
		(layer "In2.Cu")
		(net "DRIVE_A_34_INS")
	)
	(segment
		(start 263.07034 -251.316998)
		(end 261.11454 -253.272798)
		(width 0.13335)
		(layer "In2.Cu")
		(net "DRIVE_A_34_INS")
	)
	(segment
		(start 275.93798 -245.823232)
		(end 270.444214 -251.316998)
		(width 0.13335)
		(layer "In2.Cu")
		(net "DRIVE_A_34_INS")
	)
	(segment
		(start 261.11454 -253.272798)
		(end 256.849118 -253.272798)
		(width 0.13335)
		(layer "In2.Cu")
		(net "DRIVE_A_34_INS")
	)
	(segment
		(start 320.365628 -246.765572)
		(end 307.182774 -233.582718)
		(width 0.13335)
		(layer "In2.Cu")
		(net "DRIVE_A_34_INS")
	)
	(segment
		(start 283.918152 -245.823232)
		(end 275.93798 -245.823232)
		(width 0.13335)
		(layer "In2.Cu")
		(net "DRIVE_A_34_INS")
	)
	(segment
		(start 256.849118 -253.272798)
		(end 256.645156 -253.47676)
		(width 0.13335)
		(layer "In2.Cu")
		(net "DRIVE_A_34_INS")
	)
	(segment
		(start 270.444214 -251.316998)
		(end 263.07034 -251.316998)
		(width 0.13335)
		(layer "In2.Cu")
		(net "DRIVE_A_34_INS")
	)
	(segment
		(start 328.221848 -248.6406)
		(end 326.34682 -246.765572)
		(width 0.13335)
		(layer "In2.Cu")
		(net "DRIVE_A_34_INS")
	)
	(segment
		(start 408.882342 -248.6406)
		(end 328.221848 -248.6406)
		(width 0.13335)
		(layer "In2.Cu")
		(net "DRIVE_A_34_INS")
	)
	(segment
		(start 410.335476 -247.187466)
		(end 408.882342 -248.6406)
		(width 0.13335)
		(layer "In2.Cu")
		(net "DRIVE_A_34_INS")
	)
	(segment
		(start 409.432506 -246.284496)
		(end 409.432506 -244.592856)
		(width 0.12065)
		(layer "In4.Cu")
		(net "DRIVE_A_34_INS")
	)
	(segment
		(start 409.432506 -244.592856)
		(end 409.63723 -244.388132)
		(width 0.12065)
		(layer "In4.Cu")
		(net "DRIVE_A_34_INS")
	)
	(segment
		(start 415.374328 -114.089434)
		(end 415.374328 -101.846126)
		(width 0.12065)
		(layer "In4.Cu")
		(net "DRIVE_A_34_INS")
	)
	(segment
		(start 413.34436 -167.40251)
		(end 413.34436 -156.43479)
		(width 0.12065)
		(layer "In4.Cu")
		(net "DRIVE_A_34_INS")
	)
	(segment
		(start 411.619954 -154.710384)
		(end 411.619954 -117.843808)
		(width 0.12065)
		(layer "In4.Cu")
		(net "DRIVE_A_34_INS")
	)
	(segment
		(start 413.34436 -156.43479)
		(end 411.619954 -154.710384)
		(width 0.12065)
		(layer "In4.Cu")
		(net "DRIVE_A_34_INS")
	)
	(segment
		(start 416.256978 -100.963476)
		(end 416.256978 -100.429822)
		(width 0.12065)
		(layer "In4.Cu")
		(net "DRIVE_A_34_INS")
	)
	(segment
		(start 416.256978 -100.429822)
		(end 443.8777 -72.8091)
		(width 0.12065)
		(layer "In4.Cu")
		(net "DRIVE_A_34_INS")
	)
	(segment
		(start 409.432506 -232.328974)
		(end 407.66619 -230.562658)
		(width 0.12065)
		(layer "In4.Cu")
		(net "DRIVE_A_34_INS")
	)
	(segment
		(start 410.335476 -247.187466)
		(end 409.432506 -246.284496)
		(width 0.12065)
		(layer "In4.Cu")
		(net "DRIVE_A_34_INS")
	)
	(segment
		(start 409.63723 -243.980208)
		(end 409.432506 -243.775484)
		(width 0.12065)
		(layer "In4.Cu")
		(net "DRIVE_A_34_INS")
	)
	(segment
		(start 415.374328 -101.846126)
		(end 416.256978 -100.963476)
		(width 0.12065)
		(layer "In4.Cu")
		(net "DRIVE_A_34_INS")
	)
	(segment
		(start 443.8777 -72.8091)
		(end 443.8777 -67.31)
		(width 0.12065)
		(layer "In4.Cu")
		(net "DRIVE_A_34_INS")
	)
	(segment
		(start 409.63723 -244.388132)
		(end 409.63723 -243.980208)
		(width 0.12065)
		(layer "In4.Cu")
		(net "DRIVE_A_34_INS")
	)
	(segment
		(start 407.66619 -173.08068)
		(end 413.34436 -167.40251)
		(width 0.12065)
		(layer "In4.Cu")
		(net "DRIVE_A_34_INS")
	)
	(segment
		(start 409.432506 -243.775484)
		(end 409.432506 -232.328974)
		(width 0.12065)
		(layer "In4.Cu")
		(net "DRIVE_A_34_INS")
	)
	(segment
		(start 411.619954 -117.843808)
		(end 415.374328 -114.089434)
		(width 0.12065)
		(layer "In4.Cu")
		(net "DRIVE_A_34_INS")
	)
	(segment
		(start 407.66619 -230.562658)
		(end 407.66619 -173.08068)
		(width 0.12065)
		(layer "In4.Cu")
		(net "DRIVE_A_34_INS")
	)
	(segment
		(start 289.241738 -283.957268)
		(end 289.241738 -284.74416)
		(width 0.17145)
		(layer "F.Cu")
		(net "DRIVE_A_34_FLT_LED")
	)
	(segment
		(start 215.800178 -1.450086)
		(end 215.800178 -0.196088)
		(width 0.17145)
		(layer "F.Cu")
		(net "DRIVE_A_34_FLT_LED")
	)
	(segment
		(start 215.800178 -0.196088)
		(end 215.768936 -0.164846)
		(width 0.17145)
		(layer "F.Cu")
		(net "DRIVE_A_34_FLT_LED")
	)
	(segment
		(start 289.42284 -283.036264)
		(end 289.42284 -281.2034)
		(width 0.17145)
		(layer "F.Cu")
		(net "DRIVE_A_34_FLT_LED")
	)
	(segment
		(start 289.241738 -284.74416)
		(end 289.439096 -284.941518)
		(width 0.17145)
		(layer "F.Cu")
		(net "DRIVE_A_34_FLT_LED")
	)
	(segment
		(start 289.241738 -283.922724)
		(end 289.241738 -283.217366)
		(width 0.17145)
		(layer "F.Cu")
		(net "DRIVE_A_34_FLT_LED")
	)
	(segment
		(start 289.224466 -283.939996)
		(end 289.241738 -283.957268)
		(width 0.17145)
		(layer "F.Cu")
		(net "DRIVE_A_34_FLT_LED")
	)
	(segment
		(start 289.241738 -283.217366)
		(end 289.42284 -283.036264)
		(width 0.17145)
		(layer "F.Cu")
		(net "DRIVE_A_34_FLT_LED")
	)
	(segment
		(start 289.224466 -283.939996)
		(end 289.241738 -283.922724)
		(width 0.17145)
		(layer "F.Cu")
		(net "DRIVE_A_34_FLT_LED")
	)
	(via
		(at 215.768936 -0.164846)
		(size 0.5588)
		(drill 0.3048)
		(layers "F.Cu" "B.Cu")
		(net "DRIVE_A_34_FLT_LED")
	)
	(via
		(at 289.439096 -284.941518)
		(size 0.5588)
		(drill 0.3048)
		(layers "F.Cu" "B.Cu")
		(net "DRIVE_A_34_FLT_LED")
	)
	(via
		(at 289.224466 -283.939996)
		(size 0.6604)
		(drill 0.3302)
		(layers "F.Cu" "B.Cu")
		(net "DRIVE_A_34_FLT_LED")
	)
	(segment
		(start 295.542462 25.669748)
		(end 289.230816 31.981394)
		(width 0.12065)
		(layer "In4.Cu")
		(net "DRIVE_A_34_FLT_LED")
	)
	(segment
		(start 310.0705 -259.747258)
		(end 310.0705 -129.86004)
		(width 0.12065)
		(layer "In4.Cu")
		(net "DRIVE_A_34_FLT_LED")
	)
	(segment
		(start 297.628056 -272.998438)
		(end 297.628056 -272.189702)
		(width 0.12065)
		(layer "In4.Cu")
		(net "DRIVE_A_34_FLT_LED")
	)
	(segment
		(start 291.05225 -284.89275)
		(end 291.05225 -279.574244)
		(width 0.12065)
		(layer "In4.Cu")
		(net "DRIVE_A_34_FLT_LED")
	)
	(segment
		(start 295.542462 -30.418278)
		(end 295.542462 25.669748)
		(width 0.12065)
		(layer "In4.Cu")
		(net "DRIVE_A_34_FLT_LED")
	)
	(segment
		(start 295.503346 -30.418278)
		(end 295.542462 -30.418278)
		(width 0.12065)
		(layer "In4.Cu")
		(net "DRIVE_A_34_FLT_LED")
	)
	(segment
		(start 290.790122 -285.154878)
		(end 291.05225 -284.89275)
		(width 0.12065)
		(layer "In4.Cu")
		(net "DRIVE_A_34_FLT_LED")
	)
	(segment
		(start 289.652456 -285.154878)
		(end 290.790122 -285.154878)
		(width 0.12065)
		(layer "In4.Cu")
		(net "DRIVE_A_34_FLT_LED")
	)
	(segment
		(start 294.62857 -59.767978)
		(end 295.503346 -58.893202)
		(width 0.12065)
		(layer "In4.Cu")
		(net "DRIVE_A_34_FLT_LED")
	)
	(segment
		(start 291.05225 -279.574244)
		(end 297.628056 -272.998438)
		(width 0.12065)
		(layer "In4.Cu")
		(net "DRIVE_A_34_FLT_LED")
	)
	(segment
		(start 223.642174 19.712432)
		(end 223.642174 2.490216)
		(width 0.12065)
		(layer "In4.Cu")
		(net "DRIVE_A_34_FLT_LED")
	)
	(segment
		(start 289.439096 -284.941518)
		(end 289.652456 -285.154878)
		(width 0.12065)
		(layer "In4.Cu")
		(net "DRIVE_A_34_FLT_LED")
	)
	(segment
		(start 295.503346 -58.893202)
		(end 295.503346 -30.418278)
		(width 0.12065)
		(layer "In4.Cu")
		(net "DRIVE_A_34_FLT_LED")
	)
	(segment
		(start 229.447598 25.517856)
		(end 223.642174 19.712432)
		(width 0.12065)
		(layer "In4.Cu")
		(net "DRIVE_A_34_FLT_LED")
	)
	(segment
		(start 289.230816 31.981394)
		(end 235.924344 31.981394)
		(width 0.12065)
		(layer "In4.Cu")
		(net "DRIVE_A_34_FLT_LED")
	)
	(segment
		(start 310.0705 -129.86004)
		(end 294.62857 -114.41811)
		(width 0.12065)
		(layer "In4.Cu")
		(net "DRIVE_A_34_FLT_LED")
	)
	(segment
		(start 294.62857 -114.41811)
		(end 294.62857 -59.767978)
		(width 0.12065)
		(layer "In4.Cu")
		(net "DRIVE_A_34_FLT_LED")
	)
	(segment
		(start 297.628056 -272.189702)
		(end 310.0705 -259.747258)
		(width 0.12065)
		(layer "In4.Cu")
		(net "DRIVE_A_34_FLT_LED")
	)
	(segment
		(start 235.924344 31.981394)
		(end 229.460806 25.517856)
		(width 0.12065)
		(layer "In4.Cu")
		(net "DRIVE_A_34_FLT_LED")
	)
	(segment
		(start 223.642174 2.490216)
		(end 220.466666 -0.685292)
		(width 0.12065)
		(layer "In4.Cu")
		(net "DRIVE_A_34_FLT_LED")
	)
	(segment
		(start 216.289382 -0.685292)
		(end 215.768936 -0.164846)
		(width 0.12065)
		(layer "In4.Cu")
		(net "DRIVE_A_34_FLT_LED")
	)
	(segment
		(start 220.466666 -0.685292)
		(end 216.289382 -0.685292)
		(width 0.12065)
		(layer "In4.Cu")
		(net "DRIVE_A_34_FLT_LED")
	)
	(segment
		(start 229.460806 25.517856)
		(end 229.447598 25.517856)
		(width 0.12065)
		(layer "In4.Cu")
		(net "DRIVE_A_34_FLT_LED")
	)
	(segment
		(start 225.150172 1.8669)
		(end 220.659198 1.8669)
		(width 0.17145)
		(layer "F.Cu")
		(net "DRIVE_A_34_ACT")
	)
	(segment
		(start 217.903552 0.851662)
		(end 216.800176 -0.251714)
		(width 0.17145)
		(layer "F.Cu")
		(net "DRIVE_A_34_ACT")
	)
	(segment
		(start 219.64396 0.851662)
		(end 217.903552 0.851662)
		(width 0.17145)
		(layer "F.Cu")
		(net "DRIVE_A_34_ACT")
	)
	(segment
		(start 220.659198 1.8669)
		(end 219.64396 0.851662)
		(width 0.17145)
		(layer "F.Cu")
		(net "DRIVE_A_34_ACT")
	)
	(segment
		(start 216.800176 -0.251714)
		(end 216.800176 -1.450086)
		(width 0.17145)
		(layer "F.Cu")
		(net "DRIVE_A_34_ACT")
	)
	(via
		(at 201.234802 -298.313094)
		(size 0.6604)
		(drill 0.3048)
		(layers "F.Cu" "B.Cu")
		(net "DRIVE_A_34_ACT")
	)
	(via
		(at 225.150172 1.8669)
		(size 0.5588)
		(drill 0.3048)
		(layers "F.Cu" "B.Cu")
		(net "DRIVE_A_34_ACT")
	)
	(segment
		(start 283.398468 -297.343322)
		(end 284.236668 -296.505122)
		(width 0.13335)
		(layer "In2.Cu")
		(net "DRIVE_A_34_ACT")
	)
	(segment
		(start 201.234802 -298.313094)
		(end 206.015336 -298.313094)
		(width 0.13335)
		(layer "In2.Cu")
		(net "DRIVE_A_34_ACT")
	)
	(segment
		(start 206.015336 -298.313094)
		(end 210.4517 -302.749458)
		(width 0.13335)
		(layer "In2.Cu")
		(net "DRIVE_A_34_ACT")
	)
	(segment
		(start 210.4517 -302.749458)
		(end 252.138942 -302.749458)
		(width 0.13335)
		(layer "In2.Cu")
		(net "DRIVE_A_34_ACT")
	)
	(segment
		(start 259.4102 -301.9552)
		(end 265.43 -295.9354)
		(width 0.13335)
		(layer "In2.Cu")
		(net "DRIVE_A_34_ACT")
	)
	(segment
		(start 265.43 -295.9354)
		(end 275.3868 -295.9354)
		(width 0.13335)
		(layer "In2.Cu")
		(net "DRIVE_A_34_ACT")
	)
	(segment
		(start 276.794722 -297.343322)
		(end 283.398468 -297.343322)
		(width 0.13335)
		(layer "In2.Cu")
		(net "DRIVE_A_34_ACT")
	)
	(segment
		(start 275.3868 -295.9354)
		(end 276.794722 -297.343322)
		(width 0.13335)
		(layer "In2.Cu")
		(net "DRIVE_A_34_ACT")
	)
	(segment
		(start 252.9332 -301.9552)
		(end 259.4102 -301.9552)
		(width 0.13335)
		(layer "In2.Cu")
		(net "DRIVE_A_34_ACT")
	)
	(segment
		(start 252.138942 -302.749458)
		(end 252.9332 -301.9552)
		(width 0.13335)
		(layer "In2.Cu")
		(net "DRIVE_A_34_ACT")
	)
	(segment
		(start 212.202522 -79.136748)
		(end 216.876884 -74.462386)
		(width 0.12065)
		(layer "In4.Cu")
		(net "DRIVE_A_34_ACT")
	)
	(segment
		(start 211.606384 -49.249838)
		(end 211.606384 -13.656564)
		(width 0.12065)
		(layer "In4.Cu")
		(net "DRIVE_A_34_ACT")
	)
	(segment
		(start 214.398352 -124.40158)
		(end 212.202522 -122.20575)
		(width 0.12065)
		(layer "In4.Cu")
		(net "DRIVE_A_34_ACT")
	)
	(segment
		(start 215.561418 -146.447256)
		(end 214.398352 -145.28419)
		(width 0.12065)
		(layer "In4.Cu")
		(net "DRIVE_A_34_ACT")
	)
	(segment
		(start 214.930228 -10.33272)
		(end 214.930228 -8.521446)
		(width 0.12065)
		(layer "In4.Cu")
		(net "DRIVE_A_34_ACT")
	)
	(segment
		(start 207.528668 -279.77211)
		(end 207.528668 -203.40574)
		(width 0.12065)
		(layer "In4.Cu")
		(net "DRIVE_A_34_ACT")
	)
	(segment
		(start 201.234802 -298.313094)
		(end 200.715118 -297.79341)
		(width 0.12065)
		(layer "In4.Cu")
		(net "DRIVE_A_34_ACT")
	)
	(segment
		(start 200.715118 -286.58566)
		(end 207.528668 -279.77211)
		(width 0.12065)
		(layer "In4.Cu")
		(net "DRIVE_A_34_ACT")
	)
	(segment
		(start 212.202522 -122.20575)
		(end 212.202522 -79.136748)
		(width 0.12065)
		(layer "In4.Cu")
		(net "DRIVE_A_34_ACT")
	)
	(segment
		(start 200.715118 -297.79341)
		(end 200.715118 -286.58566)
		(width 0.12065)
		(layer "In4.Cu")
		(net "DRIVE_A_34_ACT")
	)
	(segment
		(start 219.848684 -57.492138)
		(end 211.606384 -49.249838)
		(width 0.12065)
		(layer "In4.Cu")
		(net "DRIVE_A_34_ACT")
	)
	(segment
		(start 219.848684 -63.135764)
		(end 219.848684 -57.492138)
		(width 0.12065)
		(layer "In4.Cu")
		(net "DRIVE_A_34_ACT")
	)
	(segment
		(start 214.398352 -145.28419)
		(end 214.398352 -124.40158)
		(width 0.12065)
		(layer "In4.Cu")
		(net "DRIVE_A_34_ACT")
	)
	(segment
		(start 215.561418 -195.37299)
		(end 215.561418 -146.447256)
		(width 0.12065)
		(layer "In4.Cu")
		(net "DRIVE_A_34_ACT")
	)
	(segment
		(start 207.528668 -203.40574)
		(end 215.561418 -195.37299)
		(width 0.12065)
		(layer "In4.Cu")
		(net "DRIVE_A_34_ACT")
	)
	(segment
		(start 211.606384 -13.656564)
		(end 214.930228 -10.33272)
		(width 0.12065)
		(layer "In4.Cu")
		(net "DRIVE_A_34_ACT")
	)
	(segment
		(start 219.823284 -63.161164)
		(end 219.848684 -63.135764)
		(width 0.12065)
		(layer "In4.Cu")
		(net "DRIVE_A_34_ACT")
	)
	(segment
		(start 216.876884 -69.685154)
		(end 219.823284 -66.738754)
		(width 0.12065)
		(layer "In4.Cu")
		(net "DRIVE_A_34_ACT")
	)
	(segment
		(start 225.150172 1.698498)
		(end 225.150172 1.8669)
		(width 0.12065)
		(layer "In4.Cu")
		(net "DRIVE_A_34_ACT")
	)
	(segment
		(start 219.823284 -66.738754)
		(end 219.823284 -63.161164)
		(width 0.12065)
		(layer "In4.Cu")
		(net "DRIVE_A_34_ACT")
	)
	(segment
		(start 216.876884 -74.462386)
		(end 216.876884 -69.685154)
		(width 0.12065)
		(layer "In4.Cu")
		(net "DRIVE_A_34_ACT")
	)
	(segment
		(start 214.930228 -8.521446)
		(end 225.150172 1.698498)
		(width 0.12065)
		(layer "In4.Cu")
		(net "DRIVE_A_34_ACT")
	)
	(segment
		(start 432.682904 -42.141394)
		(end 431.721768 -42.141394)
		(width 0.17145)
		(layer "F.Cu")
		(net "DRIVE_A_33_PWR")
	)
	(segment
		(start 432.710336 -42.168826)
		(end 432.682904 -42.141394)
		(width 0.17145)
		(layer "F.Cu")
		(net "DRIVE_A_33_PWR")
	)
	(segment
		(start 263.76884 -239.6744)
		(end 263.76884 -237.862364)
		(width 0.17145)
		(layer "F.Cu")
		(net "DRIVE_A_33_PWR")
	)
	(segment
		(start 430.438052 -42.141394)
		(end 431.721768 -42.141394)
		(width 0.17145)
		(layer "F.Cu")
		(net "DRIVE_A_33_PWR")
	)
	(segment
		(start 263.76884 -237.862364)
		(end 265.201654 -236.42955)
		(width 0.17145)
		(layer "F.Cu")
		(net "DRIVE_A_33_PWR")
	)
	(segment
		(start 265.201654 -236.42955)
		(end 265.201654 -235.49102)
		(width 0.17145)
		(layer "F.Cu")
		(net "DRIVE_A_33_PWR")
	)
	(via
		(at 408.4828 -232.2576)
		(size 0.5588)
		(drill 0.3048)
		(layers "F.Cu" "B.Cu")
		(net "DRIVE_A_33_PWR")
	)
	(via
		(at 432.710336 -42.168826)
		(size 0.5588)
		(drill 0.3048)
		(layers "F.Cu" "B.Cu")
		(net "DRIVE_A_33_PWR")
	)
	(via
		(at 265.201654 -235.49102)
		(size 0.5588)
		(drill 0.3048)
		(layers "F.Cu" "B.Cu")
		(net "DRIVE_A_33_PWR")
	)
	(via
		(at 431.721768 -42.141394)
		(size 0.6604)
		(drill 0.3302)
		(layers "F.Cu" "B.Cu")
		(net "DRIVE_A_33_PWR")
	)
	(segment
		(start 270.518128 -233.552746)
		(end 267.360654 -233.552746)
		(width 0.13335)
		(layer "In2.Cu")
		(net "DRIVE_A_33_PWR")
	)
	(segment
		(start 289.226498 -224.943162)
		(end 279.127712 -224.943162)
		(width 0.13335)
		(layer "In2.Cu")
		(net "DRIVE_A_33_PWR")
	)
	(segment
		(start 267.360654 -233.552746)
		(end 265.42238 -235.49102)
		(width 0.13335)
		(layer "In2.Cu")
		(net "DRIVE_A_33_PWR")
	)
	(segment
		(start 324.887336 -232.2576)
		(end 315.018166 -222.38843)
		(width 0.13335)
		(layer "In2.Cu")
		(net "DRIVE_A_33_PWR")
	)
	(segment
		(start 291.78123 -222.38843)
		(end 289.226498 -224.943162)
		(width 0.13335)
		(layer "In2.Cu")
		(net "DRIVE_A_33_PWR")
	)
	(segment
		(start 315.018166 -222.38843)
		(end 291.78123 -222.38843)
		(width 0.13335)
		(layer "In2.Cu")
		(net "DRIVE_A_33_PWR")
	)
	(segment
		(start 279.127712 -224.943162)
		(end 270.518128 -233.552746)
		(width 0.13335)
		(layer "In2.Cu")
		(net "DRIVE_A_33_PWR")
	)
	(segment
		(start 265.42238 -235.49102)
		(end 265.201654 -235.49102)
		(width 0.13335)
		(layer "In2.Cu")
		(net "DRIVE_A_33_PWR")
	)
	(segment
		(start 408.4828 -232.2576)
		(end 324.887336 -232.2576)
		(width 0.13335)
		(layer "In2.Cu")
		(net "DRIVE_A_33_PWR")
	)
	(segment
		(start 407.00198 -230.77678)
		(end 408.4828 -232.2576)
		(width 0.12065)
		(layer "In4.Cu")
		(net "DRIVE_A_33_PWR")
	)
	(segment
		(start 432.710336 -46.380908)
		(end 432.520852 -46.570392)
		(width 0.12065)
		(layer "In4.Cu")
		(net "DRIVE_A_33_PWR")
	)
	(segment
		(start 407.081482 -131.256532)
		(end 407.081482 -131.664456)
		(width 0.12065)
		(layer "In4.Cu")
		(net "DRIVE_A_33_PWR")
	)
	(segment
		(start 407.081482 -131.664456)
		(end 407.00198 -131.743958)
		(width 0.12065)
		(layer "In4.Cu")
		(net "DRIVE_A_33_PWR")
	)
	(segment
		(start 406.757124 -130.968242)
		(end 406.793192 -130.968242)
		(width 0.12065)
		(layer "In4.Cu")
		(net "DRIVE_A_33_PWR")
	)
	(segment
		(start 406.757124 -106.246676)
		(end 406.757124 -130.968242)
		(width 0.12065)
		(layer "In4.Cu")
		(net "DRIVE_A_33_PWR")
	)
	(segment
		(start 412.93161 -167.231314)
		(end 407.00198 -173.160944)
		(width 0.12065)
		(layer "In4.Cu")
		(net "DRIVE_A_33_PWR")
	)
	(segment
		(start 432.710336 -42.168826)
		(end 432.710336 -46.380908)
		(width 0.12065)
		(layer "In4.Cu")
		(net "DRIVE_A_33_PWR")
	)
	(segment
		(start 432.520852 -80.482948)
		(end 406.757124 -106.246676)
		(width 0.12065)
		(layer "In4.Cu")
		(net "DRIVE_A_33_PWR")
	)
	(segment
		(start 432.520852 -46.570392)
		(end 432.520852 -80.482948)
		(width 0.12065)
		(layer "In4.Cu")
		(net "DRIVE_A_33_PWR")
	)
	(segment
		(start 407.00198 -131.743958)
		(end 407.00198 -150.676356)
		(width 0.12065)
		(layer "In4.Cu")
		(net "DRIVE_A_33_PWR")
	)
	(segment
		(start 406.793192 -130.968242)
		(end 407.081482 -131.256532)
		(width 0.12065)
		(layer "In4.Cu")
		(net "DRIVE_A_33_PWR")
	)
	(segment
		(start 407.00198 -173.160944)
		(end 407.00198 -230.77678)
		(width 0.12065)
		(layer "In4.Cu")
		(net "DRIVE_A_33_PWR")
	)
	(segment
		(start 407.00198 -150.676356)
		(end 412.93161 -156.605986)
		(width 0.12065)
		(layer "In4.Cu")
		(net "DRIVE_A_33_PWR")
	)
	(segment
		(start 412.93161 -156.605986)
		(end 412.93161 -167.231314)
		(width 0.12065)
		(layer "In4.Cu")
		(net "DRIVE_A_33_PWR")
	)
	(segment
		(start 412.175452 -66.167)
		(end 412.175452 -67.294252)
		(width 0.17145)
		(layer "F.Cu")
		(net "DRIVE_A_33_INS")
	)
	(segment
		(start 255.344676 -254.44196)
		(end 255.994916 -253.79172)
		(width 0.17145)
		(layer "F.Cu")
		(net "DRIVE_A_33_INS")
	)
	(segment
		(start 255.994916 -253.79172)
		(end 255.994916 -252.15596)
		(width 0.17145)
		(layer "F.Cu")
		(net "DRIVE_A_33_INS")
	)
	(segment
		(start 412.175452 -65.039494)
		(end 412.175452 -66.167)
		(width 0.17145)
		(layer "F.Cu")
		(net "DRIVE_A_33_INS")
	)
	(via
		(at 412.175452 -66.167)
		(size 0.6604)
		(drill 0.3302)
		(layers "F.Cu" "B.Cu")
		(net "DRIVE_A_33_INS")
	)
	(via
		(at 412.175452 -67.294252)
		(size 0.5588)
		(drill 0.3048)
		(layers "F.Cu" "B.Cu")
		(net "DRIVE_A_33_INS")
	)
	(via
		(at 399.942304 -248.0818)
		(size 0.5588)
		(drill 0.3048)
		(layers "F.Cu" "B.Cu")
		(net "DRIVE_A_33_INS")
	)
	(via
		(at 255.344676 -254.44196)
		(size 0.5588)
		(drill 0.3048)
		(layers "F.Cu" "B.Cu")
		(net "DRIVE_A_33_INS")
	)
	(segment
		(start 328.453496 -248.0818)
		(end 399.942304 -248.0818)
		(width 0.13335)
		(layer "In2.Cu")
		(net "DRIVE_A_33_INS")
	)
	(segment
		(start 255.9304 -253.401068)
		(end 256.61747 -252.713998)
		(width 0.13335)
		(layer "In2.Cu")
		(net "DRIVE_A_33_INS")
	)
	(segment
		(start 256.61747 -252.713998)
		(end 260.882892 -252.713998)
		(width 0.13335)
		(layer "In2.Cu")
		(net "DRIVE_A_33_INS")
	)
	(segment
		(start 307.414422 -233.023918)
		(end 320.597276 -246.206772)
		(width 0.13335)
		(layer "In2.Cu")
		(net "DRIVE_A_33_INS")
	)
	(segment
		(start 320.597276 -246.206772)
		(end 326.578468 -246.206772)
		(width 0.13335)
		(layer "In2.Cu")
		(net "DRIVE_A_33_INS")
	)
	(segment
		(start 262.838692 -250.758198)
		(end 270.212566 -250.758198)
		(width 0.13335)
		(layer "In2.Cu")
		(net "DRIVE_A_33_INS")
	)
	(segment
		(start 255.9304 -253.856236)
		(end 255.9304 -253.401068)
		(width 0.13335)
		(layer "In2.Cu")
		(net "DRIVE_A_33_INS")
	)
	(segment
		(start 295.927018 -233.023918)
		(end 307.414422 -233.023918)
		(width 0.13335)
		(layer "In2.Cu")
		(net "DRIVE_A_33_INS")
	)
	(segment
		(start 326.578468 -246.206772)
		(end 328.453496 -248.0818)
		(width 0.13335)
		(layer "In2.Cu")
		(net "DRIVE_A_33_INS")
	)
	(segment
		(start 255.344676 -254.44196)
		(end 255.9304 -253.856236)
		(width 0.13335)
		(layer "In2.Cu")
		(net "DRIVE_A_33_INS")
	)
	(segment
		(start 270.212566 -250.758198)
		(end 275.706332 -245.264432)
		(width 0.13335)
		(layer "In2.Cu")
		(net "DRIVE_A_33_INS")
	)
	(segment
		(start 275.706332 -245.264432)
		(end 283.686504 -245.264432)
		(width 0.13335)
		(layer "In2.Cu")
		(net "DRIVE_A_33_INS")
	)
	(segment
		(start 260.882892 -252.713998)
		(end 262.838692 -250.758198)
		(width 0.13335)
		(layer "In2.Cu")
		(net "DRIVE_A_33_INS")
	)
	(segment
		(start 283.686504 -245.264432)
		(end 295.927018 -233.023918)
		(width 0.13335)
		(layer "In2.Cu")
		(net "DRIVE_A_33_INS")
	)
	(segment
		(start 401.952206 -155.132786)
		(end 401.952206 -171.22902)
		(width 0.12065)
		(layer "In4.Cu")
		(net "DRIVE_A_33_INS")
	)
	(segment
		(start 404.5712 -99.2378)
		(end 401.383246 -102.425754)
		(width 0.12065)
		(layer "In4.Cu")
		(net "DRIVE_A_33_INS")
	)
	(segment
		(start 401.383246 -154.563826)
		(end 401.952206 -155.132786)
		(width 0.12065)
		(layer "In4.Cu")
		(net "DRIVE_A_33_INS")
	)
	(segment
		(start 401.952206 -171.22902)
		(end 404.5712 -173.848014)
		(width 0.12065)
		(layer "In4.Cu")
		(net "DRIVE_A_33_INS")
	)
	(segment
		(start 404.5712 -234.2388)
		(end 399.942304 -238.867696)
		(width 0.12065)
		(layer "In4.Cu")
		(net "DRIVE_A_33_INS")
	)
	(segment
		(start 399.942304 -238.867696)
		(end 399.942304 -248.0818)
		(width 0.12065)
		(layer "In4.Cu")
		(net "DRIVE_A_33_INS")
	)
	(segment
		(start 404.5712 -173.848014)
		(end 404.5712 -234.2388)
		(width 0.12065)
		(layer "In4.Cu")
		(net "DRIVE_A_33_INS")
	)
	(segment
		(start 404.5712 -74.898504)
		(end 404.5712 -99.2378)
		(width 0.12065)
		(layer "In4.Cu")
		(net "DRIVE_A_33_INS")
	)
	(segment
		(start 401.383246 -102.425754)
		(end 401.383246 -154.563826)
		(width 0.12065)
		(layer "In4.Cu")
		(net "DRIVE_A_33_INS")
	)
	(segment
		(start 412.175452 -67.294252)
		(end 404.5712 -74.898504)
		(width 0.12065)
		(layer "In4.Cu")
		(net "DRIVE_A_33_INS")
	)
	(segment
		(start 214.239602 -0.126746)
		(end 213.800182 -0.566166)
		(width 0.17145)
		(layer "F.Cu")
		(net "DRIVE_A_33_FLT_LED")
	)
	(segment
		(start 213.800182 -0.566166)
		(end 213.800182 -1.450086)
		(width 0.17145)
		(layer "F.Cu")
		(net "DRIVE_A_33_FLT_LED")
	)
	(segment
		(start 290.07308 -283.134054)
		(end 290.07308 -284.171898)
		(width 0.17145)
		(layer "F.Cu")
		(net "DRIVE_A_33_FLT_LED")
	)
	(segment
		(start 290.07308 -281.2034)
		(end 290.07308 -283.134054)
		(width 0.17145)
		(layer "F.Cu")
		(net "DRIVE_A_33_FLT_LED")
	)
	(segment
		(start 290.07308 -284.171898)
		(end 290.4617 -284.560518)
		(width 0.17145)
		(layer "F.Cu")
		(net "DRIVE_A_33_FLT_LED")
	)
	(segment
		(start 214.239602 -0.13462)
		(end 214.239602 -0.126746)
		(width 0.17145)
		(layer "F.Cu")
		(net "DRIVE_A_33_FLT_LED")
	)
	(via
		(at 214.239602 -0.13462)
		(size 0.5588)
		(drill 0.3048)
		(layers "F.Cu" "B.Cu")
		(net "DRIVE_A_33_FLT_LED")
	)
	(via
		(at 290.4617 -284.560518)
		(size 0.5588)
		(drill 0.3048)
		(layers "F.Cu" "B.Cu")
		(net "DRIVE_A_33_FLT_LED")
	)
	(via
		(at 290.07308 -283.134054)
		(size 0.6604)
		(drill 0.3302)
		(layers "F.Cu" "B.Cu")
		(net "DRIVE_A_33_FLT_LED")
	)
	(segment
		(start 294.424862 25.206452)
		(end 288.47542 31.155894)
		(width 0.12065)
		(layer "In4.Cu")
		(net "DRIVE_A_33_FLT_LED")
	)
	(segment
		(start 290.4617 -277.56866)
		(end 308.9529 -259.07746)
		(width 0.12065)
		(layer "In4.Cu")
		(net "DRIVE_A_33_FLT_LED")
	)
	(segment
		(start 236.266736 31.155894)
		(end 224.501456 19.390614)
		(width 0.12065)
		(layer "In4.Cu")
		(net "DRIVE_A_33_FLT_LED")
	)
	(segment
		(start 308.9529 -130.323336)
		(end 293.80307 -115.173506)
		(width 0.12065)
		(layer "In4.Cu")
		(net "DRIVE_A_33_FLT_LED")
	)
	(segment
		(start 290.4617 -284.560518)
		(end 290.4617 -277.56866)
		(width 0.12065)
		(layer "In4.Cu")
		(net "DRIVE_A_33_FLT_LED")
	)
	(segment
		(start 224.501456 1.673606)
		(end 221.708472 -1.119378)
		(width 0.12065)
		(layer "In4.Cu")
		(net "DRIVE_A_33_FLT_LED")
	)
	(segment
		(start 293.80307 -59.012582)
		(end 294.385746 -58.429906)
		(width 0.12065)
		(layer "In4.Cu")
		(net "DRIVE_A_33_FLT_LED")
	)
	(segment
		(start 293.80307 -115.173506)
		(end 293.80307 -59.012582)
		(width 0.12065)
		(layer "In4.Cu")
		(net "DRIVE_A_33_FLT_LED")
	)
	(segment
		(start 294.385746 -30.881574)
		(end 294.424862 -30.881574)
		(width 0.12065)
		(layer "In4.Cu")
		(net "DRIVE_A_33_FLT_LED")
	)
	(segment
		(start 288.47542 31.155894)
		(end 236.266736 31.155894)
		(width 0.12065)
		(layer "In4.Cu")
		(net "DRIVE_A_33_FLT_LED")
	)
	(segment
		(start 215.22436 -1.119378)
		(end 214.239602 -0.13462)
		(width 0.12065)
		(layer "In4.Cu")
		(net "DRIVE_A_33_FLT_LED")
	)
	(segment
		(start 221.708472 -1.119378)
		(end 215.22436 -1.119378)
		(width 0.12065)
		(layer "In4.Cu")
		(net "DRIVE_A_33_FLT_LED")
	)
	(segment
		(start 224.501456 19.390614)
		(end 224.501456 1.673606)
		(width 0.12065)
		(layer "In4.Cu")
		(net "DRIVE_A_33_FLT_LED")
	)
	(segment
		(start 294.385746 -58.429906)
		(end 294.385746 -30.881574)
		(width 0.12065)
		(layer "In4.Cu")
		(net "DRIVE_A_33_FLT_LED")
	)
	(segment
		(start 294.424862 -30.881574)
		(end 294.424862 25.206452)
		(width 0.12065)
		(layer "In4.Cu")
		(net "DRIVE_A_33_FLT_LED")
	)
	(segment
		(start 308.9529 -259.07746)
		(end 308.9529 -130.323336)
		(width 0.12065)
		(layer "In4.Cu")
		(net "DRIVE_A_33_FLT_LED")
	)
	(segment
		(start 214.80018 -1.450086)
		(end 214.80018 0.922782)
		(width 0.17145)
		(layer "F.Cu")
		(net "DRIVE_A_33_ACT")
	)
	(segment
		(start 214.80018 0.922782)
		(end 214.797894 0.925068)
		(width 0.17145)
		(layer "F.Cu")
		(net "DRIVE_A_33_ACT")
	)
	(via
		(at 201.234802 -300.446694)
		(size 0.6604)
		(drill 0.3048)
		(layers "F.Cu" "B.Cu")
		(net "DRIVE_A_33_ACT")
	)
	(via
		(at 214.797894 0.925068)
		(size 0.5588)
		(drill 0.3048)
		(layers "F.Cu" "B.Cu")
		(net "DRIVE_A_33_ACT")
	)
	(segment
		(start 259.873496 -303.0728)
		(end 265.359896 -297.5864)
		(width 0.13335)
		(layer "In2.Cu")
		(net "DRIVE_A_33_ACT")
	)
	(segment
		(start 256.067306 -304.165)
		(end 257.159506 -303.0728)
		(width 0.13335)
		(layer "In2.Cu")
		(net "DRIVE_A_33_ACT")
	)
	(segment
		(start 265.359896 -297.5864)
		(end 274.5486 -297.5864)
		(width 0.13335)
		(layer "In2.Cu")
		(net "DRIVE_A_33_ACT")
	)
	(segment
		(start 257.159506 -303.0728)
		(end 259.873496 -303.0728)
		(width 0.13335)
		(layer "In2.Cu")
		(net "DRIVE_A_33_ACT")
	)
	(segment
		(start 210.66379 -304.165)
		(end 256.067306 -304.165)
		(width 0.13335)
		(layer "In2.Cu")
		(net "DRIVE_A_33_ACT")
	)
	(segment
		(start 201.234802 -300.446694)
		(end 206.945484 -300.446694)
		(width 0.13335)
		(layer "In2.Cu")
		(net "DRIVE_A_33_ACT")
	)
	(segment
		(start 206.945484 -300.446694)
		(end 210.66379 -304.165)
		(width 0.13335)
		(layer "In2.Cu")
		(net "DRIVE_A_33_ACT")
	)
	(segment
		(start 280.955242 -299.1866)
		(end 281.836622 -298.30522)
		(width 0.13335)
		(layer "In2.Cu")
		(net "DRIVE_A_33_ACT")
	)
	(segment
		(start 274.5486 -297.5864)
		(end 276.1488 -299.1866)
		(width 0.13335)
		(layer "In2.Cu")
		(net "DRIVE_A_33_ACT")
	)
	(segment
		(start 276.1488 -299.1866)
		(end 280.955242 -299.1866)
		(width 0.13335)
		(layer "In2.Cu")
		(net "DRIVE_A_33_ACT")
	)
	(segment
		(start 218.997784 -62.818772)
		(end 218.997784 -66.369184)
		(width 0.12065)
		(layer "In4.Cu")
		(net "DRIVE_A_33_ACT")
	)
	(segment
		(start 218.997784 -66.369184)
		(end 216.051384 -69.315584)
		(width 0.12065)
		(layer "In4.Cu")
		(net "DRIVE_A_33_ACT")
	)
	(segment
		(start 210.675728 -10.12317)
		(end 210.675728 -49.487074)
		(width 0.12065)
		(layer "In4.Cu")
		(net "DRIVE_A_33_ACT")
	)
	(segment
		(start 219.023184 -57.83453)
		(end 219.023184 -62.793372)
		(width 0.12065)
		(layer "In4.Cu")
		(net "DRIVE_A_33_ACT")
	)
	(segment
		(start 214.443818 -147.129246)
		(end 214.443818 -194.909694)
		(width 0.12065)
		(layer "In4.Cu")
		(net "DRIVE_A_33_ACT")
	)
	(segment
		(start 213.951312 0.925068)
		(end 212.915754 -0.11049)
		(width 0.12065)
		(layer "In4.Cu")
		(net "DRIVE_A_33_ACT")
	)
	(segment
		(start 212.915754 -0.11049)
		(end 212.915754 -7.883144)
		(width 0.12065)
		(layer "In4.Cu")
		(net "DRIVE_A_33_ACT")
	)
	(segment
		(start 211.377022 -78.035404)
		(end 211.377022 -144.06245)
		(width 0.12065)
		(layer "In4.Cu")
		(net "DRIVE_A_33_ACT")
	)
	(segment
		(start 214.797894 0.925068)
		(end 213.951312 0.925068)
		(width 0.12065)
		(layer "In4.Cu")
		(net "DRIVE_A_33_ACT")
	)
	(segment
		(start 199.88149 -299.093382)
		(end 201.234802 -300.446694)
		(width 0.12065)
		(layer "In4.Cu")
		(net "DRIVE_A_33_ACT")
	)
	(segment
		(start 216.051384 -69.315584)
		(end 216.051384 -73.361042)
		(width 0.12065)
		(layer "In4.Cu")
		(net "DRIVE_A_33_ACT")
	)
	(segment
		(start 214.443818 -194.909694)
		(end 206.411068 -202.942444)
		(width 0.12065)
		(layer "In4.Cu")
		(net "DRIVE_A_33_ACT")
	)
	(segment
		(start 211.377022 -144.06245)
		(end 214.443818 -147.129246)
		(width 0.12065)
		(layer "In4.Cu")
		(net "DRIVE_A_33_ACT")
	)
	(segment
		(start 212.915754 -7.883144)
		(end 210.675728 -10.12317)
		(width 0.12065)
		(layer "In4.Cu")
		(net "DRIVE_A_33_ACT")
	)
	(segment
		(start 199.88149 -285.838392)
		(end 199.88149 -299.093382)
		(width 0.12065)
		(layer "In4.Cu")
		(net "DRIVE_A_33_ACT")
	)
	(segment
		(start 206.411068 -202.942444)
		(end 206.411068 -279.308814)
		(width 0.12065)
		(layer "In4.Cu")
		(net "DRIVE_A_33_ACT")
	)
	(segment
		(start 210.675728 -49.487074)
		(end 219.023184 -57.83453)
		(width 0.12065)
		(layer "In4.Cu")
		(net "DRIVE_A_33_ACT")
	)
	(segment
		(start 216.051384 -73.361042)
		(end 211.377022 -78.035404)
		(width 0.12065)
		(layer "In4.Cu")
		(net "DRIVE_A_33_ACT")
	)
	(segment
		(start 206.411068 -279.308814)
		(end 199.88149 -285.838392)
		(width 0.12065)
		(layer "In4.Cu")
		(net "DRIVE_A_33_ACT")
	)
	(segment
		(start 219.023184 -62.793372)
		(end 218.997784 -62.818772)
		(width 0.12065)
		(layer "In4.Cu")
		(net "DRIVE_A_33_ACT")
	)
	(segment
		(start 263.253474 -236.157008)
		(end 263.253474 -234.935522)
		(width 0.17145)
		(layer "F.Cu")
		(net "DRIVE_A_32_PWR")
	)
	(segment
		(start 263.253474 -234.935522)
		(end 263.1186 -234.800648)
		(width 0.17145)
		(layer "F.Cu")
		(net "DRIVE_A_32_PWR")
	)
	(segment
		(start 401.160234 -42.168826)
		(end 401.132802 -42.141394)
		(width 0.17145)
		(layer "F.Cu")
		(net "DRIVE_A_32_PWR")
	)
	(segment
		(start 401.132802 -42.141394)
		(end 400.171666 -42.141394)
		(width 0.17145)
		(layer "F.Cu")
		(net "DRIVE_A_32_PWR")
	)
	(segment
		(start 263.1186 -234.800648)
		(end 263.1186 -234.0356)
		(width 0.17145)
		(layer "F.Cu")
		(net "DRIVE_A_32_PWR")
	)
	(segment
		(start 398.88795 -42.141394)
		(end 400.171666 -42.141394)
		(width 0.17145)
		(layer "F.Cu")
		(net "DRIVE_A_32_PWR")
	)
	(via
		(at 400.171666 -42.141394)
		(size 0.6604)
		(drill 0.3302)
		(layers "F.Cu" "B.Cu")
		(net "DRIVE_A_32_PWR")
	)
	(via
		(at 401.160234 -42.168826)
		(size 0.5588)
		(drill 0.3048)
		(layers "F.Cu" "B.Cu")
		(net "DRIVE_A_32_PWR")
	)
	(via
		(at 403.1996 -231.6988)
		(size 0.5588)
		(drill 0.3048)
		(layers "F.Cu" "B.Cu")
		(net "DRIVE_A_32_PWR")
	)
	(via
		(at 263.253474 -236.157008)
		(size 0.5588)
		(drill 0.3048)
		(layers "F.Cu" "B.Cu")
		(net "DRIVE_A_32_PWR")
	)
	(segment
		(start 265.547094 -234.654344)
		(end 264.756138 -234.654344)
		(width 0.13335)
		(layer "In2.Cu")
		(net "DRIVE_A_32_PWR")
	)
	(segment
		(start 278.896064 -224.384362)
		(end 270.28648 -232.993946)
		(width 0.13335)
		(layer "In2.Cu")
		(net "DRIVE_A_32_PWR")
	)
	(segment
		(start 315.249814 -221.82963)
		(end 291.549582 -221.82963)
		(width 0.13335)
		(layer "In2.Cu")
		(net "DRIVE_A_32_PWR")
	)
	(segment
		(start 270.28648 -232.993946)
		(end 267.207492 -232.993946)
		(width 0.13335)
		(layer "In2.Cu")
		(net "DRIVE_A_32_PWR")
	)
	(segment
		(start 291.549582 -221.82963)
		(end 288.99485 -224.384362)
		(width 0.13335)
		(layer "In2.Cu")
		(net "DRIVE_A_32_PWR")
	)
	(segment
		(start 325.118984 -231.6988)
		(end 315.249814 -221.82963)
		(width 0.13335)
		(layer "In2.Cu")
		(net "DRIVE_A_32_PWR")
	)
	(segment
		(start 288.99485 -224.384362)
		(end 278.896064 -224.384362)
		(width 0.13335)
		(layer "In2.Cu")
		(net "DRIVE_A_32_PWR")
	)
	(segment
		(start 264.756138 -234.654344)
		(end 263.253474 -236.157008)
		(width 0.13335)
		(layer "In2.Cu")
		(net "DRIVE_A_32_PWR")
	)
	(segment
		(start 267.207492 -232.993946)
		(end 265.547094 -234.654344)
		(width 0.13335)
		(layer "In2.Cu")
		(net "DRIVE_A_32_PWR")
	)
	(segment
		(start 403.1996 -231.6988)
		(end 325.118984 -231.6988)
		(width 0.13335)
		(layer "In2.Cu")
		(net "DRIVE_A_32_PWR")
	)
	(segment
		(start 401.539456 -155.303982)
		(end 401.539456 -171.400216)
		(width 0.12065)
		(layer "In4.Cu")
		(net "DRIVE_A_32_PWR")
	)
	(segment
		(start 400.70532 -154.469846)
		(end 401.539456 -155.303982)
		(width 0.12065)
		(layer "In4.Cu")
		(net "DRIVE_A_32_PWR")
	)
	(segment
		(start 404.0124 -45.020992)
		(end 404.0124 -99.006152)
		(width 0.12065)
		(layer "In4.Cu")
		(net "DRIVE_A_32_PWR")
	)
	(segment
		(start 404.0124 -99.006152)
		(end 400.70532 -102.313232)
		(width 0.12065)
		(layer "In4.Cu")
		(net "DRIVE_A_32_PWR")
	)
	(segment
		(start 400.70532 -102.313232)
		(end 400.70532 -154.469846)
		(width 0.12065)
		(layer "In4.Cu")
		(net "DRIVE_A_32_PWR")
	)
	(segment
		(start 401.160234 -42.168826)
		(end 404.0124 -45.020992)
		(width 0.12065)
		(layer "In4.Cu")
		(net "DRIVE_A_32_PWR")
	)
	(segment
		(start 401.539456 -171.400216)
		(end 403.1996 -173.06036)
		(width 0.12065)
		(layer "In4.Cu")
		(net "DRIVE_A_32_PWR")
	)
	(segment
		(start 403.1996 -173.06036)
		(end 403.1996 -231.6988)
		(width 0.12065)
		(layer "In4.Cu")
		(net "DRIVE_A_32_PWR")
	)
	(segment
		(start 380.24435 -79.0702)
		(end 380.24435 -69.4436)
		(width 0.17145)
		(layer "F.Cu")
		(net "DRIVE_A_32_INS")
	)
	(segment
		(start 255.344676 -252.15596)
		(end 255.344676 -253.47676)
		(width 0.17145)
		(layer "F.Cu")
		(net "DRIVE_A_32_INS")
	)
	(segment
		(start 383.26695 -82.0928)
		(end 380.24435 -79.0702)
		(width 0.17145)
		(layer "F.Cu")
		(net "DRIVE_A_32_INS")
	)
	(segment
		(start 380.24435 -69.4436)
		(end 380.24435 -65.039494)
		(width 0.17145)
		(layer "F.Cu")
		(net "DRIVE_A_32_INS")
	)
	(via
		(at 255.344676 -253.47676)
		(size 0.5588)
		(drill 0.3048)
		(layers "F.Cu" "B.Cu")
		(net "DRIVE_A_32_INS")
	)
	(via
		(at 383.26695 -82.0928)
		(size 0.5588)
		(drill 0.3048)
		(layers "F.Cu" "B.Cu")
		(net "DRIVE_A_32_INS")
	)
	(via
		(at 380.24435 -69.4436)
		(size 0.6604)
		(drill 0.3302)
		(layers "F.Cu" "B.Cu")
		(net "DRIVE_A_32_INS")
	)
	(via
		(at 381.862076 -245.917466)
		(size 0.5588)
		(drill 0.3048)
		(layers "F.Cu" "B.Cu")
		(net "DRIVE_A_32_INS")
	)
	(segment
		(start 269.980918 -250.199398)
		(end 275.474684 -244.705632)
		(width 0.13335)
		(layer "In2.Cu")
		(net "DRIVE_A_32_INS")
	)
	(segment
		(start 260.651244 -252.155198)
		(end 262.607044 -250.199398)
		(width 0.13335)
		(layer "In2.Cu")
		(net "DRIVE_A_32_INS")
	)
	(segment
		(start 307.64607 -232.465118)
		(end 320.828924 -245.647972)
		(width 0.13335)
		(layer "In2.Cu")
		(net "DRIVE_A_32_INS")
	)
	(segment
		(start 275.474684 -244.705632)
		(end 283.454856 -244.705632)
		(width 0.13335)
		(layer "In2.Cu")
		(net "DRIVE_A_32_INS")
	)
	(segment
		(start 255.344676 -253.47676)
		(end 255.344676 -253.163324)
		(width 0.13335)
		(layer "In2.Cu")
		(net "DRIVE_A_32_INS")
	)
	(segment
		(start 262.607044 -250.199398)
		(end 269.980918 -250.199398)
		(width 0.13335)
		(layer "In2.Cu")
		(net "DRIVE_A_32_INS")
	)
	(segment
		(start 295.69537 -232.465118)
		(end 307.64607 -232.465118)
		(width 0.13335)
		(layer "In2.Cu")
		(net "DRIVE_A_32_INS")
	)
	(segment
		(start 326.810116 -245.647972)
		(end 328.685144 -247.523)
		(width 0.13335)
		(layer "In2.Cu")
		(net "DRIVE_A_32_INS")
	)
	(segment
		(start 328.685144 -247.523)
		(end 380.256542 -247.523)
		(width 0.13335)
		(layer "In2.Cu")
		(net "DRIVE_A_32_INS")
	)
	(segment
		(start 320.828924 -245.647972)
		(end 326.810116 -245.647972)
		(width 0.13335)
		(layer "In2.Cu")
		(net "DRIVE_A_32_INS")
	)
	(segment
		(start 256.352802 -252.155198)
		(end 260.651244 -252.155198)
		(width 0.13335)
		(layer "In2.Cu")
		(net "DRIVE_A_32_INS")
	)
	(segment
		(start 283.454856 -244.705632)
		(end 295.69537 -232.465118)
		(width 0.13335)
		(layer "In2.Cu")
		(net "DRIVE_A_32_INS")
	)
	(segment
		(start 255.344676 -253.163324)
		(end 256.352802 -252.155198)
		(width 0.13335)
		(layer "In2.Cu")
		(net "DRIVE_A_32_INS")
	)
	(segment
		(start 380.256542 -247.523)
		(end 381.862076 -245.917466)
		(width 0.13335)
		(layer "In2.Cu")
		(net "DRIVE_A_32_INS")
	)
	(segment
		(start 381.881126 -245.898416)
		(end 381.881126 -181.313074)
		(width 0.12065)
		(layer "In4.Cu")
		(net "DRIVE_A_32_INS")
	)
	(segment
		(start 383.8702 -179.324)
		(end 383.8702 -156.724604)
		(width 0.12065)
		(layer "In4.Cu")
		(net "DRIVE_A_32_INS")
	)
	(segment
		(start 381.881126 -181.313074)
		(end 383.8702 -179.324)
		(width 0.12065)
		(layer "In4.Cu")
		(net "DRIVE_A_32_INS")
	)
	(segment
		(start 383.26695 -115.460018)
		(end 383.26695 -82.0928)
		(width 0.12065)
		(layer "In4.Cu")
		(net "DRIVE_A_32_INS")
	)
	(segment
		(start 383.8702 -156.724604)
		(end 395.236192 -145.358612)
		(width 0.12065)
		(layer "In4.Cu")
		(net "DRIVE_A_32_INS")
	)
	(segment
		(start 395.236192 -127.42926)
		(end 383.26695 -115.460018)
		(width 0.12065)
		(layer "In4.Cu")
		(net "DRIVE_A_32_INS")
	)
	(segment
		(start 381.862076 -245.917466)
		(end 381.881126 -245.898416)
		(width 0.12065)
		(layer "In4.Cu")
		(net "DRIVE_A_32_INS")
	)
	(segment
		(start 395.236192 -145.358612)
		(end 395.236192 -127.42926)
		(width 0.12065)
		(layer "In4.Cu")
		(net "DRIVE_A_32_INS")
	)
	(segment
		(start 213.800182 -7.55015)
		(end 213.800182 -9.310116)
		(width 0.17145)
		(layer "F.Cu")
		(net "DRIVE_A_32_FLT_LED")
	)
	(segment
		(start 290.72332 -282.384754)
		(end 291.067744 -282.729178)
		(width 0.17145)
		(layer "F.Cu")
		(net "DRIVE_A_32_FLT_LED")
	)
	(segment
		(start 291.752782 -283.414216)
		(end 292.095936 -283.414216)
		(width 0.17145)
		(layer "F.Cu")
		(net "DRIVE_A_32_FLT_LED")
	)
	(segment
		(start 291.067744 -282.729178)
		(end 291.752782 -283.414216)
		(width 0.17145)
		(layer "F.Cu")
		(net "DRIVE_A_32_FLT_LED")
	)
	(segment
		(start 290.72332 -281.2034)
		(end 290.72332 -282.384754)
		(width 0.17145)
		(layer "F.Cu")
		(net "DRIVE_A_32_FLT_LED")
	)
	(via
		(at 291.067744 -282.729178)
		(size 0.6604)
		(drill 0.3302)
		(layers "F.Cu" "B.Cu")
		(net "DRIVE_A_32_FLT_LED")
	)
	(via
		(at 292.095936 -283.414216)
		(size 0.5588)
		(drill 0.3048)
		(layers "F.Cu" "B.Cu")
		(net "DRIVE_A_32_FLT_LED")
	)
	(via
		(at 213.800182 -9.310116)
		(size 0.5588)
		(drill 0.3048)
		(layers "F.Cu" "B.Cu")
		(net "DRIVE_A_32_FLT_LED")
	)
	(segment
		(start 298.962826 -274.950174)
		(end 298.962826 -273.019774)
		(width 0.12065)
		(layer "In4.Cu")
		(net "DRIVE_A_32_FLT_LED")
	)
	(segment
		(start 214.04707 0.40767)
		(end 213.640416 0.001016)
		(width 0.12065)
		(layer "In4.Cu")
		(net "DRIVE_A_32_FLT_LED")
	)
	(segment
		(start 311.7469 -260.2357)
		(end 311.7469 -129.165096)
		(width 0.12065)
		(layer "In4.Cu")
		(net "DRIVE_A_32_FLT_LED")
	)
	(segment
		(start 292.095936 -281.817064)
		(end 298.962826 -274.950174)
		(width 0.12065)
		(layer "In4.Cu")
		(net "DRIVE_A_32_FLT_LED")
	)
	(segment
		(start 219.238068 0.40767)
		(end 214.04707 0.40767)
		(width 0.12065)
		(layer "In4.Cu")
		(net "DRIVE_A_32_FLT_LED")
	)
	(segment
		(start 235.397548 33.219644)
		(end 222.340424 20.16252)
		(width 0.12065)
		(layer "In4.Cu")
		(net "DRIVE_A_32_FLT_LED")
	)
	(segment
		(start 213.640416 0.001016)
		(end 213.640416 -9.15035)
		(width 0.12065)
		(layer "In4.Cu")
		(net "DRIVE_A_32_FLT_LED")
	)
	(segment
		(start 295.86682 -113.285016)
		(end 295.86682 -60.488068)
		(width 0.12065)
		(layer "In4.Cu")
		(net "DRIVE_A_32_FLT_LED")
	)
	(segment
		(start 213.640416 -9.15035)
		(end 213.800182 -9.310116)
		(width 0.12065)
		(layer "In4.Cu")
		(net "DRIVE_A_32_FLT_LED")
	)
	(segment
		(start 297.179746 -29.723334)
		(end 297.218862 -29.723334)
		(width 0.12065)
		(layer "In4.Cu")
		(net "DRIVE_A_32_FLT_LED")
	)
	(segment
		(start 297.218862 26.364692)
		(end 290.36391 33.219644)
		(width 0.12065)
		(layer "In4.Cu")
		(net "DRIVE_A_32_FLT_LED")
	)
	(segment
		(start 292.095936 -283.414216)
		(end 292.095936 -281.817064)
		(width 0.12065)
		(layer "In4.Cu")
		(net "DRIVE_A_32_FLT_LED")
	)
	(segment
		(start 222.340424 20.16252)
		(end 222.340424 3.510026)
		(width 0.12065)
		(layer "In4.Cu")
		(net "DRIVE_A_32_FLT_LED")
	)
	(segment
		(start 290.36391 33.219644)
		(end 235.397548 33.219644)
		(width 0.12065)
		(layer "In4.Cu")
		(net "DRIVE_A_32_FLT_LED")
	)
	(segment
		(start 222.340424 3.510026)
		(end 219.238068 0.40767)
		(width 0.12065)
		(layer "In4.Cu")
		(net "DRIVE_A_32_FLT_LED")
	)
	(segment
		(start 295.86682 -60.488068)
		(end 297.179746 -59.175142)
		(width 0.12065)
		(layer "In4.Cu")
		(net "DRIVE_A_32_FLT_LED")
	)
	(segment
		(start 311.7469 -129.165096)
		(end 295.86682 -113.285016)
		(width 0.12065)
		(layer "In4.Cu")
		(net "DRIVE_A_32_FLT_LED")
	)
	(segment
		(start 297.179746 -59.175142)
		(end 297.179746 -29.723334)
		(width 0.12065)
		(layer "In4.Cu")
		(net "DRIVE_A_32_FLT_LED")
	)
	(segment
		(start 297.218862 -29.723334)
		(end 297.218862 26.364692)
		(width 0.12065)
		(layer "In4.Cu")
		(net "DRIVE_A_32_FLT_LED")
	)
	(segment
		(start 298.962826 -273.019774)
		(end 311.7469 -260.2357)
		(width 0.12065)
		(layer "In4.Cu")
		(net "DRIVE_A_32_FLT_LED")
	)
	(segment
		(start 213.98738 -10.48893)
		(end 214.80018 -9.67613)
		(width 0.17145)
		(layer "F.Cu")
		(net "DRIVE_A_32_ACT")
	)
	(segment
		(start 214.80018 -9.67613)
		(end 214.80018 -7.55015)
		(width 0.17145)
		(layer "F.Cu")
		(net "DRIVE_A_32_ACT")
	)
	(via
		(at 201.234802 -299.379894)
		(size 0.6604)
		(drill 0.3048)
		(layers "F.Cu" "B.Cu")
		(net "DRIVE_A_32_ACT")
	)
	(via
		(at 213.98738 -10.48893)
		(size 0.5588)
		(drill 0.3048)
		(layers "F.Cu" "B.Cu")
		(net "DRIVE_A_32_ACT")
	)
	(via
		(at 265.9126 -296.672)
		(size 0.5588)
		(drill 0.3048)
		(layers "F.Cu" "B.Cu")
		(net "DRIVE_A_32_ACT")
	)
	(segment
		(start 256.927858 -302.514)
		(end 259.641848 -302.514)
		(width 0.13335)
		(layer "In2.Cu")
		(net "DRIVE_A_32_ACT")
	)
	(segment
		(start 201.234802 -299.379894)
		(end 206.48041 -299.379894)
		(width 0.13335)
		(layer "In2.Cu")
		(net "DRIVE_A_32_ACT")
	)
	(segment
		(start 265.483848 -296.672)
		(end 265.9126 -296.672)
		(width 0.13335)
		(layer "In2.Cu")
		(net "DRIVE_A_32_ACT")
	)
	(segment
		(start 255.835658 -303.6062)
		(end 256.927858 -302.514)
		(width 0.13335)
		(layer "In2.Cu")
		(net "DRIVE_A_32_ACT")
	)
	(segment
		(start 210.706716 -303.6062)
		(end 255.835658 -303.6062)
		(width 0.13335)
		(layer "In2.Cu")
		(net "DRIVE_A_32_ACT")
	)
	(segment
		(start 206.48041 -299.379894)
		(end 210.706716 -303.6062)
		(width 0.13335)
		(layer "In2.Cu")
		(net "DRIVE_A_32_ACT")
	)
	(segment
		(start 259.641848 -302.514)
		(end 265.483848 -296.672)
		(width 0.13335)
		(layer "In2.Cu")
		(net "DRIVE_A_32_ACT")
	)
	(segment
		(start 282.378404 -299.212)
		(end 283.23667 -298.353734)
		(width 0.12065)
		(layer "In4.Cu")
		(net "DRIVE_A_32_ACT")
	)
	(segment
		(start 283.23667 -298.353734)
		(end 283.23667 -298.30522)
		(width 0.12065)
		(layer "In4.Cu")
		(net "DRIVE_A_32_ACT")
	)
	(segment
		(start 200.302368 -286.414464)
		(end 200.302368 -298.44746)
		(width 0.12065)
		(layer "In4.Cu")
		(net "DRIVE_A_32_ACT")
	)
	(segment
		(start 219.410534 -62.989968)
		(end 219.410534 -66.54038)
		(width 0.12065)
		(layer "In4.Cu")
		(net "DRIVE_A_32_ACT")
	)
	(segment
		(start 216.464134 -69.48678)
		(end 216.464134 -74.084688)
		(width 0.12065)
		(layer "In4.Cu")
		(net "DRIVE_A_32_ACT")
	)
	(segment
		(start 206.969868 -279.540462)
		(end 200.418446 -286.091884)
		(width 0.12065)
		(layer "In4.Cu")
		(net "DRIVE_A_32_ACT")
	)
	(segment
		(start 213.98738 -10.48893)
		(end 211.088478 -13.387832)
		(width 0.12065)
		(layer "In4.Cu")
		(net "DRIVE_A_32_ACT")
	)
	(segment
		(start 277.0632 -299.212)
		(end 282.378404 -299.212)
		(width 0.12065)
		(layer "In4.Cu")
		(net "DRIVE_A_32_ACT")
	)
	(segment
		(start 265.9126 -296.672)
		(end 274.5232 -296.672)
		(width 0.12065)
		(layer "In4.Cu")
		(net "DRIVE_A_32_ACT")
	)
	(segment
		(start 200.418446 -286.091884)
		(end 200.418446 -286.298386)
		(width 0.12065)
		(layer "In4.Cu")
		(net "DRIVE_A_32_ACT")
	)
	(segment
		(start 219.410534 -66.54038)
		(end 216.464134 -69.48678)
		(width 0.12065)
		(layer "In4.Cu")
		(net "DRIVE_A_32_ACT")
	)
	(segment
		(start 215.002618 -195.141342)
		(end 206.969868 -203.174092)
		(width 0.12065)
		(layer "In4.Cu")
		(net "DRIVE_A_32_ACT")
	)
	(segment
		(start 211.088478 -13.387832)
		(end 211.088478 -49.315878)
		(width 0.12065)
		(layer "In4.Cu")
		(net "DRIVE_A_32_ACT")
	)
	(segment
		(start 211.789772 -143.684752)
		(end 215.002618 -146.897598)
		(width 0.12065)
		(layer "In4.Cu")
		(net "DRIVE_A_32_ACT")
	)
	(segment
		(start 215.002618 -146.897598)
		(end 215.002618 -195.141342)
		(width 0.12065)
		(layer "In4.Cu")
		(net "DRIVE_A_32_ACT")
	)
	(segment
		(start 200.302368 -298.44746)
		(end 201.234802 -299.379894)
		(width 0.12065)
		(layer "In4.Cu")
		(net "DRIVE_A_32_ACT")
	)
	(segment
		(start 274.5232 -296.672)
		(end 277.0632 -299.212)
		(width 0.12065)
		(layer "In4.Cu")
		(net "DRIVE_A_32_ACT")
	)
	(segment
		(start 216.464134 -74.084688)
		(end 211.789772 -78.75905)
		(width 0.12065)
		(layer "In4.Cu")
		(net "DRIVE_A_32_ACT")
	)
	(segment
		(start 211.088478 -49.315878)
		(end 219.435934 -57.663334)
		(width 0.12065)
		(layer "In4.Cu")
		(net "DRIVE_A_32_ACT")
	)
	(segment
		(start 219.435934 -62.964568)
		(end 219.410534 -62.989968)
		(width 0.12065)
		(layer "In4.Cu")
		(net "DRIVE_A_32_ACT")
	)
	(segment
		(start 200.418446 -286.298386)
		(end 200.302368 -286.414464)
		(width 0.12065)
		(layer "In4.Cu")
		(net "DRIVE_A_32_ACT")
	)
	(segment
		(start 211.789772 -78.75905)
		(end 211.789772 -143.684752)
		(width 0.12065)
		(layer "In4.Cu")
		(net "DRIVE_A_32_ACT")
	)
	(segment
		(start 219.435934 -57.663334)
		(end 219.435934 -62.964568)
		(width 0.12065)
		(layer "In4.Cu")
		(net "DRIVE_A_32_ACT")
	)
	(segment
		(start 206.969868 -203.174092)
		(end 206.969868 -279.540462)
		(width 0.12065)
		(layer "In4.Cu")
		(net "DRIVE_A_32_ACT")
	)
	(segment
		(start 367.344706 -42.147998)
		(end 368.4778 -42.147998)
		(width 0.17145)
		(layer "F.Cu")
		(net "DRIVE_A_31_PWR")
	)
	(segment
		(start 369.148106 -42.147998)
		(end 369.918742 -42.918634)
		(width 0.17145)
		(layer "F.Cu")
		(net "DRIVE_A_31_PWR")
	)
	(segment
		(start 244.76964 -238.71936)
		(end 244.76964 -239.8014)
		(width 0.17145)
		(layer "F.Cu")
		(net "DRIVE_A_31_PWR")
	)
	(segment
		(start 367.338102 -42.141394)
		(end 367.344706 -42.147998)
		(width 0.17145)
		(layer "F.Cu")
		(net "DRIVE_A_31_PWR")
	)
	(segment
		(start 245.364 -238.125)
		(end 244.76964 -238.71936)
		(width 0.17145)
		(layer "F.Cu")
		(net "DRIVE_A_31_PWR")
	)
	(segment
		(start 368.4778 -42.147998)
		(end 369.148106 -42.147998)
		(width 0.17145)
		(layer "F.Cu")
		(net "DRIVE_A_31_PWR")
	)
	(via
		(at 367.792 -231.14)
		(size 0.5588)
		(drill 0.3048)
		(layers "F.Cu" "B.Cu")
		(net "DRIVE_A_31_PWR")
	)
	(via
		(at 245.364 -238.125)
		(size 0.5588)
		(drill 0.3048)
		(layers "F.Cu" "B.Cu")
		(net "DRIVE_A_31_PWR")
	)
	(via
		(at 368.4778 -42.147998)
		(size 0.6604)
		(drill 0.3302)
		(layers "F.Cu" "B.Cu")
		(net "DRIVE_A_31_PWR")
	)
	(via
		(at 369.918742 -42.918634)
		(size 0.5588)
		(drill 0.3048)
		(layers "F.Cu" "B.Cu")
		(net "DRIVE_A_31_PWR")
	)
	(segment
		(start 263.177274 -234.784646)
		(end 263.757664 -234.784646)
		(width 0.13335)
		(layer "In2.Cu")
		(net "DRIVE_A_31_PWR")
	)
	(segment
		(start 293.041832 -219.485718)
		(end 313.69635 -219.485718)
		(width 0.13335)
		(layer "In2.Cu")
		(net "DRIVE_A_31_PWR")
	)
	(segment
		(start 325.350632 -231.14)
		(end 367.792 -231.14)
		(width 0.13335)
		(layer "In2.Cu")
		(net "DRIVE_A_31_PWR")
	)
	(segment
		(start 260.416802 -237.545118)
		(end 263.177274 -234.784646)
		(width 0.13335)
		(layer "In2.Cu")
		(net "DRIVE_A_31_PWR")
	)
	(segment
		(start 246.347742 -239.108742)
		(end 249.917204 -239.108742)
		(width 0.13335)
		(layer "In2.Cu")
		(net "DRIVE_A_31_PWR")
	)
	(segment
		(start 288.701988 -223.825562)
		(end 293.041832 -219.485718)
		(width 0.13335)
		(layer "In2.Cu")
		(net "DRIVE_A_31_PWR")
	)
	(segment
		(start 270.02105 -232.41)
		(end 278.605488 -223.825562)
		(width 0.13335)
		(layer "In2.Cu")
		(net "DRIVE_A_31_PWR")
	)
	(segment
		(start 249.917204 -239.108742)
		(end 251.480828 -237.545118)
		(width 0.13335)
		(layer "In2.Cu")
		(net "DRIVE_A_31_PWR")
	)
	(segment
		(start 245.364 -238.125)
		(end 246.347742 -239.108742)
		(width 0.13335)
		(layer "In2.Cu")
		(net "DRIVE_A_31_PWR")
	)
	(segment
		(start 251.480828 -237.545118)
		(end 260.416802 -237.545118)
		(width 0.13335)
		(layer "In2.Cu")
		(net "DRIVE_A_31_PWR")
	)
	(segment
		(start 263.757664 -234.784646)
		(end 266.13231 -232.41)
		(width 0.13335)
		(layer "In2.Cu")
		(net "DRIVE_A_31_PWR")
	)
	(segment
		(start 266.13231 -232.41)
		(end 270.02105 -232.41)
		(width 0.13335)
		(layer "In2.Cu")
		(net "DRIVE_A_31_PWR")
	)
	(segment
		(start 278.605488 -223.825562)
		(end 288.701988 -223.825562)
		(width 0.13335)
		(layer "In2.Cu")
		(net "DRIVE_A_31_PWR")
	)
	(segment
		(start 313.69635 -219.485718)
		(end 325.350632 -231.14)
		(width 0.13335)
		(layer "In2.Cu")
		(net "DRIVE_A_31_PWR")
	)
	(segment
		(start 386.388864 -130.883406)
		(end 386.388864 -142.025116)
		(width 0.12065)
		(layer "In4.Cu")
		(net "DRIVE_A_31_PWR")
	)
	(segment
		(start 367.6904 -231.0384)
		(end 367.792 -231.14)
		(width 0.12065)
		(layer "In4.Cu")
		(net "DRIVE_A_31_PWR")
	)
	(segment
		(start 386.388864 -142.025116)
		(end 373.09298 -155.321)
		(width 0.12065)
		(layer "In4.Cu")
		(net "DRIVE_A_31_PWR")
	)
	(segment
		(start 369.918742 -42.918634)
		(end 369.918742 -114.413284)
		(width 0.12065)
		(layer "In4.Cu")
		(net "DRIVE_A_31_PWR")
	)
	(segment
		(start 373.09298 -210.44662)
		(end 367.6904 -215.8492)
		(width 0.12065)
		(layer "In4.Cu")
		(net "DRIVE_A_31_PWR")
	)
	(segment
		(start 367.6904 -215.8492)
		(end 367.6904 -231.0384)
		(width 0.12065)
		(layer "In4.Cu")
		(net "DRIVE_A_31_PWR")
	)
	(segment
		(start 369.918742 -114.413284)
		(end 386.388864 -130.883406)
		(width 0.12065)
		(layer "In4.Cu")
		(net "DRIVE_A_31_PWR")
	)
	(segment
		(start 373.09298 -155.321)
		(end 373.09298 -210.44662)
		(width 0.12065)
		(layer "In4.Cu")
		(net "DRIVE_A_31_PWR")
	)
	(segment
		(start 243.49964 -256.50444)
		(end 243.49964 -257.7084)
		(width 0.17145)
		(layer "F.Cu")
		(net "DRIVE_A_31_INS")
	)
	(segment
		(start 351.717102 -82.0928)
		(end 351.717102 -71.885302)
		(width 0.17145)
		(layer "F.Cu")
		(net "DRIVE_A_31_INS")
	)
	(segment
		(start 242.9764 -255.9812)
		(end 243.49964 -256.50444)
		(width 0.17145)
		(layer "F.Cu")
		(net "DRIVE_A_31_INS")
	)
	(segment
		(start 351.717102 -71.885302)
		(end 349.177102 -69.345302)
		(width 0.17145)
		(layer "F.Cu")
		(net "DRIVE_A_31_INS")
	)
	(segment
		(start 349.177102 -69.345302)
		(end 349.177102 -67.0306)
		(width 0.17145)
		(layer "F.Cu")
		(net "DRIVE_A_31_INS")
	)
	(segment
		(start 349.177102 -65.064894)
		(end 349.177102 -67.0306)
		(width 0.17145)
		(layer "F.Cu")
		(net "DRIVE_A_31_INS")
	)
	(segment
		(start 242.9764 -255.4478)
		(end 242.9764 -255.9812)
		(width 0.17145)
		(layer "F.Cu")
		(net "DRIVE_A_31_INS")
	)
	(via
		(at 349.177102 -67.0306)
		(size 0.6604)
		(drill 0.3302)
		(layers "F.Cu" "B.Cu")
		(net "DRIVE_A_31_INS")
	)
	(via
		(at 351.717102 -82.0928)
		(size 0.5588)
		(drill 0.3048)
		(layers "F.Cu" "B.Cu")
		(net "DRIVE_A_31_INS")
	)
	(via
		(at 242.9764 -255.4478)
		(size 0.5588)
		(drill 0.3048)
		(layers "F.Cu" "B.Cu")
		(net "DRIVE_A_31_INS")
	)
	(via
		(at 350.0374 -246.9134)
		(size 0.5588)
		(drill 0.3048)
		(layers "F.Cu" "B.Cu")
		(net "DRIVE_A_31_INS")
	)
	(segment
		(start 260.419596 -251.596398)
		(end 262.375396 -249.640598)
		(width 0.13335)
		(layer "In2.Cu")
		(net "DRIVE_A_31_INS")
	)
	(segment
		(start 262.375396 -249.640598)
		(end 269.74927 -249.640598)
		(width 0.13335)
		(layer "In2.Cu")
		(net "DRIVE_A_31_INS")
	)
	(segment
		(start 307.877718 -231.906318)
		(end 321.060572 -245.089172)
		(width 0.13335)
		(layer "In2.Cu")
		(net "DRIVE_A_31_INS")
	)
	(segment
		(start 327.029572 -245.089172)
		(end 328.8538 -246.9134)
		(width 0.13335)
		(layer "In2.Cu")
		(net "DRIVE_A_31_INS")
	)
	(segment
		(start 321.060572 -245.089172)
		(end 327.029572 -245.089172)
		(width 0.13335)
		(layer "In2.Cu")
		(net "DRIVE_A_31_INS")
	)
	(segment
		(start 283.223208 -244.146832)
		(end 295.463722 -231.906318)
		(width 0.13335)
		(layer "In2.Cu")
		(net "DRIVE_A_31_INS")
	)
	(segment
		(start 275.243036 -244.146832)
		(end 283.223208 -244.146832)
		(width 0.13335)
		(layer "In2.Cu")
		(net "DRIVE_A_31_INS")
	)
	(segment
		(start 254.1778 -253.572772)
		(end 256.154174 -251.596398)
		(width 0.13335)
		(layer "In2.Cu")
		(net "DRIVE_A_31_INS")
	)
	(segment
		(start 328.8538 -246.9134)
		(end 350.0374 -246.9134)
		(width 0.13335)
		(layer "In2.Cu")
		(net "DRIVE_A_31_INS")
	)
	(segment
		(start 243.686584 -256.4892)
		(end 252.222 -256.4892)
		(width 0.13335)
		(layer "In2.Cu")
		(net "DRIVE_A_31_INS")
	)
	(segment
		(start 256.154174 -251.596398)
		(end 260.419596 -251.596398)
		(width 0.13335)
		(layer "In2.Cu")
		(net "DRIVE_A_31_INS")
	)
	(segment
		(start 254.1778 -254.5334)
		(end 254.1778 -253.572772)
		(width 0.13335)
		(layer "In2.Cu")
		(net "DRIVE_A_31_INS")
	)
	(segment
		(start 252.222 -256.4892)
		(end 254.1778 -254.5334)
		(width 0.13335)
		(layer "In2.Cu")
		(net "DRIVE_A_31_INS")
	)
	(segment
		(start 242.9764 -255.4478)
		(end 242.9764 -255.779016)
		(width 0.13335)
		(layer "In2.Cu")
		(net "DRIVE_A_31_INS")
	)
	(segment
		(start 242.9764 -255.779016)
		(end 243.686584 -256.4892)
		(width 0.13335)
		(layer "In2.Cu")
		(net "DRIVE_A_31_INS")
	)
	(segment
		(start 295.463722 -231.906318)
		(end 307.877718 -231.906318)
		(width 0.13335)
		(layer "In2.Cu")
		(net "DRIVE_A_31_INS")
	)
	(segment
		(start 269.74927 -249.640598)
		(end 275.243036 -244.146832)
		(width 0.13335)
		(layer "In2.Cu")
		(net "DRIVE_A_31_INS")
	)
	(segment
		(start 351.717102 -106.032046)
		(end 335.502504 -122.246644)
		(width 0.12065)
		(layer "In4.Cu")
		(net "DRIVE_A_31_INS")
	)
	(segment
		(start 351.717102 -82.0928)
		(end 351.717102 -106.032046)
		(width 0.12065)
		(layer "In4.Cu")
		(net "DRIVE_A_31_INS")
	)
	(segment
		(start 348.111572 -200.603358)
		(end 349.972122 -202.463908)
		(width 0.12065)
		(layer "In4.Cu")
		(net "DRIVE_A_31_INS")
	)
	(segment
		(start 335.502504 -159.907986)
		(end 339.4964 -163.901882)
		(width 0.12065)
		(layer "In4.Cu")
		(net "DRIVE_A_31_INS")
	)
	(segment
		(start 349.972122 -202.463908)
		(end 349.972122 -246.848122)
		(width 0.12065)
		(layer "In4.Cu")
		(net "DRIVE_A_31_INS")
	)
	(segment
		(start 349.972122 -246.848122)
		(end 350.0374 -246.9134)
		(width 0.12065)
		(layer "In4.Cu")
		(net "DRIVE_A_31_INS")
	)
	(segment
		(start 339.4964 -169.6212)
		(end 340.943946 -171.068746)
		(width 0.12065)
		(layer "In4.Cu")
		(net "DRIVE_A_31_INS")
	)
	(segment
		(start 339.4964 -163.901882)
		(end 339.4964 -169.6212)
		(width 0.12065)
		(layer "In4.Cu")
		(net "DRIVE_A_31_INS")
	)
	(segment
		(start 340.943946 -171.068746)
		(end 340.943946 -174.795942)
		(width 0.12065)
		(layer "In4.Cu")
		(net "DRIVE_A_31_INS")
	)
	(segment
		(start 335.502504 -122.246644)
		(end 335.502504 -159.907986)
		(width 0.12065)
		(layer "In4.Cu")
		(net "DRIVE_A_31_INS")
	)
	(segment
		(start 348.111572 -181.963568)
		(end 348.111572 -200.603358)
		(width 0.12065)
		(layer "In4.Cu")
		(net "DRIVE_A_31_INS")
	)
	(segment
		(start 340.943946 -174.795942)
		(end 348.111572 -181.963568)
		(width 0.12065)
		(layer "In4.Cu")
		(net "DRIVE_A_31_INS")
	)
	(segment
		(start 290.07308 -275.5646)
		(end 290.07308 -276.473412)
		(width 0.17145)
		(layer "F.Cu")
		(net "DRIVE_A_31_FLT_LED")
	)
	(segment
		(start 291.803582 -277.14448)
		(end 292.776656 -277.14448)
		(width 0.17145)
		(layer "F.Cu")
		(net "DRIVE_A_31_FLT_LED")
	)
	(segment
		(start 291.80282 -277.143718)
		(end 291.803582 -277.14448)
		(width 0.17145)
		(layer "F.Cu")
		(net "DRIVE_A_31_FLT_LED")
	)
	(segment
		(start 221.800166 -0.2413)
		(end 221.968568 -0.072898)
		(width 0.17145)
		(layer "F.Cu")
		(net "DRIVE_A_31_FLT_LED")
	)
	(segment
		(start 292.776656 -277.14448)
		(end 292.781228 -277.149052)
		(width 0.17145)
		(layer "F.Cu")
		(net "DRIVE_A_31_FLT_LED")
	)
	(segment
		(start 291.802058 -277.14448)
		(end 291.80282 -277.143718)
		(width 0.17145)
		(layer "F.Cu")
		(net "DRIVE_A_31_FLT_LED")
	)
	(segment
		(start 290.07308 -276.473412)
		(end 290.744148 -277.14448)
		(width 0.17145)
		(layer "F.Cu")
		(net "DRIVE_A_31_FLT_LED")
	)
	(segment
		(start 290.744148 -277.14448)
		(end 291.802058 -277.14448)
		(width 0.17145)
		(layer "F.Cu")
		(net "DRIVE_A_31_FLT_LED")
	)
	(segment
		(start 221.800166 -1.450086)
		(end 221.800166 -0.2413)
		(width 0.17145)
		(layer "F.Cu")
		(net "DRIVE_A_31_FLT_LED")
	)
	(via
		(at 291.80282 -277.143718)
		(size 0.6604)
		(drill 0.3302)
		(layers "F.Cu" "B.Cu")
		(net "DRIVE_A_31_FLT_LED")
	)
	(via
		(at 292.781228 -277.149052)
		(size 0.5588)
		(drill 0.3048)
		(layers "F.Cu" "B.Cu")
		(net "DRIVE_A_31_FLT_LED")
	)
	(via
		(at 221.968568 -0.072898)
		(size 0.5588)
		(drill 0.3048)
		(layers "F.Cu" "B.Cu")
		(net "DRIVE_A_31_FLT_LED")
	)
	(segment
		(start 294.983662 -30.649926)
		(end 294.983662 25.4381)
		(width 0.12065)
		(layer "In4.Cu")
		(net "DRIVE_A_31_FLT_LED")
	)
	(segment
		(start 294.944546 -58.661554)
		(end 294.944546 -30.649926)
		(width 0.12065)
		(layer "In4.Cu")
		(net "DRIVE_A_31_FLT_LED")
	)
	(segment
		(start 224.07626 19.549364)
		(end 224.07626 2.034794)
		(width 0.12065)
		(layer "In4.Cu")
		(net "DRIVE_A_31_FLT_LED")
	)
	(segment
		(start 292.781228 -277.149052)
		(end 292.781228 -276.03958)
		(width 0.12065)
		(layer "In4.Cu")
		(net "DRIVE_A_31_FLT_LED")
	)
	(segment
		(start 309.5117 -130.091688)
		(end 294.21582 -114.795808)
		(width 0.12065)
		(layer "In4.Cu")
		(net "DRIVE_A_31_FLT_LED")
	)
	(segment
		(start 292.781228 -276.03958)
		(end 309.5117 -259.309108)
		(width 0.12065)
		(layer "In4.Cu")
		(net "DRIVE_A_31_FLT_LED")
	)
	(segment
		(start 294.21582 -59.39028)
		(end 294.944546 -58.661554)
		(width 0.12065)
		(layer "In4.Cu")
		(net "DRIVE_A_31_FLT_LED")
	)
	(segment
		(start 309.5117 -259.309108)
		(end 309.5117 -130.091688)
		(width 0.12065)
		(layer "In4.Cu")
		(net "DRIVE_A_31_FLT_LED")
	)
	(segment
		(start 294.21582 -114.795808)
		(end 294.21582 -59.39028)
		(width 0.12065)
		(layer "In4.Cu")
		(net "DRIVE_A_31_FLT_LED")
	)
	(segment
		(start 294.944546 -30.649926)
		(end 294.983662 -30.649926)
		(width 0.12065)
		(layer "In4.Cu")
		(net "DRIVE_A_31_FLT_LED")
	)
	(segment
		(start 236.09554 31.568644)
		(end 224.07626 19.549364)
		(width 0.12065)
		(layer "In4.Cu")
		(net "DRIVE_A_31_FLT_LED")
	)
	(segment
		(start 224.07626 2.034794)
		(end 221.968568 -0.072898)
		(width 0.12065)
		(layer "In4.Cu")
		(net "DRIVE_A_31_FLT_LED")
	)
	(segment
		(start 288.853118 31.568644)
		(end 236.09554 31.568644)
		(width 0.12065)
		(layer "In4.Cu")
		(net "DRIVE_A_31_FLT_LED")
	)
	(segment
		(start 294.983662 25.4381)
		(end 288.853118 31.568644)
		(width 0.12065)
		(layer "In4.Cu")
		(net "DRIVE_A_31_FLT_LED")
	)
	(segment
		(start 225.152458 -0.965708)
		(end 224.56013 -0.37338)
		(width 0.17145)
		(layer "F.Cu")
		(net "DRIVE_A_31_ACT")
	)
	(segment
		(start 223.143318 -0.37338)
		(end 222.800164 -0.716534)
		(width 0.17145)
		(layer "F.Cu")
		(net "DRIVE_A_31_ACT")
	)
	(segment
		(start 224.56013 -0.37338)
		(end 223.143318 -0.37338)
		(width 0.17145)
		(layer "F.Cu")
		(net "DRIVE_A_31_ACT")
	)
	(segment
		(start 222.800164 -0.716534)
		(end 222.800164 -1.450086)
		(width 0.17145)
		(layer "F.Cu")
		(net "DRIVE_A_31_ACT")
	)
	(via
		(at 202.49515 -301.075598)
		(size 0.6604)
		(drill 0.3048)
		(layers "F.Cu" "B.Cu")
		(net "DRIVE_A_31_ACT")
	)
	(via
		(at 225.152458 -0.965708)
		(size 0.5588)
		(drill 0.3048)
		(layers "F.Cu" "B.Cu")
		(net "DRIVE_A_31_ACT")
	)
	(via
		(at 267.650722 -298.252134)
		(size 0.5588)
		(drill 0.3048)
		(layers "F.Cu" "B.Cu")
		(net "DRIVE_A_31_ACT")
	)
	(segment
		(start 206.618078 -301.075598)
		(end 202.49515 -301.075598)
		(width 0.13335)
		(layer "In2.Cu")
		(net "DRIVE_A_31_ACT")
	)
	(segment
		(start 267.650722 -298.252134)
		(end 260.671056 -305.2318)
		(width 0.13335)
		(layer "In2.Cu")
		(net "DRIVE_A_31_ACT")
	)
	(segment
		(start 260.671056 -305.2318)
		(end 210.77428 -305.2318)
		(width 0.13335)
		(layer "In2.Cu")
		(net "DRIVE_A_31_ACT")
	)
	(segment
		(start 210.77428 -305.2318)
		(end 206.618078 -301.075598)
		(width 0.13335)
		(layer "In2.Cu")
		(net "DRIVE_A_31_ACT")
	)
	(segment
		(start 209.205068 -280.467054)
		(end 209.205068 -204.100684)
		(width 0.12065)
		(layer "In4.Cu")
		(net "DRIVE_A_31_ACT")
	)
	(segment
		(start 217.237818 -196.067934)
		(end 217.237818 -145.752312)
		(width 0.12065)
		(layer "In4.Cu")
		(net "DRIVE_A_31_ACT")
	)
	(segment
		(start 221.086934 -56.97855)
		(end 212.949282 -48.840898)
		(width 0.12065)
		(layer "In4.Cu")
		(net "DRIVE_A_31_ACT")
	)
	(segment
		(start 202.49515 -301.075598)
		(end 202.49515 -287.176972)
		(width 0.12065)
		(layer "In4.Cu")
		(net "DRIVE_A_31_ACT")
	)
	(segment
		(start 215.636602 -144.151096)
		(end 215.636602 -123.721622)
		(width 0.12065)
		(layer "In4.Cu")
		(net "DRIVE_A_31_ACT")
	)
	(segment
		(start 218.492832 -76.761594)
		(end 218.492832 -70.994778)
		(width 0.12065)
		(layer "In4.Cu")
		(net "DRIVE_A_31_ACT")
	)
	(segment
		(start 221.086934 -63.649352)
		(end 221.086934 -56.97855)
		(width 0.12065)
		(layer "In4.Cu")
		(net "DRIVE_A_31_ACT")
	)
	(segment
		(start 221.061534 -63.674752)
		(end 221.086934 -63.649352)
		(width 0.12065)
		(layer "In4.Cu")
		(net "DRIVE_A_31_ACT")
	)
	(segment
		(start 213.462108 -81.792318)
		(end 218.492832 -76.761594)
		(width 0.12065)
		(layer "In4.Cu")
		(net "DRIVE_A_31_ACT")
	)
	(segment
		(start 281.951684 -300.99)
		(end 282.83662 -300.105064)
		(width 0.12065)
		(layer "In4.Cu")
		(net "DRIVE_A_31_ACT")
	)
	(segment
		(start 216.168478 -9.490456)
		(end 224.693226 -0.965708)
		(width 0.12065)
		(layer "In4.Cu")
		(net "DRIVE_A_31_ACT")
	)
	(segment
		(start 267.650722 -298.252134)
		(end 267.757656 -298.1452)
		(width 0.12065)
		(layer "In4.Cu")
		(net "DRIVE_A_31_ACT")
	)
	(segment
		(start 216.168478 -10.927842)
		(end 216.168478 -9.490456)
		(width 0.12065)
		(layer "In4.Cu")
		(net "DRIVE_A_31_ACT")
	)
	(segment
		(start 217.237818 -145.752312)
		(end 215.636602 -144.151096)
		(width 0.12065)
		(layer "In4.Cu")
		(net "DRIVE_A_31_ACT")
	)
	(segment
		(start 224.693226 -0.965708)
		(end 225.152458 -0.965708)
		(width 0.12065)
		(layer "In4.Cu")
		(net "DRIVE_A_31_ACT")
	)
	(segment
		(start 202.49515 -287.176972)
		(end 209.205068 -280.467054)
		(width 0.12065)
		(layer "In4.Cu")
		(net "DRIVE_A_31_ACT")
	)
	(segment
		(start 221.061534 -68.426076)
		(end 221.061534 -63.674752)
		(width 0.12065)
		(layer "In4.Cu")
		(net "DRIVE_A_31_ACT")
	)
	(segment
		(start 213.462108 -121.547128)
		(end 213.462108 -81.792318)
		(width 0.12065)
		(layer "In4.Cu")
		(net "DRIVE_A_31_ACT")
	)
	(segment
		(start 212.949282 -48.840898)
		(end 212.949282 -14.147038)
		(width 0.12065)
		(layer "In4.Cu")
		(net "DRIVE_A_31_ACT")
	)
	(segment
		(start 277.7744 -300.99)
		(end 281.951684 -300.99)
		(width 0.12065)
		(layer "In4.Cu")
		(net "DRIVE_A_31_ACT")
	)
	(segment
		(start 215.636602 -123.721622)
		(end 213.462108 -121.547128)
		(width 0.12065)
		(layer "In4.Cu")
		(net "DRIVE_A_31_ACT")
	)
	(segment
		(start 212.949282 -14.147038)
		(end 216.168478 -10.927842)
		(width 0.12065)
		(layer "In4.Cu")
		(net "DRIVE_A_31_ACT")
	)
	(segment
		(start 274.9296 -298.1452)
		(end 277.7744 -300.99)
		(width 0.12065)
		(layer "In4.Cu")
		(net "DRIVE_A_31_ACT")
	)
	(segment
		(start 218.492832 -70.994778)
		(end 221.061534 -68.426076)
		(width 0.12065)
		(layer "In4.Cu")
		(net "DRIVE_A_31_ACT")
	)
	(segment
		(start 267.757656 -298.1452)
		(end 274.9296 -298.1452)
		(width 0.12065)
		(layer "In4.Cu")
		(net "DRIVE_A_31_ACT")
	)
	(segment
		(start 209.205068 -204.100684)
		(end 217.237818 -196.067934)
		(width 0.12065)
		(layer "In4.Cu")
		(net "DRIVE_A_31_ACT")
	)
	(segment
		(start 247.958102 -238.466884)
		(end 245.885716 -238.466884)
		(width 0.17145)
		(layer "F.Cu")
		(net "DRIVE_A_30_PWR")
	)
	(segment
		(start 335.788 -42.141394)
		(end 336.8802 -42.141394)
		(width 0.17145)
		(layer "F.Cu")
		(net "DRIVE_A_30_PWR")
	)
	(segment
		(start 245.41988 -238.93272)
		(end 245.41988 -239.8014)
		(width 0.17145)
		(layer "F.Cu")
		(net "DRIVE_A_30_PWR")
	)
	(segment
		(start 245.885716 -238.466884)
		(end 245.41988 -238.93272)
		(width 0.17145)
		(layer "F.Cu")
		(net "DRIVE_A_30_PWR")
	)
	(segment
		(start 338.832952 -41.013634)
		(end 337.705192 -42.141394)
		(width 0.17145)
		(layer "F.Cu")
		(net "DRIVE_A_30_PWR")
	)
	(segment
		(start 337.705192 -42.141394)
		(end 336.8802 -42.141394)
		(width 0.17145)
		(layer "F.Cu")
		(net "DRIVE_A_30_PWR")
	)
	(via
		(at 341.90432 -230.379016)
		(size 0.5588)
		(drill 0.3048)
		(layers "F.Cu" "B.Cu")
		(net "DRIVE_A_30_PWR")
	)
	(via
		(at 247.958102 -238.466884)
		(size 0.5588)
		(drill 0.3048)
		(layers "F.Cu" "B.Cu")
		(net "DRIVE_A_30_PWR")
	)
	(via
		(at 338.832952 -41.013634)
		(size 0.5588)
		(drill 0.3048)
		(layers "F.Cu" "B.Cu")
		(net "DRIVE_A_30_PWR")
	)
	(via
		(at 336.8802 -42.141394)
		(size 0.6604)
		(drill 0.3302)
		(layers "F.Cu" "B.Cu")
		(net "DRIVE_A_30_PWR")
	)
	(segment
		(start 260.13664 -237.119668)
		(end 262.897112 -234.359196)
		(width 0.13335)
		(layer "In2.Cu")
		(net "DRIVE_A_30_PWR")
	)
	(segment
		(start 341.903304 -230.378)
		(end 341.90432 -230.379016)
		(width 0.13335)
		(layer "In2.Cu")
		(net "DRIVE_A_30_PWR")
	)
	(segment
		(start 249.957336 -238.466884)
		(end 251.304552 -237.119668)
		(width 0.13335)
		(layer "In2.Cu")
		(net "DRIVE_A_30_PWR")
	)
	(segment
		(start 265.905996 -231.845866)
		(end 269.794736 -231.845866)
		(width 0.13335)
		(layer "In2.Cu")
		(net "DRIVE_A_30_PWR")
	)
	(segment
		(start 263.392666 -234.359196)
		(end 265.905996 -231.845866)
		(width 0.13335)
		(layer "In2.Cu")
		(net "DRIVE_A_30_PWR")
	)
	(segment
		(start 269.794736 -231.845866)
		(end 282.713684 -218.926918)
		(width 0.13335)
		(layer "In2.Cu")
		(net "DRIVE_A_30_PWR")
	)
	(segment
		(start 247.958102 -238.466884)
		(end 249.957336 -238.466884)
		(width 0.13335)
		(layer "In2.Cu")
		(net "DRIVE_A_30_PWR")
	)
	(segment
		(start 262.897112 -234.359196)
		(end 263.392666 -234.359196)
		(width 0.13335)
		(layer "In2.Cu")
		(net "DRIVE_A_30_PWR")
	)
	(segment
		(start 325.37908 -230.378)
		(end 341.903304 -230.378)
		(width 0.13335)
		(layer "In2.Cu")
		(net "DRIVE_A_30_PWR")
	)
	(segment
		(start 251.304552 -237.119668)
		(end 260.13664 -237.119668)
		(width 0.13335)
		(layer "In2.Cu")
		(net "DRIVE_A_30_PWR")
	)
	(segment
		(start 313.927998 -218.926918)
		(end 325.37908 -230.378)
		(width 0.13335)
		(layer "In2.Cu")
		(net "DRIVE_A_30_PWR")
	)
	(segment
		(start 282.713684 -218.926918)
		(end 313.927998 -218.926918)
		(width 0.13335)
		(layer "In2.Cu")
		(net "DRIVE_A_30_PWR")
	)
	(segment
		(start 337.8962 -75.245468)
		(end 339.96884 -77.318108)
		(width 0.12065)
		(layer "In4.Cu")
		(net "DRIVE_A_30_PWR")
	)
	(segment
		(start 338.832952 -41.013634)
		(end 338.832952 -48.287686)
		(width 0.12065)
		(layer "In4.Cu")
		(net "DRIVE_A_30_PWR")
	)
	(segment
		(start 325.237094 -146.989292)
		(end 322.632324 -149.594062)
		(width 0.12065)
		(layer "In4.Cu")
		(net "DRIVE_A_30_PWR")
	)
	(segment
		(start 322.632324 -149.594062)
		(end 322.632324 -171.309284)
		(width 0.12065)
		(layer "In4.Cu")
		(net "DRIVE_A_30_PWR")
	)
	(segment
		(start 323.6468 -178.5112)
		(end 328.7395 -183.6039)
		(width 0.12065)
		(layer "In4.Cu")
		(net "DRIVE_A_30_PWR")
	)
	(segment
		(start 325.237094 -120.212866)
		(end 325.237094 -146.989292)
		(width 0.12065)
		(layer "In4.Cu")
		(net "DRIVE_A_30_PWR")
	)
	(segment
		(start 323.6468 -172.32376)
		(end 323.6468 -178.5112)
		(width 0.12065)
		(layer "In4.Cu")
		(net "DRIVE_A_30_PWR")
	)
	(segment
		(start 322.632324 -171.309284)
		(end 323.6468 -172.32376)
		(width 0.12065)
		(layer "In4.Cu")
		(net "DRIVE_A_30_PWR")
	)
	(segment
		(start 337.8962 -49.224438)
		(end 337.8962 -75.245468)
		(width 0.12065)
		(layer "In4.Cu")
		(net "DRIVE_A_30_PWR")
	)
	(segment
		(start 339.96884 -77.318108)
		(end 339.96884 -105.48112)
		(width 0.12065)
		(layer "In4.Cu")
		(net "DRIVE_A_30_PWR")
	)
	(segment
		(start 328.7395 -183.6039)
		(end 328.7395 -193.79438)
		(width 0.12065)
		(layer "In4.Cu")
		(net "DRIVE_A_30_PWR")
	)
	(segment
		(start 338.832952 -48.287686)
		(end 337.8962 -49.224438)
		(width 0.12065)
		(layer "In4.Cu")
		(net "DRIVE_A_30_PWR")
	)
	(segment
		(start 339.96884 -105.48112)
		(end 325.237094 -120.212866)
		(width 0.12065)
		(layer "In4.Cu")
		(net "DRIVE_A_30_PWR")
	)
	(segment
		(start 328.7395 -193.79438)
		(end 341.90432 -206.9592)
		(width 0.12065)
		(layer "In4.Cu")
		(net "DRIVE_A_30_PWR")
	)
	(segment
		(start 341.90432 -206.9592)
		(end 341.90432 -230.379016)
		(width 0.12065)
		(layer "In4.Cu")
		(net "DRIVE_A_30_PWR")
	)
	(segment
		(start 317.627 -65.064894)
		(end 317.627 -66.7004)
		(width 0.17145)
		(layer "F.Cu")
		(net "DRIVE_A_30_INS")
	)
	(segment
		(start 243.5352 -255.547368)
		(end 244.14988 -256.162048)
		(width 0.17145)
		(layer "F.Cu")
		(net "DRIVE_A_30_INS")
	)
	(segment
		(start 242.9764 -254.4318)
		(end 243.5352 -254.9906)
		(width 0.17145)
		(layer "F.Cu")
		(net "DRIVE_A_30_INS")
	)
	(segment
		(start 243.5352 -254.9906)
		(end 243.5352 -255.547368)
		(width 0.17145)
		(layer "F.Cu")
		(net "DRIVE_A_30_INS")
	)
	(segment
		(start 317.627 -66.7004)
		(end 317.627 -67.7164)
		(width 0.17145)
		(layer "F.Cu")
		(net "DRIVE_A_30_INS")
	)
	(segment
		(start 244.14988 -256.162048)
		(end 244.14988 -257.7084)
		(width 0.17145)
		(layer "F.Cu")
		(net "DRIVE_A_30_INS")
	)
	(via
		(at 317.627 -66.7004)
		(size 0.6604)
		(drill 0.3302)
		(layers "F.Cu" "B.Cu")
		(net "DRIVE_A_30_INS")
	)
	(via
		(at 317.627 -67.7164)
		(size 0.5588)
		(drill 0.3048)
		(layers "F.Cu" "B.Cu")
		(net "DRIVE_A_30_INS")
	)
	(via
		(at 242.9764 -254.4318)
		(size 0.5588)
		(drill 0.3048)
		(layers "F.Cu" "B.Cu")
		(net "DRIVE_A_30_INS")
	)
	(via
		(at 315.7728 -237.1598)
		(size 0.5588)
		(drill 0.3048)
		(layers "F.Cu" "B.Cu")
		(net "DRIVE_A_30_INS")
	)
	(segment
		(start 242.9764 -254.4318)
		(end 243.586 -255.0414)
		(width 0.13335)
		(layer "In2.Cu")
		(net "DRIVE_A_30_INS")
	)
	(segment
		(start 255.463802 -251.037598)
		(end 260.187948 -251.037598)
		(width 0.13335)
		(layer "In2.Cu")
		(net "DRIVE_A_30_INS")
	)
	(segment
		(start 269.517622 -249.081798)
		(end 275.011388 -243.588032)
		(width 0.13335)
		(layer "In2.Cu")
		(net "DRIVE_A_30_INS")
	)
	(segment
		(start 275.011388 -243.588032)
		(end 282.99156 -243.588032)
		(width 0.13335)
		(layer "In2.Cu")
		(net "DRIVE_A_30_INS")
	)
	(segment
		(start 309.960518 -231.347518)
		(end 315.7728 -237.1598)
		(width 0.13335)
		(layer "In2.Cu")
		(net "DRIVE_A_30_INS")
	)
	(segment
		(start 243.586 -255.598168)
		(end 243.918232 -255.9304)
		(width 0.13335)
		(layer "In2.Cu")
		(net "DRIVE_A_30_INS")
	)
	(segment
		(start 251.714 -255.218184)
		(end 251.714 -254.7874)
		(width 0.13335)
		(layer "In2.Cu")
		(net "DRIVE_A_30_INS")
	)
	(segment
		(start 243.586 -255.0414)
		(end 243.586 -255.598168)
		(width 0.13335)
		(layer "In2.Cu")
		(net "DRIVE_A_30_INS")
	)
	(segment
		(start 282.99156 -243.588032)
		(end 295.232074 -231.347518)
		(width 0.13335)
		(layer "In2.Cu")
		(net "DRIVE_A_30_INS")
	)
	(segment
		(start 262.143748 -249.081798)
		(end 269.517622 -249.081798)
		(width 0.13335)
		(layer "In2.Cu")
		(net "DRIVE_A_30_INS")
	)
	(segment
		(start 251.001784 -255.9304)
		(end 251.714 -255.218184)
		(width 0.13335)
		(layer "In2.Cu")
		(net "DRIVE_A_30_INS")
	)
	(segment
		(start 260.187948 -251.037598)
		(end 262.143748 -249.081798)
		(width 0.13335)
		(layer "In2.Cu")
		(net "DRIVE_A_30_INS")
	)
	(segment
		(start 251.714 -254.7874)
		(end 255.463802 -251.037598)
		(width 0.13335)
		(layer "In2.Cu")
		(net "DRIVE_A_30_INS")
	)
	(segment
		(start 243.918232 -255.9304)
		(end 251.001784 -255.9304)
		(width 0.13335)
		(layer "In2.Cu")
		(net "DRIVE_A_30_INS")
	)
	(segment
		(start 295.232074 -231.347518)
		(end 309.960518 -231.347518)
		(width 0.13335)
		(layer "In2.Cu")
		(net "DRIVE_A_30_INS")
	)
	(segment
		(start 318.963294 -145.670016)
		(end 318.963294 -69.052694)
		(width 0.12065)
		(layer "In4.Cu")
		(net "DRIVE_A_30_INS")
	)
	(segment
		(start 316.989206 -170.433746)
		(end 316.989206 -147.644104)
		(width 0.12065)
		(layer "In4.Cu")
		(net "DRIVE_A_30_INS")
	)
	(segment
		(start 315.7728 -237.1598)
		(end 314.818522 -236.205522)
		(width 0.12065)
		(layer "In4.Cu")
		(net "DRIVE_A_30_INS")
	)
	(segment
		(start 318.963294 -69.052694)
		(end 317.627 -67.7164)
		(width 0.12065)
		(layer "In4.Cu")
		(net "DRIVE_A_30_INS")
	)
	(segment
		(start 314.818522 -236.205522)
		(end 314.818522 -172.60443)
		(width 0.12065)
		(layer "In4.Cu")
		(net "DRIVE_A_30_INS")
	)
	(segment
		(start 316.989206 -147.644104)
		(end 318.963294 -145.670016)
		(width 0.12065)
		(layer "In4.Cu")
		(net "DRIVE_A_30_INS")
	)
	(segment
		(start 314.818522 -172.60443)
		(end 316.989206 -170.433746)
		(width 0.12065)
		(layer "In4.Cu")
		(net "DRIVE_A_30_INS")
	)
	(segment
		(start 292.83152 -278.808688)
		(end 291.845238 -278.808688)
		(width 0.17145)
		(layer "F.Cu")
		(net "DRIVE_A_30_FLT_LED")
	)
	(segment
		(start 289.42284 -277.10384)
		(end 289.42284 -275.5646)
		(width 0.17145)
		(layer "F.Cu")
		(net "DRIVE_A_30_FLT_LED")
	)
	(segment
		(start 291.127688 -278.808688)
		(end 289.42284 -277.10384)
		(width 0.17145)
		(layer "F.Cu")
		(net "DRIVE_A_30_FLT_LED")
	)
	(segment
		(start 219.80017 -0.537972)
		(end 220.23832 -0.099822)
		(width 0.17145)
		(layer "F.Cu")
		(net "DRIVE_A_30_FLT_LED")
	)
	(segment
		(start 291.845238 -278.808688)
		(end 291.127688 -278.808688)
		(width 0.17145)
		(layer "F.Cu")
		(net "DRIVE_A_30_FLT_LED")
	)
	(segment
		(start 219.80017 -1.450086)
		(end 219.80017 -0.537972)
		(width 0.17145)
		(layer "F.Cu")
		(net "DRIVE_A_30_FLT_LED")
	)
	(via
		(at 291.845238 -278.808688)
		(size 0.6604)
		(drill 0.3302)
		(layers "F.Cu" "B.Cu")
		(net "DRIVE_A_30_FLT_LED")
	)
	(via
		(at 220.23832 -0.099822)
		(size 0.5588)
		(drill 0.3048)
		(layers "F.Cu" "B.Cu")
		(net "DRIVE_A_30_FLT_LED")
	)
	(via
		(at 292.83152 -278.808688)
		(size 0.5588)
		(drill 0.3048)
		(layers "F.Cu" "B.Cu")
		(net "DRIVE_A_30_FLT_LED")
	)
	(segment
		(start 296.101262 25.901396)
		(end 289.608514 32.394144)
		(width 0.12065)
		(layer "In4.Cu")
		(net "DRIVE_A_30_FLT_LED")
	)
	(segment
		(start 223.186752 19.840956)
		(end 223.186752 2.84861)
		(width 0.12065)
		(layer "In4.Cu")
		(net "DRIVE_A_30_FLT_LED")
	)
	(segment
		(start 295.04132 -114.040412)
		(end 295.04132 -60.145676)
		(width 0.12065)
		(layer "In4.Cu")
		(net "DRIVE_A_30_FLT_LED")
	)
	(segment
		(start 296.101262 -30.18663)
		(end 296.101262 25.901396)
		(width 0.12065)
		(layer "In4.Cu")
		(net "DRIVE_A_30_FLT_LED")
	)
	(segment
		(start 295.04132 -60.145676)
		(end 296.062146 -59.12485)
		(width 0.12065)
		(layer "In4.Cu")
		(net "DRIVE_A_30_FLT_LED")
	)
	(segment
		(start 229.28961 25.930606)
		(end 229.276402 25.930606)
		(width 0.12065)
		(layer "In4.Cu")
		(net "DRIVE_A_30_FLT_LED")
	)
	(segment
		(start 229.276402 25.930606)
		(end 223.186752 19.840956)
		(width 0.12065)
		(layer "In4.Cu")
		(net "DRIVE_A_30_FLT_LED")
	)
	(segment
		(start 298.040806 -273.599402)
		(end 298.040806 -272.360898)
		(width 0.12065)
		(layer "In4.Cu")
		(net "DRIVE_A_30_FLT_LED")
	)
	(segment
		(start 223.186752 2.84861)
		(end 220.23832 -0.099822)
		(width 0.12065)
		(layer "In4.Cu")
		(net "DRIVE_A_30_FLT_LED")
	)
	(segment
		(start 296.062146 -59.12485)
		(end 296.062146 -30.18663)
		(width 0.12065)
		(layer "In4.Cu")
		(net "DRIVE_A_30_FLT_LED")
	)
	(segment
		(start 310.6293 -259.772404)
		(end 310.6293 -129.628392)
		(width 0.12065)
		(layer "In4.Cu")
		(net "DRIVE_A_30_FLT_LED")
	)
	(segment
		(start 235.753148 32.394144)
		(end 229.28961 25.930606)
		(width 0.12065)
		(layer "In4.Cu")
		(net "DRIVE_A_30_FLT_LED")
	)
	(segment
		(start 289.608514 32.394144)
		(end 235.753148 32.394144)
		(width 0.12065)
		(layer "In4.Cu")
		(net "DRIVE_A_30_FLT_LED")
	)
	(segment
		(start 296.062146 -30.18663)
		(end 296.101262 -30.18663)
		(width 0.12065)
		(layer "In4.Cu")
		(net "DRIVE_A_30_FLT_LED")
	)
	(segment
		(start 298.040806 -272.360898)
		(end 310.6293 -259.772404)
		(width 0.12065)
		(layer "In4.Cu")
		(net "DRIVE_A_30_FLT_LED")
	)
	(segment
		(start 310.6293 -129.628392)
		(end 295.04132 -114.040412)
		(width 0.12065)
		(layer "In4.Cu")
		(net "DRIVE_A_30_FLT_LED")
	)
	(segment
		(start 292.83152 -278.808688)
		(end 298.040806 -273.599402)
		(width 0.12065)
		(layer "In4.Cu")
		(net "DRIVE_A_30_FLT_LED")
	)
	(segment
		(start 224.613724 0.494538)
		(end 221.770956 0.494538)
		(width 0.17145)
		(layer "F.Cu")
		(net "DRIVE_A_30_ACT")
	)
	(segment
		(start 221.770956 0.494538)
		(end 220.800168 -0.47625)
		(width 0.17145)
		(layer "F.Cu")
		(net "DRIVE_A_30_ACT")
	)
	(segment
		(start 225.125788 -0.017526)
		(end 224.613724 0.494538)
		(width 0.17145)
		(layer "F.Cu")
		(net "DRIVE_A_30_ACT")
	)
	(segment
		(start 220.800168 -0.47625)
		(end 220.800168 -1.450086)
		(width 0.17145)
		(layer "F.Cu")
		(net "DRIVE_A_30_ACT")
	)
	(via
		(at 225.125788 -0.017526)
		(size 0.5588)
		(drill 0.3048)
		(layers "F.Cu" "B.Cu")
		(net "DRIVE_A_30_ACT")
	)
	(via
		(at 202.482958 -302.142398)
		(size 0.6604)
		(drill 0.3048)
		(layers "F.Cu" "B.Cu")
		(net "DRIVE_A_30_ACT")
	)
	(segment
		(start 261.445248 -305.7906)
		(end 268.404848 -298.831)
		(width 0.13335)
		(layer "In2.Cu")
		(net "DRIVE_A_30_ACT")
	)
	(segment
		(start 268.404848 -298.831)
		(end 274.574 -298.831)
		(width 0.13335)
		(layer "In2.Cu")
		(net "DRIVE_A_30_ACT")
	)
	(segment
		(start 283.326332 -301.0154)
		(end 284.236668 -300.105064)
		(width 0.13335)
		(layer "In2.Cu")
		(net "DRIVE_A_30_ACT")
	)
	(segment
		(start 207.034892 -302.142398)
		(end 210.683094 -305.7906)
		(width 0.13335)
		(layer "In2.Cu")
		(net "DRIVE_A_30_ACT")
	)
	(segment
		(start 210.683094 -305.7906)
		(end 261.445248 -305.7906)
		(width 0.13335)
		(layer "In2.Cu")
		(net "DRIVE_A_30_ACT")
	)
	(segment
		(start 274.574 -298.831)
		(end 276.7584 -301.0154)
		(width 0.13335)
		(layer "In2.Cu")
		(net "DRIVE_A_30_ACT")
	)
	(segment
		(start 276.7584 -301.0154)
		(end 283.326332 -301.0154)
		(width 0.13335)
		(layer "In2.Cu")
		(net "DRIVE_A_30_ACT")
	)
	(segment
		(start 202.482958 -302.142398)
		(end 207.034892 -302.142398)
		(width 0.13335)
		(layer "In2.Cu")
		(net "DRIVE_A_30_ACT")
	)
	(segment
		(start 217.972132 -76.190094)
		(end 217.972132 -70.660768)
		(width 0.12065)
		(layer "In4.Cu")
		(net "DRIVE_A_30_ACT")
	)
	(segment
		(start 224.76841 -0.017526)
		(end 225.125788 -0.017526)
		(width 0.12065)
		(layer "In4.Cu")
		(net "DRIVE_A_30_ACT")
	)
	(segment
		(start 215.223852 -124.059188)
		(end 213.028022 -121.863358)
		(width 0.12065)
		(layer "In4.Cu")
		(net "DRIVE_A_30_ACT")
	)
	(segment
		(start 216.679018 -145.98396)
		(end 215.223852 -144.528794)
		(width 0.12065)
		(layer "In4.Cu")
		(net "DRIVE_A_30_ACT")
	)
	(segment
		(start 215.755728 -10.68959)
		(end 215.755728 -9.030208)
		(width 0.12065)
		(layer "In4.Cu")
		(net "DRIVE_A_30_ACT")
	)
	(segment
		(start 216.679018 -195.836286)
		(end 216.679018 -145.98396)
		(width 0.12065)
		(layer "In4.Cu")
		(net "DRIVE_A_30_ACT")
	)
	(segment
		(start 202.482958 -302.142398)
		(end 201.809096 -301.468536)
		(width 0.12065)
		(layer "In4.Cu")
		(net "DRIVE_A_30_ACT")
	)
	(segment
		(start 212.50529 -48.980852)
		(end 212.50529 -13.940028)
		(width 0.12065)
		(layer "In4.Cu")
		(net "DRIVE_A_30_ACT")
	)
	(segment
		(start 201.809096 -287.072578)
		(end 208.646268 -280.235406)
		(width 0.12065)
		(layer "In4.Cu")
		(net "DRIVE_A_30_ACT")
	)
	(segment
		(start 215.223852 -144.528794)
		(end 215.223852 -124.059188)
		(width 0.12065)
		(layer "In4.Cu")
		(net "DRIVE_A_30_ACT")
	)
	(segment
		(start 213.028022 -121.863358)
		(end 213.028022 -81.134204)
		(width 0.12065)
		(layer "In4.Cu")
		(net "DRIVE_A_30_ACT")
	)
	(segment
		(start 201.809096 -301.468536)
		(end 201.809096 -287.072578)
		(width 0.12065)
		(layer "In4.Cu")
		(net "DRIVE_A_30_ACT")
	)
	(segment
		(start 220.674184 -57.149746)
		(end 212.50529 -48.980852)
		(width 0.12065)
		(layer "In4.Cu")
		(net "DRIVE_A_30_ACT")
	)
	(segment
		(start 220.648784 -63.503556)
		(end 220.674184 -63.478156)
		(width 0.12065)
		(layer "In4.Cu")
		(net "DRIVE_A_30_ACT")
	)
	(segment
		(start 208.646268 -280.235406)
		(end 208.646268 -203.869036)
		(width 0.12065)
		(layer "In4.Cu")
		(net "DRIVE_A_30_ACT")
	)
	(segment
		(start 212.50529 -13.940028)
		(end 215.755728 -10.68959)
		(width 0.12065)
		(layer "In4.Cu")
		(net "DRIVE_A_30_ACT")
	)
	(segment
		(start 217.972132 -70.660768)
		(end 220.648784 -67.984116)
		(width 0.12065)
		(layer "In4.Cu")
		(net "DRIVE_A_30_ACT")
	)
	(segment
		(start 220.674184 -63.478156)
		(end 220.674184 -57.149746)
		(width 0.12065)
		(layer "In4.Cu")
		(net "DRIVE_A_30_ACT")
	)
	(segment
		(start 208.646268 -203.869036)
		(end 216.679018 -195.836286)
		(width 0.12065)
		(layer "In4.Cu")
		(net "DRIVE_A_30_ACT")
	)
	(segment
		(start 215.755728 -9.030208)
		(end 224.76841 -0.017526)
		(width 0.12065)
		(layer "In4.Cu")
		(net "DRIVE_A_30_ACT")
	)
	(segment
		(start 213.028022 -81.134204)
		(end 217.972132 -76.190094)
		(width 0.12065)
		(layer "In4.Cu")
		(net "DRIVE_A_30_ACT")
	)
	(segment
		(start 220.648784 -67.984116)
		(end 220.648784 -63.503556)
		(width 0.12065)
		(layer "In4.Cu")
		(net "DRIVE_A_30_ACT")
	)
	(segment
		(start 229.998524 -245.315232)
		(end 229.998524 -243.43741)
		(width 0.17145)
		(layer "F.Cu")
		(net "DRIVE_A_3_PWR")
	)
	(segment
		(start 229.998524 -243.43741)
		(end 229.998524 -241.987324)
		(width 0.17145)
		(layer "F.Cu")
		(net "DRIVE_A_3_PWR")
	)
	(segment
		(start 112.388142 -272.281904)
		(end 112.388142 -271.456404)
		(width 0.17145)
		(layer "F.Cu")
		(net "DRIVE_A_3_PWR")
	)
	(segment
		(start 229.998524 -241.987324)
		(end 230.94188 -241.043968)
		(width 0.17145)
		(layer "F.Cu")
		(net "DRIVE_A_3_PWR")
	)
	(segment
		(start 230.94188 -241.043968)
		(end 230.94188 -239.8014)
		(width 0.17145)
		(layer "F.Cu")
		(net "DRIVE_A_3_PWR")
	)
	(segment
		(start 228.560884 -246.752872)
		(end 229.998524 -245.315232)
		(width 0.17145)
		(layer "F.Cu")
		(net "DRIVE_A_3_PWR")
	)
	(via
		(at 112.4204 -253.5682)
		(size 0.5588)
		(drill 0.3048)
		(layers "F.Cu" "B.Cu")
		(net "DRIVE_A_3_PWR")
	)
	(via
		(at 228.560884 -246.752872)
		(size 0.5588)
		(drill 0.3048)
		(layers "F.Cu" "B.Cu")
		(net "DRIVE_A_3_PWR")
	)
	(via
		(at 229.998524 -243.43741)
		(size 0.6604)
		(drill 0.3302)
		(layers "F.Cu" "B.Cu")
		(net "DRIVE_A_3_PWR")
	)
	(via
		(at 112.388142 -271.456404)
		(size 0.5588)
		(drill 0.3048)
		(layers "F.Cu" "B.Cu")
		(net "DRIVE_A_3_PWR")
	)
	(segment
		(start 171.857162 -253.415546)
		(end 171.451016 -253.0094)
		(width 0.13335)
		(layer "In2.Cu")
		(net "DRIVE_A_3_PWR")
	)
	(segment
		(start 113.03 -254.1778)
		(end 112.4204 -253.5682)
		(width 0.13335)
		(layer "In2.Cu")
		(net "DRIVE_A_3_PWR")
	)
	(segment
		(start 142.6718 -253.0094)
		(end 141.5034 -254.1778)
		(width 0.13335)
		(layer "In2.Cu")
		(net "DRIVE_A_3_PWR")
	)
	(segment
		(start 228.560884 -246.752872)
		(end 227.179632 -246.752872)
		(width 0.13335)
		(layer "In2.Cu")
		(net "DRIVE_A_3_PWR")
	)
	(segment
		(start 141.5034 -254.1778)
		(end 113.03 -254.1778)
		(width 0.13335)
		(layer "In2.Cu")
		(net "DRIVE_A_3_PWR")
	)
	(segment
		(start 220.516958 -253.415546)
		(end 171.857162 -253.415546)
		(width 0.13335)
		(layer "In2.Cu")
		(net "DRIVE_A_3_PWR")
	)
	(segment
		(start 227.179632 -246.752872)
		(end 220.516958 -253.415546)
		(width 0.13335)
		(layer "In2.Cu")
		(net "DRIVE_A_3_PWR")
	)
	(segment
		(start 171.451016 -253.0094)
		(end 142.6718 -253.0094)
		(width 0.13335)
		(layer "In2.Cu")
		(net "DRIVE_A_3_PWR")
	)
	(segment
		(start 112.388142 -253.600458)
		(end 112.4204 -253.5682)
		(width 0.12065)
		(layer "In4.Cu")
		(net "DRIVE_A_3_PWR")
	)
	(segment
		(start 112.388142 -271.456404)
		(end 112.388142 -253.600458)
		(width 0.12065)
		(layer "In4.Cu")
		(net "DRIVE_A_3_PWR")
	)
	(segment
		(start 128.491996 -288.232342)
		(end 128.491996 -287.241742)
		(width 0.17145)
		(layer "F.Cu")
		(net "DRIVE_A_3_INS")
	)
	(segment
		(start 232.1814 -266.453366)
		(end 230.17861 -264.450576)
		(width 0.17145)
		(layer "F.Cu")
		(net "DRIVE_A_3_INS")
	)
	(segment
		(start 231.57688 -258.79552)
		(end 231.57688 -257.4544)
		(width 0.17145)
		(layer "F.Cu")
		(net "DRIVE_A_3_INS")
	)
	(segment
		(start 230.17861 -260.19379)
		(end 231.57688 -258.79552)
		(width 0.17145)
		(layer "F.Cu")
		(net "DRIVE_A_3_INS")
	)
	(segment
		(start 230.17861 -264.450576)
		(end 230.17861 -260.19379)
		(width 0.17145)
		(layer "F.Cu")
		(net "DRIVE_A_3_INS")
	)
	(segment
		(start 230.753158 -269.703042)
		(end 232.1814 -268.2748)
		(width 0.17145)
		(layer "F.Cu")
		(net "DRIVE_A_3_INS")
	)
	(segment
		(start 232.1814 -268.2748)
		(end 232.1814 -266.453366)
		(width 0.17145)
		(layer "F.Cu")
		(net "DRIVE_A_3_INS")
	)
	(via
		(at 232.1814 -268.2748)
		(size 0.6604)
		(drill 0.3302)
		(layers "F.Cu" "B.Cu")
		(net "DRIVE_A_3_INS")
	)
	(via
		(at 230.753158 -269.703042)
		(size 0.5588)
		(drill 0.3048)
		(layers "F.Cu" "B.Cu")
		(net "DRIVE_A_3_INS")
	)
	(via
		(at 128.491996 -288.232342)
		(size 0.5588)
		(drill 0.3048)
		(layers "F.Cu" "B.Cu")
		(net "DRIVE_A_3_INS")
	)
	(via
		(at 128.651 -267.1826)
		(size 0.5588)
		(drill 0.3048)
		(layers "F.Cu" "B.Cu")
		(net "DRIVE_A_3_INS")
	)
	(segment
		(start 189.813438 -269.703042)
		(end 187.06592 -266.955524)
		(width 0.13335)
		(layer "In2.Cu")
		(net "DRIVE_A_3_INS")
	)
	(segment
		(start 187.06592 -266.955524)
		(end 182.732172 -266.955524)
		(width 0.13335)
		(layer "In2.Cu")
		(net "DRIVE_A_3_INS")
	)
	(segment
		(start 158.048452 -266.955524)
		(end 152.625298 -266.955524)
		(width 0.13335)
		(layer "In2.Cu")
		(net "DRIVE_A_3_INS")
	)
	(segment
		(start 172.936154 -276.751542)
		(end 167.84447 -276.751542)
		(width 0.13335)
		(layer "In2.Cu")
		(net "DRIVE_A_3_INS")
	)
	(segment
		(start 152.398222 -267.1826)
		(end 128.651 -267.1826)
		(width 0.13335)
		(layer "In2.Cu")
		(net "DRIVE_A_3_INS")
	)
	(segment
		(start 167.84447 -276.751542)
		(end 158.048452 -266.955524)
		(width 0.13335)
		(layer "In2.Cu")
		(net "DRIVE_A_3_INS")
	)
	(segment
		(start 152.625298 -266.955524)
		(end 152.398222 -267.1826)
		(width 0.13335)
		(layer "In2.Cu")
		(net "DRIVE_A_3_INS")
	)
	(segment
		(start 182.732172 -266.955524)
		(end 172.936154 -276.751542)
		(width 0.13335)
		(layer "In2.Cu")
		(net "DRIVE_A_3_INS")
	)
	(segment
		(start 230.753158 -269.703042)
		(end 189.813438 -269.703042)
		(width 0.13335)
		(layer "In2.Cu")
		(net "DRIVE_A_3_INS")
	)
	(segment
		(start 127.5842 -280.6446)
		(end 127.5842 -287.324546)
		(width 0.12065)
		(layer "In4.Cu")
		(net "DRIVE_A_3_INS")
	)
	(segment
		(start 127.5842 -287.324546)
		(end 128.491996 -288.232342)
		(width 0.12065)
		(layer "In4.Cu")
		(net "DRIVE_A_3_INS")
	)
	(segment
		(start 128.651 -279.5778)
		(end 127.5842 -280.6446)
		(width 0.12065)
		(layer "In4.Cu")
		(net "DRIVE_A_3_INS")
	)
	(segment
		(start 128.651 -267.1826)
		(end 128.651 -279.5778)
		(width 0.12065)
		(layer "In4.Cu")
		(net "DRIVE_A_3_INS")
	)
	(segment
		(start 264.48512 -275.3106)
		(end 264.48512 -277.2918)
		(width 0.17145)
		(layer "F.Cu")
		(net "DRIVE_A_3_FLT_LED")
	)
	(segment
		(start 98.754184 -187.870084)
		(end 98.752152 -187.872116)
		(width 0.17145)
		(layer "F.Cu")
		(net "DRIVE_A_3_FLT_LED")
	)
	(segment
		(start 100.162868 -187.870084)
		(end 98.754184 -187.870084)
		(width 0.17145)
		(layer "F.Cu")
		(net "DRIVE_A_3_FLT_LED")
	)
	(segment
		(start 100.172266 -187.879482)
		(end 100.162868 -187.870084)
		(width 0.17145)
		(layer "F.Cu")
		(net "DRIVE_A_3_FLT_LED")
	)
	(segment
		(start 98.752152 -187.872116)
		(end 98.752152 -189.218062)
		(width 0.17145)
		(layer "F.Cu")
		(net "DRIVE_A_3_FLT_LED")
	)
	(segment
		(start 98.752152 -189.218062)
		(end 98.752152 -190.367666)
		(width 0.17145)
		(layer "F.Cu")
		(net "DRIVE_A_3_FLT_LED")
	)
	(via
		(at 98.752152 -189.218062)
		(size 0.6604)
		(drill 0.3302)
		(layers "F.Cu" "B.Cu")
		(net "DRIVE_A_3_FLT_LED")
	)
	(via
		(at 98.752152 -190.367666)
		(size 0.5588)
		(drill 0.3048)
		(layers "F.Cu" "B.Cu")
		(net "DRIVE_A_3_FLT_LED")
	)
	(via
		(at 98.777552 -284.015942)
		(size 0.5588)
		(drill 0.3048)
		(layers "F.Cu" "B.Cu")
		(net "DRIVE_A_3_FLT_LED")
	)
	(via
		(at 264.48512 -277.2918)
		(size 0.5588)
		(drill 0.3048)
		(layers "F.Cu" "B.Cu")
		(net "DRIVE_A_3_FLT_LED")
	)
	(segment
		(start 263.7028 -278.529288)
		(end 263.162288 -279.0698)
		(width 0.13335)
		(layer "In2.Cu")
		(net "DRIVE_A_3_FLT_LED")
	)
	(segment
		(start 116.158264 -284.015942)
		(end 98.777552 -284.015942)
		(width 0.13335)
		(layer "In2.Cu")
		(net "DRIVE_A_3_FLT_LED")
	)
	(segment
		(start 263.162288 -279.0698)
		(end 256.76733 -279.0698)
		(width 0.13335)
		(layer "In2.Cu")
		(net "DRIVE_A_3_FLT_LED")
	)
	(segment
		(start 173.427898 -286.92475)
		(end 119.067072 -286.92475)
		(width 0.13335)
		(layer "In2.Cu")
		(net "DRIVE_A_3_FLT_LED")
	)
	(segment
		(start 176.963832 -283.388816)
		(end 173.427898 -286.92475)
		(width 0.13335)
		(layer "In2.Cu")
		(net "DRIVE_A_3_FLT_LED")
	)
	(segment
		(start 247.667272 -288.169858)
		(end 207.518762 -288.169858)
		(width 0.13335)
		(layer "In2.Cu")
		(net "DRIVE_A_3_FLT_LED")
	)
	(segment
		(start 207.518762 -288.169858)
		(end 202.73772 -283.388816)
		(width 0.13335)
		(layer "In2.Cu")
		(net "DRIVE_A_3_FLT_LED")
	)
	(segment
		(start 119.067072 -286.92475)
		(end 116.158264 -284.015942)
		(width 0.13335)
		(layer "In2.Cu")
		(net "DRIVE_A_3_FLT_LED")
	)
	(segment
		(start 263.7028 -278.07412)
		(end 263.7028 -278.529288)
		(width 0.13335)
		(layer "In2.Cu")
		(net "DRIVE_A_3_FLT_LED")
	)
	(segment
		(start 256.76733 -279.0698)
		(end 247.667272 -288.169858)
		(width 0.13335)
		(layer "In2.Cu")
		(net "DRIVE_A_3_FLT_LED")
	)
	(segment
		(start 264.48512 -277.2918)
		(end 263.7028 -278.07412)
		(width 0.13335)
		(layer "In2.Cu")
		(net "DRIVE_A_3_FLT_LED")
	)
	(segment
		(start 202.73772 -283.388816)
		(end 176.963832 -283.388816)
		(width 0.13335)
		(layer "In2.Cu")
		(net "DRIVE_A_3_FLT_LED")
	)
	(segment
		(start 98.752152 -190.367666)
		(end 104.037384 -195.652898)
		(width 0.12065)
		(layer "In4.Cu")
		(net "DRIVE_A_3_FLT_LED")
	)
	(segment
		(start 104.037384 -195.652898)
		(end 104.037384 -227.839016)
		(width 0.12065)
		(layer "In4.Cu")
		(net "DRIVE_A_3_FLT_LED")
	)
	(segment
		(start 104.037384 -227.839016)
		(end 102.1461 -229.7303)
		(width 0.12065)
		(layer "In4.Cu")
		(net "DRIVE_A_3_FLT_LED")
	)
	(segment
		(start 102.1461 -267.649452)
		(end 98.777552 -271.018)
		(width 0.12065)
		(layer "In4.Cu")
		(net "DRIVE_A_3_FLT_LED")
	)
	(segment
		(start 98.777552 -271.018)
		(end 98.777552 -284.015942)
		(width 0.12065)
		(layer "In4.Cu")
		(net "DRIVE_A_3_FLT_LED")
	)
	(segment
		(start 102.1461 -229.7303)
		(end 102.1461 -267.649452)
		(width 0.12065)
		(layer "In4.Cu")
		(net "DRIVE_A_3_FLT_LED")
	)
	(segment
		(start 101.263958 -181.362858)
		(end 101.263958 -180.18379)
		(width 0.17145)
		(layer "F.Cu")
		(net "DRIVE_A_3_ACT")
	)
	(segment
		(start 100.17125 -184.089802)
		(end 100.17125 -183.595264)
		(width 0.17145)
		(layer "F.Cu")
		(net "DRIVE_A_3_ACT")
	)
	(segment
		(start 100.17125 -183.595264)
		(end 101.263958 -182.502556)
		(width 0.17145)
		(layer "F.Cu")
		(net "DRIVE_A_3_ACT")
	)
	(segment
		(start 101.263958 -182.502556)
		(end 101.263958 -181.362858)
		(width 0.17145)
		(layer "F.Cu")
		(net "DRIVE_A_3_ACT")
	)
	(via
		(at 101.263958 -180.18379)
		(size 0.5588)
		(drill 0.3048)
		(layers "F.Cu" "B.Cu")
		(net "DRIVE_A_3_ACT")
	)
	(via
		(at 101.263958 -182.502556)
		(size 0.6604)
		(drill 0.3302)
		(layers "F.Cu" "B.Cu")
		(net "DRIVE_A_3_ACT")
	)
	(via
		(at 273.6342 -323.0118)
		(size 0.5588)
		(drill 0.3048)
		(layers "F.Cu" "B.Cu")
		(net "DRIVE_A_3_ACT")
	)
	(via
		(at 104.7242 -336.8548)
		(size 0.5588)
		(drill 0.3048)
		(layers "F.Cu" "B.Cu")
		(net "DRIVE_A_3_ACT")
	)
	(segment
		(start 190.800228 -323.0118)
		(end 187.472828 -326.3392)
		(width 0.13335)
		(layer "In2.Cu")
		(net "DRIVE_A_3_ACT")
	)
	(segment
		(start 143.765016 -337.508596)
		(end 143.13662 -336.8802)
		(width 0.13335)
		(layer "In2.Cu")
		(net "DRIVE_A_3_ACT")
	)
	(segment
		(start 187.472828 -326.3392)
		(end 174.761652 -326.3392)
		(width 0.13335)
		(layer "In2.Cu")
		(net "DRIVE_A_3_ACT")
	)
	(segment
		(start 174.761652 -326.3392)
		(end 163.592256 -337.508596)
		(width 0.13335)
		(layer "In2.Cu")
		(net "DRIVE_A_3_ACT")
	)
	(segment
		(start 163.592256 -337.508596)
		(end 143.765016 -337.508596)
		(width 0.13335)
		(layer "In2.Cu")
		(net "DRIVE_A_3_ACT")
	)
	(segment
		(start 273.6342 -323.0118)
		(end 190.800228 -323.0118)
		(width 0.13335)
		(layer "In2.Cu")
		(net "DRIVE_A_3_ACT")
	)
	(segment
		(start 143.13662 -336.8802)
		(end 104.7496 -336.8802)
		(width 0.13335)
		(layer "In2.Cu")
		(net "DRIVE_A_3_ACT")
	)
	(segment
		(start 104.7496 -336.8802)
		(end 104.7242 -336.8548)
		(width 0.13335)
		(layer "In2.Cu")
		(net "DRIVE_A_3_ACT")
	)
	(segment
		(start 104.862884 -187.952126)
		(end 101.263958 -184.3532)
		(width 0.12065)
		(layer "In4.Cu")
		(net "DRIVE_A_3_ACT")
	)
	(segment
		(start 99.3394 -285.307024)
		(end 99.3394 -271.6022)
		(width 0.12065)
		(layer "In4.Cu")
		(net "DRIVE_A_3_ACT")
	)
	(segment
		(start 104.862884 -266.078716)
		(end 104.862884 -187.952126)
		(width 0.12065)
		(layer "In4.Cu")
		(net "DRIVE_A_3_ACT")
	)
	(segment
		(start 104.7242 -336.8548)
		(end 104.7242 -319.7098)
		(width 0.12065)
		(layer "In4.Cu")
		(net "DRIVE_A_3_ACT")
	)
	(segment
		(start 274.828 -323.0118)
		(end 276.1996 -324.3834)
		(width 0.12065)
		(layer "In4.Cu")
		(net "DRIVE_A_3_ACT")
	)
	(segment
		(start 101.263958 -184.3532)
		(end 101.263958 -180.18379)
		(width 0.12065)
		(layer "In4.Cu")
		(net "DRIVE_A_3_ACT")
	)
	(segment
		(start 96.40316 -299.607224)
		(end 96.40316 -288.243264)
		(width 0.12065)
		(layer "In4.Cu")
		(net "DRIVE_A_3_ACT")
	)
	(segment
		(start 273.6342 -323.0118)
		(end 274.828 -323.0118)
		(width 0.12065)
		(layer "In4.Cu")
		(net "DRIVE_A_3_ACT")
	)
	(segment
		(start 98.056446 -301.26051)
		(end 96.40316 -299.607224)
		(width 0.12065)
		(layer "In4.Cu")
		(net "DRIVE_A_3_ACT")
	)
	(segment
		(start 98.056446 -313.042046)
		(end 98.056446 -301.26051)
		(width 0.12065)
		(layer "In4.Cu")
		(net "DRIVE_A_3_ACT")
	)
	(segment
		(start 281.914854 -324.3834)
		(end 282.83662 -325.305166)
		(width 0.12065)
		(layer "In4.Cu")
		(net "DRIVE_A_3_ACT")
	)
	(segment
		(start 104.7242 -319.7098)
		(end 98.056446 -313.042046)
		(width 0.12065)
		(layer "In4.Cu")
		(net "DRIVE_A_3_ACT")
	)
	(segment
		(start 96.40316 -288.243264)
		(end 99.3394 -285.307024)
		(width 0.12065)
		(layer "In4.Cu")
		(net "DRIVE_A_3_ACT")
	)
	(segment
		(start 276.1996 -324.3834)
		(end 281.914854 -324.3834)
		(width 0.12065)
		(layer "In4.Cu")
		(net "DRIVE_A_3_ACT")
	)
	(segment
		(start 99.3394 -271.6022)
		(end 104.862884 -266.078716)
		(width 0.12065)
		(layer "In4.Cu")
		(net "DRIVE_A_3_ACT")
	)
	(segment
		(start 246.07012 -241.2492)
		(end 246.07012 -242.8748)
		(width 0.17145)
		(layer "F.Cu")
		(net "DRIVE_A_29_PWR")
	)
	(segment
		(start 246.07012 -239.8014)
		(end 246.07012 -241.2492)
		(width 0.17145)
		(layer "F.Cu")
		(net "DRIVE_A_29_PWR")
	)
	(segment
		(start 181.1909 -44.821094)
		(end 182.165752 -44.821094)
		(width 0.17145)
		(layer "F.Cu")
		(net "DRIVE_A_29_PWR")
	)
	(via
		(at 182.165752 -44.821094)
		(size 0.5588)
		(drill 0.3048)
		(layers "F.Cu" "B.Cu")
		(net "DRIVE_A_29_PWR")
	)
	(via
		(at 246.07012 -241.2492)
		(size 0.6604)
		(drill 0.3302)
		(layers "F.Cu" "B.Cu")
		(net "DRIVE_A_29_PWR")
	)
	(via
		(at 198.3232 -243.6622)
		(size 0.5588)
		(drill 0.3048)
		(layers "F.Cu" "B.Cu")
		(net "DRIVE_A_29_PWR")
	)
	(via
		(at 246.07012 -242.8748)
		(size 0.5588)
		(drill 0.3048)
		(layers "F.Cu" "B.Cu")
		(net "DRIVE_A_29_PWR")
	)
	(segment
		(start 237.944406 -242.600988)
		(end 236.567218 -241.2238)
		(width 0.13335)
		(layer "In2.Cu")
		(net "DRIVE_A_29_PWR")
	)
	(segment
		(start 224.903792 -241.2238)
		(end 222.465392 -243.6622)
		(width 0.13335)
		(layer "In2.Cu")
		(net "DRIVE_A_29_PWR")
	)
	(segment
		(start 246.07012 -242.8748)
		(end 245.796308 -242.600988)
		(width 0.13335)
		(layer "In2.Cu")
		(net "DRIVE_A_29_PWR")
	)
	(segment
		(start 236.567218 -241.2238)
		(end 224.903792 -241.2238)
		(width 0.13335)
		(layer "In2.Cu")
		(net "DRIVE_A_29_PWR")
	)
	(segment
		(start 245.796308 -242.600988)
		(end 237.944406 -242.600988)
		(width 0.13335)
		(layer "In2.Cu")
		(net "DRIVE_A_29_PWR")
	)
	(segment
		(start 222.465392 -243.6622)
		(end 198.3232 -243.6622)
		(width 0.13335)
		(layer "In2.Cu")
		(net "DRIVE_A_29_PWR")
	)
	(segment
		(start 181.4068 -47.903384)
		(end 188.191394 -54.687978)
		(width 0.12065)
		(layer "In4.Cu")
		(net "DRIVE_A_29_PWR")
	)
	(segment
		(start 188.191394 -187.505848)
		(end 188.52515 -187.839604)
		(width 0.12065)
		(layer "In4.Cu")
		(net "DRIVE_A_29_PWR")
	)
	(segment
		(start 188.52515 -192.08115)
		(end 198.3232 -201.8792)
		(width 0.12065)
		(layer "In4.Cu")
		(net "DRIVE_A_29_PWR")
	)
	(segment
		(start 181.4068 -45.580046)
		(end 181.4068 -47.903384)
		(width 0.12065)
		(layer "In4.Cu")
		(net "DRIVE_A_29_PWR")
	)
	(segment
		(start 188.191394 -150.697184)
		(end 188.325252 -150.831042)
		(width 0.12065)
		(layer "In4.Cu")
		(net "DRIVE_A_29_PWR")
	)
	(segment
		(start 198.3232 -201.8792)
		(end 198.3232 -243.6622)
		(width 0.12065)
		(layer "In4.Cu")
		(net "DRIVE_A_29_PWR")
	)
	(segment
		(start 188.52515 -187.839604)
		(end 188.52515 -192.08115)
		(width 0.12065)
		(layer "In4.Cu")
		(net "DRIVE_A_29_PWR")
	)
	(segment
		(start 182.165752 -44.821094)
		(end 181.4068 -45.580046)
		(width 0.12065)
		(layer "In4.Cu")
		(net "DRIVE_A_29_PWR")
	)
	(segment
		(start 188.325252 -151.238966)
		(end 188.191394 -151.372824)
		(width 0.12065)
		(layer "In4.Cu")
		(net "DRIVE_A_29_PWR")
	)
	(segment
		(start 188.191394 -54.687978)
		(end 188.191394 -150.697184)
		(width 0.12065)
		(layer "In4.Cu")
		(net "DRIVE_A_29_PWR")
	)
	(segment
		(start 188.191394 -151.372824)
		(end 188.191394 -187.505848)
		(width 0.12065)
		(layer "In4.Cu")
		(net "DRIVE_A_29_PWR")
	)
	(segment
		(start 188.325252 -150.831042)
		(end 188.325252 -151.238966)
		(width 0.12065)
		(layer "In4.Cu")
		(net "DRIVE_A_29_PWR")
	)
	(segment
		(start 244.80012 -257.7084)
		(end 244.80012 -259.6896)
		(width 0.17145)
		(layer "F.Cu")
		(net "DRIVE_A_29_INS")
	)
	(segment
		(start 191.95034 -42.069512)
		(end 192.689226 -42.808398)
		(width 0.17145)
		(layer "F.Cu")
		(net "DRIVE_A_29_INS")
	)
	(segment
		(start 190.807086 -42.069512)
		(end 191.95034 -42.069512)
		(width 0.17145)
		(layer "F.Cu")
		(net "DRIVE_A_29_INS")
	)
	(via
		(at 244.80012 -259.6896)
		(size 0.5588)
		(drill 0.3048)
		(layers "F.Cu" "B.Cu")
		(net "DRIVE_A_29_INS")
	)
	(via
		(at 199.136 -260.096)
		(size 0.5588)
		(drill 0.3048)
		(layers "F.Cu" "B.Cu")
		(net "DRIVE_A_29_INS")
	)
	(via
		(at 192.689226 -42.808398)
		(size 0.5588)
		(drill 0.3048)
		(layers "F.Cu" "B.Cu")
		(net "DRIVE_A_29_INS")
	)
	(segment
		(start 233.170984 -259.843016)
		(end 232.4862 -260.5278)
		(width 0.13335)
		(layer "In2.Cu")
		(net "DRIVE_A_29_INS")
	)
	(segment
		(start 226.835716 -260.5278)
		(end 226.403916 -260.096)
		(width 0.13335)
		(layer "In2.Cu")
		(net "DRIVE_A_29_INS")
	)
	(segment
		(start 244.80012 -259.6896)
		(end 244.646704 -259.843016)
		(width 0.13335)
		(layer "In2.Cu")
		(net "DRIVE_A_29_INS")
	)
	(segment
		(start 226.403916 -260.096)
		(end 199.136 -260.096)
		(width 0.13335)
		(layer "In2.Cu")
		(net "DRIVE_A_29_INS")
	)
	(segment
		(start 244.646704 -259.843016)
		(end 233.170984 -259.843016)
		(width 0.13335)
		(layer "In2.Cu")
		(net "DRIVE_A_29_INS")
	)
	(segment
		(start 232.4862 -260.5278)
		(end 226.835716 -260.5278)
		(width 0.13335)
		(layer "In2.Cu")
		(net "DRIVE_A_29_INS")
	)
	(segment
		(start 190.3857 -169.7355)
		(end 191.976502 -168.144698)
		(width 0.12065)
		(layer "In4.Cu")
		(net "DRIVE_A_29_INS")
	)
	(segment
		(start 190.3857 -193.1035)
		(end 190.3857 -169.7355)
		(width 0.12065)
		(layer "In4.Cu")
		(net "DRIVE_A_29_INS")
	)
	(segment
		(start 191.976502 -168.144698)
		(end 191.976502 -43.521122)
		(width 0.12065)
		(layer "In4.Cu")
		(net "DRIVE_A_29_INS")
	)
	(segment
		(start 199.136 -201.8538)
		(end 190.3857 -193.1035)
		(width 0.12065)
		(layer "In4.Cu")
		(net "DRIVE_A_29_INS")
	)
	(segment
		(start 199.136 -260.096)
		(end 199.136 -201.8538)
		(width 0.12065)
		(layer "In4.Cu")
		(net "DRIVE_A_29_INS")
	)
	(segment
		(start 191.976502 -43.521122)
		(end 192.689226 -42.808398)
		(width 0.12065)
		(layer "In4.Cu")
		(net "DRIVE_A_29_INS")
	)
	(segment
		(start 207.79994 -1.450086)
		(end 207.79994 0.116332)
		(width 0.17145)
		(layer "F.Cu")
		(net "DRIVE_A_29_FLT_LED")
	)
	(segment
		(start 288.7726 -278.659336)
		(end 288.7726 -275.5646)
		(width 0.17145)
		(layer "F.Cu")
		(net "DRIVE_A_29_FLT_LED")
	)
	(segment
		(start 288.062162 -279.369774)
		(end 288.7726 -278.659336)
		(width 0.17145)
		(layer "F.Cu")
		(net "DRIVE_A_29_FLT_LED")
	)
	(via
		(at 207.79994 0.116332)
		(size 0.5588)
		(drill 0.3048)
		(layers "F.Cu" "B.Cu")
		(net "DRIVE_A_29_FLT_LED")
	)
	(via
		(at 288.062162 -279.369774)
		(size 0.5588)
		(drill 0.3048)
		(layers "F.Cu" "B.Cu")
		(net "DRIVE_A_29_FLT_LED")
	)
	(via
		(at 290.142422 9.530588)
		(size 0.5588)
		(drill 0.3048)
		(layers "F.Cu" "B.Cu")
		(net "DRIVE_A_29_FLT_LED")
	)
	(segment
		(start 293.39032 -115.551204)
		(end 308.3941 -130.554984)
		(width 0.12065)
		(layer "In4.Cu")
		(net "DRIVE_A_29_FLT_LED")
	)
	(segment
		(start 308.3941 -257.5179)
		(end 295.148 -270.764)
		(width 0.12065)
		(layer "In4.Cu")
		(net "DRIVE_A_29_FLT_LED")
	)
	(segment
		(start 308.3941 -130.554984)
		(end 308.3941 -257.5179)
		(width 0.12065)
		(layer "In4.Cu")
		(net "DRIVE_A_29_FLT_LED")
	)
	(segment
		(start 293.39032 -58.634884)
		(end 293.39032 -115.551204)
		(width 0.12065)
		(layer "In4.Cu")
		(net "DRIVE_A_29_FLT_LED")
	)
	(segment
		(start 293.826946 -58.198258)
		(end 293.39032 -58.634884)
		(width 0.12065)
		(layer "In4.Cu")
		(net "DRIVE_A_29_FLT_LED")
	)
	(segment
		(start 290.142422 9.530588)
		(end 290.225734 9.447276)
		(width 0.12065)
		(layer "In4.Cu")
		(net "DRIVE_A_29_FLT_LED")
	)
	(segment
		(start 290.225734 9.447276)
		(end 292.388798 9.447276)
		(width 0.12065)
		(layer "In4.Cu")
		(net "DRIVE_A_29_FLT_LED")
	)
	(segment
		(start 295.148 -270.764)
		(end 295.148 -272.283936)
		(width 0.12065)
		(layer "In4.Cu")
		(net "DRIVE_A_29_FLT_LED")
	)
	(segment
		(start 295.148 -272.283936)
		(end 288.062162 -279.369774)
		(width 0.12065)
		(layer "In4.Cu")
		(net "DRIVE_A_29_FLT_LED")
	)
	(segment
		(start 293.826946 8.009128)
		(end 293.826946 -58.198258)
		(width 0.12065)
		(layer "In4.Cu")
		(net "DRIVE_A_29_FLT_LED")
	)
	(segment
		(start 292.388798 9.447276)
		(end 293.826946 8.009128)
		(width 0.12065)
		(layer "In4.Cu")
		(net "DRIVE_A_29_FLT_LED")
	)
	(segment
		(start 234.134152 -2.652776)
		(end 210.569048 -2.652776)
		(width 0.13335)
		(layer "In9.Cu")
		(net "DRIVE_A_29_FLT_LED")
	)
	(segment
		(start 237.558326 0.771398)
		(end 234.134152 -2.652776)
		(width 0.13335)
		(layer "In9.Cu")
		(net "DRIVE_A_29_FLT_LED")
	)
	(segment
		(start 288.5567 9.530588)
		(end 279.79751 0.771398)
		(width 0.13335)
		(layer "In9.Cu")
		(net "DRIVE_A_29_FLT_LED")
	)
	(segment
		(start 210.569048 -2.652776)
		(end 207.79994 0.116332)
		(width 0.13335)
		(layer "In9.Cu")
		(net "DRIVE_A_29_FLT_LED")
	)
	(segment
		(start 290.142422 9.530588)
		(end 288.5567 9.530588)
		(width 0.13335)
		(layer "In9.Cu")
		(net "DRIVE_A_29_FLT_LED")
	)
	(segment
		(start 279.79751 0.771398)
		(end 237.558326 0.771398)
		(width 0.13335)
		(layer "In9.Cu")
		(net "DRIVE_A_29_FLT_LED")
	)
	(segment
		(start 208.799938 -1.450086)
		(end 208.799938 0.116332)
		(width 0.17145)
		(layer "F.Cu")
		(net "DRIVE_A_29_ACT")
	)
	(via
		(at 273.2024 -299.48886)
		(size 0.5588)
		(drill 0.3048)
		(layers "F.Cu" "B.Cu")
		(net "DRIVE_A_29_ACT")
	)
	(via
		(at 198.00189 -299.839126)
		(size 0.6604)
		(drill 0.3048)
		(layers "F.Cu" "B.Cu")
		(net "DRIVE_A_29_ACT")
	)
	(via
		(at 208.799938 0.116332)
		(size 0.5588)
		(drill 0.3048)
		(layers "F.Cu" "B.Cu")
		(net "DRIVE_A_29_ACT")
	)
	(segment
		(start 198.00189 -299.839126)
		(end 204.512164 -306.3494)
		(width 0.13335)
		(layer "In2.Cu")
		(net "DRIVE_A_29_ACT")
	)
	(segment
		(start 261.867904 -306.3494)
		(end 268.728444 -299.48886)
		(width 0.13335)
		(layer "In2.Cu")
		(net "DRIVE_A_29_ACT")
	)
	(segment
		(start 268.728444 -299.48886)
		(end 273.2024 -299.48886)
		(width 0.13335)
		(layer "In2.Cu")
		(net "DRIVE_A_29_ACT")
	)
	(segment
		(start 204.512164 -306.3494)
		(end 261.867904 -306.3494)
		(width 0.13335)
		(layer "In2.Cu")
		(net "DRIVE_A_29_ACT")
	)
	(segment
		(start 204.734668 -202.2475)
		(end 204.734668 -278.267668)
		(width 0.12065)
		(layer "In4.Cu")
		(net "DRIVE_A_29_ACT")
	)
	(segment
		(start 281.836622 -301.905162)
		(end 280.973784 -302.768)
		(width 0.12065)
		(layer "In4.Cu")
		(net "DRIVE_A_29_ACT")
	)
	(segment
		(start 212.767418 -194.21475)
		(end 204.734668 -202.2475)
		(width 0.12065)
		(layer "In4.Cu")
		(net "DRIVE_A_29_ACT")
	)
	(segment
		(start 208.8261 0.09017)
		(end 208.8261 -54.317392)
		(width 0.12065)
		(layer "In4.Cu")
		(net "DRIVE_A_29_ACT")
	)
	(segment
		(start 208.8261 -54.317392)
		(end 213.755732 -59.247024)
		(width 0.12065)
		(layer "In4.Cu")
		(net "DRIVE_A_29_ACT")
	)
	(segment
		(start 209.846672 -76.559918)
		(end 209.846672 -144.903444)
		(width 0.12065)
		(layer "In4.Cu")
		(net "DRIVE_A_29_ACT")
	)
	(segment
		(start 198.00189 -285.000446)
		(end 198.00189 -299.839126)
		(width 0.12065)
		(layer "In4.Cu")
		(net "DRIVE_A_29_ACT")
	)
	(segment
		(start 209.846672 -144.903444)
		(end 212.767418 -147.82419)
		(width 0.12065)
		(layer "In4.Cu")
		(net "DRIVE_A_29_ACT")
	)
	(segment
		(start 204.734668 -278.267668)
		(end 198.00189 -285.000446)
		(width 0.12065)
		(layer "In4.Cu")
		(net "DRIVE_A_29_ACT")
	)
	(segment
		(start 213.755732 -59.247024)
		(end 213.755732 -72.650858)
		(width 0.12065)
		(layer "In4.Cu")
		(net "DRIVE_A_29_ACT")
	)
	(segment
		(start 280.973784 -302.768)
		(end 276.48154 -302.768)
		(width 0.12065)
		(layer "In4.Cu")
		(net "DRIVE_A_29_ACT")
	)
	(segment
		(start 212.767418 -147.82419)
		(end 212.767418 -194.21475)
		(width 0.12065)
		(layer "In4.Cu")
		(net "DRIVE_A_29_ACT")
	)
	(segment
		(start 208.799938 0.116332)
		(end 208.8261 0.09017)
		(width 0.12065)
		(layer "In4.Cu")
		(net "DRIVE_A_29_ACT")
	)
	(segment
		(start 213.755732 -72.650858)
		(end 209.846672 -76.559918)
		(width 0.12065)
		(layer "In4.Cu")
		(net "DRIVE_A_29_ACT")
	)
	(segment
		(start 276.48154 -302.768)
		(end 273.2024 -299.48886)
		(width 0.12065)
		(layer "In4.Cu")
		(net "DRIVE_A_29_ACT")
	)
	(segment
		(start 150.562818 -45.508418)
		(end 150.562818 -45.536358)
		(width 0.17145)
		(layer "F.Cu")
		(net "DRIVE_A_28_PWR")
	)
	(segment
		(start 246.07012 -243.84)
		(end 246.72036 -243.18976)
		(width 0.17145)
		(layer "F.Cu")
		(net "DRIVE_A_28_PWR")
	)
	(segment
		(start 149.926294 -44.871894)
		(end 150.562818 -45.508418)
		(width 0.17145)
		(layer "F.Cu")
		(net "DRIVE_A_28_PWR")
	)
	(segment
		(start 246.72036 -243.18976)
		(end 246.72036 -242.1382)
		(width 0.17145)
		(layer "F.Cu")
		(net "DRIVE_A_28_PWR")
	)
	(segment
		(start 246.72036 -242.1382)
		(end 246.72036 -239.8014)
		(width 0.17145)
		(layer "F.Cu")
		(net "DRIVE_A_28_PWR")
	)
	(segment
		(start 149.640798 -44.871894)
		(end 149.926294 -44.871894)
		(width 0.17145)
		(layer "F.Cu")
		(net "DRIVE_A_28_PWR")
	)
	(via
		(at 246.07012 -243.84)
		(size 0.5588)
		(drill 0.3048)
		(layers "F.Cu" "B.Cu")
		(net "DRIVE_A_28_PWR")
	)
	(via
		(at 246.72036 -242.1382)
		(size 0.6604)
		(drill 0.3302)
		(layers "F.Cu" "B.Cu")
		(net "DRIVE_A_28_PWR")
	)
	(via
		(at 172.074078 -239.978184)
		(size 0.5588)
		(drill 0.3048)
		(layers "F.Cu" "B.Cu")
		(net "DRIVE_A_28_PWR")
	)
	(via
		(at 150.562818 -45.536358)
		(size 0.5588)
		(drill 0.3048)
		(layers "F.Cu" "B.Cu")
		(net "DRIVE_A_28_PWR")
	)
	(segment
		(start 236.524292 -241.7826)
		(end 225.13544 -241.7826)
		(width 0.13335)
		(layer "In2.Cu")
		(net "DRIVE_A_28_PWR")
	)
	(segment
		(start 246.07012 -243.84)
		(end 245.415816 -244.494304)
		(width 0.13335)
		(layer "In2.Cu")
		(net "DRIVE_A_28_PWR")
	)
	(segment
		(start 172.766736 -239.978184)
		(end 172.074078 -239.978184)
		(width 0.13335)
		(layer "In2.Cu")
		(net "DRIVE_A_28_PWR")
	)
	(segment
		(start 245.415816 -244.494304)
		(end 239.235996 -244.494304)
		(width 0.13335)
		(layer "In2.Cu")
		(net "DRIVE_A_28_PWR")
	)
	(segment
		(start 239.235996 -244.494304)
		(end 236.524292 -241.7826)
		(width 0.13335)
		(layer "In2.Cu")
		(net "DRIVE_A_28_PWR")
	)
	(segment
		(start 225.13544 -241.7826)
		(end 221.139766 -245.778274)
		(width 0.13335)
		(layer "In2.Cu")
		(net "DRIVE_A_28_PWR")
	)
	(segment
		(start 178.566826 -245.778274)
		(end 172.766736 -239.978184)
		(width 0.13335)
		(layer "In2.Cu")
		(net "DRIVE_A_28_PWR")
	)
	(segment
		(start 221.139766 -245.778274)
		(end 178.566826 -245.778274)
		(width 0.13335)
		(layer "In2.Cu")
		(net "DRIVE_A_28_PWR")
	)
	(segment
		(start 175.133 -162.692588)
		(end 175.133 -170.434)
		(width 0.12065)
		(layer "In4.Cu")
		(net "DRIVE_A_28_PWR")
	)
	(segment
		(start 150.9268 -45.90034)
		(end 150.9268 -70.322948)
		(width 0.12065)
		(layer "In4.Cu")
		(net "DRIVE_A_28_PWR")
	)
	(segment
		(start 172.0596 -199.517)
		(end 172.0596 -239.963706)
		(width 0.12065)
		(layer "In4.Cu")
		(net "DRIVE_A_28_PWR")
	)
	(segment
		(start 179.319936 -161.168588)
		(end 176.657 -161.168588)
		(width 0.12065)
		(layer "In4.Cu")
		(net "DRIVE_A_28_PWR")
	)
	(segment
		(start 169.639996 -89.036144)
		(end 169.639996 -124.425202)
		(width 0.12065)
		(layer "In4.Cu")
		(net "DRIVE_A_28_PWR")
	)
	(segment
		(start 150.9268 -70.322948)
		(end 169.639996 -89.036144)
		(width 0.12065)
		(layer "In4.Cu")
		(net "DRIVE_A_28_PWR")
	)
	(segment
		(start 181.102 -135.887206)
		(end 181.102 -159.386524)
		(width 0.12065)
		(layer "In4.Cu")
		(net "DRIVE_A_28_PWR")
	)
	(segment
		(start 169.0878 -196.5452)
		(end 172.0596 -199.517)
		(width 0.12065)
		(layer "In4.Cu")
		(net "DRIVE_A_28_PWR")
	)
	(segment
		(start 172.0596 -239.963706)
		(end 172.074078 -239.978184)
		(width 0.12065)
		(layer "In4.Cu")
		(net "DRIVE_A_28_PWR")
	)
	(segment
		(start 169.639996 -124.425202)
		(end 181.102 -135.887206)
		(width 0.12065)
		(layer "In4.Cu")
		(net "DRIVE_A_28_PWR")
	)
	(segment
		(start 175.133 -170.434)
		(end 169.0878 -176.4792)
		(width 0.12065)
		(layer "In4.Cu")
		(net "DRIVE_A_28_PWR")
	)
	(segment
		(start 181.102 -159.386524)
		(end 179.319936 -161.168588)
		(width 0.12065)
		(layer "In4.Cu")
		(net "DRIVE_A_28_PWR")
	)
	(segment
		(start 150.562818 -45.536358)
		(end 150.9268 -45.90034)
		(width 0.12065)
		(layer "In4.Cu")
		(net "DRIVE_A_28_PWR")
	)
	(segment
		(start 169.0878 -176.4792)
		(end 169.0878 -196.5452)
		(width 0.12065)
		(layer "In4.Cu")
		(net "DRIVE_A_28_PWR")
	)
	(segment
		(start 176.657 -161.168588)
		(end 175.133 -162.692588)
		(width 0.12065)
		(layer "In4.Cu")
		(net "DRIVE_A_28_PWR")
	)
	(segment
		(start 244.80012 -260.6548)
		(end 245.45036 -260.00456)
		(width 0.17145)
		(layer "F.Cu")
		(net "DRIVE_A_28_INS")
	)
	(segment
		(start 245.45036 -260.00456)
		(end 245.45036 -257.7084)
		(width 0.17145)
		(layer "F.Cu")
		(net "DRIVE_A_28_INS")
	)
	(segment
		(start 163.140898 -66.5988)
		(end 163.140898 -67.681094)
		(width 0.17145)
		(layer "F.Cu")
		(net "DRIVE_A_28_INS")
	)
	(segment
		(start 163.140898 -65.064894)
		(end 163.140898 -66.5988)
		(width 0.17145)
		(layer "F.Cu")
		(net "DRIVE_A_28_INS")
	)
	(via
		(at 244.80012 -260.6548)
		(size 0.5588)
		(drill 0.3048)
		(layers "F.Cu" "B.Cu")
		(net "DRIVE_A_28_INS")
	)
	(via
		(at 173.2788 -260.731)
		(size 0.5588)
		(drill 0.3048)
		(layers "F.Cu" "B.Cu")
		(net "DRIVE_A_28_INS")
	)
	(via
		(at 163.140898 -66.5988)
		(size 0.6604)
		(drill 0.3302)
		(layers "F.Cu" "B.Cu")
		(net "DRIVE_A_28_INS")
	)
	(via
		(at 163.140898 -67.681094)
		(size 0.5588)
		(drill 0.3048)
		(layers "F.Cu" "B.Cu")
		(net "DRIVE_A_28_INS")
	)
	(segment
		(start 239.715548 -260.6548)
		(end 239.232948 -261.1374)
		(width 0.13335)
		(layer "In2.Cu")
		(net "DRIVE_A_28_INS")
	)
	(segment
		(start 193.929 -260.731)
		(end 173.2788 -260.731)
		(width 0.13335)
		(layer "In2.Cu")
		(net "DRIVE_A_28_INS")
	)
	(segment
		(start 194.3354 -261.1374)
		(end 193.929 -260.731)
		(width 0.13335)
		(layer "In2.Cu")
		(net "DRIVE_A_28_INS")
	)
	(segment
		(start 239.232948 -261.1374)
		(end 194.3354 -261.1374)
		(width 0.13335)
		(layer "In2.Cu")
		(net "DRIVE_A_28_INS")
	)
	(segment
		(start 244.80012 -260.6548)
		(end 239.715548 -260.6548)
		(width 0.13335)
		(layer "In2.Cu")
		(net "DRIVE_A_28_INS")
	)
	(segment
		(start 175.641 -162.851338)
		(end 176.911 -161.581338)
		(width 0.12065)
		(layer "In4.Cu")
		(net "DRIVE_A_28_INS")
	)
	(segment
		(start 181.6608 -135.655558)
		(end 170.198796 -124.193554)
		(width 0.12065)
		(layer "In4.Cu")
		(net "DRIVE_A_28_INS")
	)
	(segment
		(start 173.2788 -173.0502)
		(end 175.641 -170.688)
		(width 0.12065)
		(layer "In4.Cu")
		(net "DRIVE_A_28_INS")
	)
	(segment
		(start 170.198796 -124.193554)
		(end 170.198796 -88.301068)
		(width 0.12065)
		(layer "In4.Cu")
		(net "DRIVE_A_28_INS")
	)
	(segment
		(start 176.911 -161.581338)
		(end 179.491132 -161.581338)
		(width 0.12065)
		(layer "In4.Cu")
		(net "DRIVE_A_28_INS")
	)
	(segment
		(start 175.641 -170.688)
		(end 175.641 -162.851338)
		(width 0.12065)
		(layer "In4.Cu")
		(net "DRIVE_A_28_INS")
	)
	(segment
		(start 179.491132 -161.581338)
		(end 181.6608 -159.41167)
		(width 0.12065)
		(layer "In4.Cu")
		(net "DRIVE_A_28_INS")
	)
	(segment
		(start 181.6608 -159.41167)
		(end 181.6608 -135.655558)
		(width 0.12065)
		(layer "In4.Cu")
		(net "DRIVE_A_28_INS")
	)
	(segment
		(start 173.2788 -260.731)
		(end 173.2788 -173.0502)
		(width 0.12065)
		(layer "In4.Cu")
		(net "DRIVE_A_28_INS")
	)
	(segment
		(start 170.198796 -88.301068)
		(end 163.140898 -81.24317)
		(width 0.12065)
		(layer "In4.Cu")
		(net "DRIVE_A_28_INS")
	)
	(segment
		(start 163.140898 -81.24317)
		(end 163.140898 -67.681094)
		(width 0.12065)
		(layer "In4.Cu")
		(net "DRIVE_A_28_INS")
	)
	(segment
		(start 288.12236 -277.434548)
		(end 288.036508 -277.5204)
		(width 0.17145)
		(layer "F.Cu")
		(net "DRIVE_A_28_FLT_LED")
	)
	(segment
		(start 288.12236 -275.5646)
		(end 288.12236 -277.434548)
		(width 0.17145)
		(layer "F.Cu")
		(net "DRIVE_A_28_FLT_LED")
	)
	(segment
		(start 205.799944 -1.450086)
		(end 205.799944 0.116332)
		(width 0.17145)
		(layer "F.Cu")
		(net "DRIVE_A_28_FLT_LED")
	)
	(via
		(at 288.036508 -277.5204)
		(size 0.5588)
		(drill 0.3048)
		(layers "F.Cu" "B.Cu")
		(net "DRIVE_A_28_FLT_LED")
	)
	(via
		(at 205.799944 0.116332)
		(size 0.5588)
		(drill 0.3048)
		(layers "F.Cu" "B.Cu")
		(net "DRIVE_A_28_FLT_LED")
	)
	(via
		(at 292.023546 8.928862)
		(size 0.5588)
		(drill 0.3048)
		(layers "F.Cu" "B.Cu")
		(net "DRIVE_A_28_FLT_LED")
	)
	(segment
		(start 288.036508 -277.5204)
		(end 288.8996 -277.5204)
		(width 0.12065)
		(layer "In4.Cu")
		(net "DRIVE_A_28_FLT_LED")
	)
	(segment
		(start 307.8353 -257.286252)
		(end 307.8353 -130.786632)
		(width 0.12065)
		(layer "In4.Cu")
		(net "DRIVE_A_28_FLT_LED")
	)
	(segment
		(start 294.513 -271.907)
		(end 294.513 -270.608552)
		(width 0.12065)
		(layer "In4.Cu")
		(net "DRIVE_A_28_FLT_LED")
	)
	(segment
		(start 294.513 -270.608552)
		(end 307.8353 -257.286252)
		(width 0.12065)
		(layer "In4.Cu")
		(net "DRIVE_A_28_FLT_LED")
	)
	(segment
		(start 288.8996 -277.5204)
		(end 294.513 -271.907)
		(width 0.12065)
		(layer "In4.Cu")
		(net "DRIVE_A_28_FLT_LED")
	)
	(segment
		(start 293.268146 7.684262)
		(end 292.023546 8.928862)
		(width 0.12065)
		(layer "In4.Cu")
		(net "DRIVE_A_28_FLT_LED")
	)
	(segment
		(start 307.8353 -130.786632)
		(end 292.97757 -115.928902)
		(width 0.12065)
		(layer "In4.Cu")
		(net "DRIVE_A_28_FLT_LED")
	)
	(segment
		(start 292.97757 -58.257186)
		(end 293.268146 -57.96661)
		(width 0.12065)
		(layer "In4.Cu")
		(net "DRIVE_A_28_FLT_LED")
	)
	(segment
		(start 293.268146 -57.96661)
		(end 293.268146 7.684262)
		(width 0.12065)
		(layer "In4.Cu")
		(net "DRIVE_A_28_FLT_LED")
	)
	(segment
		(start 292.97757 -115.928902)
		(end 292.97757 -58.257186)
		(width 0.12065)
		(layer "In4.Cu")
		(net "DRIVE_A_28_FLT_LED")
	)
	(segment
		(start 292.023546 8.928862)
		(end 289.172396 8.928862)
		(width 0.13335)
		(layer "In9.Cu")
		(net "DRIVE_A_28_FLT_LED")
	)
	(segment
		(start 280.588466 0.344932)
		(end 237.736126 0.344932)
		(width 0.13335)
		(layer "In9.Cu")
		(net "DRIVE_A_28_FLT_LED")
	)
	(segment
		(start 209.042762 -3.126486)
		(end 205.799944 0.116332)
		(width 0.13335)
		(layer "In9.Cu")
		(net "DRIVE_A_28_FLT_LED")
	)
	(segment
		(start 234.264708 -3.126486)
		(end 209.042762 -3.126486)
		(width 0.13335)
		(layer "In9.Cu")
		(net "DRIVE_A_28_FLT_LED")
	)
	(segment
		(start 237.736126 0.344932)
		(end 234.264708 -3.126486)
		(width 0.13335)
		(layer "In9.Cu")
		(net "DRIVE_A_28_FLT_LED")
	)
	(segment
		(start 289.172396 8.928862)
		(end 280.588466 0.344932)
		(width 0.13335)
		(layer "In9.Cu")
		(net "DRIVE_A_28_FLT_LED")
	)
	(segment
		(start 206.799942 -1.450086)
		(end 206.799942 0.116332)
		(width 0.17145)
		(layer "F.Cu")
		(net "DRIVE_A_28_ACT")
	)
	(via
		(at 198.00189 -300.905926)
		(size 0.6604)
		(drill 0.3048)
		(layers "F.Cu" "B.Cu")
		(net "DRIVE_A_28_ACT")
	)
	(via
		(at 206.799942 0.116332)
		(size 0.5588)
		(drill 0.3048)
		(layers "F.Cu" "B.Cu")
		(net "DRIVE_A_28_ACT")
	)
	(segment
		(start 198.00189 -300.905926)
		(end 204.004164 -306.9082)
		(width 0.13335)
		(layer "In2.Cu")
		(net "DRIVE_A_28_ACT")
	)
	(segment
		(start 262.099552 -306.9082)
		(end 268.805152 -300.2026)
		(width 0.13335)
		(layer "In2.Cu")
		(net "DRIVE_A_28_ACT")
	)
	(segment
		(start 275.271484 -302.525684)
		(end 282.616148 -302.525684)
		(width 0.13335)
		(layer "In2.Cu")
		(net "DRIVE_A_28_ACT")
	)
	(segment
		(start 272.9484 -300.2026)
		(end 275.271484 -302.525684)
		(width 0.13335)
		(layer "In2.Cu")
		(net "DRIVE_A_28_ACT")
	)
	(segment
		(start 282.616148 -302.525684)
		(end 283.23667 -301.905162)
		(width 0.13335)
		(layer "In2.Cu")
		(net "DRIVE_A_28_ACT")
	)
	(segment
		(start 268.805152 -300.2026)
		(end 272.9484 -300.2026)
		(width 0.13335)
		(layer "In2.Cu")
		(net "DRIVE_A_28_ACT")
	)
	(segment
		(start 204.004164 -306.9082)
		(end 262.099552 -306.9082)
		(width 0.13335)
		(layer "In2.Cu")
		(net "DRIVE_A_28_ACT")
	)
	(segment
		(start 208.340452 -9.705594)
		(end 208.340452 -54.51856)
		(width 0.12065)
		(layer "In4.Cu")
		(net "DRIVE_A_28_ACT")
	)
	(segment
		(start 213.270084 -72.346058)
		(end 209.287872 -76.32827)
		(width 0.12065)
		(layer "In4.Cu")
		(net "DRIVE_A_28_ACT")
	)
	(segment
		(start 206.799942 -8.165084)
		(end 208.340452 -9.705594)
		(width 0.12065)
		(layer "In4.Cu")
		(net "DRIVE_A_28_ACT")
	)
	(segment
		(start 197.423532 -300.327568)
		(end 198.00189 -300.905926)
		(width 0.12065)
		(layer "In4.Cu")
		(net "DRIVE_A_28_ACT")
	)
	(segment
		(start 212.208618 -193.983102)
		(end 204.175868 -202.015852)
		(width 0.12065)
		(layer "In4.Cu")
		(net "DRIVE_A_28_ACT")
	)
	(segment
		(start 206.799942 0.116332)
		(end 206.799942 -8.165084)
		(width 0.12065)
		(layer "In4.Cu")
		(net "DRIVE_A_28_ACT")
	)
	(segment
		(start 204.175868 -202.015852)
		(end 204.175868 -278.03602)
		(width 0.12065)
		(layer "In4.Cu")
		(net "DRIVE_A_28_ACT")
	)
	(segment
		(start 197.423532 -284.788356)
		(end 197.423532 -300.327568)
		(width 0.12065)
		(layer "In4.Cu")
		(net "DRIVE_A_28_ACT")
	)
	(segment
		(start 209.287872 -145.135092)
		(end 212.208618 -148.055838)
		(width 0.12065)
		(layer "In4.Cu")
		(net "DRIVE_A_28_ACT")
	)
	(segment
		(start 208.340452 -54.51856)
		(end 213.270084 -59.448192)
		(width 0.12065)
		(layer "In4.Cu")
		(net "DRIVE_A_28_ACT")
	)
	(segment
		(start 204.175868 -278.03602)
		(end 197.423532 -284.788356)
		(width 0.12065)
		(layer "In4.Cu")
		(net "DRIVE_A_28_ACT")
	)
	(segment
		(start 213.270084 -59.448192)
		(end 213.270084 -72.346058)
		(width 0.12065)
		(layer "In4.Cu")
		(net "DRIVE_A_28_ACT")
	)
	(segment
		(start 212.208618 -148.055838)
		(end 212.208618 -193.983102)
		(width 0.12065)
		(layer "In4.Cu")
		(net "DRIVE_A_28_ACT")
	)
	(segment
		(start 209.287872 -76.32827)
		(end 209.287872 -145.135092)
		(width 0.12065)
		(layer "In4.Cu")
		(net "DRIVE_A_28_ACT")
	)
	(segment
		(start 118.090696 -44.821094)
		(end 118.090696 -44.661582)
		(width 0.17145)
		(layer "F.Cu")
		(net "DRIVE_A_27_PWR")
	)
	(segment
		(start 247.3706 -239.8014)
		(end 247.3706 -241.2492)
		(width 0.17145)
		(layer "F.Cu")
		(net "DRIVE_A_27_PWR")
	)
	(segment
		(start 118.090696 -44.661582)
		(end 117.3988 -43.969686)
		(width 0.17145)
		(layer "F.Cu")
		(net "DRIVE_A_27_PWR")
	)
	(segment
		(start 247.3706 -241.2492)
		(end 247.3706 -242.8748)
		(width 0.17145)
		(layer "F.Cu")
		(net "DRIVE_A_27_PWR")
	)
	(via
		(at 114.080798 -245.810278)
		(size 0.5588)
		(drill 0.3048)
		(layers "F.Cu" "B.Cu")
		(net "DRIVE_A_27_PWR")
	)
	(via
		(at 247.3706 -242.8748)
		(size 0.5588)
		(drill 0.3048)
		(layers "F.Cu" "B.Cu")
		(net "DRIVE_A_27_PWR")
	)
	(via
		(at 247.3706 -241.2492)
		(size 0.6604)
		(drill 0.3302)
		(layers "F.Cu" "B.Cu")
		(net "DRIVE_A_27_PWR")
	)
	(via
		(at 117.3988 -43.969686)
		(size 0.5588)
		(drill 0.3048)
		(layers "F.Cu" "B.Cu")
		(net "DRIVE_A_27_PWR")
	)
	(segment
		(start 247.3706 -242.8748)
		(end 246.7864 -243.459)
		(width 0.13335)
		(layer "In2.Cu")
		(net "DRIVE_A_27_PWR")
	)
	(segment
		(start 246.7864 -243.964968)
		(end 245.831614 -244.919754)
		(width 0.13335)
		(layer "In2.Cu")
		(net "DRIVE_A_27_PWR")
	)
	(segment
		(start 236.481366 -242.3414)
		(end 225.367088 -242.3414)
		(width 0.13335)
		(layer "In2.Cu")
		(net "DRIVE_A_27_PWR")
	)
	(segment
		(start 245.831614 -244.919754)
		(end 239.05972 -244.919754)
		(width 0.13335)
		(layer "In2.Cu")
		(net "DRIVE_A_27_PWR")
	)
	(segment
		(start 221.099888 -246.6086)
		(end 114.87912 -246.6086)
		(width 0.13335)
		(layer "In2.Cu")
		(net "DRIVE_A_27_PWR")
	)
	(segment
		(start 225.367088 -242.3414)
		(end 221.099888 -246.6086)
		(width 0.13335)
		(layer "In2.Cu")
		(net "DRIVE_A_27_PWR")
	)
	(segment
		(start 239.05972 -244.919754)
		(end 236.481366 -242.3414)
		(width 0.13335)
		(layer "In2.Cu")
		(net "DRIVE_A_27_PWR")
	)
	(segment
		(start 246.7864 -243.459)
		(end 246.7864 -243.964968)
		(width 0.13335)
		(layer "In2.Cu")
		(net "DRIVE_A_27_PWR")
	)
	(segment
		(start 114.87912 -246.6086)
		(end 114.080798 -245.810278)
		(width 0.13335)
		(layer "In2.Cu")
		(net "DRIVE_A_27_PWR")
	)
	(segment
		(start 121.05767 -161.942272)
		(end 121.05767 -173.721522)
		(width 0.12065)
		(layer "In4.Cu")
		(net "DRIVE_A_27_PWR")
	)
	(segment
		(start 110.088934 -184.690258)
		(end 110.088934 -227.720144)
		(width 0.12065)
		(layer "In4.Cu")
		(net "DRIVE_A_27_PWR")
	)
	(segment
		(start 114.033808 -231.665018)
		(end 114.033808 -245.763288)
		(width 0.12065)
		(layer "In4.Cu")
		(net "DRIVE_A_27_PWR")
	)
	(segment
		(start 122.868182 -88.288368)
		(end 122.868182 -123.003818)
		(width 0.12065)
		(layer "In4.Cu")
		(net "DRIVE_A_27_PWR")
	)
	(segment
		(start 118.782338 -159.66694)
		(end 121.05767 -161.942272)
		(width 0.12065)
		(layer "In4.Cu")
		(net "DRIVE_A_27_PWR")
	)
	(segment
		(start 118.052342 -83.472528)
		(end 122.868182 -88.288368)
		(width 0.12065)
		(layer "In4.Cu")
		(net "DRIVE_A_27_PWR")
	)
	(segment
		(start 117.3988 -43.969686)
		(end 118.052342 -44.623228)
		(width 0.12065)
		(layer "In4.Cu")
		(net "DRIVE_A_27_PWR")
	)
	(segment
		(start 118.782338 -127.089662)
		(end 118.782338 -159.66694)
		(width 0.12065)
		(layer "In4.Cu")
		(net "DRIVE_A_27_PWR")
	)
	(segment
		(start 110.088934 -227.720144)
		(end 114.033808 -231.665018)
		(width 0.12065)
		(layer "In4.Cu")
		(net "DRIVE_A_27_PWR")
	)
	(segment
		(start 122.868182 -123.003818)
		(end 118.782338 -127.089662)
		(width 0.12065)
		(layer "In4.Cu")
		(net "DRIVE_A_27_PWR")
	)
	(segment
		(start 118.052342 -44.623228)
		(end 118.052342 -83.472528)
		(width 0.12065)
		(layer "In4.Cu")
		(net "DRIVE_A_27_PWR")
	)
	(segment
		(start 121.05767 -173.721522)
		(end 110.088934 -184.690258)
		(width 0.12065)
		(layer "In4.Cu")
		(net "DRIVE_A_27_PWR")
	)
	(segment
		(start 114.033808 -245.763288)
		(end 114.080798 -245.810278)
		(width 0.12065)
		(layer "In4.Cu")
		(net "DRIVE_A_27_PWR")
	)
	(segment
		(start 246.1006 -257.7084)
		(end 246.1006 -259.6896)
		(width 0.17145)
		(layer "F.Cu")
		(net "DRIVE_A_27_INS")
	)
	(segment
		(start 131.590796 -66.167)
		(end 131.590796 -68.535804)
		(width 0.17145)
		(layer "F.Cu")
		(net "DRIVE_A_27_INS")
	)
	(segment
		(start 131.590796 -68.535804)
		(end 129.7178 -70.4088)
		(width 0.17145)
		(layer "F.Cu")
		(net "DRIVE_A_27_INS")
	)
	(segment
		(start 131.590796 -65.064894)
		(end 131.590796 -66.167)
		(width 0.17145)
		(layer "F.Cu")
		(net "DRIVE_A_27_INS")
	)
	(via
		(at 131.590796 -66.167)
		(size 0.6604)
		(drill 0.3302)
		(layers "F.Cu" "B.Cu")
		(net "DRIVE_A_27_INS")
	)
	(via
		(at 134.8232 -261.1882)
		(size 0.5588)
		(drill 0.3048)
		(layers "F.Cu" "B.Cu")
		(net "DRIVE_A_27_INS")
	)
	(via
		(at 129.7178 -70.4088)
		(size 0.5588)
		(drill 0.3048)
		(layers "F.Cu" "B.Cu")
		(net "DRIVE_A_27_INS")
	)
	(via
		(at 246.1006 -259.6896)
		(size 0.5588)
		(drill 0.3048)
		(layers "F.Cu" "B.Cu")
		(net "DRIVE_A_27_INS")
	)
	(segment
		(start 194.02679 -261.71779)
		(end 193.675 -261.366)
		(width 0.13335)
		(layer "In2.Cu")
		(net "DRIVE_A_27_INS")
	)
	(segment
		(start 239.947196 -261.2136)
		(end 239.443006 -261.71779)
		(width 0.13335)
		(layer "In2.Cu")
		(net "DRIVE_A_27_INS")
	)
	(segment
		(start 193.675 -261.366)
		(end 135.001 -261.366)
		(width 0.13335)
		(layer "In2.Cu")
		(net "DRIVE_A_27_INS")
	)
	(segment
		(start 245.031768 -261.2136)
		(end 239.947196 -261.2136)
		(width 0.13335)
		(layer "In2.Cu")
		(net "DRIVE_A_27_INS")
	)
	(segment
		(start 135.001 -261.366)
		(end 134.8232 -261.1882)
		(width 0.13335)
		(layer "In2.Cu")
		(net "DRIVE_A_27_INS")
	)
	(segment
		(start 246.1006 -259.6896)
		(end 245.5418 -260.2484)
		(width 0.13335)
		(layer "In2.Cu")
		(net "DRIVE_A_27_INS")
	)
	(segment
		(start 245.5418 -260.703568)
		(end 245.031768 -261.2136)
		(width 0.13335)
		(layer "In2.Cu")
		(net "DRIVE_A_27_INS")
	)
	(segment
		(start 245.5418 -260.2484)
		(end 245.5418 -260.703568)
		(width 0.13335)
		(layer "In2.Cu")
		(net "DRIVE_A_27_INS")
	)
	(segment
		(start 239.443006 -261.71779)
		(end 194.02679 -261.71779)
		(width 0.13335)
		(layer "In2.Cu")
		(net "DRIVE_A_27_INS")
	)
	(segment
		(start 120.655588 -159.572706)
		(end 124.210572 -163.12769)
		(width 0.12065)
		(layer "In4.Cu")
		(net "DRIVE_A_27_INS")
	)
	(segment
		(start 134.822946 -236.576362)
		(end 134.822946 -241.937794)
		(width 0.12065)
		(layer "In4.Cu")
		(net "DRIVE_A_27_INS")
	)
	(segment
		(start 124.7521 -88.710008)
		(end 124.7521 -89.255346)
		(width 0.12065)
		(layer "In4.Cu")
		(net "DRIVE_A_27_INS")
	)
	(segment
		(start 120.655588 -127.371856)
		(end 120.655588 -159.572706)
		(width 0.12065)
		(layer "In4.Cu")
		(net "DRIVE_A_27_INS")
	)
	(segment
		(start 124.210572 -163.12769)
		(end 124.210572 -164.974016)
		(width 0.12065)
		(layer "In4.Cu")
		(net "DRIVE_A_27_INS")
	)
	(segment
		(start 142.979648 -228.41966)
		(end 134.822946 -236.576362)
		(width 0.12065)
		(layer "In4.Cu")
		(net "DRIVE_A_27_INS")
	)
	(segment
		(start 124.751846 -123.275598)
		(end 120.655588 -127.371856)
		(width 0.12065)
		(layer "In4.Cu")
		(net "DRIVE_A_27_INS")
	)
	(segment
		(start 131.645406 -183.691784)
		(end 142.979648 -195.026026)
		(width 0.12065)
		(layer "In4.Cu")
		(net "DRIVE_A_27_INS")
	)
	(segment
		(start 134.8232 -241.938048)
		(end 134.8232 -261.1882)
		(width 0.12065)
		(layer "In4.Cu")
		(net "DRIVE_A_27_INS")
	)
	(segment
		(start 134.822946 -241.937794)
		(end 134.8232 -241.938048)
		(width 0.12065)
		(layer "In4.Cu")
		(net "DRIVE_A_27_INS")
	)
	(segment
		(start 124.751846 -89.2556)
		(end 124.751846 -123.275598)
		(width 0.12065)
		(layer "In4.Cu")
		(net "DRIVE_A_27_INS")
	)
	(segment
		(start 142.979648 -195.026026)
		(end 142.979648 -228.41966)
		(width 0.12065)
		(layer "In4.Cu")
		(net "DRIVE_A_27_INS")
	)
	(segment
		(start 130.302254 -171.065698)
		(end 130.302254 -180.746654)
		(width 0.12065)
		(layer "In4.Cu")
		(net "DRIVE_A_27_INS")
	)
	(segment
		(start 131.645406 -182.089806)
		(end 131.645406 -183.691784)
		(width 0.12065)
		(layer "In4.Cu")
		(net "DRIVE_A_27_INS")
	)
	(segment
		(start 124.7521 -89.255346)
		(end 124.751846 -89.2556)
		(width 0.12065)
		(layer "In4.Cu")
		(net "DRIVE_A_27_INS")
	)
	(segment
		(start 129.7178 -70.4088)
		(end 129.7178 -83.744308)
		(width 0.12065)
		(layer "In4.Cu")
		(net "DRIVE_A_27_INS")
	)
	(segment
		(start 124.210572 -164.974016)
		(end 130.302254 -171.065698)
		(width 0.12065)
		(layer "In4.Cu")
		(net "DRIVE_A_27_INS")
	)
	(segment
		(start 130.302254 -180.746654)
		(end 131.645406 -182.089806)
		(width 0.12065)
		(layer "In4.Cu")
		(net "DRIVE_A_27_INS")
	)
	(segment
		(start 129.7178 -83.744308)
		(end 124.7521 -88.710008)
		(width 0.12065)
		(layer "In4.Cu")
		(net "DRIVE_A_27_INS")
	)
	(segment
		(start 287.47212 -277.896828)
		(end 287.47212 -275.5646)
		(width 0.17145)
		(layer "F.Cu")
		(net "DRIVE_A_27_FLT_LED")
	)
	(segment
		(start 288.031174 -278.455882)
		(end 287.47212 -277.896828)
		(width 0.17145)
		(layer "F.Cu")
		(net "DRIVE_A_27_FLT_LED")
	)
	(segment
		(start 203.799948 -1.450086)
		(end 203.799948 0.116332)
		(width 0.17145)
		(layer "F.Cu")
		(net "DRIVE_A_27_FLT_LED")
	)
	(via
		(at 288.031174 -278.455882)
		(size 0.5588)
		(drill 0.3048)
		(layers "F.Cu" "B.Cu")
		(net "DRIVE_A_27_FLT_LED")
	)
	(via
		(at 289.511232 7.917434)
		(size 0.5588)
		(drill 0.3048)
		(layers "F.Cu" "B.Cu")
		(net "DRIVE_A_27_FLT_LED")
	)
	(via
		(at 203.799948 0.116332)
		(size 0.5588)
		(drill 0.3048)
		(layers "F.Cu" "B.Cu")
		(net "DRIVE_A_27_FLT_LED")
	)
	(segment
		(start 292.419024 -106.685588)
		(end 292.56482 -106.831384)
		(width 0.12065)
		(layer "In4.Cu")
		(net "DRIVE_A_27_FLT_LED")
	)
	(segment
		(start 290.046156 8.452358)
		(end 291.629592 8.452358)
		(width 0.12065)
		(layer "In4.Cu")
		(net "DRIVE_A_27_FLT_LED")
	)
	(segment
		(start 292.56482 -253.498604)
		(end 294.7162 -255.649984)
		(width 0.12065)
		(layer "In4.Cu")
		(net "DRIVE_A_27_FLT_LED")
	)
	(segment
		(start 287.980882 -278.455882)
		(end 288.031174 -278.455882)
		(width 0.12065)
		(layer "In4.Cu")
		(net "DRIVE_A_27_FLT_LED")
	)
	(segment
		(start 287.274 -276.606)
		(end 287.274 -277.749)
		(width 0.12065)
		(layer "In4.Cu")
		(net "DRIVE_A_27_FLT_LED")
	)
	(segment
		(start 294.7162 -255.649984)
		(end 294.7162 -269.1638)
		(width 0.12065)
		(layer "In4.Cu")
		(net "DRIVE_A_27_FLT_LED")
	)
	(segment
		(start 289.511232 7.917434)
		(end 290.046156 8.452358)
		(width 0.12065)
		(layer "In4.Cu")
		(net "DRIVE_A_27_FLT_LED")
	)
	(segment
		(start 294.7162 -269.1638)
		(end 287.274 -276.606)
		(width 0.12065)
		(layer "In4.Cu")
		(net "DRIVE_A_27_FLT_LED")
	)
	(segment
		(start 292.411912 7.271766)
		(end 292.40861 7.268464)
		(width 0.12065)
		(layer "In4.Cu")
		(net "DRIVE_A_27_FLT_LED")
	)
	(segment
		(start 292.411912 6.62432)
		(end 292.411912 -106.65333)
		(width 0.12065)
		(layer "In4.Cu")
		(net "DRIVE_A_27_FLT_LED")
	)
	(segment
		(start 292.419024 -106.660442)
		(end 292.419024 -106.685588)
		(width 0.12065)
		(layer "In4.Cu")
		(net "DRIVE_A_27_FLT_LED")
	)
	(segment
		(start 287.274 -277.749)
		(end 287.980882 -278.455882)
		(width 0.12065)
		(layer "In4.Cu")
		(net "DRIVE_A_27_FLT_LED")
	)
	(segment
		(start 292.411912 -106.65333)
		(end 292.419024 -106.660442)
		(width 0.12065)
		(layer "In4.Cu")
		(net "DRIVE_A_27_FLT_LED")
	)
	(segment
		(start 292.40861 7.268464)
		(end 292.40861 6.627622)
		(width 0.12065)
		(layer "In4.Cu")
		(net "DRIVE_A_27_FLT_LED")
	)
	(segment
		(start 292.411912 7.670038)
		(end 292.411912 7.271766)
		(width 0.12065)
		(layer "In4.Cu")
		(net "DRIVE_A_27_FLT_LED")
	)
	(segment
		(start 291.629592 8.452358)
		(end 292.411912 7.670038)
		(width 0.12065)
		(layer "In4.Cu")
		(net "DRIVE_A_27_FLT_LED")
	)
	(segment
		(start 292.40861 6.627622)
		(end 292.411912 6.62432)
		(width 0.12065)
		(layer "In4.Cu")
		(net "DRIVE_A_27_FLT_LED")
	)
	(segment
		(start 292.56482 -106.831384)
		(end 292.56482 -253.498604)
		(width 0.12065)
		(layer "In4.Cu")
		(net "DRIVE_A_27_FLT_LED")
	)
	(segment
		(start 207.51673 -3.60045)
		(end 203.799948 0.116332)
		(width 0.13335)
		(layer "In9.Cu")
		(net "DRIVE_A_27_FLT_LED")
	)
	(segment
		(start 237.968028 -0.081534)
		(end 234.449112 -3.60045)
		(width 0.13335)
		(layer "In9.Cu")
		(net "DRIVE_A_27_FLT_LED")
	)
	(segment
		(start 234.449112 -3.60045)
		(end 207.51673 -3.60045)
		(width 0.13335)
		(layer "In9.Cu")
		(net "DRIVE_A_27_FLT_LED")
	)
	(segment
		(start 281.512264 -0.081534)
		(end 237.968028 -0.081534)
		(width 0.13335)
		(layer "In9.Cu")
		(net "DRIVE_A_27_FLT_LED")
	)
	(segment
		(start 289.511232 7.917434)
		(end 281.512264 -0.081534)
		(width 0.13335)
		(layer "In9.Cu")
		(net "DRIVE_A_27_FLT_LED")
	)
	(segment
		(start 204.799946 -1.450086)
		(end 204.799946 0.116332)
		(width 0.17145)
		(layer "F.Cu")
		(net "DRIVE_A_27_ACT")
	)
	(via
		(at 271.78 -300.7614)
		(size 0.5588)
		(drill 0.3048)
		(layers "F.Cu" "B.Cu")
		(net "DRIVE_A_27_ACT")
	)
	(via
		(at 198.00189 -302.074326)
		(size 0.6604)
		(drill 0.3048)
		(layers "F.Cu" "B.Cu")
		(net "DRIVE_A_27_ACT")
	)
	(via
		(at 204.799946 0.116332)
		(size 0.5588)
		(drill 0.3048)
		(layers "F.Cu" "B.Cu")
		(net "DRIVE_A_27_ACT")
	)
	(segment
		(start 198.00189 -302.074326)
		(end 203.394564 -307.467)
		(width 0.13335)
		(layer "In2.Cu")
		(net "DRIVE_A_27_ACT")
	)
	(segment
		(start 203.394564 -307.467)
		(end 262.3312 -307.467)
		(width 0.13335)
		(layer "In2.Cu")
		(net "DRIVE_A_27_ACT")
	)
	(segment
		(start 269.0368 -300.7614)
		(end 271.78 -300.7614)
		(width 0.13335)
		(layer "In2.Cu")
		(net "DRIVE_A_27_ACT")
	)
	(segment
		(start 262.3312 -307.467)
		(end 269.0368 -300.7614)
		(width 0.13335)
		(layer "In2.Cu")
		(net "DRIVE_A_27_ACT")
	)
	(segment
		(start 204.799946 0.116332)
		(end 206.129382 -1.213104)
		(width 0.12065)
		(layer "In4.Cu")
		(net "DRIVE_A_27_ACT")
	)
	(segment
		(start 212.720174 -59.67603)
		(end 212.720174 -60.801504)
		(width 0.12065)
		(layer "In4.Cu")
		(net "DRIVE_A_27_ACT")
	)
	(segment
		(start 212.661754 -72.16394)
		(end 208.729072 -76.096622)
		(width 0.12065)
		(layer "In4.Cu")
		(net "DRIVE_A_27_ACT")
	)
	(segment
		(start 277.3426 -304.5714)
		(end 273.5326 -300.7614)
		(width 0.12065)
		(layer "In4.Cu")
		(net "DRIVE_A_27_ACT")
	)
	(segment
		(start 281.97048 -304.5714)
		(end 277.3426 -304.5714)
		(width 0.12065)
		(layer "In4.Cu")
		(net "DRIVE_A_27_ACT")
	)
	(segment
		(start 197.010782 -284.61716)
		(end 197.010782 -301.083218)
		(width 0.12065)
		(layer "In4.Cu")
		(net "DRIVE_A_27_ACT")
	)
	(segment
		(start 203.617068 -201.784204)
		(end 203.617068 -277.804372)
		(width 0.12065)
		(layer "In4.Cu")
		(net "DRIVE_A_27_ACT")
	)
	(segment
		(start 197.014084 -284.613858)
		(end 197.010782 -284.61716)
		(width 0.12065)
		(layer "In4.Cu")
		(net "DRIVE_A_27_ACT")
	)
	(segment
		(start 203.617068 -277.804372)
		(end 197.014084 -284.407356)
		(width 0.12065)
		(layer "In4.Cu")
		(net "DRIVE_A_27_ACT")
	)
	(segment
		(start 212.661754 -60.859924)
		(end 212.661754 -72.16394)
		(width 0.12065)
		(layer "In4.Cu")
		(net "DRIVE_A_27_ACT")
	)
	(segment
		(start 273.5326 -300.7614)
		(end 271.78 -300.7614)
		(width 0.12065)
		(layer "In4.Cu")
		(net "DRIVE_A_27_ACT")
	)
	(segment
		(start 211.649818 -193.751454)
		(end 203.617068 -201.784204)
		(width 0.12065)
		(layer "In4.Cu")
		(net "DRIVE_A_27_ACT")
	)
	(segment
		(start 197.010782 -301.083218)
		(end 198.00189 -302.074326)
		(width 0.12065)
		(layer "In4.Cu")
		(net "DRIVE_A_27_ACT")
	)
	(segment
		(start 206.129382 -11.299444)
		(end 207.790542 -12.960604)
		(width 0.12065)
		(layer "In4.Cu")
		(net "DRIVE_A_27_ACT")
	)
	(segment
		(start 282.83662 -303.70526)
		(end 281.97048 -304.5714)
		(width 0.12065)
		(layer "In4.Cu")
		(net "DRIVE_A_27_ACT")
	)
	(segment
		(start 206.129382 -1.213104)
		(end 206.129382 -11.299444)
		(width 0.12065)
		(layer "In4.Cu")
		(net "DRIVE_A_27_ACT")
	)
	(segment
		(start 208.729072 -76.096622)
		(end 208.729072 -145.36674)
		(width 0.12065)
		(layer "In4.Cu")
		(net "DRIVE_A_27_ACT")
	)
	(segment
		(start 211.649818 -148.287486)
		(end 211.649818 -193.751454)
		(width 0.12065)
		(layer "In4.Cu")
		(net "DRIVE_A_27_ACT")
	)
	(segment
		(start 207.790542 -12.960604)
		(end 207.790542 -54.746398)
		(width 0.12065)
		(layer "In4.Cu")
		(net "DRIVE_A_27_ACT")
	)
	(segment
		(start 207.790542 -54.746398)
		(end 212.720174 -59.67603)
		(width 0.12065)
		(layer "In4.Cu")
		(net "DRIVE_A_27_ACT")
	)
	(segment
		(start 208.729072 -145.36674)
		(end 211.649818 -148.287486)
		(width 0.12065)
		(layer "In4.Cu")
		(net "DRIVE_A_27_ACT")
	)
	(segment
		(start 197.014084 -284.407356)
		(end 197.014084 -284.613858)
		(width 0.12065)
		(layer "In4.Cu")
		(net "DRIVE_A_27_ACT")
	)
	(segment
		(start 212.720174 -60.801504)
		(end 212.661754 -60.859924)
		(width 0.12065)
		(layer "In4.Cu")
		(net "DRIVE_A_27_ACT")
	)
	(segment
		(start 86.566248 -44.821094)
		(end 87.391748 -44.821094)
		(width 0.17145)
		(layer "F.Cu")
		(net "DRIVE_A_26_PWR")
	)
	(segment
		(start 247.3706 -243.84)
		(end 248.02084 -243.18976)
		(width 0.17145)
		(layer "F.Cu")
		(net "DRIVE_A_26_PWR")
	)
	(segment
		(start 248.02084 -243.18976)
		(end 248.02084 -242.1382)
		(width 0.17145)
		(layer "F.Cu")
		(net "DRIVE_A_26_PWR")
	)
	(segment
		(start 248.02084 -242.1382)
		(end 248.02084 -239.8014)
		(width 0.17145)
		(layer "F.Cu")
		(net "DRIVE_A_26_PWR")
	)
	(via
		(at 247.3706 -243.84)
		(size 0.5588)
		(drill 0.3048)
		(layers "F.Cu" "B.Cu")
		(net "DRIVE_A_26_PWR")
	)
	(via
		(at 87.391748 -44.821094)
		(size 0.5588)
		(drill 0.3048)
		(layers "F.Cu" "B.Cu")
		(net "DRIVE_A_26_PWR")
	)
	(via
		(at 85.6234 -246.9134)
		(size 0.5588)
		(drill 0.3048)
		(layers "F.Cu" "B.Cu")
		(net "DRIVE_A_26_PWR")
	)
	(via
		(at 248.02084 -242.1382)
		(size 0.6604)
		(drill 0.3302)
		(layers "F.Cu" "B.Cu")
		(net "DRIVE_A_26_PWR")
	)
	(segment
		(start 236.249718 -242.9002)
		(end 238.828072 -245.478554)
		(width 0.13335)
		(layer "In2.Cu")
		(net "DRIVE_A_26_PWR")
	)
	(segment
		(start 246.138446 -245.478554)
		(end 247.3706 -244.2464)
		(width 0.13335)
		(layer "In2.Cu")
		(net "DRIVE_A_26_PWR")
	)
	(segment
		(start 221.229936 -247.269)
		(end 225.598736 -242.9002)
		(width 0.13335)
		(layer "In2.Cu")
		(net "DRIVE_A_26_PWR")
	)
	(segment
		(start 225.598736 -242.9002)
		(end 236.249718 -242.9002)
		(width 0.13335)
		(layer "In2.Cu")
		(net "DRIVE_A_26_PWR")
	)
	(segment
		(start 247.3706 -244.2464)
		(end 247.3706 -243.84)
		(width 0.13335)
		(layer "In2.Cu")
		(net "DRIVE_A_26_PWR")
	)
	(segment
		(start 85.979 -247.269)
		(end 221.229936 -247.269)
		(width 0.13335)
		(layer "In2.Cu")
		(net "DRIVE_A_26_PWR")
	)
	(segment
		(start 238.828072 -245.478554)
		(end 246.138446 -245.478554)
		(width 0.13335)
		(layer "In2.Cu")
		(net "DRIVE_A_26_PWR")
	)
	(segment
		(start 85.6234 -246.9134)
		(end 85.979 -247.269)
		(width 0.13335)
		(layer "In2.Cu")
		(net "DRIVE_A_26_PWR")
	)
	(segment
		(start 85.6234 -246.9134)
		(end 86.3854 -246.1514)
		(width 0.12065)
		(layer "In4.Cu")
		(net "DRIVE_A_26_PWR")
	)
	(segment
		(start 85.725 -157.226)
		(end 85.725 -80.4164)
		(width 0.12065)
		(layer "In4.Cu")
		(net "DRIVE_A_26_PWR")
	)
	(segment
		(start 88.0872 -159.5882)
		(end 85.725 -157.226)
		(width 0.12065)
		(layer "In4.Cu")
		(net "DRIVE_A_26_PWR")
	)
	(segment
		(start 86.3854 -246.1514)
		(end 86.3854 -188.598048)
		(width 0.12065)
		(layer "In4.Cu")
		(net "DRIVE_A_26_PWR")
	)
	(segment
		(start 88.0872 -45.516546)
		(end 87.391748 -44.821094)
		(width 0.12065)
		(layer "In4.Cu")
		(net "DRIVE_A_26_PWR")
	)
	(segment
		(start 88.0872 -186.896248)
		(end 88.0872 -159.5882)
		(width 0.12065)
		(layer "In4.Cu")
		(net "DRIVE_A_26_PWR")
	)
	(segment
		(start 85.725 -80.4164)
		(end 88.0872 -78.0542)
		(width 0.12065)
		(layer "In4.Cu")
		(net "DRIVE_A_26_PWR")
	)
	(segment
		(start 86.3854 -188.598048)
		(end 88.0872 -186.896248)
		(width 0.12065)
		(layer "In4.Cu")
		(net "DRIVE_A_26_PWR")
	)
	(segment
		(start 88.0872 -78.0542)
		(end 88.0872 -45.516546)
		(width 0.12065)
		(layer "In4.Cu")
		(net "DRIVE_A_26_PWR")
	)
	(segment
		(start 100.040948 -66.176652)
		(end 99.564444 -66.653156)
		(width 0.17145)
		(layer "F.Cu")
		(net "DRIVE_A_26_INS")
	)
	(segment
		(start 246.75084 -260.00456)
		(end 246.75084 -257.7084)
		(width 0.17145)
		(layer "F.Cu")
		(net "DRIVE_A_26_INS")
	)
	(segment
		(start 99.2124 -67.0052)
		(end 98.2472 -67.0052)
		(width 0.17145)
		(layer "F.Cu")
		(net "DRIVE_A_26_INS")
	)
	(segment
		(start 100.040948 -65.064894)
		(end 100.040948 -66.176652)
		(width 0.17145)
		(layer "F.Cu")
		(net "DRIVE_A_26_INS")
	)
	(segment
		(start 246.1006 -260.6548)
		(end 246.75084 -260.00456)
		(width 0.17145)
		(layer "F.Cu")
		(net "DRIVE_A_26_INS")
	)
	(segment
		(start 99.564444 -66.653156)
		(end 99.2124 -67.0052)
		(width 0.17145)
		(layer "F.Cu")
		(net "DRIVE_A_26_INS")
	)
	(via
		(at 98.2472 -67.0052)
		(size 0.5588)
		(drill 0.3048)
		(layers "F.Cu" "B.Cu")
		(net "DRIVE_A_26_INS")
	)
	(via
		(at 99.564444 -66.653156)
		(size 0.6604)
		(drill 0.3302)
		(layers "F.Cu" "B.Cu")
		(net "DRIVE_A_26_INS")
	)
	(via
		(at 246.1006 -260.6548)
		(size 0.5588)
		(drill 0.3048)
		(layers "F.Cu" "B.Cu")
		(net "DRIVE_A_26_INS")
	)
	(via
		(at 89.070942 -261.9248)
		(size 0.5588)
		(drill 0.3048)
		(layers "F.Cu" "B.Cu")
		(net "DRIVE_A_26_INS")
	)
	(segment
		(start 243.91239 -263.123426)
		(end 240.517426 -263.123426)
		(width 0.13335)
		(layer "In2.Cu")
		(net "DRIVE_A_26_INS")
	)
	(segment
		(start 193.798952 -262.2804)
		(end 193.443352 -261.9248)
		(width 0.13335)
		(layer "In2.Cu")
		(net "DRIVE_A_26_INS")
	)
	(segment
		(start 240.517426 -263.123426)
		(end 239.6744 -262.2804)
		(width 0.13335)
		(layer "In2.Cu")
		(net "DRIVE_A_26_INS")
	)
	(segment
		(start 246.1006 -260.6548)
		(end 246.1006 -260.935216)
		(width 0.13335)
		(layer "In2.Cu")
		(net "DRIVE_A_26_INS")
	)
	(segment
		(start 239.6744 -262.2804)
		(end 193.798952 -262.2804)
		(width 0.13335)
		(layer "In2.Cu")
		(net "DRIVE_A_26_INS")
	)
	(segment
		(start 193.443352 -261.9248)
		(end 89.070942 -261.9248)
		(width 0.13335)
		(layer "In2.Cu")
		(net "DRIVE_A_26_INS")
	)
	(segment
		(start 246.1006 -260.935216)
		(end 243.91239 -263.123426)
		(width 0.13335)
		(layer "In2.Cu")
		(net "DRIVE_A_26_INS")
	)
	(segment
		(start 89.070942 -186.9948)
		(end 89.070942 -159.781494)
		(width 0.12065)
		(layer "In4.Cu")
		(net "DRIVE_A_26_INS")
	)
	(segment
		(start 87.122 -244.2972)
		(end 87.122 -192.8114)
		(width 0.12065)
		(layer "In4.Cu")
		(net "DRIVE_A_26_INS")
	)
	(segment
		(start 86.2838 -84.409026)
		(end 98.2472 -72.445626)
		(width 0.12065)
		(layer "In4.Cu")
		(net "DRIVE_A_26_INS")
	)
	(segment
		(start 87.122 -192.8114)
		(end 88.0237 -191.9097)
		(width 0.12065)
		(layer "In4.Cu")
		(net "DRIVE_A_26_INS")
	)
	(segment
		(start 89.070942 -261.9248)
		(end 89.070942 -246.246142)
		(width 0.12065)
		(layer "In4.Cu")
		(net "DRIVE_A_26_INS")
	)
	(segment
		(start 98.2472 -72.445626)
		(end 98.2472 -67.0052)
		(width 0.12065)
		(layer "In4.Cu")
		(net "DRIVE_A_26_INS")
	)
	(segment
		(start 89.070942 -246.246142)
		(end 87.122 -244.2972)
		(width 0.12065)
		(layer "In4.Cu")
		(net "DRIVE_A_26_INS")
	)
	(segment
		(start 86.2838 -156.994352)
		(end 86.2838 -84.409026)
		(width 0.12065)
		(layer "In4.Cu")
		(net "DRIVE_A_26_INS")
	)
	(segment
		(start 88.0237 -188.042042)
		(end 89.070942 -186.9948)
		(width 0.12065)
		(layer "In4.Cu")
		(net "DRIVE_A_26_INS")
	)
	(segment
		(start 89.070942 -159.781494)
		(end 86.2838 -156.994352)
		(width 0.12065)
		(layer "In4.Cu")
		(net "DRIVE_A_26_INS")
	)
	(segment
		(start 88.0237 -191.9097)
		(end 88.0237 -188.042042)
		(width 0.12065)
		(layer "In4.Cu")
		(net "DRIVE_A_26_INS")
	)
	(segment
		(start 203.799948 -9.121394)
		(end 203.7969 -9.124442)
		(width 0.17145)
		(layer "F.Cu")
		(net "DRIVE_A_26_FLT_LED")
	)
	(segment
		(start 285.3944 -279.4)
		(end 285.7246 -279.4)
		(width 0.17145)
		(layer "F.Cu")
		(net "DRIVE_A_26_FLT_LED")
	)
	(segment
		(start 203.799948 -7.55015)
		(end 203.799948 -9.121394)
		(width 0.17145)
		(layer "F.Cu")
		(net "DRIVE_A_26_FLT_LED")
	)
	(segment
		(start 286.82188 -278.30272)
		(end 286.82188 -275.5646)
		(width 0.17145)
		(layer "F.Cu")
		(net "DRIVE_A_26_FLT_LED")
	)
	(segment
		(start 285.7246 -279.4)
		(end 286.82188 -278.30272)
		(width 0.17145)
		(layer "F.Cu")
		(net "DRIVE_A_26_FLT_LED")
	)
	(via
		(at 291.279072 7.934452)
		(size 0.5588)
		(drill 0.3048)
		(layers "F.Cu" "B.Cu")
		(net "DRIVE_A_26_FLT_LED")
	)
	(via
		(at 285.3944 -279.4)
		(size 0.5588)
		(drill 0.3048)
		(layers "F.Cu" "B.Cu")
		(net "DRIVE_A_26_FLT_LED")
	)
	(via
		(at 203.7969 -9.124442)
		(size 0.5588)
		(drill 0.3048)
		(layers "F.Cu" "B.Cu")
		(net "DRIVE_A_26_FLT_LED")
	)
	(segment
		(start 291.731192 -106.53141)
		(end 291.731192 7.482332)
		(width 0.12065)
		(layer "In4.Cu")
		(net "DRIVE_A_26_FLT_LED")
	)
	(segment
		(start 286.639 -276.391624)
		(end 294.1574 -268.873224)
		(width 0.12065)
		(layer "In4.Cu")
		(net "DRIVE_A_26_FLT_LED")
	)
	(segment
		(start 291.731192 7.482332)
		(end 291.279072 7.934452)
		(width 0.12065)
		(layer "In4.Cu")
		(net "DRIVE_A_26_FLT_LED")
	)
	(segment
		(start 292.00602 -253.730252)
		(end 292.00602 -106.831384)
		(width 0.12065)
		(layer "In4.Cu")
		(net "DRIVE_A_26_FLT_LED")
	)
	(segment
		(start 294.1574 -268.873224)
		(end 294.1574 -255.881632)
		(width 0.12065)
		(layer "In4.Cu")
		(net "DRIVE_A_26_FLT_LED")
	)
	(segment
		(start 285.75 -279.4)
		(end 286.639 -278.511)
		(width 0.12065)
		(layer "In4.Cu")
		(net "DRIVE_A_26_FLT_LED")
	)
	(segment
		(start 285.3944 -279.4)
		(end 285.75 -279.4)
		(width 0.12065)
		(layer "In4.Cu")
		(net "DRIVE_A_26_FLT_LED")
	)
	(segment
		(start 292.00602 -106.831384)
		(end 291.860224 -106.685588)
		(width 0.12065)
		(layer "In4.Cu")
		(net "DRIVE_A_26_FLT_LED")
	)
	(segment
		(start 291.860224 -106.685588)
		(end 291.860224 -106.660442)
		(width 0.12065)
		(layer "In4.Cu")
		(net "DRIVE_A_26_FLT_LED")
	)
	(segment
		(start 294.1574 -255.881632)
		(end 292.00602 -253.730252)
		(width 0.12065)
		(layer "In4.Cu")
		(net "DRIVE_A_26_FLT_LED")
	)
	(segment
		(start 291.860224 -106.660442)
		(end 291.731192 -106.53141)
		(width 0.12065)
		(layer "In4.Cu")
		(net "DRIVE_A_26_FLT_LED")
	)
	(segment
		(start 286.639 -278.511)
		(end 286.639 -276.391624)
		(width 0.12065)
		(layer "In4.Cu")
		(net "DRIVE_A_26_FLT_LED")
	)
	(segment
		(start 290.777422 7.909052)
		(end 291.253672 7.909052)
		(width 0.13335)
		(layer "In9.Cu")
		(net "DRIVE_A_26_FLT_LED")
	)
	(segment
		(start 282.334716 -0.533654)
		(end 290.777422 7.909052)
		(width 0.13335)
		(layer "In9.Cu")
		(net "DRIVE_A_26_FLT_LED")
	)
	(segment
		(start 203.7969 -9.124442)
		(end 208.83245 -4.088892)
		(width 0.13335)
		(layer "In9.Cu")
		(net "DRIVE_A_26_FLT_LED")
	)
	(segment
		(start 208.83245 -4.088892)
		(end 234.739434 -4.088892)
		(width 0.13335)
		(layer "In9.Cu")
		(net "DRIVE_A_26_FLT_LED")
	)
	(segment
		(start 238.294672 -0.533654)
		(end 282.334716 -0.533654)
		(width 0.13335)
		(layer "In9.Cu")
		(net "DRIVE_A_26_FLT_LED")
	)
	(segment
		(start 291.253672 7.909052)
		(end 291.279072 7.934452)
		(width 0.13335)
		(layer "In9.Cu")
		(net "DRIVE_A_26_FLT_LED")
	)
	(segment
		(start 234.739434 -4.088892)
		(end 238.294672 -0.533654)
		(width 0.13335)
		(layer "In9.Cu")
		(net "DRIVE_A_26_FLT_LED")
	)
	(segment
		(start 204.799946 -9.127998)
		(end 204.799946 -7.55015)
		(width 0.17145)
		(layer "F.Cu")
		(net "DRIVE_A_26_ACT")
	)
	(segment
		(start 204.803756 -9.131808)
		(end 204.799946 -9.127998)
		(width 0.17145)
		(layer "F.Cu")
		(net "DRIVE_A_26_ACT")
	)
	(via
		(at 204.803756 -9.131808)
		(size 0.5588)
		(drill 0.3048)
		(layers "F.Cu" "B.Cu")
		(net "DRIVE_A_26_ACT")
	)
	(via
		(at 198.00189 -303.141126)
		(size 0.6604)
		(drill 0.3048)
		(layers "F.Cu" "B.Cu")
		(net "DRIVE_A_26_ACT")
	)
	(segment
		(start 269.24 -301.4472)
		(end 272.9992 -301.4472)
		(width 0.13335)
		(layer "In2.Cu")
		(net "DRIVE_A_26_ACT")
	)
	(segment
		(start 283.608272 -304.333656)
		(end 284.236668 -303.70526)
		(width 0.13335)
		(layer "In2.Cu")
		(net "DRIVE_A_26_ACT")
	)
	(segment
		(start 198.00189 -303.141126)
		(end 202.886564 -308.0258)
		(width 0.13335)
		(layer "In2.Cu")
		(net "DRIVE_A_26_ACT")
	)
	(segment
		(start 275.885656 -304.333656)
		(end 283.608272 -304.333656)
		(width 0.13335)
		(layer "In2.Cu")
		(net "DRIVE_A_26_ACT")
	)
	(segment
		(start 272.9992 -301.4472)
		(end 275.885656 -304.333656)
		(width 0.13335)
		(layer "In2.Cu")
		(net "DRIVE_A_26_ACT")
	)
	(segment
		(start 262.6614 -308.0258)
		(end 269.24 -301.4472)
		(width 0.13335)
		(layer "In2.Cu")
		(net "DRIVE_A_26_ACT")
	)
	(segment
		(start 202.886564 -308.0258)
		(end 262.6614 -308.0258)
		(width 0.13335)
		(layer "In2.Cu")
		(net "DRIVE_A_26_ACT")
	)
	(segment
		(start 212.249004 -59.871356)
		(end 207.319372 -54.941724)
		(width 0.12065)
		(layer "In4.Cu")
		(net "DRIVE_A_26_ACT")
	)
	(segment
		(start 196.703188 -283.927804)
		(end 203.058268 -277.572724)
		(width 0.12065)
		(layer "In4.Cu")
		(net "DRIVE_A_26_ACT")
	)
	(segment
		(start 198.00189 -303.141126)
		(end 196.598032 -301.737268)
		(width 0.12065)
		(layer "In4.Cu")
		(net "DRIVE_A_26_ACT")
	)
	(segment
		(start 196.598032 -301.737268)
		(end 196.598032 -284.445964)
		(width 0.12065)
		(layer "In4.Cu")
		(net "DRIVE_A_26_ACT")
	)
	(segment
		(start 212.249004 -71.786242)
		(end 212.249004 -59.871356)
		(width 0.12065)
		(layer "In4.Cu")
		(net "DRIVE_A_26_ACT")
	)
	(segment
		(start 207.99044 -76.044806)
		(end 212.249004 -71.786242)
		(width 0.12065)
		(layer "In4.Cu")
		(net "DRIVE_A_26_ACT")
	)
	(segment
		(start 207.319372 -54.941724)
		(end 207.319372 -13.286232)
		(width 0.12065)
		(layer "In4.Cu")
		(net "DRIVE_A_26_ACT")
	)
	(segment
		(start 204.799946 -9.135618)
		(end 204.803756 -9.131808)
		(width 0.12065)
		(layer "In4.Cu")
		(net "DRIVE_A_26_ACT")
	)
	(segment
		(start 203.058268 -277.572724)
		(end 203.058268 -201.552556)
		(width 0.12065)
		(layer "In4.Cu")
		(net "DRIVE_A_26_ACT")
	)
	(segment
		(start 196.601334 -284.23616)
		(end 196.703188 -284.134306)
		(width 0.12065)
		(layer "In4.Cu")
		(net "DRIVE_A_26_ACT")
	)
	(segment
		(start 211.091018 -148.519134)
		(end 207.99044 -145.418556)
		(width 0.12065)
		(layer "In4.Cu")
		(net "DRIVE_A_26_ACT")
	)
	(segment
		(start 207.319372 -13.286232)
		(end 204.799946 -10.766806)
		(width 0.12065)
		(layer "In4.Cu")
		(net "DRIVE_A_26_ACT")
	)
	(segment
		(start 204.799946 -10.766806)
		(end 204.799946 -9.135618)
		(width 0.12065)
		(layer "In4.Cu")
		(net "DRIVE_A_26_ACT")
	)
	(segment
		(start 196.703188 -284.134306)
		(end 196.703188 -283.927804)
		(width 0.12065)
		(layer "In4.Cu")
		(net "DRIVE_A_26_ACT")
	)
	(segment
		(start 196.598032 -284.445964)
		(end 196.601334 -284.442662)
		(width 0.12065)
		(layer "In4.Cu")
		(net "DRIVE_A_26_ACT")
	)
	(segment
		(start 203.058268 -201.552556)
		(end 211.091018 -193.519806)
		(width 0.12065)
		(layer "In4.Cu")
		(net "DRIVE_A_26_ACT")
	)
	(segment
		(start 196.601334 -284.442662)
		(end 196.601334 -284.23616)
		(width 0.12065)
		(layer "In4.Cu")
		(net "DRIVE_A_26_ACT")
	)
	(segment
		(start 211.091018 -193.519806)
		(end 211.091018 -148.519134)
		(width 0.12065)
		(layer "In4.Cu")
		(net "DRIVE_A_26_ACT")
	)
	(segment
		(start 207.99044 -145.418556)
		(end 207.99044 -76.044806)
		(width 0.12065)
		(layer "In4.Cu")
		(net "DRIVE_A_26_ACT")
	)
	(segment
		(start 248.67108 -241.2238)
		(end 248.67108 -242.8748)
		(width 0.17145)
		(layer "F.Cu")
		(net "DRIVE_A_25_PWR")
	)
	(segment
		(start 248.67108 -239.8014)
		(end 248.67108 -241.2238)
		(width 0.17145)
		(layer "F.Cu")
		(net "DRIVE_A_25_PWR")
	)
	(segment
		(start 54.990746 -44.871894)
		(end 55.816246 -44.871894)
		(width 0.17145)
		(layer "F.Cu")
		(net "DRIVE_A_25_PWR")
	)
	(via
		(at 69.4182 -249.3518)
		(size 0.5588)
		(drill 0.3048)
		(layers "F.Cu" "B.Cu")
		(net "DRIVE_A_25_PWR")
	)
	(via
		(at 248.67108 -241.2238)
		(size 0.6604)
		(drill 0.3302)
		(layers "F.Cu" "B.Cu")
		(net "DRIVE_A_25_PWR")
	)
	(via
		(at 55.816246 -44.871894)
		(size 0.5588)
		(drill 0.3048)
		(layers "F.Cu" "B.Cu")
		(net "DRIVE_A_25_PWR")
	)
	(via
		(at 248.67108 -242.8748)
		(size 0.5588)
		(drill 0.3048)
		(layers "F.Cu" "B.Cu")
		(net "DRIVE_A_25_PWR")
	)
	(segment
		(start 241.401854 -246.037354)
		(end 246.214646 -246.037354)
		(width 0.13335)
		(layer "In2.Cu")
		(net "DRIVE_A_25_PWR")
	)
	(segment
		(start 221.436184 -247.8532)
		(end 225.830384 -243.459)
		(width 0.13335)
		(layer "In2.Cu")
		(net "DRIVE_A_25_PWR")
	)
	(segment
		(start 69.4182 -249.3518)
		(end 71.291704 -249.3518)
		(width 0.13335)
		(layer "In2.Cu")
		(net "DRIVE_A_25_PWR")
	)
	(segment
		(start 238.596678 -246.037608)
		(end 241.4016 -246.037608)
		(width 0.13335)
		(layer "In2.Cu")
		(net "DRIVE_A_25_PWR")
	)
	(segment
		(start 236.01807 -243.459)
		(end 238.596678 -246.037608)
		(width 0.13335)
		(layer "In2.Cu")
		(net "DRIVE_A_25_PWR")
	)
	(segment
		(start 241.4016 -246.037608)
		(end 241.401854 -246.037354)
		(width 0.13335)
		(layer "In2.Cu")
		(net "DRIVE_A_25_PWR")
	)
	(segment
		(start 71.926704 -248.7168)
		(end 73.2028 -248.7168)
		(width 0.13335)
		(layer "In2.Cu")
		(net "DRIVE_A_25_PWR")
	)
	(segment
		(start 247.9294 -243.61648)
		(end 248.67108 -242.8748)
		(width 0.13335)
		(layer "In2.Cu")
		(net "DRIVE_A_25_PWR")
	)
	(segment
		(start 225.830384 -243.459)
		(end 236.01807 -243.459)
		(width 0.13335)
		(layer "In2.Cu")
		(net "DRIVE_A_25_PWR")
	)
	(segment
		(start 74.0664 -247.8532)
		(end 221.436184 -247.8532)
		(width 0.13335)
		(layer "In2.Cu")
		(net "DRIVE_A_25_PWR")
	)
	(segment
		(start 71.291704 -249.3518)
		(end 71.926704 -248.7168)
		(width 0.13335)
		(layer "In2.Cu")
		(net "DRIVE_A_25_PWR")
	)
	(segment
		(start 246.214646 -246.037354)
		(end 247.9294 -244.3226)
		(width 0.13335)
		(layer "In2.Cu")
		(net "DRIVE_A_25_PWR")
	)
	(segment
		(start 247.9294 -244.3226)
		(end 247.9294 -243.61648)
		(width 0.13335)
		(layer "In2.Cu")
		(net "DRIVE_A_25_PWR")
	)
	(segment
		(start 73.2028 -248.7168)
		(end 74.0664 -247.8532)
		(width 0.13335)
		(layer "In2.Cu")
		(net "DRIVE_A_25_PWR")
	)
	(segment
		(start 77.229462 -142.244064)
		(end 66.699638 -131.71424)
		(width 0.12065)
		(layer "In4.Cu")
		(net "DRIVE_A_25_PWR")
	)
	(segment
		(start 72.780144 -189.017656)
		(end 72.780144 -159.742124)
		(width 0.12065)
		(layer "In4.Cu")
		(net "DRIVE_A_25_PWR")
	)
	(segment
		(start 66.699638 -131.71424)
		(end 66.699638 -62.203838)
		(width 0.12065)
		(layer "In4.Cu")
		(net "DRIVE_A_25_PWR")
	)
	(segment
		(start 54.3814 -49.8856)
		(end 54.3814 -46.30674)
		(width 0.12065)
		(layer "In4.Cu")
		(net "DRIVE_A_25_PWR")
	)
	(segment
		(start 66.699638 -62.203838)
		(end 54.3814 -49.8856)
		(width 0.12065)
		(layer "In4.Cu")
		(net "DRIVE_A_25_PWR")
	)
	(segment
		(start 69.342 -249.2756)
		(end 69.342 -192.4558)
		(width 0.12065)
		(layer "In4.Cu")
		(net "DRIVE_A_25_PWR")
	)
	(segment
		(start 54.3814 -46.30674)
		(end 55.816246 -44.871894)
		(width 0.12065)
		(layer "In4.Cu")
		(net "DRIVE_A_25_PWR")
	)
	(segment
		(start 69.4182 -249.3518)
		(end 69.342 -249.2756)
		(width 0.12065)
		(layer "In4.Cu")
		(net "DRIVE_A_25_PWR")
	)
	(segment
		(start 72.780144 -159.742124)
		(end 77.229462 -155.292806)
		(width 0.12065)
		(layer "In4.Cu")
		(net "DRIVE_A_25_PWR")
	)
	(segment
		(start 77.229462 -155.292806)
		(end 77.229462 -142.244064)
		(width 0.12065)
		(layer "In4.Cu")
		(net "DRIVE_A_25_PWR")
	)
	(segment
		(start 69.342 -192.4558)
		(end 72.780144 -189.017656)
		(width 0.12065)
		(layer "In4.Cu")
		(net "DRIVE_A_25_PWR")
	)
	(segment
		(start 68.490846 -67.630294)
		(end 68.490846 -66.2432)
		(width 0.17145)
		(layer "F.Cu")
		(net "DRIVE_A_25_INS")
	)
	(segment
		(start 247.40108 -257.7084)
		(end 247.40108 -259.6896)
		(width 0.17145)
		(layer "F.Cu")
		(net "DRIVE_A_25_INS")
	)
	(segment
		(start 68.490846 -66.2432)
		(end 68.490846 -65.064894)
		(width 0.17145)
		(layer "F.Cu")
		(net "DRIVE_A_25_INS")
	)
	(via
		(at 71.4248 -262.382)
		(size 0.5588)
		(drill 0.3048)
		(layers "F.Cu" "B.Cu")
		(net "DRIVE_A_25_INS")
	)
	(via
		(at 68.490846 -67.630294)
		(size 0.5588)
		(drill 0.3048)
		(layers "F.Cu" "B.Cu")
		(net "DRIVE_A_25_INS")
	)
	(via
		(at 247.40108 -259.6896)
		(size 0.5588)
		(drill 0.3048)
		(layers "F.Cu" "B.Cu")
		(net "DRIVE_A_25_INS")
	)
	(via
		(at 68.490846 -66.2432)
		(size 0.6604)
		(drill 0.3302)
		(layers "F.Cu" "B.Cu")
		(net "DRIVE_A_25_INS")
	)
	(segment
		(start 246.8372 -260.25348)
		(end 246.8372 -260.989064)
		(width 0.13335)
		(layer "In2.Cu")
		(net "DRIVE_A_25_INS")
	)
	(segment
		(start 193.274696 -262.546592)
		(end 74.64806 -262.546592)
		(width 0.13335)
		(layer "In2.Cu")
		(net "DRIVE_A_25_INS")
	)
	(segment
		(start 247.40108 -259.6896)
		(end 246.8372 -260.25348)
		(width 0.13335)
		(layer "In2.Cu")
		(net "DRIVE_A_25_INS")
	)
	(segment
		(start 244.12194 -263.704324)
		(end 231.879648 -263.704324)
		(width 0.13335)
		(layer "In2.Cu")
		(net "DRIVE_A_25_INS")
	)
	(segment
		(start 74.483468 -262.382)
		(end 71.4248 -262.382)
		(width 0.13335)
		(layer "In2.Cu")
		(net "DRIVE_A_25_INS")
	)
	(segment
		(start 246.8372 -260.989064)
		(end 244.12194 -263.704324)
		(width 0.13335)
		(layer "In2.Cu")
		(net "DRIVE_A_25_INS")
	)
	(segment
		(start 231.075992 -262.900668)
		(end 193.628772 -262.900668)
		(width 0.13335)
		(layer "In2.Cu")
		(net "DRIVE_A_25_INS")
	)
	(segment
		(start 231.879648 -263.704324)
		(end 231.075992 -262.900668)
		(width 0.13335)
		(layer "In2.Cu")
		(net "DRIVE_A_25_INS")
	)
	(segment
		(start 193.628772 -262.900668)
		(end 193.274696 -262.546592)
		(width 0.13335)
		(layer "In2.Cu")
		(net "DRIVE_A_25_INS")
	)
	(segment
		(start 74.64806 -262.546592)
		(end 74.483468 -262.382)
		(width 0.13335)
		(layer "In2.Cu")
		(net "DRIVE_A_25_INS")
	)
	(segment
		(start 71.4248 -262.382)
		(end 70.4596 -261.4168)
		(width 0.12065)
		(layer "In4.Cu")
		(net "DRIVE_A_25_INS")
	)
	(segment
		(start 67.969638 -132.193792)
		(end 67.969638 -68.151502)
		(width 0.12065)
		(layer "In4.Cu")
		(net "DRIVE_A_25_INS")
	)
	(segment
		(start 73.338944 -189.37986)
		(end 73.338944 -159.973772)
		(width 0.12065)
		(layer "In4.Cu")
		(net "DRIVE_A_25_INS")
	)
	(segment
		(start 67.969638 -68.151502)
		(end 68.490846 -67.630294)
		(width 0.12065)
		(layer "In4.Cu")
		(net "DRIVE_A_25_INS")
	)
	(segment
		(start 73.338944 -159.973772)
		(end 77.80655 -155.506166)
		(width 0.12065)
		(layer "In4.Cu")
		(net "DRIVE_A_25_INS")
	)
	(segment
		(start 77.80655 -155.506166)
		(end 77.80655 -142.030704)
		(width 0.12065)
		(layer "In4.Cu")
		(net "DRIVE_A_25_INS")
	)
	(segment
		(start 70.4596 -261.4168)
		(end 70.4596 -192.259204)
		(width 0.12065)
		(layer "In4.Cu")
		(net "DRIVE_A_25_INS")
	)
	(segment
		(start 77.80655 -142.030704)
		(end 67.969638 -132.193792)
		(width 0.12065)
		(layer "In4.Cu")
		(net "DRIVE_A_25_INS")
	)
	(segment
		(start 70.4596 -192.259204)
		(end 73.338944 -189.37986)
		(width 0.12065)
		(layer "In4.Cu")
		(net "DRIVE_A_25_INS")
	)
	(segment
		(start 211.799932 -0.112014)
		(end 211.752434 -0.064516)
		(width 0.17145)
		(layer "F.Cu")
		(net "DRIVE_A_25_FLT_LED")
	)
	(segment
		(start 285.454852 -277.5712)
		(end 286.17164 -276.854412)
		(width 0.17145)
		(layer "F.Cu")
		(net "DRIVE_A_25_FLT_LED")
	)
	(segment
		(start 286.17164 -276.854412)
		(end 286.17164 -275.5646)
		(width 0.17145)
		(layer "F.Cu")
		(net "DRIVE_A_25_FLT_LED")
	)
	(segment
		(start 211.799932 -1.450086)
		(end 211.799932 -0.112014)
		(width 0.17145)
		(layer "F.Cu")
		(net "DRIVE_A_25_FLT_LED")
	)
	(via
		(at 286.70631 8.711438)
		(size 0.5588)
		(drill 0.3048)
		(layers "F.Cu" "B.Cu")
		(net "DRIVE_A_25_FLT_LED")
	)
	(via
		(at 211.752434 -0.064516)
		(size 0.5588)
		(drill 0.3048)
		(layers "F.Cu" "B.Cu")
		(net "DRIVE_A_25_FLT_LED")
	)
	(via
		(at 285.454852 -277.5712)
		(size 0.5588)
		(drill 0.3048)
		(layers "F.Cu" "B.Cu")
		(net "DRIVE_A_25_FLT_LED")
	)
	(segment
		(start 291.172392 -43.97883)
		(end 291.176202 -43.98264)
		(width 0.12065)
		(layer "In4.Cu")
		(net "DRIVE_A_25_FLT_LED")
	)
	(segment
		(start 293.5986 -268.3764)
		(end 285.454852 -276.520148)
		(width 0.12065)
		(layer "In4.Cu")
		(net "DRIVE_A_25_FLT_LED")
	)
	(segment
		(start 291.172392 4.245356)
		(end 291.172392 -43.97883)
		(width 0.12065)
		(layer "In4.Cu")
		(net "DRIVE_A_25_FLT_LED")
	)
	(segment
		(start 291.301424 -106.660442)
		(end 291.301424 -106.685588)
		(width 0.12065)
		(layer "In4.Cu")
		(net "DRIVE_A_25_FLT_LED")
	)
	(segment
		(start 291.176202 -44.732956)
		(end 291.172392 -44.736766)
		(width 0.12065)
		(layer "In4.Cu")
		(net "DRIVE_A_25_FLT_LED")
	)
	(segment
		(start 291.172392 -106.53141)
		(end 291.301424 -106.660442)
		(width 0.12065)
		(layer "In4.Cu")
		(net "DRIVE_A_25_FLT_LED")
	)
	(segment
		(start 291.172392 -44.736766)
		(end 291.172392 -106.53141)
		(width 0.12065)
		(layer "In4.Cu")
		(net "DRIVE_A_25_FLT_LED")
	)
	(segment
		(start 291.44722 -106.831384)
		(end 291.44722 -253.9619)
		(width 0.12065)
		(layer "In4.Cu")
		(net "DRIVE_A_25_FLT_LED")
	)
	(segment
		(start 291.44722 -253.9619)
		(end 293.5986 -256.11328)
		(width 0.12065)
		(layer "In4.Cu")
		(net "DRIVE_A_25_FLT_LED")
	)
	(segment
		(start 293.5986 -256.11328)
		(end 293.5986 -268.3764)
		(width 0.12065)
		(layer "In4.Cu")
		(net "DRIVE_A_25_FLT_LED")
	)
	(segment
		(start 291.301424 -106.685588)
		(end 291.44722 -106.831384)
		(width 0.12065)
		(layer "In4.Cu")
		(net "DRIVE_A_25_FLT_LED")
	)
	(segment
		(start 291.176202 -43.98264)
		(end 291.176202 -44.732956)
		(width 0.12065)
		(layer "In4.Cu")
		(net "DRIVE_A_25_FLT_LED")
	)
	(segment
		(start 285.454852 -276.520148)
		(end 285.454852 -277.5712)
		(width 0.12065)
		(layer "In4.Cu")
		(net "DRIVE_A_25_FLT_LED")
	)
	(segment
		(start 286.70631 8.711438)
		(end 291.172392 4.245356)
		(width 0.12065)
		(layer "In4.Cu")
		(net "DRIVE_A_25_FLT_LED")
	)
	(segment
		(start 286.70631 8.711438)
		(end 285.26359 8.711438)
		(width 0.13335)
		(layer "In9.Cu")
		(net "DRIVE_A_25_FLT_LED")
	)
	(segment
		(start 233.713782 -1.734566)
		(end 213.422484 -1.734566)
		(width 0.13335)
		(layer "In9.Cu")
		(net "DRIVE_A_25_FLT_LED")
	)
	(segment
		(start 278.25319 1.701038)
		(end 237.149386 1.701038)
		(width 0.13335)
		(layer "In9.Cu")
		(net "DRIVE_A_25_FLT_LED")
	)
	(segment
		(start 213.422484 -1.734566)
		(end 211.752434 -0.064516)
		(width 0.13335)
		(layer "In9.Cu")
		(net "DRIVE_A_25_FLT_LED")
	)
	(segment
		(start 237.149386 1.701038)
		(end 233.713782 -1.734566)
		(width 0.13335)
		(layer "In9.Cu")
		(net "DRIVE_A_25_FLT_LED")
	)
	(segment
		(start 285.26359 8.711438)
		(end 278.25319 1.701038)
		(width 0.13335)
		(layer "In9.Cu")
		(net "DRIVE_A_25_FLT_LED")
	)
	(segment
		(start 212.79993 -0.18415)
		(end 211.765896 0.849884)
		(width 0.17145)
		(layer "F.Cu")
		(net "DRIVE_A_25_ACT")
	)
	(segment
		(start 212.79993 -1.450086)
		(end 212.79993 -0.18415)
		(width 0.17145)
		(layer "F.Cu")
		(net "DRIVE_A_25_ACT")
	)
	(via
		(at 211.765896 0.849884)
		(size 0.5588)
		(drill 0.3048)
		(layers "F.Cu" "B.Cu")
		(net "DRIVE_A_25_ACT")
	)
	(via
		(at 273.312128 -302.550576)
		(size 0.5588)
		(drill 0.3048)
		(layers "F.Cu" "B.Cu")
		(net "DRIVE_A_25_ACT")
	)
	(via
		(at 199.274176 -306.318412)
		(size 0.6604)
		(drill 0.3048)
		(layers "F.Cu" "B.Cu")
		(net "DRIVE_A_25_ACT")
	)
	(segment
		(start 201.540364 -308.5846)
		(end 263.293352 -308.5846)
		(width 0.13335)
		(layer "In2.Cu")
		(net "DRIVE_A_25_ACT")
	)
	(segment
		(start 269.327376 -302.550576)
		(end 273.312128 -302.550576)
		(width 0.13335)
		(layer "In2.Cu")
		(net "DRIVE_A_25_ACT")
	)
	(segment
		(start 263.293352 -308.5846)
		(end 269.327376 -302.550576)
		(width 0.13335)
		(layer "In2.Cu")
		(net "DRIVE_A_25_ACT")
	)
	(segment
		(start 199.274176 -306.318412)
		(end 201.540364 -308.5846)
		(width 0.13335)
		(layer "In2.Cu")
		(net "DRIVE_A_25_ACT")
	)
	(segment
		(start 280.916126 -306.4256)
		(end 275.2852 -306.4256)
		(width 0.12065)
		(layer "In4.Cu")
		(net "DRIVE_A_25_ACT")
	)
	(segment
		(start 209.727546 -10.225278)
		(end 212.28685 -7.665974)
		(width 0.12065)
		(layer "In4.Cu")
		(net "DRIVE_A_25_ACT")
	)
	(segment
		(start 275.2852 -306.4256)
		(end 273.312128 -304.452528)
		(width 0.12065)
		(layer "In4.Cu")
		(net "DRIVE_A_25_ACT")
	)
	(segment
		(start 215.155272 -58.667142)
		(end 209.727546 -53.239416)
		(width 0.12065)
		(layer "In4.Cu")
		(net "DRIVE_A_25_ACT")
	)
	(segment
		(start 199.274176 -285.309056)
		(end 205.852268 -278.730964)
		(width 0.12065)
		(layer "In4.Cu")
		(net "DRIVE_A_25_ACT")
	)
	(segment
		(start 212.28685 -7.665974)
		(end 212.28685 0.32639)
		(width 0.12065)
		(layer "In4.Cu")
		(net "DRIVE_A_25_ACT")
	)
	(segment
		(start 209.727546 -53.239416)
		(end 209.727546 -10.225278)
		(width 0.12065)
		(layer "In4.Cu")
		(net "DRIVE_A_25_ACT")
	)
	(segment
		(start 205.852268 -202.710796)
		(end 213.885018 -194.678046)
		(width 0.12065)
		(layer "In4.Cu")
		(net "DRIVE_A_25_ACT")
	)
	(segment
		(start 212.28685 0.32639)
		(end 211.763356 0.849884)
		(width 0.12065)
		(layer "In4.Cu")
		(net "DRIVE_A_25_ACT")
	)
	(segment
		(start 199.274176 -306.318412)
		(end 199.274176 -285.309056)
		(width 0.12065)
		(layer "In4.Cu")
		(net "DRIVE_A_25_ACT")
	)
	(segment
		(start 210.964272 -77.023214)
		(end 215.155272 -72.832214)
		(width 0.12065)
		(layer "In4.Cu")
		(net "DRIVE_A_25_ACT")
	)
	(segment
		(start 210.964272 -144.440148)
		(end 210.964272 -77.023214)
		(width 0.12065)
		(layer "In4.Cu")
		(net "DRIVE_A_25_ACT")
	)
	(segment
		(start 205.852268 -278.730964)
		(end 205.852268 -202.710796)
		(width 0.12065)
		(layer "In4.Cu")
		(net "DRIVE_A_25_ACT")
	)
	(segment
		(start 215.155272 -72.832214)
		(end 215.155272 -58.667142)
		(width 0.12065)
		(layer "In4.Cu")
		(net "DRIVE_A_25_ACT")
	)
	(segment
		(start 281.836622 -305.505104)
		(end 280.916126 -306.4256)
		(width 0.12065)
		(layer "In4.Cu")
		(net "DRIVE_A_25_ACT")
	)
	(segment
		(start 213.885018 -194.678046)
		(end 213.885018 -147.360894)
		(width 0.12065)
		(layer "In4.Cu")
		(net "DRIVE_A_25_ACT")
	)
	(segment
		(start 273.312128 -304.452528)
		(end 273.312128 -302.550576)
		(width 0.12065)
		(layer "In4.Cu")
		(net "DRIVE_A_25_ACT")
	)
	(segment
		(start 213.885018 -147.360894)
		(end 210.964272 -144.440148)
		(width 0.12065)
		(layer "In4.Cu")
		(net "DRIVE_A_25_ACT")
	)
	(segment
		(start 211.763356 0.849884)
		(end 211.765896 0.849884)
		(width 0.12065)
		(layer "In4.Cu")
		(net "DRIVE_A_25_ACT")
	)
	(segment
		(start 23.415498 -44.871894)
		(end 24.240998 -44.871894)
		(width 0.17145)
		(layer "F.Cu")
		(net "DRIVE_A_24_PWR")
	)
	(segment
		(start 249.32132 -242.1382)
		(end 249.32132 -239.8014)
		(width 0.17145)
		(layer "F.Cu")
		(net "DRIVE_A_24_PWR")
	)
	(segment
		(start 248.67108 -243.84)
		(end 249.32132 -243.18976)
		(width 0.17145)
		(layer "F.Cu")
		(net "DRIVE_A_24_PWR")
	)
	(segment
		(start 249.32132 -243.18976)
		(end 249.32132 -242.1382)
		(width 0.17145)
		(layer "F.Cu")
		(net "DRIVE_A_24_PWR")
	)
	(via
		(at 249.32132 -242.1382)
		(size 0.6604)
		(drill 0.3302)
		(layers "F.Cu" "B.Cu")
		(net "DRIVE_A_24_PWR")
	)
	(via
		(at 248.67108 -243.84)
		(size 0.5588)
		(drill 0.3048)
		(layers "F.Cu" "B.Cu")
		(net "DRIVE_A_24_PWR")
	)
	(via
		(at 24.240998 -44.871894)
		(size 0.5588)
		(drill 0.3048)
		(layers "F.Cu" "B.Cu")
		(net "DRIVE_A_24_PWR")
	)
	(via
		(at 68.0974 -249.5042)
		(size 0.5588)
		(drill 0.3048)
		(layers "F.Cu" "B.Cu")
		(net "DRIVE_A_24_PWR")
	)
	(segment
		(start 68.5038 -249.9106)
		(end 71.523352 -249.9106)
		(width 0.13335)
		(layer "In2.Cu")
		(net "DRIVE_A_24_PWR")
	)
	(segment
		(start 71.523352 -249.9106)
		(end 72.082152 -249.3518)
		(width 0.13335)
		(layer "In2.Cu")
		(net "DRIVE_A_24_PWR")
	)
	(segment
		(start 68.0974 -249.5042)
		(end 68.5038 -249.9106)
		(width 0.13335)
		(layer "In2.Cu")
		(net "DRIVE_A_24_PWR")
	)
	(segment
		(start 246.443246 -246.596154)
		(end 248.67108 -244.36832)
		(width 0.13335)
		(layer "In2.Cu")
		(net "DRIVE_A_24_PWR")
	)
	(segment
		(start 241.633502 -246.596154)
		(end 246.443246 -246.596154)
		(width 0.13335)
		(layer "In2.Cu")
		(net "DRIVE_A_24_PWR")
	)
	(segment
		(start 248.67108 -244.36832)
		(end 248.67108 -243.84)
		(width 0.13335)
		(layer "In2.Cu")
		(net "DRIVE_A_24_PWR")
	)
	(segment
		(start 235.786422 -244.0178)
		(end 238.36503 -246.596408)
		(width 0.13335)
		(layer "In2.Cu")
		(net "DRIVE_A_24_PWR")
	)
	(segment
		(start 72.082152 -249.3518)
		(end 220.728032 -249.3518)
		(width 0.13335)
		(layer "In2.Cu")
		(net "DRIVE_A_24_PWR")
	)
	(segment
		(start 238.36503 -246.596408)
		(end 241.633248 -246.596408)
		(width 0.13335)
		(layer "In2.Cu")
		(net "DRIVE_A_24_PWR")
	)
	(segment
		(start 226.062032 -244.0178)
		(end 235.786422 -244.0178)
		(width 0.13335)
		(layer "In2.Cu")
		(net "DRIVE_A_24_PWR")
	)
	(segment
		(start 220.728032 -249.3518)
		(end 226.062032 -244.0178)
		(width 0.13335)
		(layer "In2.Cu")
		(net "DRIVE_A_24_PWR")
	)
	(segment
		(start 241.633248 -246.596408)
		(end 241.633502 -246.596154)
		(width 0.13335)
		(layer "In2.Cu")
		(net "DRIVE_A_24_PWR")
	)
	(segment
		(start 65.429638 -75.030838)
		(end 64.3128 -73.914)
		(width 0.12065)
		(layer "In4.Cu")
		(net "DRIVE_A_24_PWR")
	)
	(segment
		(start 64.3128 -73.914)
		(end 37.2364 -73.914)
		(width 0.12065)
		(layer "In4.Cu")
		(net "DRIVE_A_24_PWR")
	)
	(segment
		(start 68.7451 -186.191652)
		(end 71.374 -183.562752)
		(width 0.12065)
		(layer "In4.Cu")
		(net "DRIVE_A_24_PWR")
	)
	(segment
		(start 23.3172 -59.9948)
		(end 23.3172 -50.4698)
		(width 0.12065)
		(layer "In4.Cu")
		(net "DRIVE_A_24_PWR")
	)
	(segment
		(start 65.429638 -132.025136)
		(end 65.429638 -75.030838)
		(width 0.12065)
		(layer "In4.Cu")
		(net "DRIVE_A_24_PWR")
	)
	(segment
		(start 70.7898 -160.151572)
		(end 76.111862 -154.82951)
		(width 0.12065)
		(layer "In4.Cu")
		(net "DRIVE_A_24_PWR")
	)
	(segment
		(start 68.0974 -249.5042)
		(end 68.0974 -191.6176)
		(width 0.12065)
		(layer "In4.Cu")
		(net "DRIVE_A_24_PWR")
	)
	(segment
		(start 70.7898 -178.7652)
		(end 70.7898 -160.151572)
		(width 0.12065)
		(layer "In4.Cu")
		(net "DRIVE_A_24_PWR")
	)
	(segment
		(start 71.374 -179.3494)
		(end 70.7898 -178.7652)
		(width 0.12065)
		(layer "In4.Cu")
		(net "DRIVE_A_24_PWR")
	)
	(segment
		(start 22.9108 -50.0634)
		(end 22.9108 -46.202092)
		(width 0.12065)
		(layer "In4.Cu")
		(net "DRIVE_A_24_PWR")
	)
	(segment
		(start 76.111862 -142.70736)
		(end 65.429638 -132.025136)
		(width 0.12065)
		(layer "In4.Cu")
		(net "DRIVE_A_24_PWR")
	)
	(segment
		(start 37.2364 -73.914)
		(end 23.3172 -59.9948)
		(width 0.12065)
		(layer "In4.Cu")
		(net "DRIVE_A_24_PWR")
	)
	(segment
		(start 76.111862 -154.82951)
		(end 76.111862 -142.70736)
		(width 0.12065)
		(layer "In4.Cu")
		(net "DRIVE_A_24_PWR")
	)
	(segment
		(start 68.7451 -190.9699)
		(end 68.7451 -186.191652)
		(width 0.12065)
		(layer "In4.Cu")
		(net "DRIVE_A_24_PWR")
	)
	(segment
		(start 23.3172 -50.4698)
		(end 22.9108 -50.0634)
		(width 0.12065)
		(layer "In4.Cu")
		(net "DRIVE_A_24_PWR")
	)
	(segment
		(start 68.0974 -191.6176)
		(end 68.7451 -190.9699)
		(width 0.12065)
		(layer "In4.Cu")
		(net "DRIVE_A_24_PWR")
	)
	(segment
		(start 22.9108 -46.202092)
		(end 24.240998 -44.871894)
		(width 0.12065)
		(layer "In4.Cu")
		(net "DRIVE_A_24_PWR")
	)
	(segment
		(start 71.374 -183.562752)
		(end 71.374 -179.3494)
		(width 0.12065)
		(layer "In4.Cu")
		(net "DRIVE_A_24_PWR")
	)
	(segment
		(start 248.05132 -260.00456)
		(end 248.05132 -257.7084)
		(width 0.17145)
		(layer "F.Cu")
		(net "DRIVE_A_24_INS")
	)
	(segment
		(start 247.40108 -260.6548)
		(end 248.05132 -260.00456)
		(width 0.17145)
		(layer "F.Cu")
		(net "DRIVE_A_24_INS")
	)
	(segment
		(start 36.940998 -66.3194)
		(end 36.940998 -67.452494)
		(width 0.17145)
		(layer "F.Cu")
		(net "DRIVE_A_24_INS")
	)
	(segment
		(start 36.940998 -65.064894)
		(end 36.940998 -66.3194)
		(width 0.17145)
		(layer "F.Cu")
		(net "DRIVE_A_24_INS")
	)
	(via
		(at 36.940998 -67.452494)
		(size 0.5588)
		(drill 0.3048)
		(layers "F.Cu" "B.Cu")
		(net "DRIVE_A_24_INS")
	)
	(via
		(at 247.40108 -260.6548)
		(size 0.5588)
		(drill 0.3048)
		(layers "F.Cu" "B.Cu")
		(net "DRIVE_A_24_INS")
	)
	(via
		(at 71.501 -263.332976)
		(size 0.5588)
		(drill 0.3048)
		(layers "F.Cu" "B.Cu")
		(net "DRIVE_A_24_INS")
	)
	(via
		(at 36.940998 -66.3194)
		(size 0.6604)
		(drill 0.3302)
		(layers "F.Cu" "B.Cu")
		(net "DRIVE_A_24_INS")
	)
	(segment
		(start 193.397124 -263.459468)
		(end 193.132456 -263.1948)
		(width 0.13335)
		(layer "In2.Cu")
		(net "DRIVE_A_24_INS")
	)
	(segment
		(start 231.057958 -263.870186)
		(end 230.64724 -263.459468)
		(width 0.13335)
		(layer "In2.Cu")
		(net "DRIVE_A_24_INS")
	)
	(segment
		(start 244.353588 -264.263124)
		(end 231.450642 -264.263124)
		(width 0.13335)
		(layer "In2.Cu")
		(net "DRIVE_A_24_INS")
	)
	(segment
		(start 74.749152 -263.1948)
		(end 74.610976 -263.332976)
		(width 0.13335)
		(layer "In2.Cu")
		(net "DRIVE_A_24_INS")
	)
	(segment
		(start 231.450642 -264.263124)
		(end 231.057958 -263.87044)
		(width 0.13335)
		(layer "In2.Cu")
		(net "DRIVE_A_24_INS")
	)
	(segment
		(start 231.057958 -263.87044)
		(end 231.057958 -263.870186)
		(width 0.13335)
		(layer "In2.Cu")
		(net "DRIVE_A_24_INS")
	)
	(segment
		(start 230.64724 -263.459468)
		(end 193.397124 -263.459468)
		(width 0.13335)
		(layer "In2.Cu")
		(net "DRIVE_A_24_INS")
	)
	(segment
		(start 247.40108 -260.6548)
		(end 247.40108 -261.215632)
		(width 0.13335)
		(layer "In2.Cu")
		(net "DRIVE_A_24_INS")
	)
	(segment
		(start 193.132456 -263.1948)
		(end 74.749152 -263.1948)
		(width 0.13335)
		(layer "In2.Cu")
		(net "DRIVE_A_24_INS")
	)
	(segment
		(start 74.610976 -263.332976)
		(end 71.501 -263.332976)
		(width 0.13335)
		(layer "In2.Cu")
		(net "DRIVE_A_24_INS")
	)
	(segment
		(start 247.40108 -261.215632)
		(end 244.353588 -264.263124)
		(width 0.13335)
		(layer "In2.Cu")
		(net "DRIVE_A_24_INS")
	)
	(segment
		(start 68.7324 -253.107952)
		(end 68.7324 -191.9224)
		(width 0.12065)
		(layer "In4.Cu")
		(net "DRIVE_A_24_INS")
	)
	(segment
		(start 69.3039 -186.4233)
		(end 72.0598 -183.6674)
		(width 0.12065)
		(layer "In4.Cu")
		(net "DRIVE_A_24_INS")
	)
	(segment
		(start 65.988438 -74.79919)
		(end 64.544194 -73.354946)
		(width 0.12065)
		(layer "In4.Cu")
		(net "DRIVE_A_24_INS")
	)
	(segment
		(start 76.670662 -142.475712)
		(end 65.988438 -131.793488)
		(width 0.12065)
		(layer "In4.Cu")
		(net "DRIVE_A_24_INS")
	)
	(segment
		(start 37.467794 -73.354946)
		(end 36.940998 -72.82815)
		(width 0.12065)
		(layer "In4.Cu")
		(net "DRIVE_A_24_INS")
	)
	(segment
		(start 69.3039 -191.3509)
		(end 69.3039 -186.4233)
		(width 0.12065)
		(layer "In4.Cu")
		(net "DRIVE_A_24_INS")
	)
	(segment
		(start 69.1134 -260.945376)
		(end 69.1134 -253.488952)
		(width 0.12065)
		(layer "In4.Cu")
		(net "DRIVE_A_24_INS")
	)
	(segment
		(start 68.7324 -191.9224)
		(end 69.3039 -191.3509)
		(width 0.12065)
		(layer "In4.Cu")
		(net "DRIVE_A_24_INS")
	)
	(segment
		(start 72.0598 -179.2224)
		(end 71.501 -178.6636)
		(width 0.12065)
		(layer "In4.Cu")
		(net "DRIVE_A_24_INS")
	)
	(segment
		(start 72.0598 -183.6674)
		(end 72.0598 -179.2224)
		(width 0.12065)
		(layer "In4.Cu")
		(net "DRIVE_A_24_INS")
	)
	(segment
		(start 71.501 -178.6636)
		(end 71.501 -160.23082)
		(width 0.12065)
		(layer "In4.Cu")
		(net "DRIVE_A_24_INS")
	)
	(segment
		(start 36.940998 -72.82815)
		(end 36.940998 -67.452494)
		(width 0.12065)
		(layer "In4.Cu")
		(net "DRIVE_A_24_INS")
	)
	(segment
		(start 71.501 -263.332976)
		(end 69.1134 -260.945376)
		(width 0.12065)
		(layer "In4.Cu")
		(net "DRIVE_A_24_INS")
	)
	(segment
		(start 76.670662 -155.061158)
		(end 76.670662 -142.475712)
		(width 0.12065)
		(layer "In4.Cu")
		(net "DRIVE_A_24_INS")
	)
	(segment
		(start 69.1134 -253.488952)
		(end 68.7324 -253.107952)
		(width 0.12065)
		(layer "In4.Cu")
		(net "DRIVE_A_24_INS")
	)
	(segment
		(start 71.501 -160.23082)
		(end 76.670662 -155.061158)
		(width 0.12065)
		(layer "In4.Cu")
		(net "DRIVE_A_24_INS")
	)
	(segment
		(start 64.544194 -73.354946)
		(end 37.467794 -73.354946)
		(width 0.12065)
		(layer "In4.Cu")
		(net "DRIVE_A_24_INS")
	)
	(segment
		(start 65.988438 -131.793488)
		(end 65.988438 -74.79919)
		(width 0.12065)
		(layer "In4.Cu")
		(net "DRIVE_A_24_INS")
	)
	(segment
		(start 209.799936 -1.450086)
		(end 209.799936 0.116332)
		(width 0.17145)
		(layer "F.Cu")
		(net "DRIVE_A_24_FLT_LED")
	)
	(segment
		(start 285.3944 -278.4856)
		(end 284.861 -277.9522)
		(width 0.17145)
		(layer "F.Cu")
		(net "DRIVE_A_24_FLT_LED")
	)
	(segment
		(start 285.5214 -276.5806)
		(end 285.5214 -275.5646)
		(width 0.17145)
		(layer "F.Cu")
		(net "DRIVE_A_24_FLT_LED")
	)
	(segment
		(start 284.861 -277.9522)
		(end 284.861 -277.241)
		(width 0.17145)
		(layer "F.Cu")
		(net "DRIVE_A_24_FLT_LED")
	)
	(segment
		(start 284.861 -277.241)
		(end 285.5214 -276.5806)
		(width 0.17145)
		(layer "F.Cu")
		(net "DRIVE_A_24_FLT_LED")
	)
	(via
		(at 285.502096 7.83336)
		(size 0.5588)
		(drill 0.3048)
		(layers "F.Cu" "B.Cu")
		(net "DRIVE_A_24_FLT_LED")
	)
	(via
		(at 209.799936 0.116332)
		(size 0.5588)
		(drill 0.3048)
		(layers "F.Cu" "B.Cu")
		(net "DRIVE_A_24_FLT_LED")
	)
	(via
		(at 285.3944 -278.4856)
		(size 0.5588)
		(drill 0.3048)
		(layers "F.Cu" "B.Cu")
		(net "DRIVE_A_24_FLT_LED")
	)
	(segment
		(start 290.68395 -1.733804)
		(end 290.68395 -44.074334)
		(width 0.12065)
		(layer "In4.Cu")
		(net "DRIVE_A_24_FLT_LED")
	)
	(segment
		(start 285.502096 7.83336)
		(end 290.495736 2.83972)
		(width 0.12065)
		(layer "In4.Cu")
		(net "DRIVE_A_24_FLT_LED")
	)
	(segment
		(start 290.495736 2.83972)
		(end 290.495736 -1.54559)
		(width 0.12065)
		(layer "In4.Cu")
		(net "DRIVE_A_24_FLT_LED")
	)
	(segment
		(start 284.861 -278.003)
		(end 285.3436 -278.4856)
		(width 0.12065)
		(layer "In4.Cu")
		(net "DRIVE_A_24_FLT_LED")
	)
	(segment
		(start 285.3436 -278.4856)
		(end 285.3944 -278.4856)
		(width 0.12065)
		(layer "In4.Cu")
		(net "DRIVE_A_24_FLT_LED")
	)
	(segment
		(start 290.763452 -44.153836)
		(end 290.763452 -44.56176)
		(width 0.12065)
		(layer "In4.Cu")
		(net "DRIVE_A_24_FLT_LED")
	)
	(segment
		(start 290.613592 -106.556556)
		(end 290.88842 -106.831384)
		(width 0.12065)
		(layer "In4.Cu")
		(net "DRIVE_A_24_FLT_LED")
	)
	(segment
		(start 290.88842 -106.831384)
		(end 290.88842 -254.193548)
		(width 0.12065)
		(layer "In4.Cu")
		(net "DRIVE_A_24_FLT_LED")
	)
	(segment
		(start 290.88842 -254.193548)
		(end 293.0398 -256.344928)
		(width 0.12065)
		(layer "In4.Cu")
		(net "DRIVE_A_24_FLT_LED")
	)
	(segment
		(start 290.613592 -44.71162)
		(end 290.613592 -106.556556)
		(width 0.12065)
		(layer "In4.Cu")
		(net "DRIVE_A_24_FLT_LED")
	)
	(segment
		(start 290.68395 -44.074334)
		(end 290.763452 -44.153836)
		(width 0.12065)
		(layer "In4.Cu")
		(net "DRIVE_A_24_FLT_LED")
	)
	(segment
		(start 284.861 -276.352)
		(end 284.861 -278.003)
		(width 0.12065)
		(layer "In4.Cu")
		(net "DRIVE_A_24_FLT_LED")
	)
	(segment
		(start 293.0398 -256.344928)
		(end 293.0398 -268.1732)
		(width 0.12065)
		(layer "In4.Cu")
		(net "DRIVE_A_24_FLT_LED")
	)
	(segment
		(start 290.763452 -44.56176)
		(end 290.613592 -44.71162)
		(width 0.12065)
		(layer "In4.Cu")
		(net "DRIVE_A_24_FLT_LED")
	)
	(segment
		(start 290.495736 -1.54559)
		(end 290.68395 -1.733804)
		(width 0.12065)
		(layer "In4.Cu")
		(net "DRIVE_A_24_FLT_LED")
	)
	(segment
		(start 293.0398 -268.1732)
		(end 284.861 -276.352)
		(width 0.12065)
		(layer "In4.Cu")
		(net "DRIVE_A_24_FLT_LED")
	)
	(segment
		(start 212.124798 -2.20853)
		(end 209.799936 0.116332)
		(width 0.13335)
		(layer "In9.Cu")
		(net "DRIVE_A_24_FLT_LED")
	)
	(segment
		(start 237.303564 1.227328)
		(end 233.867706 -2.20853)
		(width 0.13335)
		(layer "In9.Cu")
		(net "DRIVE_A_24_FLT_LED")
	)
	(segment
		(start 233.867706 -2.20853)
		(end 212.124798 -2.20853)
		(width 0.13335)
		(layer "In9.Cu")
		(net "DRIVE_A_24_FLT_LED")
	)
	(segment
		(start 285.092394 7.83336)
		(end 278.486362 1.227328)
		(width 0.13335)
		(layer "In9.Cu")
		(net "DRIVE_A_24_FLT_LED")
	)
	(segment
		(start 278.486362 1.227328)
		(end 237.303564 1.227328)
		(width 0.13335)
		(layer "In9.Cu")
		(net "DRIVE_A_24_FLT_LED")
	)
	(segment
		(start 285.502096 7.83336)
		(end 285.092394 7.83336)
		(width 0.13335)
		(layer "In9.Cu")
		(net "DRIVE_A_24_FLT_LED")
	)
	(segment
		(start 210.799934 -1.450086)
		(end 210.799934 0.116332)
		(width 0.17145)
		(layer "F.Cu")
		(net "DRIVE_A_24_ACT")
	)
	(via
		(at 199.274176 -307.385212)
		(size 0.6604)
		(drill 0.3048)
		(layers "F.Cu" "B.Cu")
		(net "DRIVE_A_24_ACT")
	)
	(via
		(at 210.799934 0.116332)
		(size 0.5588)
		(drill 0.3048)
		(layers "F.Cu" "B.Cu")
		(net "DRIVE_A_24_ACT")
	)
	(segment
		(start 282.290774 -306.451)
		(end 283.23667 -305.505104)
		(width 0.13335)
		(layer "In2.Cu")
		(net "DRIVE_A_24_ACT")
	)
	(segment
		(start 201.032364 -309.1434)
		(end 263.525 -309.1434)
		(width 0.13335)
		(layer "In2.Cu")
		(net "DRIVE_A_24_ACT")
	)
	(segment
		(start 263.525 -309.1434)
		(end 266.2174 -306.451)
		(width 0.13335)
		(layer "In2.Cu")
		(net "DRIVE_A_24_ACT")
	)
	(segment
		(start 199.274176 -307.385212)
		(end 201.032364 -309.1434)
		(width 0.13335)
		(layer "In2.Cu")
		(net "DRIVE_A_24_ACT")
	)
	(segment
		(start 266.2174 -306.451)
		(end 282.290774 -306.451)
		(width 0.13335)
		(layer "In2.Cu")
		(net "DRIVE_A_24_ACT")
	)
	(segment
		(start 205.293468 -202.479148)
		(end 205.293468 -278.499316)
		(width 0.12065)
		(layer "In4.Cu")
		(net "DRIVE_A_24_ACT")
	)
	(segment
		(start 198.781924 -285.01086)
		(end 198.781924 -306.89296)
		(width 0.12065)
		(layer "In4.Cu")
		(net "DRIVE_A_24_ACT")
	)
	(segment
		(start 198.781924 -306.89296)
		(end 199.274176 -307.385212)
		(width 0.12065)
		(layer "In4.Cu")
		(net "DRIVE_A_24_ACT")
	)
	(segment
		(start 209.313018 -53.824632)
		(end 214.44839 -58.960004)
		(width 0.12065)
		(layer "In4.Cu")
		(net "DRIVE_A_24_ACT")
	)
	(segment
		(start 209.313018 -9.408668)
		(end 209.313018 -53.824632)
		(width 0.12065)
		(layer "In4.Cu")
		(net "DRIVE_A_24_ACT")
	)
	(segment
		(start 210.405472 -76.791566)
		(end 210.405472 -144.671796)
		(width 0.12065)
		(layer "In4.Cu")
		(net "DRIVE_A_24_ACT")
	)
	(segment
		(start 214.44839 -71.13143)
		(end 214.459058 -71.142098)
		(width 0.12065)
		(layer "In4.Cu")
		(net "DRIVE_A_24_ACT")
	)
	(segment
		(start 214.44839 -58.960004)
		(end 214.44839 -71.13143)
		(width 0.12065)
		(layer "In4.Cu")
		(net "DRIVE_A_24_ACT")
	)
	(segment
		(start 213.326218 -194.446398)
		(end 205.293468 -202.479148)
		(width 0.12065)
		(layer "In4.Cu")
		(net "DRIVE_A_24_ACT")
	)
	(segment
		(start 205.293468 -278.499316)
		(end 198.781924 -285.01086)
		(width 0.12065)
		(layer "In4.Cu")
		(net "DRIVE_A_24_ACT")
	)
	(segment
		(start 210.799934 0.116332)
		(end 210.799934 -7.921752)
		(width 0.12065)
		(layer "In4.Cu")
		(net "DRIVE_A_24_ACT")
	)
	(segment
		(start 214.459058 -71.142098)
		(end 214.459058 -72.73798)
		(width 0.12065)
		(layer "In4.Cu")
		(net "DRIVE_A_24_ACT")
	)
	(segment
		(start 210.405472 -144.671796)
		(end 213.326218 -147.592542)
		(width 0.12065)
		(layer "In4.Cu")
		(net "DRIVE_A_24_ACT")
	)
	(segment
		(start 213.326218 -147.592542)
		(end 213.326218 -194.446398)
		(width 0.12065)
		(layer "In4.Cu")
		(net "DRIVE_A_24_ACT")
	)
	(segment
		(start 214.459058 -72.73798)
		(end 210.405472 -76.791566)
		(width 0.12065)
		(layer "In4.Cu")
		(net "DRIVE_A_24_ACT")
	)
	(segment
		(start 210.799934 -7.921752)
		(end 209.313018 -9.408668)
		(width 0.12065)
		(layer "In4.Cu")
		(net "DRIVE_A_24_ACT")
	)
	(segment
		(start 467.592918 -156.078174)
		(end 467.586314 -156.07157)
		(width 0.17145)
		(layer "F.Cu")
		(net "DRIVE_A_23_PWR")
	)
	(segment
		(start 467.586314 -153.983944)
		(end 467.57717 -153.9748)
		(width 0.17145)
		(layer "F.Cu")
		(net "DRIVE_A_23_PWR")
	)
	(segment
		(start 467.586314 -156.07157)
		(end 467.586314 -154.961844)
		(width 0.17145)
		(layer "F.Cu")
		(net "DRIVE_A_23_PWR")
	)
	(segment
		(start 249.346466 -237.916212)
		(end 248.67108 -237.240826)
		(width 0.17145)
		(layer "F.Cu")
		(net "DRIVE_A_23_PWR")
	)
	(segment
		(start 467.586314 -154.961844)
		(end 467.586314 -153.983944)
		(width 0.17145)
		(layer "F.Cu")
		(net "DRIVE_A_23_PWR")
	)
	(segment
		(start 248.67108 -237.240826)
		(end 248.67108 -234.1626)
		(width 0.17145)
		(layer "F.Cu")
		(net "DRIVE_A_23_PWR")
	)
	(via
		(at 249.346466 -237.916212)
		(size 0.5588)
		(drill 0.3048)
		(layers "F.Cu" "B.Cu")
		(net "DRIVE_A_23_PWR")
	)
	(via
		(at 467.586314 -154.961844)
		(size 0.6604)
		(drill 0.3302)
		(layers "F.Cu" "B.Cu")
		(net "DRIVE_A_23_PWR")
	)
	(via
		(at 463.279998 -226.284282)
		(size 0.5588)
		(drill 0.3048)
		(layers "F.Cu" "B.Cu")
		(net "DRIVE_A_23_PWR")
	)
	(via
		(at 467.57717 -153.9748)
		(size 0.5588)
		(drill 0.3048)
		(layers "F.Cu" "B.Cu")
		(net "DRIVE_A_23_PWR")
	)
	(segment
		(start 269.563088 -231.287066)
		(end 265.264138 -231.287066)
		(width 0.13335)
		(layer "In2.Cu")
		(net "DRIVE_A_23_PWR")
	)
	(segment
		(start 250.56846 -236.694218)
		(end 249.346466 -237.916212)
		(width 0.13335)
		(layer "In2.Cu")
		(net "DRIVE_A_23_PWR")
	)
	(segment
		(start 282.482036 -218.368118)
		(end 269.563088 -231.287066)
		(width 0.13335)
		(layer "In2.Cu")
		(net "DRIVE_A_23_PWR")
	)
	(segment
		(start 315.279278 -218.368118)
		(end 282.482036 -218.368118)
		(width 0.13335)
		(layer "In2.Cu")
		(net "DRIVE_A_23_PWR")
	)
	(segment
		(start 265.264138 -231.287066)
		(end 259.856986 -236.694218)
		(width 0.13335)
		(layer "In2.Cu")
		(net "DRIVE_A_23_PWR")
	)
	(segment
		(start 259.856986 -236.694218)
		(end 250.56846 -236.694218)
		(width 0.13335)
		(layer "In2.Cu")
		(net "DRIVE_A_23_PWR")
	)
	(segment
		(start 460.20228 -229.362)
		(end 326.27316 -229.362)
		(width 0.13335)
		(layer "In2.Cu")
		(net "DRIVE_A_23_PWR")
	)
	(segment
		(start 463.279998 -226.284282)
		(end 460.20228 -229.362)
		(width 0.13335)
		(layer "In2.Cu")
		(net "DRIVE_A_23_PWR")
	)
	(segment
		(start 326.27316 -229.362)
		(end 315.279278 -218.368118)
		(width 0.13335)
		(layer "In2.Cu")
		(net "DRIVE_A_23_PWR")
	)
	(segment
		(start 467.275418 -155.595574)
		(end 467.57717 -155.293822)
		(width 0.12065)
		(layer "In4.Cu")
		(net "DRIVE_A_23_PWR")
	)
	(segment
		(start 467.57717 -155.293822)
		(end 467.57717 -153.9748)
		(width 0.12065)
		(layer "In4.Cu")
		(net "DRIVE_A_23_PWR")
	)
	(segment
		(start 467.275418 -179.943252)
		(end 467.275418 -155.595574)
		(width 0.12065)
		(layer "In4.Cu")
		(net "DRIVE_A_23_PWR")
	)
	(segment
		(start 465.012278 -224.552002)
		(end 465.012278 -182.206392)
		(width 0.12065)
		(layer "In4.Cu")
		(net "DRIVE_A_23_PWR")
	)
	(segment
		(start 463.279998 -226.284282)
		(end 465.012278 -224.552002)
		(width 0.12065)
		(layer "In4.Cu")
		(net "DRIVE_A_23_PWR")
	)
	(segment
		(start 465.012278 -182.206392)
		(end 467.275418 -179.943252)
		(width 0.12065)
		(layer "In4.Cu")
		(net "DRIVE_A_23_PWR")
	)
	(segment
		(start 246.75084 -255.3716)
		(end 247.40108 -254.72136)
		(width 0.17145)
		(layer "F.Cu")
		(net "DRIVE_A_23_INS")
	)
	(segment
		(start 474.853 -161.925)
		(end 474.3704 -162.4076)
		(width 0.17145)
		(layer "F.Cu")
		(net "DRIVE_A_23_INS")
	)
	(segment
		(start 473.641674 -160.909)
		(end 473.456 -161.094674)
		(width 0.17145)
		(layer "F.Cu")
		(net "DRIVE_A_23_INS")
	)
	(segment
		(start 474.3704 -162.4076)
		(end 473.8116 -162.4076)
		(width 0.17145)
		(layer "F.Cu")
		(net "DRIVE_A_23_INS")
	)
	(segment
		(start 247.40108 -254.72136)
		(end 247.40108 -252.0696)
		(width 0.17145)
		(layer "F.Cu")
		(net "DRIVE_A_23_INS")
	)
	(segment
		(start 473.456 -161.094674)
		(end 473.456 -162.052)
		(width 0.17145)
		(layer "F.Cu")
		(net "DRIVE_A_23_INS")
	)
	(segment
		(start 474.853 -160.909)
		(end 473.641674 -160.909)
		(width 0.17145)
		(layer "F.Cu")
		(net "DRIVE_A_23_INS")
	)
	(segment
		(start 473.8116 -162.4076)
		(end 473.456 -162.052)
		(width 0.17145)
		(layer "F.Cu")
		(net "DRIVE_A_23_INS")
	)
	(via
		(at 460.718154 -235.561124)
		(size 0.5588)
		(drill 0.3048)
		(layers "F.Cu" "B.Cu")
		(net "DRIVE_A_23_INS")
	)
	(via
		(at 246.75084 -255.3716)
		(size 0.5588)
		(drill 0.3048)
		(layers "F.Cu" "B.Cu")
		(net "DRIVE_A_23_INS")
	)
	(via
		(at 474.853 -160.909)
		(size 0.5588)
		(drill 0.3048)
		(layers "F.Cu" "B.Cu")
		(net "DRIVE_A_23_INS")
	)
	(via
		(at 473.456 -162.052)
		(size 0.6604)
		(drill 0.3302)
		(layers "F.Cu" "B.Cu")
		(net "DRIVE_A_23_INS")
	)
	(segment
		(start 261.9883 -248.446798)
		(end 269.362174 -248.446798)
		(width 0.13335)
		(layer "In2.Cu")
		(net "DRIVE_A_23_INS")
	)
	(segment
		(start 247.15724 -254.9652)
		(end 249.870722 -254.9652)
		(width 0.13335)
		(layer "In2.Cu")
		(net "DRIVE_A_23_INS")
	)
	(segment
		(start 246.75084 -255.3716)
		(end 247.15724 -254.9652)
		(width 0.13335)
		(layer "In2.Cu")
		(net "DRIVE_A_23_INS")
	)
	(segment
		(start 254.357124 -250.478798)
		(end 259.9563 -250.478798)
		(width 0.13335)
		(layer "In2.Cu")
		(net "DRIVE_A_23_INS")
	)
	(segment
		(start 259.9563 -250.478798)
		(end 261.9883 -248.446798)
		(width 0.13335)
		(layer "In2.Cu")
		(net "DRIVE_A_23_INS")
	)
	(segment
		(start 425.605448 -237.109)
		(end 459.170278 -237.109)
		(width 0.13335)
		(layer "In2.Cu")
		(net "DRIVE_A_23_INS")
	)
	(segment
		(start 269.362174 -248.446798)
		(end 274.77974 -243.029232)
		(width 0.13335)
		(layer "In2.Cu")
		(net "DRIVE_A_23_INS")
	)
	(segment
		(start 310.44642 -230.788718)
		(end 319.670938 -240.013236)
		(width 0.13335)
		(layer "In2.Cu")
		(net "DRIVE_A_23_INS")
	)
	(segment
		(start 295.000426 -230.788718)
		(end 310.44642 -230.788718)
		(width 0.13335)
		(layer "In2.Cu")
		(net "DRIVE_A_23_INS")
	)
	(segment
		(start 459.170278 -237.109)
		(end 460.718154 -235.561124)
		(width 0.13335)
		(layer "In2.Cu")
		(net "DRIVE_A_23_INS")
	)
	(segment
		(start 274.77974 -243.029232)
		(end 282.759912 -243.029232)
		(width 0.13335)
		(layer "In2.Cu")
		(net "DRIVE_A_23_INS")
	)
	(segment
		(start 282.759912 -243.029232)
		(end 295.000426 -230.788718)
		(width 0.13335)
		(layer "In2.Cu")
		(net "DRIVE_A_23_INS")
	)
	(segment
		(start 422.701212 -240.013236)
		(end 425.605448 -237.109)
		(width 0.13335)
		(layer "In2.Cu")
		(net "DRIVE_A_23_INS")
	)
	(segment
		(start 319.670938 -240.013236)
		(end 422.701212 -240.013236)
		(width 0.13335)
		(layer "In2.Cu")
		(net "DRIVE_A_23_INS")
	)
	(segment
		(start 249.870722 -254.9652)
		(end 254.357124 -250.478798)
		(width 0.13335)
		(layer "In2.Cu")
		(net "DRIVE_A_23_INS")
	)
	(segment
		(start 474.3196 -161.4424)
		(end 474.853 -160.909)
		(width 0.12065)
		(layer "In4.Cu")
		(net "DRIVE_A_23_INS")
	)
	(segment
		(start 466.363812 -226.058984)
		(end 466.363812 -183.614314)
		(width 0.12065)
		(layer "In4.Cu")
		(net "DRIVE_A_23_INS")
	)
	(segment
		(start 466.363812 -183.614314)
		(end 474.3196 -175.658526)
		(width 0.12065)
		(layer "In4.Cu")
		(net "DRIVE_A_23_INS")
	)
	(segment
		(start 460.718154 -235.561124)
		(end 460.718154 -231.704642)
		(width 0.12065)
		(layer "In4.Cu")
		(net "DRIVE_A_23_INS")
	)
	(segment
		(start 460.718154 -231.704642)
		(end 466.363812 -226.058984)
		(width 0.12065)
		(layer "In4.Cu")
		(net "DRIVE_A_23_INS")
	)
	(segment
		(start 474.3196 -175.658526)
		(end 474.3196 -161.4424)
		(width 0.12065)
		(layer "In4.Cu")
		(net "DRIVE_A_23_INS")
	)
	(segment
		(start 471.1192 -130.3274)
		(end 471.15984 -130.28676)
		(width 0.17145)
		(layer "F.Cu")
		(net "DRIVE_A_23_FLT_LED")
	)
	(segment
		(start 469.65743 -131.42849)
		(end 469.65743 -130.376168)
		(width 0.17145)
		(layer "F.Cu")
		(net "DRIVE_A_23_FLT_LED")
	)
	(segment
		(start 471.15984 -129.136902)
		(end 470.732104 -128.709166)
		(width 0.17145)
		(layer "F.Cu")
		(net "DRIVE_A_23_FLT_LED")
	)
	(segment
		(start 279.15108 -274.56892)
		(end 279.15108 -275.5646)
		(width 0.17145)
		(layer "F.Cu")
		(net "DRIVE_A_23_FLT_LED")
	)
	(segment
		(start 471.070432 -130.376168)
		(end 471.1192 -130.3274)
		(width 0.17145)
		(layer "F.Cu")
		(net "DRIVE_A_23_FLT_LED")
	)
	(segment
		(start 280.3652 -273.2024)
		(end 280.3652 -273.3548)
		(width 0.17145)
		(layer "F.Cu")
		(net "DRIVE_A_23_FLT_LED")
	)
	(segment
		(start 471.15984 -130.28676)
		(end 471.15984 -129.136902)
		(width 0.17145)
		(layer "F.Cu")
		(net "DRIVE_A_23_FLT_LED")
	)
	(segment
		(start 469.65743 -130.376168)
		(end 471.070432 -130.376168)
		(width 0.17145)
		(layer "F.Cu")
		(net "DRIVE_A_23_FLT_LED")
	)
	(segment
		(start 280.3652 -273.3548)
		(end 279.15108 -274.56892)
		(width 0.17145)
		(layer "F.Cu")
		(net "DRIVE_A_23_FLT_LED")
	)
	(via
		(at 471.1192 -130.3274)
		(size 0.6604)
		(drill 0.3302)
		(layers "F.Cu" "B.Cu")
		(net "DRIVE_A_23_FLT_LED")
	)
	(via
		(at 280.3652 -273.2024)
		(size 0.5588)
		(drill 0.3048)
		(layers "F.Cu" "B.Cu")
		(net "DRIVE_A_23_FLT_LED")
	)
	(via
		(at 429.330866 -256.927604)
		(size 0.5588)
		(drill 0.3048)
		(layers "F.Cu" "B.Cu")
		(net "DRIVE_A_23_FLT_LED")
	)
	(via
		(at 469.65743 -131.42849)
		(size 0.5588)
		(drill 0.3048)
		(layers "F.Cu" "B.Cu")
		(net "DRIVE_A_23_FLT_LED")
	)
	(segment
		(start 309.070248 -270.532606)
		(end 322.67525 -256.927604)
		(width 0.13335)
		(layer "In2.Cu")
		(net "DRIVE_A_23_FLT_LED")
	)
	(segment
		(start 283.034994 -270.532606)
		(end 309.070248 -270.532606)
		(width 0.13335)
		(layer "In2.Cu")
		(net "DRIVE_A_23_FLT_LED")
	)
	(segment
		(start 280.3652 -273.2024)
		(end 283.034994 -270.532606)
		(width 0.13335)
		(layer "In2.Cu")
		(net "DRIVE_A_23_FLT_LED")
	)
	(segment
		(start 322.67525 -256.927604)
		(end 429.330866 -256.927604)
		(width 0.13335)
		(layer "In2.Cu")
		(net "DRIVE_A_23_FLT_LED")
	)
	(segment
		(start 429.330866 -256.927604)
		(end 429.330866 -241.518694)
		(width 0.12065)
		(layer "In4.Cu")
		(net "DRIVE_A_23_FLT_LED")
	)
	(segment
		(start 433.02936 -237.8202)
		(end 453.953118 -237.8202)
		(width 0.12065)
		(layer "In4.Cu")
		(net "DRIVE_A_23_FLT_LED")
	)
	(segment
		(start 472.774518 -158.771082)
		(end 472.774518 -134.545578)
		(width 0.12065)
		(layer "In4.Cu")
		(net "DRIVE_A_23_FLT_LED")
	)
	(segment
		(start 453.953118 -237.8202)
		(end 465.913216 -225.860102)
		(width 0.12065)
		(layer "In4.Cu")
		(net "DRIVE_A_23_FLT_LED")
	)
	(segment
		(start 429.330866 -241.518694)
		(end 433.02936 -237.8202)
		(width 0.12065)
		(layer "In4.Cu")
		(net "DRIVE_A_23_FLT_LED")
	)
	(segment
		(start 472.385644 -159.159956)
		(end 472.774518 -158.771082)
		(width 0.12065)
		(layer "In4.Cu")
		(net "DRIVE_A_23_FLT_LED")
	)
	(segment
		(start 472.385644 -176.95418)
		(end 472.385644 -159.159956)
		(width 0.12065)
		(layer "In4.Cu")
		(net "DRIVE_A_23_FLT_LED")
	)
	(segment
		(start 472.774518 -134.545578)
		(end 469.65743 -131.42849)
		(width 0.12065)
		(layer "In4.Cu")
		(net "DRIVE_A_23_FLT_LED")
	)
	(segment
		(start 465.913216 -183.426608)
		(end 472.385644 -176.95418)
		(width 0.12065)
		(layer "In4.Cu")
		(net "DRIVE_A_23_FLT_LED")
	)
	(segment
		(start 465.913216 -225.860102)
		(end 465.913216 -183.426608)
		(width 0.12065)
		(layer "In4.Cu")
		(net "DRIVE_A_23_FLT_LED")
	)
	(segment
		(start 467.293706 -130.368294)
		(end 467.36 -130.302)
		(width 0.17145)
		(layer "F.Cu")
		(net "DRIVE_A_23_ACT")
	)
	(segment
		(start 467.472776 -129.033778)
		(end 467.148418 -128.70942)
		(width 0.17145)
		(layer "F.Cu")
		(net "DRIVE_A_23_ACT")
	)
	(segment
		(start 466.066632 -130.368294)
		(end 467.293706 -130.368294)
		(width 0.17145)
		(layer "F.Cu")
		(net "DRIVE_A_23_ACT")
	)
	(segment
		(start 466.063584 -130.371342)
		(end 466.063584 -131.723638)
		(width 0.17145)
		(layer "F.Cu")
		(net "DRIVE_A_23_ACT")
	)
	(segment
		(start 467.472776 -130.189224)
		(end 467.472776 -129.033778)
		(width 0.17145)
		(layer "F.Cu")
		(net "DRIVE_A_23_ACT")
	)
	(segment
		(start 467.36 -130.302)
		(end 467.472776 -130.189224)
		(width 0.17145)
		(layer "F.Cu")
		(net "DRIVE_A_23_ACT")
	)
	(segment
		(start 466.066632 -130.368294)
		(end 466.063584 -130.371342)
		(width 0.17145)
		(layer "F.Cu")
		(net "DRIVE_A_23_ACT")
	)
	(via
		(at 466.063584 -131.723638)
		(size 0.5588)
		(drill 0.3048)
		(layers "F.Cu" "B.Cu")
		(net "DRIVE_A_23_ACT")
	)
	(via
		(at 445.9986 -308.026816)
		(size 0.5588)
		(drill 0.3048)
		(layers "F.Cu" "B.Cu")
		(net "DRIVE_A_23_ACT")
	)
	(via
		(at 467.36 -130.302)
		(size 0.6604)
		(drill 0.3302)
		(layers "F.Cu" "B.Cu")
		(net "DRIVE_A_23_ACT")
	)
	(segment
		(start 324.029832 -308.108604)
		(end 356.129336 -308.108604)
		(width 0.13335)
		(layer "In2.Cu")
		(net "DRIVE_A_23_ACT")
	)
	(segment
		(start 284.06725 -306.38115)
		(end 322.302378 -306.38115)
		(width 0.13335)
		(layer "In2.Cu")
		(net "DRIVE_A_23_ACT")
	)
	(segment
		(start 282.83662 -307.305202)
		(end 283.143198 -307.305202)
		(width 0.13335)
		(layer "In2.Cu")
		(net "DRIVE_A_23_ACT")
	)
	(segment
		(start 356.129336 -308.108604)
		(end 356.164642 -308.14391)
		(width 0.13335)
		(layer "In2.Cu")
		(net "DRIVE_A_23_ACT")
	)
	(segment
		(start 322.302378 -306.38115)
		(end 324.029832 -308.108604)
		(width 0.13335)
		(layer "In2.Cu")
		(net "DRIVE_A_23_ACT")
	)
	(segment
		(start 356.164642 -308.14391)
		(end 445.881506 -308.14391)
		(width 0.13335)
		(layer "In2.Cu")
		(net "DRIVE_A_23_ACT")
	)
	(segment
		(start 445.881506 -308.14391)
		(end 445.9986 -308.026816)
		(width 0.13335)
		(layer "In2.Cu")
		(net "DRIVE_A_23_ACT")
	)
	(segment
		(start 283.143198 -307.305202)
		(end 284.06725 -306.38115)
		(width 0.13335)
		(layer "In2.Cu")
		(net "DRIVE_A_23_ACT")
	)
	(segment
		(start 440.075066 -270.74368)
		(end 440.075066 -280.715466)
		(width 0.12065)
		(layer "In4.Cu")
		(net "DRIVE_A_23_ACT")
	)
	(segment
		(start 466.063584 -131.723638)
		(end 470.894918 -136.554972)
		(width 0.12065)
		(layer "In4.Cu")
		(net "DRIVE_A_23_ACT")
	)
	(segment
		(start 440.075066 -280.715466)
		(end 445.9986 -286.639)
		(width 0.12065)
		(layer "In4.Cu")
		(net "DRIVE_A_23_ACT")
	)
	(segment
		(start 428.7012 -259.369814)
		(end 440.075066 -270.74368)
		(width 0.12065)
		(layer "In4.Cu")
		(net "DRIVE_A_23_ACT")
	)
	(segment
		(start 465.500212 -182.751476)
		(end 465.500212 -225.482658)
		(width 0.12065)
		(layer "In4.Cu")
		(net "DRIVE_A_23_ACT")
	)
	(segment
		(start 453.72147 -237.2614)
		(end 432.797712 -237.2614)
		(width 0.12065)
		(layer "In4.Cu")
		(net "DRIVE_A_23_ACT")
	)
	(segment
		(start 470.894918 -177.35677)
		(end 465.500212 -182.751476)
		(width 0.12065)
		(layer "In4.Cu")
		(net "DRIVE_A_23_ACT")
	)
	(segment
		(start 432.797712 -237.2614)
		(end 428.7012 -241.357912)
		(width 0.12065)
		(layer "In4.Cu")
		(net "DRIVE_A_23_ACT")
	)
	(segment
		(start 428.7012 -241.357912)
		(end 428.7012 -259.369814)
		(width 0.12065)
		(layer "In4.Cu")
		(net "DRIVE_A_23_ACT")
	)
	(segment
		(start 470.894918 -136.554972)
		(end 470.894918 -177.35677)
		(width 0.12065)
		(layer "In4.Cu")
		(net "DRIVE_A_23_ACT")
	)
	(segment
		(start 445.9986 -286.639)
		(end 445.9986 -308.026816)
		(width 0.12065)
		(layer "In4.Cu")
		(net "DRIVE_A_23_ACT")
	)
	(segment
		(start 465.500212 -225.482658)
		(end 453.72147 -237.2614)
		(width 0.12065)
		(layer "In4.Cu")
		(net "DRIVE_A_23_ACT")
	)
	(segment
		(start 461.9879 -157.141418)
		(end 463.179922 -157.141418)
		(width 0.17145)
		(layer "F.Cu")
		(net "DRIVE_A_22_PWR")
	)
	(segment
		(start 248.02084 -234.1626)
		(end 248.02084 -235.684314)
		(width 0.17145)
		(layer "F.Cu")
		(net "DRIVE_A_22_PWR")
	)
	(segment
		(start 464.227418 -157.150562)
		(end 464.218274 -157.141418)
		(width 0.17145)
		(layer "F.Cu")
		(net "DRIVE_A_22_PWR")
	)
	(segment
		(start 464.218274 -157.141418)
		(end 463.179922 -157.141418)
		(width 0.17145)
		(layer "F.Cu")
		(net "DRIVE_A_22_PWR")
	)
	(via
		(at 463.179922 -157.141418)
		(size 0.6604)
		(drill 0.3302)
		(layers "F.Cu" "B.Cu")
		(net "DRIVE_A_22_PWR")
	)
	(via
		(at 463.33918 -225.132646)
		(size 0.5588)
		(drill 0.3048)
		(layers "F.Cu" "B.Cu")
		(net "DRIVE_A_22_PWR")
	)
	(via
		(at 248.02084 -235.684314)
		(size 0.5588)
		(drill 0.3048)
		(layers "F.Cu" "B.Cu")
		(net "DRIVE_A_22_PWR")
	)
	(via
		(at 464.227418 -157.150562)
		(size 0.5588)
		(drill 0.3048)
		(layers "F.Cu" "B.Cu")
		(net "DRIVE_A_22_PWR")
	)
	(segment
		(start 259.056124 -235.39577)
		(end 248.309384 -235.39577)
		(width 0.13335)
		(layer "In2.Cu")
		(net "DRIVE_A_22_PWR")
	)
	(segment
		(start 463.33918 -225.132646)
		(end 459.770226 -228.7016)
		(width 0.13335)
		(layer "In2.Cu")
		(net "DRIVE_A_22_PWR")
	)
	(segment
		(start 269.33144 -230.728266)
		(end 264.391902 -230.728266)
		(width 0.13335)
		(layer "In2.Cu")
		(net "DRIVE_A_22_PWR")
	)
	(segment
		(start 459.770226 -228.7016)
		(end 326.403208 -228.7016)
		(width 0.13335)
		(layer "In2.Cu")
		(net "DRIVE_A_22_PWR")
	)
	(segment
		(start 262.011922 -233.108246)
		(end 261.343648 -233.108246)
		(width 0.13335)
		(layer "In2.Cu")
		(net "DRIVE_A_22_PWR")
	)
	(segment
		(start 315.510926 -217.809318)
		(end 282.250388 -217.809318)
		(width 0.13335)
		(layer "In2.Cu")
		(net "DRIVE_A_22_PWR")
	)
	(segment
		(start 282.250388 -217.809318)
		(end 269.33144 -230.728266)
		(width 0.13335)
		(layer "In2.Cu")
		(net "DRIVE_A_22_PWR")
	)
	(segment
		(start 261.343648 -233.108246)
		(end 259.056124 -235.39577)
		(width 0.13335)
		(layer "In2.Cu")
		(net "DRIVE_A_22_PWR")
	)
	(segment
		(start 248.309384 -235.39577)
		(end 248.02084 -235.684314)
		(width 0.13335)
		(layer "In2.Cu")
		(net "DRIVE_A_22_PWR")
	)
	(segment
		(start 264.391902 -230.728266)
		(end 262.011922 -233.108246)
		(width 0.13335)
		(layer "In2.Cu")
		(net "DRIVE_A_22_PWR")
	)
	(segment
		(start 326.403208 -228.7016)
		(end 315.510926 -217.809318)
		(width 0.13335)
		(layer "In2.Cu")
		(net "DRIVE_A_22_PWR")
	)
	(segment
		(start 464.4898 -223.982026)
		(end 464.4898 -157.412944)
		(width 0.12065)
		(layer "In4.Cu")
		(net "DRIVE_A_22_PWR")
	)
	(segment
		(start 463.33918 -225.132646)
		(end 464.4898 -223.982026)
		(width 0.12065)
		(layer "In4.Cu")
		(net "DRIVE_A_22_PWR")
	)
	(segment
		(start 464.4898 -157.412944)
		(end 464.227418 -157.150562)
		(width 0.12065)
		(layer "In4.Cu")
		(net "DRIVE_A_22_PWR")
	)
	(segment
		(start 444.496444 -191.037464)
		(end 447.167 -188.366908)
		(width 0.17145)
		(layer "F.Cu")
		(net "DRIVE_A_22_INS")
	)
	(segment
		(start 445.008 -236.0168)
		(end 445.008 -228.865938)
		(width 0.17145)
		(layer "F.Cu")
		(net "DRIVE_A_22_INS")
	)
	(segment
		(start 246.75084 -252.0696)
		(end 246.75084 -254.4064)
		(width 0.17145)
		(layer "F.Cu")
		(net "DRIVE_A_22_INS")
	)
	(segment
		(start 444.496444 -193.573654)
		(end 444.496444 -191.037464)
		(width 0.17145)
		(layer "F.Cu")
		(net "DRIVE_A_22_INS")
	)
	(segment
		(start 445.008 -228.865938)
		(end 445.008 -194.08521)
		(width 0.17145)
		(layer "F.Cu")
		(net "DRIVE_A_22_INS")
	)
	(segment
		(start 447.167 -188.366908)
		(end 447.167 -185.674)
		(width 0.17145)
		(layer "F.Cu")
		(net "DRIVE_A_22_INS")
	)
	(segment
		(start 445.008 -194.08521)
		(end 444.496444 -193.573654)
		(width 0.17145)
		(layer "F.Cu")
		(net "DRIVE_A_22_INS")
	)
	(via
		(at 246.75084 -254.4064)
		(size 0.5588)
		(drill 0.3048)
		(layers "F.Cu" "B.Cu")
		(net "DRIVE_A_22_INS")
	)
	(via
		(at 445.008 -236.0168)
		(size 0.5588)
		(drill 0.3048)
		(layers "F.Cu" "B.Cu")
		(net "DRIVE_A_22_INS")
	)
	(via
		(at 445.008 -228.865938)
		(size 0.6604)
		(drill 0.3302)
		(layers "F.Cu" "B.Cu")
		(net "DRIVE_A_22_INS")
	)
	(segment
		(start 278.118062 -238.900462)
		(end 286.098234 -238.900462)
		(width 0.13335)
		(layer "In2.Cu")
		(net "DRIVE_A_22_INS")
	)
	(segment
		(start 254.125476 -249.919998)
		(end 259.724652 -249.919998)
		(width 0.13335)
		(layer "In2.Cu")
		(net "DRIVE_A_22_INS")
	)
	(segment
		(start 444.5508 -236.474)
		(end 445.008 -236.0168)
		(width 0.13335)
		(layer "In2.Cu")
		(net "DRIVE_A_22_INS")
	)
	(segment
		(start 294.768778 -230.229918)
		(end 310.678068 -230.229918)
		(width 0.13335)
		(layer "In2.Cu")
		(net "DRIVE_A_22_INS")
	)
	(segment
		(start 246.75084 -254.4064)
		(end 249.639074 -254.4064)
		(width 0.13335)
		(layer "In2.Cu")
		(net "DRIVE_A_22_INS")
	)
	(segment
		(start 319.902586 -239.454436)
		(end 422.469564 -239.454436)
		(width 0.13335)
		(layer "In2.Cu")
		(net "DRIVE_A_22_INS")
	)
	(segment
		(start 286.098234 -238.900462)
		(end 294.768778 -230.229918)
		(width 0.13335)
		(layer "In2.Cu")
		(net "DRIVE_A_22_INS")
	)
	(segment
		(start 249.639074 -254.4064)
		(end 254.125476 -249.919998)
		(width 0.13335)
		(layer "In2.Cu")
		(net "DRIVE_A_22_INS")
	)
	(segment
		(start 259.724652 -249.919998)
		(end 261.756652 -247.887998)
		(width 0.13335)
		(layer "In2.Cu")
		(net "DRIVE_A_22_INS")
	)
	(segment
		(start 310.678068 -230.229918)
		(end 319.902586 -239.454436)
		(width 0.13335)
		(layer "In2.Cu")
		(net "DRIVE_A_22_INS")
	)
	(segment
		(start 425.45 -236.474)
		(end 444.5508 -236.474)
		(width 0.13335)
		(layer "In2.Cu")
		(net "DRIVE_A_22_INS")
	)
	(segment
		(start 422.469564 -239.454436)
		(end 425.45 -236.474)
		(width 0.13335)
		(layer "In2.Cu")
		(net "DRIVE_A_22_INS")
	)
	(segment
		(start 261.756652 -247.887998)
		(end 269.130526 -247.887998)
		(width 0.13335)
		(layer "In2.Cu")
		(net "DRIVE_A_22_INS")
	)
	(segment
		(start 269.130526 -247.887998)
		(end 278.118062 -238.900462)
		(width 0.13335)
		(layer "In2.Cu")
		(net "DRIVE_A_22_INS")
	)
	(segment
		(start 439.70575 -130.34391)
		(end 438.20334 -130.34391)
		(width 0.17145)
		(layer "F.Cu")
		(net "DRIVE_A_22_FLT_LED")
	)
	(segment
		(start 280.3652 -271.9324)
		(end 279.4381 -272.8595)
		(width 0.17145)
		(layer "F.Cu")
		(net "DRIVE_A_22_FLT_LED")
	)
	(segment
		(start 439.278014 -128.676908)
		(end 439.70575 -129.104644)
		(width 0.17145)
		(layer "F.Cu")
		(net "DRIVE_A_22_FLT_LED")
	)
	(segment
		(start 278.50084 -274.43176)
		(end 278.50084 -275.5646)
		(width 0.17145)
		(layer "F.Cu")
		(net "DRIVE_A_22_FLT_LED")
	)
	(segment
		(start 439.70575 -129.104644)
		(end 439.70575 -130.34391)
		(width 0.17145)
		(layer "F.Cu")
		(net "DRIVE_A_22_FLT_LED")
	)
	(segment
		(start 279.4381 -272.8595)
		(end 279.4381 -273.4945)
		(width 0.17145)
		(layer "F.Cu")
		(net "DRIVE_A_22_FLT_LED")
	)
	(segment
		(start 279.4381 -273.4945)
		(end 278.50084 -274.43176)
		(width 0.17145)
		(layer "F.Cu")
		(net "DRIVE_A_22_FLT_LED")
	)
	(segment
		(start 438.1754 -130.37185)
		(end 438.1754 -131.9022)
		(width 0.17145)
		(layer "F.Cu")
		(net "DRIVE_A_22_FLT_LED")
	)
	(segment
		(start 438.20334 -130.34391)
		(end 438.1754 -130.37185)
		(width 0.17145)
		(layer "F.Cu")
		(net "DRIVE_A_22_FLT_LED")
	)
	(via
		(at 424.541188 -256.353564)
		(size 0.5588)
		(drill 0.3048)
		(layers "F.Cu" "B.Cu")
		(net "DRIVE_A_22_FLT_LED")
	)
	(via
		(at 439.70575 -130.34391)
		(size 0.6604)
		(drill 0.3302)
		(layers "F.Cu" "B.Cu")
		(net "DRIVE_A_22_FLT_LED")
	)
	(via
		(at 438.1754 -131.9022)
		(size 0.5588)
		(drill 0.3048)
		(layers "F.Cu" "B.Cu")
		(net "DRIVE_A_22_FLT_LED")
	)
	(via
		(at 280.3652 -271.9324)
		(size 0.5588)
		(drill 0.3048)
		(layers "F.Cu" "B.Cu")
		(net "DRIVE_A_22_FLT_LED")
	)
	(segment
		(start 424.541188 -256.353564)
		(end 322.458842 -256.353564)
		(width 0.13335)
		(layer "In2.Cu")
		(net "DRIVE_A_22_FLT_LED")
	)
	(segment
		(start 308.8386 -269.973806)
		(end 282.323794 -269.973806)
		(width 0.13335)
		(layer "In2.Cu")
		(net "DRIVE_A_22_FLT_LED")
	)
	(segment
		(start 282.323794 -269.973806)
		(end 280.3652 -271.9324)
		(width 0.13335)
		(layer "In2.Cu")
		(net "DRIVE_A_22_FLT_LED")
	)
	(segment
		(start 322.458842 -256.353564)
		(end 308.8386 -269.973806)
		(width 0.13335)
		(layer "In2.Cu")
		(net "DRIVE_A_22_FLT_LED")
	)
	(segment
		(start 434.730652 -174.268384)
		(end 436.88508 -176.422812)
		(width 0.12065)
		(layer "In4.Cu")
		(net "DRIVE_A_22_FLT_LED")
	)
	(segment
		(start 438.1754 -131.9022)
		(end 434.730652 -135.346948)
		(width 0.12065)
		(layer "In4.Cu")
		(net "DRIVE_A_22_FLT_LED")
	)
	(segment
		(start 441.07481 -221.78899)
		(end 424.541188 -238.322612)
		(width 0.12065)
		(layer "In4.Cu")
		(net "DRIVE_A_22_FLT_LED")
	)
	(segment
		(start 436.88508 -176.422812)
		(end 436.88508 -198.998332)
		(width 0.12065)
		(layer "In4.Cu")
		(net "DRIVE_A_22_FLT_LED")
	)
	(segment
		(start 434.730652 -135.346948)
		(end 434.730652 -174.268384)
		(width 0.12065)
		(layer "In4.Cu")
		(net "DRIVE_A_22_FLT_LED")
	)
	(segment
		(start 424.541188 -238.322612)
		(end 424.541188 -256.353564)
		(width 0.12065)
		(layer "In4.Cu")
		(net "DRIVE_A_22_FLT_LED")
	)
	(segment
		(start 436.88508 -198.998332)
		(end 441.07481 -203.188062)
		(width 0.12065)
		(layer "In4.Cu")
		(net "DRIVE_A_22_FLT_LED")
	)
	(segment
		(start 441.07481 -203.188062)
		(end 441.07481 -221.78899)
		(width 0.12065)
		(layer "In4.Cu")
		(net "DRIVE_A_22_FLT_LED")
	)
	(segment
		(start 434.612542 -130.336036)
		(end 435.987444 -130.336036)
		(width 0.17145)
		(layer "F.Cu")
		(net "DRIVE_A_22_ACT")
	)
	(segment
		(start 434.612542 -131.688332)
		(end 434.612542 -130.336036)
		(width 0.17145)
		(layer "F.Cu")
		(net "DRIVE_A_22_ACT")
	)
	(segment
		(start 434.609494 -131.69138)
		(end 434.612542 -131.688332)
		(width 0.17145)
		(layer "F.Cu")
		(net "DRIVE_A_22_ACT")
	)
	(segment
		(start 435.987444 -130.336036)
		(end 436.018686 -130.367278)
		(width 0.17145)
		(layer "F.Cu")
		(net "DRIVE_A_22_ACT")
	)
	(segment
		(start 435.694328 -128.677162)
		(end 436.018686 -129.00152)
		(width 0.17145)
		(layer "F.Cu")
		(net "DRIVE_A_22_ACT")
	)
	(segment
		(start 436.018686 -129.00152)
		(end 436.018686 -130.367278)
		(width 0.17145)
		(layer "F.Cu")
		(net "DRIVE_A_22_ACT")
	)
	(via
		(at 436.018686 -130.367278)
		(size 0.6604)
		(drill 0.3302)
		(layers "F.Cu" "B.Cu")
		(net "DRIVE_A_22_ACT")
	)
	(via
		(at 432.520852 -308.6862)
		(size 0.5588)
		(drill 0.3048)
		(layers "F.Cu" "B.Cu")
		(net "DRIVE_A_22_ACT")
	)
	(via
		(at 434.609494 -131.69138)
		(size 0.5588)
		(drill 0.3048)
		(layers "F.Cu" "B.Cu")
		(net "DRIVE_A_22_ACT")
	)
	(segment
		(start 432.504342 -308.70271)
		(end 432.520852 -308.6862)
		(width 0.13335)
		(layer "In2.Cu")
		(net "DRIVE_A_22_ACT")
	)
	(segment
		(start 285.135066 -308.2036)
		(end 323.33438 -308.2036)
		(width 0.13335)
		(layer "In2.Cu")
		(net "DRIVE_A_22_ACT")
	)
	(segment
		(start 323.798184 -308.667404)
		(end 355.897688 -308.667404)
		(width 0.13335)
		(layer "In2.Cu")
		(net "DRIVE_A_22_ACT")
	)
	(segment
		(start 284.236668 -307.305202)
		(end 285.135066 -308.2036)
		(width 0.13335)
		(layer "In2.Cu")
		(net "DRIVE_A_22_ACT")
	)
	(segment
		(start 355.897688 -308.667404)
		(end 355.932994 -308.70271)
		(width 0.13335)
		(layer "In2.Cu")
		(net "DRIVE_A_22_ACT")
	)
	(segment
		(start 355.932994 -308.70271)
		(end 432.504342 -308.70271)
		(width 0.13335)
		(layer "In2.Cu")
		(net "DRIVE_A_22_ACT")
	)
	(segment
		(start 323.33438 -308.2036)
		(end 323.798184 -308.667404)
		(width 0.13335)
		(layer "In2.Cu")
		(net "DRIVE_A_22_ACT")
	)
	(segment
		(start 434.171852 -132.129022)
		(end 434.171852 -174.390304)
		(width 0.12065)
		(layer "In4.Cu")
		(net "DRIVE_A_22_ACT")
	)
	(segment
		(start 432.520852 -269.656052)
		(end 432.520852 -308.6862)
		(width 0.12065)
		(layer "In4.Cu")
		(net "DRIVE_A_22_ACT")
	)
	(segment
		(start 436.47233 -176.690782)
		(end 436.47233 -199.169528)
		(width 0.12065)
		(layer "In4.Cu")
		(net "DRIVE_A_22_ACT")
	)
	(segment
		(start 440.58205 -203.279248)
		(end 440.58205 -221.491302)
		(width 0.12065)
		(layer "In4.Cu")
		(net "DRIVE_A_22_ACT")
	)
	(segment
		(start 423.786046 -260.921246)
		(end 432.520852 -269.656052)
		(width 0.12065)
		(layer "In4.Cu")
		(net "DRIVE_A_22_ACT")
	)
	(segment
		(start 440.58205 -221.491302)
		(end 423.786046 -238.287306)
		(width 0.12065)
		(layer "In4.Cu")
		(net "DRIVE_A_22_ACT")
	)
	(segment
		(start 423.786046 -238.287306)
		(end 423.786046 -260.921246)
		(width 0.12065)
		(layer "In4.Cu")
		(net "DRIVE_A_22_ACT")
	)
	(segment
		(start 434.171852 -174.390304)
		(end 436.47233 -176.690782)
		(width 0.12065)
		(layer "In4.Cu")
		(net "DRIVE_A_22_ACT")
	)
	(segment
		(start 436.47233 -199.169528)
		(end 440.58205 -203.279248)
		(width 0.12065)
		(layer "In4.Cu")
		(net "DRIVE_A_22_ACT")
	)
	(segment
		(start 434.609494 -131.69138)
		(end 434.171852 -132.129022)
		(width 0.12065)
		(layer "In4.Cu")
		(net "DRIVE_A_22_ACT")
	)
	(segment
		(start 247.3706 -235.993686)
		(end 247.3706 -234.1626)
		(width 0.17145)
		(layer "F.Cu")
		(net "DRIVE_A_21_PWR")
	)
	(segment
		(start 248.010426 -236.633512)
		(end 247.3706 -235.993686)
		(width 0.17145)
		(layer "F.Cu")
		(net "DRIVE_A_21_PWR")
	)
	(segment
		(start 430.438052 -157.141418)
		(end 431.746152 -157.141418)
		(width 0.17145)
		(layer "F.Cu")
		(net "DRIVE_A_21_PWR")
	)
	(segment
		(start 431.746152 -157.141418)
		(end 433.07 -157.141418)
		(width 0.17145)
		(layer "F.Cu")
		(net "DRIVE_A_21_PWR")
	)
	(via
		(at 433.07 -157.141418)
		(size 0.5588)
		(drill 0.3048)
		(layers "F.Cu" "B.Cu")
		(net "DRIVE_A_21_PWR")
	)
	(via
		(at 431.746152 -157.141418)
		(size 0.6604)
		(drill 0.3302)
		(layers "F.Cu" "B.Cu")
		(net "DRIVE_A_21_PWR")
	)
	(via
		(at 248.010426 -236.633512)
		(size 0.5588)
		(drill 0.3048)
		(layers "F.Cu" "B.Cu")
		(net "DRIVE_A_21_PWR")
	)
	(via
		(at 432.81854 -228.092)
		(size 0.5588)
		(drill 0.3048)
		(layers "F.Cu" "B.Cu")
		(net "DRIVE_A_21_PWR")
	)
	(segment
		(start 261.937246 -231.7242)
		(end 258.704842 -234.956604)
		(width 0.13335)
		(layer "In2.Cu")
		(net "DRIVE_A_21_PWR")
	)
	(segment
		(start 282.01874 -217.250518)
		(end 269.099792 -230.169466)
		(width 0.13335)
		(layer "In2.Cu")
		(net "DRIVE_A_21_PWR")
	)
	(segment
		(start 432.81854 -228.092)
		(end 326.584056 -228.092)
		(width 0.13335)
		(layer "In2.Cu")
		(net "DRIVE_A_21_PWR")
	)
	(segment
		(start 315.742574 -217.250518)
		(end 282.01874 -217.250518)
		(width 0.13335)
		(layer "In2.Cu")
		(net "DRIVE_A_21_PWR")
	)
	(segment
		(start 262.550656 -231.7242)
		(end 261.937246 -231.7242)
		(width 0.13335)
		(layer "In2.Cu")
		(net "DRIVE_A_21_PWR")
	)
	(segment
		(start 326.584056 -228.092)
		(end 315.742574 -217.250518)
		(width 0.13335)
		(layer "In2.Cu")
		(net "DRIVE_A_21_PWR")
	)
	(segment
		(start 264.10539 -230.169466)
		(end 262.550656 -231.7242)
		(width 0.13335)
		(layer "In2.Cu")
		(net "DRIVE_A_21_PWR")
	)
	(segment
		(start 258.704842 -234.956604)
		(end 247.763538 -234.956604)
		(width 0.13335)
		(layer "In2.Cu")
		(net "DRIVE_A_21_PWR")
	)
	(segment
		(start 247.763538 -234.956604)
		(end 247.461786 -235.258356)
		(width 0.13335)
		(layer "In2.Cu")
		(net "DRIVE_A_21_PWR")
	)
	(segment
		(start 269.099792 -230.169466)
		(end 264.10539 -230.169466)
		(width 0.13335)
		(layer "In2.Cu")
		(net "DRIVE_A_21_PWR")
	)
	(segment
		(start 247.461786 -235.258356)
		(end 247.461786 -236.084872)
		(width 0.13335)
		(layer "In2.Cu")
		(net "DRIVE_A_21_PWR")
	)
	(segment
		(start 247.461786 -236.084872)
		(end 248.010426 -236.633512)
		(width 0.13335)
		(layer "In2.Cu")
		(net "DRIVE_A_21_PWR")
	)
	(segment
		(start 433.613052 -174.446946)
		(end 433.613052 -171.71035)
		(width 0.12065)
		(layer "In4.Cu")
		(net "DRIVE_A_21_PWR")
	)
	(segment
		(start 432.81854 -228.092)
		(end 440.159394 -220.751146)
		(width 0.12065)
		(layer "In4.Cu")
		(net "DRIVE_A_21_PWR")
	)
	(segment
		(start 436.05958 -176.893474)
		(end 433.613052 -174.446946)
		(width 0.12065)
		(layer "In4.Cu")
		(net "DRIVE_A_21_PWR")
	)
	(segment
		(start 432.81854 -170.915838)
		(end 432.81854 -164.97046)
		(width 0.12065)
		(layer "In4.Cu")
		(net "DRIVE_A_21_PWR")
	)
	(segment
		(start 440.159394 -203.440538)
		(end 436.05958 -199.340724)
		(width 0.12065)
		(layer "In4.Cu")
		(net "DRIVE_A_21_PWR")
	)
	(segment
		(start 433.613052 -171.71035)
		(end 432.81854 -170.915838)
		(width 0.12065)
		(layer "In4.Cu")
		(net "DRIVE_A_21_PWR")
	)
	(segment
		(start 436.05958 -199.340724)
		(end 436.05958 -176.893474)
		(width 0.12065)
		(layer "In4.Cu")
		(net "DRIVE_A_21_PWR")
	)
	(segment
		(start 440.159394 -220.751146)
		(end 440.159394 -203.440538)
		(width 0.12065)
		(layer "In4.Cu")
		(net "DRIVE_A_21_PWR")
	)
	(segment
		(start 433.07 -164.719)
		(end 433.07 -157.141418)
		(width 0.12065)
		(layer "In4.Cu")
		(net "DRIVE_A_21_PWR")
	)
	(segment
		(start 432.81854 -164.97046)
		(end 433.07 -164.719)
		(width 0.12065)
		(layer "In4.Cu")
		(net "DRIVE_A_21_PWR")
	)
	(segment
		(start 411.769052 -180.064918)
		(end 411.769052 -181.5846)
		(width 0.17145)
		(layer "F.Cu")
		(net "DRIVE_A_21_INS")
	)
	(segment
		(start 245.45036 -255.3716)
		(end 246.1006 -254.72136)
		(width 0.17145)
		(layer "F.Cu")
		(net "DRIVE_A_21_INS")
	)
	(segment
		(start 246.1006 -254.72136)
		(end 246.1006 -252.0696)
		(width 0.17145)
		(layer "F.Cu")
		(net "DRIVE_A_21_INS")
	)
	(segment
		(start 411.769052 -181.5846)
		(end 411.769052 -182.686452)
		(width 0.17145)
		(layer "F.Cu")
		(net "DRIVE_A_21_INS")
	)
	(via
		(at 245.45036 -255.3716)
		(size 0.5588)
		(drill 0.3048)
		(layers "F.Cu" "B.Cu")
		(net "DRIVE_A_21_INS")
	)
	(via
		(at 411.769052 -182.686452)
		(size 0.5588)
		(drill 0.3048)
		(layers "F.Cu" "B.Cu")
		(net "DRIVE_A_21_INS")
	)
	(via
		(at 414.9344 -237.8202)
		(size 0.5588)
		(drill 0.3048)
		(layers "F.Cu" "B.Cu")
		(net "DRIVE_A_21_INS")
	)
	(via
		(at 411.769052 -181.5846)
		(size 0.6604)
		(drill 0.3302)
		(layers "F.Cu" "B.Cu")
		(net "DRIVE_A_21_INS")
	)
	(segment
		(start 320.134234 -238.895636)
		(end 310.909716 -229.671118)
		(width 0.13335)
		(layer "In2.Cu")
		(net "DRIVE_A_21_INS")
	)
	(segment
		(start 277.886414 -238.341662)
		(end 268.898878 -247.329198)
		(width 0.13335)
		(layer "In2.Cu")
		(net "DRIVE_A_21_INS")
	)
	(segment
		(start 294.53713 -229.671118)
		(end 285.866586 -238.341662)
		(width 0.13335)
		(layer "In2.Cu")
		(net "DRIVE_A_21_INS")
	)
	(segment
		(start 253.893828 -249.361198)
		(end 249.534426 -253.7206)
		(width 0.13335)
		(layer "In2.Cu")
		(net "DRIVE_A_21_INS")
	)
	(segment
		(start 261.525004 -247.329198)
		(end 259.493004 -249.361198)
		(width 0.13335)
		(layer "In2.Cu")
		(net "DRIVE_A_21_INS")
	)
	(segment
		(start 246.646192 -253.7206)
		(end 246.19204 -254.174752)
		(width 0.13335)
		(layer "In2.Cu")
		(net "DRIVE_A_21_INS")
	)
	(segment
		(start 285.866586 -238.341662)
		(end 277.886414 -238.341662)
		(width 0.13335)
		(layer "In2.Cu")
		(net "DRIVE_A_21_INS")
	)
	(segment
		(start 268.898878 -247.329198)
		(end 261.525004 -247.329198)
		(width 0.13335)
		(layer "In2.Cu")
		(net "DRIVE_A_21_INS")
	)
	(segment
		(start 246.19204 -254.174752)
		(end 246.19204 -254.62992)
		(width 0.13335)
		(layer "In2.Cu")
		(net "DRIVE_A_21_INS")
	)
	(segment
		(start 259.493004 -249.361198)
		(end 253.893828 -249.361198)
		(width 0.13335)
		(layer "In2.Cu")
		(net "DRIVE_A_21_INS")
	)
	(segment
		(start 414.8074 -237.9472)
		(end 342.914478 -237.9472)
		(width 0.13335)
		(layer "In2.Cu")
		(net "DRIVE_A_21_INS")
	)
	(segment
		(start 342.914478 -237.9472)
		(end 341.966042 -238.895636)
		(width 0.13335)
		(layer "In2.Cu")
		(net "DRIVE_A_21_INS")
	)
	(segment
		(start 414.9344 -237.8202)
		(end 414.8074 -237.9472)
		(width 0.13335)
		(layer "In2.Cu")
		(net "DRIVE_A_21_INS")
	)
	(segment
		(start 246.19204 -254.62992)
		(end 245.45036 -255.3716)
		(width 0.13335)
		(layer "In2.Cu")
		(net "DRIVE_A_21_INS")
	)
	(segment
		(start 341.966042 -238.895636)
		(end 320.134234 -238.895636)
		(width 0.13335)
		(layer "In2.Cu")
		(net "DRIVE_A_21_INS")
	)
	(segment
		(start 310.909716 -229.671118)
		(end 294.53713 -229.671118)
		(width 0.13335)
		(layer "In2.Cu")
		(net "DRIVE_A_21_INS")
	)
	(segment
		(start 249.534426 -253.7206)
		(end 246.646192 -253.7206)
		(width 0.13335)
		(layer "In2.Cu")
		(net "DRIVE_A_21_INS")
	)
	(segment
		(start 414.9344 -232.340658)
		(end 414.9344 -237.8202)
		(width 0.12065)
		(layer "In4.Cu")
		(net "DRIVE_A_21_INS")
	)
	(segment
		(start 410.505656 -227.911914)
		(end 414.9344 -232.340658)
		(width 0.12065)
		(layer "In4.Cu")
		(net "DRIVE_A_21_INS")
	)
	(segment
		(start 411.769052 -182.686452)
		(end 410.505656 -183.949848)
		(width 0.12065)
		(layer "In4.Cu")
		(net "DRIVE_A_21_INS")
	)
	(segment
		(start 410.505656 -183.949848)
		(end 410.505656 -227.911914)
		(width 0.12065)
		(layer "In4.Cu")
		(net "DRIVE_A_21_INS")
	)
	(segment
		(start 407.663904 -128.74117)
		(end 408.09164 -129.168906)
		(width 0.17145)
		(layer "F.Cu")
		(net "DRIVE_A_21_FLT_LED")
	)
	(segment
		(start 277.8506 -274.26793)
		(end 277.8506 -275.5646)
		(width 0.17145)
		(layer "F.Cu")
		(net "DRIVE_A_21_FLT_LED")
	)
	(segment
		(start 408.09164 -129.168906)
		(end 408.09164 -130.408172)
		(width 0.17145)
		(layer "F.Cu")
		(net "DRIVE_A_21_FLT_LED")
	)
	(segment
		(start 278.765 -273.0754)
		(end 278.765 -273.35353)
		(width 0.17145)
		(layer "F.Cu")
		(net "DRIVE_A_21_FLT_LED")
	)
	(segment
		(start 406.58923 -130.408172)
		(end 408.09164 -130.408172)
		(width 0.17145)
		(layer "F.Cu")
		(net "DRIVE_A_21_FLT_LED")
	)
	(segment
		(start 278.765 -273.35353)
		(end 277.8506 -274.26793)
		(width 0.17145)
		(layer "F.Cu")
		(net "DRIVE_A_21_FLT_LED")
	)
	(segment
		(start 406.58923 -131.460494)
		(end 406.58923 -130.408172)
		(width 0.17145)
		(layer "F.Cu")
		(net "DRIVE_A_21_FLT_LED")
	)
	(via
		(at 408.09164 -130.408172)
		(size 0.6604)
		(drill 0.3302)
		(layers "F.Cu" "B.Cu")
		(net "DRIVE_A_21_FLT_LED")
	)
	(via
		(at 278.765 -273.0754)
		(size 0.5588)
		(drill 0.3048)
		(layers "F.Cu" "B.Cu")
		(net "DRIVE_A_21_FLT_LED")
	)
	(via
		(at 406.58923 -131.460494)
		(size 0.5588)
		(drill 0.3048)
		(layers "F.Cu" "B.Cu")
		(net "DRIVE_A_21_FLT_LED")
	)
	(via
		(at 401.416774 -255.794764)
		(size 0.5588)
		(drill 0.3048)
		(layers "F.Cu" "B.Cu")
		(net "DRIVE_A_21_FLT_LED")
	)
	(segment
		(start 279.527 -272.3134)
		(end 279.527 -271.907)
		(width 0.13335)
		(layer "In2.Cu")
		(net "DRIVE_A_21_FLT_LED")
	)
	(segment
		(start 322.227194 -255.794764)
		(end 401.416774 -255.794764)
		(width 0.13335)
		(layer "In2.Cu")
		(net "DRIVE_A_21_FLT_LED")
	)
	(segment
		(start 279.527 -271.907)
		(end 282.018994 -269.415006)
		(width 0.13335)
		(layer "In2.Cu")
		(net "DRIVE_A_21_FLT_LED")
	)
	(segment
		(start 282.018994 -269.415006)
		(end 308.606952 -269.415006)
		(width 0.13335)
		(layer "In2.Cu")
		(net "DRIVE_A_21_FLT_LED")
	)
	(segment
		(start 278.765 -273.0754)
		(end 279.527 -272.3134)
		(width 0.13335)
		(layer "In2.Cu")
		(net "DRIVE_A_21_FLT_LED")
	)
	(segment
		(start 308.606952 -269.415006)
		(end 322.227194 -255.794764)
		(width 0.13335)
		(layer "In2.Cu")
		(net "DRIVE_A_21_FLT_LED")
	)
	(segment
		(start 406.58923 -131.460494)
		(end 406.58923 -151.047196)
		(width 0.12065)
		(layer "In4.Cu")
		(net "DRIVE_A_21_FLT_LED")
	)
	(segment
		(start 406.588976 -173.331886)
		(end 406.58923 -173.33214)
		(width 0.12065)
		(layer "In4.Cu")
		(net "DRIVE_A_21_FLT_LED")
	)
	(segment
		(start 412.51886 -167.060118)
		(end 406.588976 -172.990002)
		(width 0.12065)
		(layer "In4.Cu")
		(net "DRIVE_A_21_FLT_LED")
	)
	(segment
		(start 406.58923 -234.967018)
		(end 401.416774 -240.139474)
		(width 0.12065)
		(layer "In4.Cu")
		(net "DRIVE_A_21_FLT_LED")
	)
	(segment
		(start 406.58923 -173.33214)
		(end 406.58923 -234.967018)
		(width 0.12065)
		(layer "In4.Cu")
		(net "DRIVE_A_21_FLT_LED")
	)
	(segment
		(start 412.51886 -156.976826)
		(end 412.51886 -167.060118)
		(width 0.12065)
		(layer "In4.Cu")
		(net "DRIVE_A_21_FLT_LED")
	)
	(segment
		(start 401.416774 -240.139474)
		(end 401.416774 -255.794764)
		(width 0.12065)
		(layer "In4.Cu")
		(net "DRIVE_A_21_FLT_LED")
	)
	(segment
		(start 406.588976 -172.990002)
		(end 406.588976 -173.331886)
		(width 0.12065)
		(layer "In4.Cu")
		(net "DRIVE_A_21_FLT_LED")
	)
	(segment
		(start 406.58923 -151.047196)
		(end 412.51886 -156.976826)
		(width 0.12065)
		(layer "In4.Cu")
		(net "DRIVE_A_21_FLT_LED")
	)
	(segment
		(start 403.6568 -130.43154)
		(end 404.404576 -130.43154)
		(width 0.17145)
		(layer "F.Cu")
		(net "DRIVE_A_21_ACT")
	)
	(segment
		(start 404.404576 -129.065782)
		(end 404.404576 -130.43154)
		(width 0.17145)
		(layer "F.Cu")
		(net "DRIVE_A_21_ACT")
	)
	(segment
		(start 403.625558 -130.400298)
		(end 403.6568 -130.43154)
		(width 0.17145)
		(layer "F.Cu")
		(net "DRIVE_A_21_ACT")
	)
	(segment
		(start 402.998432 -130.400298)
		(end 402.995384 -131.755642)
		(width 0.17145)
		(layer "F.Cu")
		(net "DRIVE_A_21_ACT")
	)
	(segment
		(start 404.080218 -128.741424)
		(end 404.404576 -129.065782)
		(width 0.17145)
		(layer "F.Cu")
		(net "DRIVE_A_21_ACT")
	)
	(segment
		(start 402.998432 -130.400298)
		(end 403.625558 -130.400298)
		(width 0.17145)
		(layer "F.Cu")
		(net "DRIVE_A_21_ACT")
	)
	(via
		(at 292.7858 -308.918102)
		(size 0.5588)
		(drill 0.3048)
		(layers "F.Cu" "B.Cu")
		(net "DRIVE_A_21_ACT")
	)
	(via
		(at 395.8971 -309.226204)
		(size 0.5588)
		(drill 0.3048)
		(layers "F.Cu" "B.Cu")
		(net "DRIVE_A_21_ACT")
	)
	(via
		(at 404.404576 -130.43154)
		(size 0.6604)
		(drill 0.3302)
		(layers "F.Cu" "B.Cu")
		(net "DRIVE_A_21_ACT")
	)
	(via
		(at 402.995384 -131.755642)
		(size 0.5588)
		(drill 0.3048)
		(layers "F.Cu" "B.Cu")
		(net "DRIVE_A_21_ACT")
	)
	(segment
		(start 395.861794 -309.26151)
		(end 395.8971 -309.226204)
		(width 0.13335)
		(layer "In2.Cu")
		(net "DRIVE_A_21_ACT")
	)
	(segment
		(start 323.566536 -309.226204)
		(end 355.66604 -309.226204)
		(width 0.13335)
		(layer "In2.Cu")
		(net "DRIVE_A_21_ACT")
	)
	(segment
		(start 355.66604 -309.226204)
		(end 355.701346 -309.26151)
		(width 0.13335)
		(layer "In2.Cu")
		(net "DRIVE_A_21_ACT")
	)
	(segment
		(start 355.701346 -309.26151)
		(end 395.861794 -309.26151)
		(width 0.13335)
		(layer "In2.Cu")
		(net "DRIVE_A_21_ACT")
	)
	(segment
		(start 323.258434 -308.918102)
		(end 323.566536 -309.226204)
		(width 0.13335)
		(layer "In2.Cu")
		(net "DRIVE_A_21_ACT")
	)
	(segment
		(start 292.7858 -308.918102)
		(end 323.258434 -308.918102)
		(width 0.13335)
		(layer "In2.Cu")
		(net "DRIVE_A_21_ACT")
	)
	(segment
		(start 405.876252 -172.768514)
		(end 412.10611 -166.538656)
		(width 0.12065)
		(layer "In4.Cu")
		(net "DRIVE_A_21_ACT")
	)
	(segment
		(start 395.8971 -302.514)
		(end 397.9037 -300.5074)
		(width 0.12065)
		(layer "In4.Cu")
		(net "DRIVE_A_21_ACT")
	)
	(segment
		(start 402.995384 -148.037296)
		(end 402.995384 -131.755642)
		(width 0.12065)
		(layer "In4.Cu")
		(net "DRIVE_A_21_ACT")
	)
	(segment
		(start 400.66849 -240.09731)
		(end 405.876252 -234.889548)
		(width 0.12065)
		(layer "In4.Cu")
		(net "DRIVE_A_21_ACT")
	)
	(segment
		(start 412.10611 -166.538656)
		(end 412.10611 -157.148022)
		(width 0.12065)
		(layer "In4.Cu")
		(net "DRIVE_A_21_ACT")
	)
	(segment
		(start 400.66849 -278.80691)
		(end 400.66849 -240.09731)
		(width 0.12065)
		(layer "In4.Cu")
		(net "DRIVE_A_21_ACT")
	)
	(segment
		(start 412.10611 -157.148022)
		(end 402.995384 -148.037296)
		(width 0.12065)
		(layer "In4.Cu")
		(net "DRIVE_A_21_ACT")
	)
	(segment
		(start 397.9037 -281.5717)
		(end 400.66849 -278.80691)
		(width 0.12065)
		(layer "In4.Cu")
		(net "DRIVE_A_21_ACT")
	)
	(segment
		(start 395.8971 -309.226204)
		(end 395.8971 -302.514)
		(width 0.12065)
		(layer "In4.Cu")
		(net "DRIVE_A_21_ACT")
	)
	(segment
		(start 397.9037 -300.5074)
		(end 397.9037 -281.5717)
		(width 0.12065)
		(layer "In4.Cu")
		(net "DRIVE_A_21_ACT")
	)
	(segment
		(start 405.876252 -234.889548)
		(end 405.876252 -172.768514)
		(width 0.12065)
		(layer "In4.Cu")
		(net "DRIVE_A_21_ACT")
	)
	(segment
		(start 290.40074 -310.0324)
		(end 291.515038 -308.918102)
		(width 0.13335)
		(layer "In9.Cu")
		(net "DRIVE_A_21_ACT")
	)
	(segment
		(start 291.515038 -308.918102)
		(end 292.7858 -308.918102)
		(width 0.13335)
		(layer "In9.Cu")
		(net "DRIVE_A_21_ACT")
	)
	(segment
		(start 281.836622 -309.105046)
		(end 281.836622 -309.268622)
		(width 0.13335)
		(layer "In9.Cu")
		(net "DRIVE_A_21_ACT")
	)
	(segment
		(start 281.836622 -309.268622)
		(end 282.6004 -310.0324)
		(width 0.13335)
		(layer "In9.Cu")
		(net "DRIVE_A_21_ACT")
	)
	(segment
		(start 282.6004 -310.0324)
		(end 290.40074 -310.0324)
		(width 0.13335)
		(layer "In9.Cu")
		(net "DRIVE_A_21_ACT")
	)
	(segment
		(start 398.88795 -157.141418)
		(end 400.064478 -157.141418)
		(width 0.17145)
		(layer "F.Cu")
		(net "DRIVE_A_20_PWR")
	)
	(segment
		(start 401.047204 -157.138878)
		(end 401.044664 -157.141418)
		(width 0.17145)
		(layer "F.Cu")
		(net "DRIVE_A_20_PWR")
	)
	(segment
		(start 247.518936 -237.509812)
		(end 246.72036 -236.711236)
		(width 0.17145)
		(layer "F.Cu")
		(net "DRIVE_A_20_PWR")
	)
	(segment
		(start 401.044664 -157.141418)
		(end 400.064478 -157.141418)
		(width 0.17145)
		(layer "F.Cu")
		(net "DRIVE_A_20_PWR")
	)
	(segment
		(start 246.72036 -236.711236)
		(end 246.72036 -234.1626)
		(width 0.17145)
		(layer "F.Cu")
		(net "DRIVE_A_20_PWR")
	)
	(via
		(at 402.5392 -227.5332)
		(size 0.5588)
		(drill 0.3048)
		(layers "F.Cu" "B.Cu")
		(net "DRIVE_A_20_PWR")
	)
	(via
		(at 401.047204 -157.138878)
		(size 0.5588)
		(drill 0.3048)
		(layers "F.Cu" "B.Cu")
		(net "DRIVE_A_20_PWR")
	)
	(via
		(at 247.518936 -237.509812)
		(size 0.5588)
		(drill 0.3048)
		(layers "F.Cu" "B.Cu")
		(net "DRIVE_A_20_PWR")
	)
	(via
		(at 400.064478 -157.141418)
		(size 0.6604)
		(drill 0.3302)
		(layers "F.Cu" "B.Cu")
		(net "DRIVE_A_20_PWR")
	)
	(segment
		(start 315.974222 -216.691718)
		(end 281.787092 -216.691718)
		(width 0.13335)
		(layer "In2.Cu")
		(net "DRIVE_A_20_PWR")
	)
	(segment
		(start 263.873742 -229.610666)
		(end 262.319008 -231.1654)
		(width 0.13335)
		(layer "In2.Cu")
		(net "DRIVE_A_20_PWR")
	)
	(segment
		(start 326.803258 -227.520754)
		(end 315.974222 -216.691718)
		(width 0.13335)
		(layer "In2.Cu")
		(net "DRIVE_A_20_PWR")
	)
	(segment
		(start 262.319008 -231.1654)
		(end 261.89432 -231.1654)
		(width 0.13335)
		(layer "In2.Cu")
		(net "DRIVE_A_20_PWR")
	)
	(segment
		(start 402.5392 -227.5332)
		(end 402.526754 -227.520754)
		(width 0.13335)
		(layer "In2.Cu")
		(net "DRIVE_A_20_PWR")
	)
	(segment
		(start 268.868144 -229.610666)
		(end 263.873742 -229.610666)
		(width 0.13335)
		(layer "In2.Cu")
		(net "DRIVE_A_20_PWR")
	)
	(segment
		(start 258.528566 -234.531154)
		(end 247.33377 -234.531154)
		(width 0.13335)
		(layer "In2.Cu")
		(net "DRIVE_A_20_PWR")
	)
	(segment
		(start 246.72036 -236.711236)
		(end 247.518936 -237.509812)
		(width 0.13335)
		(layer "In2.Cu")
		(net "DRIVE_A_20_PWR")
	)
	(segment
		(start 247.33377 -234.531154)
		(end 246.72036 -235.144564)
		(width 0.13335)
		(layer "In2.Cu")
		(net "DRIVE_A_20_PWR")
	)
	(segment
		(start 402.526754 -227.520754)
		(end 326.803258 -227.520754)
		(width 0.13335)
		(layer "In2.Cu")
		(net "DRIVE_A_20_PWR")
	)
	(segment
		(start 246.72036 -235.144564)
		(end 246.72036 -236.711236)
		(width 0.13335)
		(layer "In2.Cu")
		(net "DRIVE_A_20_PWR")
	)
	(segment
		(start 281.787092 -216.691718)
		(end 268.868144 -229.610666)
		(width 0.13335)
		(layer "In2.Cu")
		(net "DRIVE_A_20_PWR")
	)
	(segment
		(start 261.89432 -231.1654)
		(end 258.528566 -234.531154)
		(width 0.13335)
		(layer "In2.Cu")
		(net "DRIVE_A_20_PWR")
	)
	(segment
		(start 401.047204 -171.512484)
		(end 402.62175 -173.08703)
		(width 0.12065)
		(layer "In4.Cu")
		(net "DRIVE_A_20_PWR")
	)
	(segment
		(start 401.047204 -157.138878)
		(end 401.047204 -171.512484)
		(width 0.12065)
		(layer "In4.Cu")
		(net "DRIVE_A_20_PWR")
	)
	(segment
		(start 402.62175 -173.08703)
		(end 402.62175 -227.45065)
		(width 0.12065)
		(layer "In4.Cu")
		(net "DRIVE_A_20_PWR")
	)
	(segment
		(start 402.62175 -227.45065)
		(end 402.5392 -227.5332)
		(width 0.12065)
		(layer "In4.Cu")
		(net "DRIVE_A_20_PWR")
	)
	(segment
		(start 382.4986 -182.2704)
		(end 381.0508 -182.2704)
		(width 0.17145)
		(layer "F.Cu")
		(net "DRIVE_A_20_INS")
	)
	(segment
		(start 245.45036 -252.0696)
		(end 245.45036 -254.4064)
		(width 0.17145)
		(layer "F.Cu")
		(net "DRIVE_A_20_INS")
	)
	(segment
		(start 380.21895 -180.064918)
		(end 380.21895 -181.43855)
		(width 0.17145)
		(layer "F.Cu")
		(net "DRIVE_A_20_INS")
	)
	(segment
		(start 381.0508 -182.2704)
		(end 380.580646 -181.800246)
		(width 0.17145)
		(layer "F.Cu")
		(net "DRIVE_A_20_INS")
	)
	(segment
		(start 380.21895 -181.43855)
		(end 380.580646 -181.800246)
		(width 0.17145)
		(layer "F.Cu")
		(net "DRIVE_A_20_INS")
	)
	(via
		(at 380.580646 -181.800246)
		(size 0.6604)
		(drill 0.3302)
		(layers "F.Cu" "B.Cu")
		(net "DRIVE_A_20_INS")
	)
	(via
		(at 382.4986 -182.2704)
		(size 0.5588)
		(drill 0.3048)
		(layers "F.Cu" "B.Cu")
		(net "DRIVE_A_20_INS")
	)
	(via
		(at 382.4986 -236.3216)
		(size 0.5588)
		(drill 0.3048)
		(layers "F.Cu" "B.Cu")
		(net "DRIVE_A_20_INS")
	)
	(via
		(at 245.45036 -254.4064)
		(size 0.5588)
		(drill 0.3048)
		(layers "F.Cu" "B.Cu")
		(net "DRIVE_A_20_INS")
	)
	(segment
		(start 261.221474 -246.76608)
		(end 268.671548 -246.76608)
		(width 0.13335)
		(layer "In2.Cu")
		(net "DRIVE_A_20_INS")
	)
	(segment
		(start 355.092 -236.3216)
		(end 382.4986 -236.3216)
		(width 0.13335)
		(layer "In2.Cu")
		(net "DRIVE_A_20_INS")
	)
	(segment
		(start 245.45036 -254.4064)
		(end 245.6688 -254.18796)
		(width 0.13335)
		(layer "In2.Cu")
		(net "DRIVE_A_20_INS")
	)
	(segment
		(start 245.6688 -253.907544)
		(end 246.414544 -253.1618)
		(width 0.13335)
		(layer "In2.Cu")
		(net "DRIVE_A_20_INS")
	)
	(segment
		(start 342.68283 -237.3884)
		(end 354.0252 -237.3884)
		(width 0.13335)
		(layer "In2.Cu")
		(net "DRIVE_A_20_INS")
	)
	(segment
		(start 245.6688 -254.18796)
		(end 245.6688 -253.907544)
		(width 0.13335)
		(layer "In2.Cu")
		(net "DRIVE_A_20_INS")
	)
	(segment
		(start 246.414544 -253.1618)
		(end 249.302778 -253.1618)
		(width 0.13335)
		(layer "In2.Cu")
		(net "DRIVE_A_20_INS")
	)
	(segment
		(start 277.654766 -237.782862)
		(end 285.634938 -237.782862)
		(width 0.13335)
		(layer "In2.Cu")
		(net "DRIVE_A_20_INS")
	)
	(segment
		(start 259.185156 -248.802398)
		(end 261.221474 -246.76608)
		(width 0.13335)
		(layer "In2.Cu")
		(net "DRIVE_A_20_INS")
	)
	(segment
		(start 285.634938 -237.782862)
		(end 294.305482 -229.112318)
		(width 0.13335)
		(layer "In2.Cu")
		(net "DRIVE_A_20_INS")
	)
	(segment
		(start 268.671548 -246.76608)
		(end 277.654766 -237.782862)
		(width 0.13335)
		(layer "In2.Cu")
		(net "DRIVE_A_20_INS")
	)
	(segment
		(start 253.66218 -248.802398)
		(end 259.185156 -248.802398)
		(width 0.13335)
		(layer "In2.Cu")
		(net "DRIVE_A_20_INS")
	)
	(segment
		(start 294.305482 -229.112318)
		(end 311.141364 -229.112318)
		(width 0.13335)
		(layer "In2.Cu")
		(net "DRIVE_A_20_INS")
	)
	(segment
		(start 354.0252 -237.3884)
		(end 355.092 -236.3216)
		(width 0.13335)
		(layer "In2.Cu")
		(net "DRIVE_A_20_INS")
	)
	(segment
		(start 341.734394 -238.336836)
		(end 342.68283 -237.3884)
		(width 0.13335)
		(layer "In2.Cu")
		(net "DRIVE_A_20_INS")
	)
	(segment
		(start 249.302778 -253.1618)
		(end 253.66218 -248.802398)
		(width 0.13335)
		(layer "In2.Cu")
		(net "DRIVE_A_20_INS")
	)
	(segment
		(start 311.141364 -229.112318)
		(end 320.365882 -238.336836)
		(width 0.13335)
		(layer "In2.Cu")
		(net "DRIVE_A_20_INS")
	)
	(segment
		(start 320.365882 -238.336836)
		(end 341.734394 -238.336836)
		(width 0.13335)
		(layer "In2.Cu")
		(net "DRIVE_A_20_INS")
	)
	(segment
		(start 382.4986 -182.2704)
		(end 382.4986 -236.3216)
		(width 0.12065)
		(layer "In4.Cu")
		(net "DRIVE_A_20_INS")
	)
	(segment
		(start 376.412252 -127.76708)
		(end 375.882662 -127.76708)
		(width 0.17145)
		(layer "F.Cu")
		(net "DRIVE_A_20_FLT_LED")
	)
	(segment
		(start 376.412252 -125.455934)
		(end 376.412252 -127.76708)
		(width 0.17145)
		(layer "F.Cu")
		(net "DRIVE_A_20_FLT_LED")
	)
	(segment
		(start 277.20036 -274.190714)
		(end 277.20036 -275.5646)
		(width 0.17145)
		(layer "F.Cu")
		(net "DRIVE_A_20_FLT_LED")
	)
	(segment
		(start 277.876 -273.515074)
		(end 277.20036 -274.190714)
		(width 0.17145)
		(layer "F.Cu")
		(net "DRIVE_A_20_FLT_LED")
	)
	(segment
		(start 376.412252 -125.455934)
		(end 376.412252 -124.441204)
		(width 0.17145)
		(layer "F.Cu")
		(net "DRIVE_A_20_FLT_LED")
	)
	(segment
		(start 278.8412 -271.9578)
		(end 277.876 -272.923)
		(width 0.17145)
		(layer "F.Cu")
		(net "DRIVE_A_20_FLT_LED")
	)
	(segment
		(start 375.882662 -127.76708)
		(end 374.99417 -128.655572)
		(width 0.17145)
		(layer "F.Cu")
		(net "DRIVE_A_20_FLT_LED")
	)
	(segment
		(start 277.876 -272.923)
		(end 277.876 -273.515074)
		(width 0.17145)
		(layer "F.Cu")
		(net "DRIVE_A_20_FLT_LED")
	)
	(via
		(at 376.412252 -124.441204)
		(size 0.5588)
		(drill 0.3048)
		(layers "F.Cu" "B.Cu")
		(net "DRIVE_A_20_FLT_LED")
	)
	(via
		(at 368.7572 -255.1938)
		(size 0.5588)
		(drill 0.3048)
		(layers "F.Cu" "B.Cu")
		(net "DRIVE_A_20_FLT_LED")
	)
	(via
		(at 376.412252 -125.455934)
		(size 0.6604)
		(drill 0.3302)
		(layers "F.Cu" "B.Cu")
		(net "DRIVE_A_20_FLT_LED")
	)
	(via
		(at 278.8412 -271.9578)
		(size 0.5588)
		(drill 0.3048)
		(layers "F.Cu" "B.Cu")
		(net "DRIVE_A_20_FLT_LED")
	)
	(segment
		(start 281.942794 -268.856206)
		(end 308.375304 -268.856206)
		(width 0.13335)
		(layer "In2.Cu")
		(net "DRIVE_A_20_FLT_LED")
	)
	(segment
		(start 308.375304 -268.856206)
		(end 322.044314 -255.187196)
		(width 0.13335)
		(layer "In2.Cu")
		(net "DRIVE_A_20_FLT_LED")
	)
	(segment
		(start 278.8412 -271.9578)
		(end 281.942794 -268.856206)
		(width 0.13335)
		(layer "In2.Cu")
		(net "DRIVE_A_20_FLT_LED")
	)
	(segment
		(start 322.044314 -255.187196)
		(end 368.750596 -255.187196)
		(width 0.13335)
		(layer "In2.Cu")
		(net "DRIVE_A_20_FLT_LED")
	)
	(segment
		(start 368.750596 -255.187196)
		(end 368.7572 -255.1938)
		(width 0.13335)
		(layer "In2.Cu")
		(net "DRIVE_A_20_FLT_LED")
	)
	(segment
		(start 367.0046 -238.633)
		(end 368.7572 -240.3856)
		(width 0.12065)
		(layer "In4.Cu")
		(net "DRIVE_A_20_FLT_LED")
	)
	(segment
		(start 376.412252 -124.441204)
		(end 379.156214 -124.441204)
		(width 0.12065)
		(layer "In4.Cu")
		(net "DRIVE_A_20_FLT_LED")
	)
	(segment
		(start 367.0046 -215.57615)
		(end 367.0046 -238.633)
		(width 0.12065)
		(layer "In4.Cu")
		(net "DRIVE_A_20_FLT_LED")
	)
	(segment
		(start 372.53418 -155.089352)
		(end 372.53418 -210.04657)
		(width 0.12065)
		(layer "In4.Cu")
		(net "DRIVE_A_20_FLT_LED")
	)
	(segment
		(start 385.830064 -141.793468)
		(end 372.53418 -155.089352)
		(width 0.12065)
		(layer "In4.Cu")
		(net "DRIVE_A_20_FLT_LED")
	)
	(segment
		(start 368.7572 -240.3856)
		(end 368.7572 -255.1938)
		(width 0.12065)
		(layer "In4.Cu")
		(net "DRIVE_A_20_FLT_LED")
	)
	(segment
		(start 379.156214 -124.441204)
		(end 385.830064 -131.115054)
		(width 0.12065)
		(layer "In4.Cu")
		(net "DRIVE_A_20_FLT_LED")
	)
	(segment
		(start 385.830064 -131.115054)
		(end 385.830064 -141.793468)
		(width 0.12065)
		(layer "In4.Cu")
		(net "DRIVE_A_20_FLT_LED")
	)
	(segment
		(start 372.53418 -210.04657)
		(end 367.0046 -215.57615)
		(width 0.12065)
		(layer "In4.Cu")
		(net "DRIVE_A_20_FLT_LED")
	)
	(segment
		(start 371.62359 -125.723396)
		(end 371.62359 -127.79629)
		(width 0.17145)
		(layer "F.Cu")
		(net "DRIVE_A_20_ACT")
	)
	(segment
		(start 371.602 -124.622052)
		(end 371.62359 -124.643642)
		(width 0.17145)
		(layer "F.Cu")
		(net "DRIVE_A_20_ACT")
	)
	(segment
		(start 371.62359 -127.79629)
		(end 371.046248 -127.79629)
		(width 0.17145)
		(layer "F.Cu")
		(net "DRIVE_A_20_ACT")
	)
	(segment
		(start 371.046248 -127.79629)
		(end 370.160804 -128.681734)
		(width 0.17145)
		(layer "F.Cu")
		(net "DRIVE_A_20_ACT")
	)
	(segment
		(start 371.62359 -124.643642)
		(end 371.62359 -125.723396)
		(width 0.17145)
		(layer "F.Cu")
		(net "DRIVE_A_20_ACT")
	)
	(via
		(at 372.618 -310.3372)
		(size 0.5588)
		(drill 0.3048)
		(layers "F.Cu" "B.Cu")
		(net "DRIVE_A_20_ACT")
	)
	(via
		(at 371.62359 -125.723396)
		(size 0.6604)
		(drill 0.3302)
		(layers "F.Cu" "B.Cu")
		(net "DRIVE_A_20_ACT")
	)
	(via
		(at 371.602 -124.622052)
		(size 0.5588)
		(drill 0.3048)
		(layers "F.Cu" "B.Cu")
		(net "DRIVE_A_20_ACT")
	)
	(segment
		(start 284.138624 -310.007)
		(end 323.542152 -310.007)
		(width 0.13335)
		(layer "In2.Cu")
		(net "DRIVE_A_20_ACT")
	)
	(segment
		(start 323.878956 -310.343804)
		(end 372.611396 -310.343804)
		(width 0.13335)
		(layer "In2.Cu")
		(net "DRIVE_A_20_ACT")
	)
	(segment
		(start 372.611396 -310.343804)
		(end 372.618 -310.3372)
		(width 0.13335)
		(layer "In2.Cu")
		(net "DRIVE_A_20_ACT")
	)
	(segment
		(start 283.23667 -309.105046)
		(end 284.138624 -310.007)
		(width 0.13335)
		(layer "In2.Cu")
		(net "DRIVE_A_20_ACT")
	)
	(segment
		(start 323.542152 -310.007)
		(end 323.878956 -310.343804)
		(width 0.13335)
		(layer "In2.Cu")
		(net "DRIVE_A_20_ACT")
	)
	(segment
		(start 371.602 -124.9172)
		(end 373.16918 -126.48438)
		(width 0.12065)
		(layer "In4.Cu")
		(net "DRIVE_A_20_ACT")
	)
	(segment
		(start 371.602 -124.622052)
		(end 371.602 -124.9172)
		(width 0.12065)
		(layer "In4.Cu")
		(net "DRIVE_A_20_ACT")
	)
	(segment
		(start 373.16918 -126.48438)
		(end 379.674628 -126.48438)
		(width 0.12065)
		(layer "In4.Cu")
		(net "DRIVE_A_20_ACT")
	)
	(segment
		(start 379.674628 -126.48438)
		(end 385.048252 -131.858004)
		(width 0.12065)
		(layer "In4.Cu")
		(net "DRIVE_A_20_ACT")
	)
	(segment
		(start 372.618 -270.637)
		(end 372.618 -310.3372)
		(width 0.12065)
		(layer "In4.Cu")
		(net "DRIVE_A_20_ACT")
	)
	(segment
		(start 371.97538 -154.857704)
		(end 371.97538 -209.88782)
		(width 0.12065)
		(layer "In4.Cu")
		(net "DRIVE_A_20_ACT")
	)
	(segment
		(start 371.97538 -209.88782)
		(end 366.395 -215.4682)
		(width 0.12065)
		(layer "In4.Cu")
		(net "DRIVE_A_20_ACT")
	)
	(segment
		(start 367.8936 -240.5126)
		(end 367.8936 -265.9126)
		(width 0.12065)
		(layer "In4.Cu")
		(net "DRIVE_A_20_ACT")
	)
	(segment
		(start 366.395 -215.4682)
		(end 366.395 -239.014)
		(width 0.12065)
		(layer "In4.Cu")
		(net "DRIVE_A_20_ACT")
	)
	(segment
		(start 366.395 -239.014)
		(end 367.8936 -240.5126)
		(width 0.12065)
		(layer "In4.Cu")
		(net "DRIVE_A_20_ACT")
	)
	(segment
		(start 385.048252 -131.858004)
		(end 385.048252 -141.784832)
		(width 0.12065)
		(layer "In4.Cu")
		(net "DRIVE_A_20_ACT")
	)
	(segment
		(start 385.048252 -141.784832)
		(end 371.97538 -154.857704)
		(width 0.12065)
		(layer "In4.Cu")
		(net "DRIVE_A_20_ACT")
	)
	(segment
		(start 367.8936 -265.9126)
		(end 372.618 -270.637)
		(width 0.12065)
		(layer "In4.Cu")
		(net "DRIVE_A_20_ACT")
	)
	(segment
		(start 229.938834 -246.71147)
		(end 230.655876 -245.994428)
		(width 0.17145)
		(layer "F.Cu")
		(net "DRIVE_A_2_PWR")
	)
	(segment
		(start 231.59212 -241.38128)
		(end 231.59212 -239.8014)
		(width 0.17145)
		(layer "F.Cu")
		(net "DRIVE_A_2_PWR")
	)
	(segment
		(start 229.938834 -247.544844)
		(end 229.938834 -246.71147)
		(width 0.17145)
		(layer "F.Cu")
		(net "DRIVE_A_2_PWR")
	)
	(segment
		(start 230.655876 -245.994428)
		(end 230.655876 -245.18493)
		(width 0.17145)
		(layer "F.Cu")
		(net "DRIVE_A_2_PWR")
	)
	(segment
		(start 86.566248 -274.846542)
		(end 87.391748 -274.846542)
		(width 0.17145)
		(layer "F.Cu")
		(net "DRIVE_A_2_PWR")
	)
	(segment
		(start 230.655876 -242.317524)
		(end 231.59212 -241.38128)
		(width 0.17145)
		(layer "F.Cu")
		(net "DRIVE_A_2_PWR")
	)
	(segment
		(start 230.655876 -245.18493)
		(end 230.655876 -242.317524)
		(width 0.17145)
		(layer "F.Cu")
		(net "DRIVE_A_2_PWR")
	)
	(via
		(at 87.563198 -252.891798)
		(size 0.5588)
		(drill 0.3048)
		(layers "F.Cu" "B.Cu")
		(net "DRIVE_A_2_PWR")
	)
	(via
		(at 229.938834 -247.544844)
		(size 0.5588)
		(drill 0.3048)
		(layers "F.Cu" "B.Cu")
		(net "DRIVE_A_2_PWR")
	)
	(via
		(at 230.655876 -245.18493)
		(size 0.6604)
		(drill 0.3302)
		(layers "F.Cu" "B.Cu")
		(net "DRIVE_A_2_PWR")
	)
	(via
		(at 87.391748 -274.846542)
		(size 0.5588)
		(drill 0.3048)
		(layers "F.Cu" "B.Cu")
		(net "DRIVE_A_2_PWR")
	)
	(segment
		(start 172.08881 -252.856746)
		(end 171.682664 -252.4506)
		(width 0.13335)
		(layer "In2.Cu")
		(net "DRIVE_A_2_PWR")
	)
	(segment
		(start 141.627098 -252.891798)
		(end 87.563198 -252.891798)
		(width 0.13335)
		(layer "In2.Cu")
		(net "DRIVE_A_2_PWR")
	)
	(segment
		(start 229.938834 -247.544844)
		(end 229.938834 -247.109234)
		(width 0.13335)
		(layer "In2.Cu")
		(net "DRIVE_A_2_PWR")
	)
	(segment
		(start 171.682664 -252.4506)
		(end 142.068296 -252.4506)
		(width 0.13335)
		(layer "In2.Cu")
		(net "DRIVE_A_2_PWR")
	)
	(segment
		(start 219.583508 -252.40488)
		(end 219.131642 -252.856746)
		(width 0.13335)
		(layer "In2.Cu")
		(net "DRIVE_A_2_PWR")
	)
	(segment
		(start 219.131642 -252.856746)
		(end 172.08881 -252.856746)
		(width 0.13335)
		(layer "In2.Cu")
		(net "DRIVE_A_2_PWR")
	)
	(segment
		(start 227.129848 -245.8974)
		(end 220.622368 -252.40488)
		(width 0.13335)
		(layer "In2.Cu")
		(net "DRIVE_A_2_PWR")
	)
	(segment
		(start 142.068296 -252.4506)
		(end 141.627098 -252.891798)
		(width 0.13335)
		(layer "In2.Cu")
		(net "DRIVE_A_2_PWR")
	)
	(segment
		(start 229.938834 -247.109234)
		(end 228.727 -245.8974)
		(width 0.13335)
		(layer "In2.Cu")
		(net "DRIVE_A_2_PWR")
	)
	(segment
		(start 220.622368 -252.40488)
		(end 219.583508 -252.40488)
		(width 0.13335)
		(layer "In2.Cu")
		(net "DRIVE_A_2_PWR")
	)
	(segment
		(start 228.727 -245.8974)
		(end 227.129848 -245.8974)
		(width 0.13335)
		(layer "In2.Cu")
		(net "DRIVE_A_2_PWR")
	)
	(segment
		(start 87.391748 -274.846542)
		(end 86.8426 -274.297394)
		(width 0.12065)
		(layer "In4.Cu")
		(net "DRIVE_A_2_PWR")
	)
	(segment
		(start 86.8426 -253.612396)
		(end 87.563198 -252.891798)
		(width 0.12065)
		(layer "In4.Cu")
		(net "DRIVE_A_2_PWR")
	)
	(segment
		(start 86.8426 -274.297394)
		(end 86.8426 -253.612396)
		(width 0.12065)
		(layer "In4.Cu")
		(net "DRIVE_A_2_PWR")
	)
	(segment
		(start 232.22712 -258.926584)
		(end 232.22712 -257.4544)
		(width 0.17145)
		(layer "F.Cu")
		(net "DRIVE_A_2_INS")
	)
	(segment
		(start 233.5276 -268.224)
		(end 233.5276 -267.0048)
		(width 0.17145)
		(layer "F.Cu")
		(net "DRIVE_A_2_INS")
	)
	(segment
		(start 99.990148 -295.064942)
		(end 99.994466 -295.060624)
		(width 0.17145)
		(layer "F.Cu")
		(net "DRIVE_A_2_INS")
	)
	(segment
		(start 233.5276 -267.0048)
		(end 230.7082 -264.1854)
		(width 0.17145)
		(layer "F.Cu")
		(net "DRIVE_A_2_INS")
	)
	(segment
		(start 233.5276 -268.935962)
		(end 233.5276 -268.224)
		(width 0.17145)
		(layer "F.Cu")
		(net "DRIVE_A_2_INS")
	)
	(segment
		(start 232.396792 -270.06677)
		(end 233.5276 -268.935962)
		(width 0.17145)
		(layer "F.Cu")
		(net "DRIVE_A_2_INS")
	)
	(segment
		(start 230.7082 -264.1854)
		(end 230.7082 -260.445504)
		(width 0.17145)
		(layer "F.Cu")
		(net "DRIVE_A_2_INS")
	)
	(segment
		(start 99.994466 -295.060624)
		(end 99.994466 -293.99992)
		(width 0.17145)
		(layer "F.Cu")
		(net "DRIVE_A_2_INS")
	)
	(segment
		(start 230.7082 -260.445504)
		(end 232.22712 -258.926584)
		(width 0.17145)
		(layer "F.Cu")
		(net "DRIVE_A_2_INS")
	)
	(via
		(at 99.994466 -293.99992)
		(size 0.5588)
		(drill 0.3048)
		(layers "F.Cu" "B.Cu")
		(net "DRIVE_A_2_INS")
	)
	(via
		(at 104.902 -267.7668)
		(size 0.5588)
		(drill 0.3048)
		(layers "F.Cu" "B.Cu")
		(net "DRIVE_A_2_INS")
	)
	(via
		(at 232.396792 -270.06677)
		(size 0.5588)
		(drill 0.3048)
		(layers "F.Cu" "B.Cu")
		(net "DRIVE_A_2_INS")
	)
	(via
		(at 233.5276 -268.224)
		(size 0.6604)
		(drill 0.3302)
		(layers "F.Cu" "B.Cu")
		(net "DRIVE_A_2_INS")
	)
	(segment
		(start 182.96382 -267.514324)
		(end 173.167802 -277.310342)
		(width 0.13335)
		(layer "In2.Cu")
		(net "DRIVE_A_2_INS")
	)
	(segment
		(start 157.816804 -267.514324)
		(end 152.856946 -267.514324)
		(width 0.13335)
		(layer "In2.Cu")
		(net "DRIVE_A_2_INS")
	)
	(segment
		(start 232.104946 -270.358616)
		(end 189.678564 -270.358616)
		(width 0.13335)
		(layer "In2.Cu")
		(net "DRIVE_A_2_INS")
	)
	(segment
		(start 189.678564 -270.358616)
		(end 186.834272 -267.514324)
		(width 0.13335)
		(layer "In2.Cu")
		(net "DRIVE_A_2_INS")
	)
	(segment
		(start 124.03582 -267.31214)
		(end 105.35666 -267.31214)
		(width 0.13335)
		(layer "In2.Cu")
		(net "DRIVE_A_2_INS")
	)
	(segment
		(start 105.35666 -267.31214)
		(end 104.902 -267.7668)
		(width 0.13335)
		(layer "In2.Cu")
		(net "DRIVE_A_2_INS")
	)
	(segment
		(start 186.834272 -267.514324)
		(end 182.96382 -267.514324)
		(width 0.13335)
		(layer "In2.Cu")
		(net "DRIVE_A_2_INS")
	)
	(segment
		(start 232.396792 -270.06677)
		(end 232.104946 -270.358616)
		(width 0.13335)
		(layer "In2.Cu")
		(net "DRIVE_A_2_INS")
	)
	(segment
		(start 173.167802 -277.310342)
		(end 167.612822 -277.310342)
		(width 0.13335)
		(layer "In2.Cu")
		(net "DRIVE_A_2_INS")
	)
	(segment
		(start 124.49048 -267.7668)
		(end 124.03582 -267.31214)
		(width 0.13335)
		(layer "In2.Cu")
		(net "DRIVE_A_2_INS")
	)
	(segment
		(start 152.60447 -267.7668)
		(end 124.49048 -267.7668)
		(width 0.13335)
		(layer "In2.Cu")
		(net "DRIVE_A_2_INS")
	)
	(segment
		(start 152.856946 -267.514324)
		(end 152.60447 -267.7668)
		(width 0.13335)
		(layer "In2.Cu")
		(net "DRIVE_A_2_INS")
	)
	(segment
		(start 167.612822 -277.310342)
		(end 157.816804 -267.514324)
		(width 0.13335)
		(layer "In2.Cu")
		(net "DRIVE_A_2_INS")
	)
	(segment
		(start 99.994466 -293.99992)
		(end 99.994466 -272.674334)
		(width 0.12065)
		(layer "In4.Cu")
		(net "DRIVE_A_2_INS")
	)
	(segment
		(start 99.994466 -272.674334)
		(end 104.902 -267.7668)
		(width 0.12065)
		(layer "In4.Cu")
		(net "DRIVE_A_2_INS")
	)
	(segment
		(start 67.1576 -189.152276)
		(end 67.241674 -189.23635)
		(width 0.17145)
		(layer "F.Cu")
		(net "DRIVE_A_2_FLT_LED")
	)
	(segment
		(start 68.636388 -187.89777)
		(end 67.253104 -187.89777)
		(width 0.17145)
		(layer "F.Cu")
		(net "DRIVE_A_2_FLT_LED")
	)
	(segment
		(start 263.83488 -277.60676)
		(end 263.83488 -275.3106)
		(width 0.17145)
		(layer "F.Cu")
		(net "DRIVE_A_2_FLT_LED")
	)
	(segment
		(start 67.253104 -187.89777)
		(end 67.243706 -187.888372)
		(width 0.17145)
		(layer "F.Cu")
		(net "DRIVE_A_2_FLT_LED")
	)
	(segment
		(start 67.241674 -189.23635)
		(end 67.241674 -190.385954)
		(width 0.17145)
		(layer "F.Cu")
		(net "DRIVE_A_2_FLT_LED")
	)
	(segment
		(start 67.243706 -187.888372)
		(end 67.1576 -187.974478)
		(width 0.17145)
		(layer "F.Cu")
		(net "DRIVE_A_2_FLT_LED")
	)
	(segment
		(start 264.48512 -278.257)
		(end 263.83488 -277.60676)
		(width 0.17145)
		(layer "F.Cu")
		(net "DRIVE_A_2_FLT_LED")
	)
	(segment
		(start 67.1576 -187.974478)
		(end 67.1576 -189.152276)
		(width 0.17145)
		(layer "F.Cu")
		(net "DRIVE_A_2_FLT_LED")
	)
	(via
		(at 67.241674 -190.385954)
		(size 0.5588)
		(drill 0.3048)
		(layers "F.Cu" "B.Cu")
		(net "DRIVE_A_2_FLT_LED")
	)
	(via
		(at 67.241674 -189.23635)
		(size 0.6604)
		(drill 0.3302)
		(layers "F.Cu" "B.Cu")
		(net "DRIVE_A_2_FLT_LED")
	)
	(via
		(at 67.275456 -284.607)
		(size 0.5588)
		(drill 0.3048)
		(layers "F.Cu" "B.Cu")
		(net "DRIVE_A_2_FLT_LED")
	)
	(via
		(at 264.48512 -278.257)
		(size 0.5588)
		(drill 0.3048)
		(layers "F.Cu" "B.Cu")
		(net "DRIVE_A_2_FLT_LED")
	)
	(segment
		(start 264.48512 -278.257)
		(end 264.48512 -278.54148)
		(width 0.13335)
		(layer "In2.Cu")
		(net "DRIVE_A_2_FLT_LED")
	)
	(segment
		(start 173.659546 -287.48355)
		(end 113.439956 -287.48355)
		(width 0.13335)
		(layer "In2.Cu")
		(net "DRIVE_A_2_FLT_LED")
	)
	(segment
		(start 177.19548 -283.947616)
		(end 173.659546 -287.48355)
		(width 0.13335)
		(layer "In2.Cu")
		(net "DRIVE_A_2_FLT_LED")
	)
	(segment
		(start 110.563406 -284.607)
		(end 67.275456 -284.607)
		(width 0.13335)
		(layer "In2.Cu")
		(net "DRIVE_A_2_FLT_LED")
	)
	(segment
		(start 263.398 -279.6286)
		(end 256.998978 -279.6286)
		(width 0.13335)
		(layer "In2.Cu")
		(net "DRIVE_A_2_FLT_LED")
	)
	(segment
		(start 256.998978 -279.6286)
		(end 247.89892 -288.728658)
		(width 0.13335)
		(layer "In2.Cu")
		(net "DRIVE_A_2_FLT_LED")
	)
	(segment
		(start 113.439956 -287.48355)
		(end 110.563406 -284.607)
		(width 0.13335)
		(layer "In2.Cu")
		(net "DRIVE_A_2_FLT_LED")
	)
	(segment
		(start 247.89892 -288.728658)
		(end 207.287114 -288.728658)
		(width 0.13335)
		(layer "In2.Cu")
		(net "DRIVE_A_2_FLT_LED")
	)
	(segment
		(start 202.506072 -283.947616)
		(end 177.19548 -283.947616)
		(width 0.13335)
		(layer "In2.Cu")
		(net "DRIVE_A_2_FLT_LED")
	)
	(segment
		(start 264.48512 -278.54148)
		(end 263.398 -279.6286)
		(width 0.13335)
		(layer "In2.Cu")
		(net "DRIVE_A_2_FLT_LED")
	)
	(segment
		(start 207.287114 -288.728658)
		(end 202.506072 -283.947616)
		(width 0.13335)
		(layer "In2.Cu")
		(net "DRIVE_A_2_FLT_LED")
	)
	(segment
		(start 66.014346 -251.970794)
		(end 67.9958 -253.952248)
		(width 0.12065)
		(layer "In4.Cu")
		(net "DRIVE_A_2_FLT_LED")
	)
	(segment
		(start 66.4972 -191.636904)
		(end 66.014346 -192.119758)
		(width 0.12065)
		(layer "In4.Cu")
		(net "DRIVE_A_2_FLT_LED")
	)
	(segment
		(start 67.9958 -268.3002)
		(end 67.275456 -269.020544)
		(width 0.12065)
		(layer "In4.Cu")
		(net "DRIVE_A_2_FLT_LED")
	)
	(segment
		(start 67.9958 -253.952248)
		(end 67.9958 -268.3002)
		(width 0.12065)
		(layer "In4.Cu")
		(net "DRIVE_A_2_FLT_LED")
	)
	(segment
		(start 66.014346 -192.119758)
		(end 66.014346 -251.970794)
		(width 0.12065)
		(layer "In4.Cu")
		(net "DRIVE_A_2_FLT_LED")
	)
	(segment
		(start 67.275456 -269.020544)
		(end 67.275456 -284.607)
		(width 0.12065)
		(layer "In4.Cu")
		(net "DRIVE_A_2_FLT_LED")
	)
	(segment
		(start 67.241674 -190.385954)
		(end 66.4972 -191.130428)
		(width 0.12065)
		(layer "In4.Cu")
		(net "DRIVE_A_2_FLT_LED")
	)
	(segment
		(start 66.4972 -191.130428)
		(end 66.4972 -191.636904)
		(width 0.12065)
		(layer "In4.Cu")
		(net "DRIVE_A_2_FLT_LED")
	)
	(segment
		(start 69.72808 -182.62092)
		(end 69.72808 -182.520844)
		(width 0.17145)
		(layer "F.Cu")
		(net "DRIVE_A_2_ACT")
	)
	(segment
		(start 68.635372 -184.10809)
		(end 68.635372 -183.713628)
		(width 0.17145)
		(layer "F.Cu")
		(net "DRIVE_A_2_ACT")
	)
	(segment
		(start 69.72808 -181.381146)
		(end 69.72808 -180.202078)
		(width 0.17145)
		(layer "F.Cu")
		(net "DRIVE_A_2_ACT")
	)
	(segment
		(start 69.72808 -182.520844)
		(end 69.72808 -181.381146)
		(width 0.17145)
		(layer "F.Cu")
		(net "DRIVE_A_2_ACT")
	)
	(segment
		(start 68.635372 -183.713628)
		(end 69.72808 -182.62092)
		(width 0.17145)
		(layer "F.Cu")
		(net "DRIVE_A_2_ACT")
	)
	(via
		(at 72.0598 -337.3882)
		(size 0.5588)
		(drill 0.3048)
		(layers "F.Cu" "B.Cu")
		(net "DRIVE_A_2_ACT")
	)
	(via
		(at 69.72808 -180.202078)
		(size 0.5588)
		(drill 0.3048)
		(layers "F.Cu" "B.Cu")
		(net "DRIVE_A_2_ACT")
	)
	(via
		(at 69.72808 -182.520844)
		(size 0.6604)
		(drill 0.3302)
		(layers "F.Cu" "B.Cu")
		(net "DRIVE_A_2_ACT")
	)
	(segment
		(start 142.854172 -337.3882)
		(end 143.533368 -338.067396)
		(width 0.13335)
		(layer "In2.Cu")
		(net "DRIVE_A_2_ACT")
	)
	(segment
		(start 191.031876 -323.5706)
		(end 275.10867 -323.5706)
		(width 0.13335)
		(layer "In2.Cu")
		(net "DRIVE_A_2_ACT")
	)
	(segment
		(start 275.10867 -323.5706)
		(end 277.77567 -326.2376)
		(width 0.13335)
		(layer "In2.Cu")
		(net "DRIVE_A_2_ACT")
	)
	(segment
		(start 283.304234 -326.2376)
		(end 284.236668 -325.305166)
		(width 0.13335)
		(layer "In2.Cu")
		(net "DRIVE_A_2_ACT")
	)
	(segment
		(start 143.533368 -338.067396)
		(end 163.823904 -338.067396)
		(width 0.13335)
		(layer "In2.Cu")
		(net "DRIVE_A_2_ACT")
	)
	(segment
		(start 174.9933 -326.898)
		(end 187.704476 -326.898)
		(width 0.13335)
		(layer "In2.Cu")
		(net "DRIVE_A_2_ACT")
	)
	(segment
		(start 187.704476 -326.898)
		(end 191.031876 -323.5706)
		(width 0.13335)
		(layer "In2.Cu")
		(net "DRIVE_A_2_ACT")
	)
	(segment
		(start 163.823904 -338.067396)
		(end 174.9933 -326.898)
		(width 0.13335)
		(layer "In2.Cu")
		(net "DRIVE_A_2_ACT")
	)
	(segment
		(start 72.0598 -337.3882)
		(end 142.854172 -337.3882)
		(width 0.13335)
		(layer "In2.Cu")
		(net "DRIVE_A_2_ACT")
	)
	(segment
		(start 277.77567 -326.2376)
		(end 283.304234 -326.2376)
		(width 0.13335)
		(layer "In2.Cu")
		(net "DRIVE_A_2_ACT")
	)
	(segment
		(start 68.1863 -181.743858)
		(end 68.1863 -190.738252)
		(width 0.12065)
		(layer "In4.Cu")
		(net "DRIVE_A_2_ACT")
	)
	(segment
		(start 66.678048 -289.207448)
		(end 66.678048 -293.226236)
		(width 0.12065)
		(layer "In4.Cu")
		(net "DRIVE_A_2_ACT")
	)
	(segment
		(start 69.434456 -264.938256)
		(end 69.434456 -286.45104)
		(width 0.12065)
		(layer "In4.Cu")
		(net "DRIVE_A_2_ACT")
	)
	(segment
		(start 66.573146 -192.351406)
		(end 66.573146 -251.739146)
		(width 0.12065)
		(layer "In4.Cu")
		(net "DRIVE_A_2_ACT")
	)
	(segment
		(start 68.5546 -253.7206)
		(end 68.5546 -264.0584)
		(width 0.12065)
		(layer "In4.Cu")
		(net "DRIVE_A_2_ACT")
	)
	(segment
		(start 66.573146 -251.739146)
		(end 68.5546 -253.7206)
		(width 0.12065)
		(layer "In4.Cu")
		(net "DRIVE_A_2_ACT")
	)
	(segment
		(start 68.59778 -299.65142)
		(end 68.59778 -314.24118)
		(width 0.12065)
		(layer "In4.Cu")
		(net "DRIVE_A_2_ACT")
	)
	(segment
		(start 69.72808 -180.202078)
		(end 68.1863 -181.743858)
		(width 0.12065)
		(layer "In4.Cu")
		(net "DRIVE_A_2_ACT")
	)
	(segment
		(start 68.1863 -190.738252)
		(end 66.573146 -192.351406)
		(width 0.12065)
		(layer "In4.Cu")
		(net "DRIVE_A_2_ACT")
	)
	(segment
		(start 72.0598 -317.7032)
		(end 72.0598 -337.3882)
		(width 0.12065)
		(layer "In4.Cu")
		(net "DRIVE_A_2_ACT")
	)
	(segment
		(start 69.310504 -295.858692)
		(end 69.310504 -298.938696)
		(width 0.12065)
		(layer "In4.Cu")
		(net "DRIVE_A_2_ACT")
	)
	(segment
		(start 69.434456 -286.45104)
		(end 66.678048 -289.207448)
		(width 0.12065)
		(layer "In4.Cu")
		(net "DRIVE_A_2_ACT")
	)
	(segment
		(start 68.59778 -314.24118)
		(end 72.0598 -317.7032)
		(width 0.12065)
		(layer "In4.Cu")
		(net "DRIVE_A_2_ACT")
	)
	(segment
		(start 68.5546 -264.0584)
		(end 69.434456 -264.938256)
		(width 0.12065)
		(layer "In4.Cu")
		(net "DRIVE_A_2_ACT")
	)
	(segment
		(start 69.310504 -298.938696)
		(end 68.59778 -299.65142)
		(width 0.12065)
		(layer "In4.Cu")
		(net "DRIVE_A_2_ACT")
	)
	(segment
		(start 66.678048 -293.226236)
		(end 69.310504 -295.858692)
		(width 0.12065)
		(layer "In4.Cu")
		(net "DRIVE_A_2_ACT")
	)
	(segment
		(start 367.338102 -157.141418)
		(end 368.558064 -157.141418)
		(width 0.17145)
		(layer "F.Cu")
		(net "DRIVE_A_19_PWR")
	)
	(segment
		(start 246.049292 -235.955078)
		(end 246.07012 -235.93425)
		(width 0.17145)
		(layer "F.Cu")
		(net "DRIVE_A_19_PWR")
	)
	(segment
		(start 369.621308 -157.113478)
		(end 369.593368 -157.141418)
		(width 0.17145)
		(layer "F.Cu")
		(net "DRIVE_A_19_PWR")
	)
	(segment
		(start 369.593368 -157.141418)
		(end 368.558064 -157.141418)
		(width 0.17145)
		(layer "F.Cu")
		(net "DRIVE_A_19_PWR")
	)
	(segment
		(start 246.07012 -235.93425)
		(end 246.07012 -234.1626)
		(width 0.17145)
		(layer "F.Cu")
		(net "DRIVE_A_19_PWR")
	)
	(via
		(at 246.049292 -235.955078)
		(size 0.5588)
		(drill 0.3048)
		(layers "F.Cu" "B.Cu")
		(net "DRIVE_A_19_PWR")
	)
	(via
		(at 369.621308 -157.113478)
		(size 0.5588)
		(drill 0.3048)
		(layers "F.Cu" "B.Cu")
		(net "DRIVE_A_19_PWR")
	)
	(via
		(at 368.558064 -157.141418)
		(size 0.6604)
		(drill 0.3302)
		(layers "F.Cu" "B.Cu")
		(net "DRIVE_A_19_PWR")
	)
	(via
		(at 365.887 -226.949)
		(size 0.5588)
		(drill 0.3048)
		(layers "F.Cu" "B.Cu")
		(net "DRIVE_A_19_PWR")
	)
	(segment
		(start 279.937464 -216.132918)
		(end 316.20587 -216.132918)
		(width 0.13335)
		(layer "In2.Cu")
		(net "DRIVE_A_19_PWR")
	)
	(segment
		(start 264.259822 -228.434138)
		(end 267.636244 -228.434138)
		(width 0.13335)
		(layer "In2.Cu")
		(net "DRIVE_A_19_PWR")
	)
	(segment
		(start 316.20587 -216.132918)
		(end 326.996552 -226.9236)
		(width 0.13335)
		(layer "In2.Cu")
		(net "DRIVE_A_19_PWR")
	)
	(segment
		(start 365.8616 -226.9236)
		(end 365.887 -226.949)
		(width 0.13335)
		(layer "In2.Cu")
		(net "DRIVE_A_19_PWR")
	)
	(segment
		(start 246.829326 -234.105704)
		(end 258.35229 -234.105704)
		(width 0.13335)
		(layer "In2.Cu")
		(net "DRIVE_A_19_PWR")
	)
	(segment
		(start 262.08736 -230.6066)
		(end 264.259822 -228.434138)
		(width 0.13335)
		(layer "In2.Cu")
		(net "DRIVE_A_19_PWR")
	)
	(segment
		(start 258.35229 -234.105704)
		(end 261.851394 -230.6066)
		(width 0.13335)
		(layer "In2.Cu")
		(net "DRIVE_A_19_PWR")
	)
	(segment
		(start 261.851394 -230.6066)
		(end 262.08736 -230.6066)
		(width 0.13335)
		(layer "In2.Cu")
		(net "DRIVE_A_19_PWR")
	)
	(segment
		(start 326.996552 -226.9236)
		(end 365.8616 -226.9236)
		(width 0.13335)
		(layer "In2.Cu")
		(net "DRIVE_A_19_PWR")
	)
	(segment
		(start 246.049292 -234.885738)
		(end 246.829326 -234.105704)
		(width 0.13335)
		(layer "In2.Cu")
		(net "DRIVE_A_19_PWR")
	)
	(segment
		(start 246.049292 -235.955078)
		(end 246.049292 -234.885738)
		(width 0.13335)
		(layer "In2.Cu")
		(net "DRIVE_A_19_PWR")
	)
	(segment
		(start 267.636244 -228.434138)
		(end 279.937464 -216.132918)
		(width 0.13335)
		(layer "In2.Cu")
		(net "DRIVE_A_19_PWR")
	)
	(segment
		(start 365.7854 -226.8474)
		(end 365.887 -226.949)
		(width 0.12065)
		(layer "In4.Cu")
		(net "DRIVE_A_19_PWR")
	)
	(segment
		(start 365.7854 -214.9094)
		(end 365.7854 -226.8474)
		(width 0.12065)
		(layer "In4.Cu")
		(net "DRIVE_A_19_PWR")
	)
	(segment
		(start 369.6208 -157.113986)
		(end 369.6208 -211.074)
		(width 0.12065)
		(layer "In4.Cu")
		(net "DRIVE_A_19_PWR")
	)
	(segment
		(start 369.621308 -157.113478)
		(end 369.6208 -157.113986)
		(width 0.12065)
		(layer "In4.Cu")
		(net "DRIVE_A_19_PWR")
	)
	(segment
		(start 369.6208 -211.074)
		(end 365.7854 -214.9094)
		(width 0.12065)
		(layer "In4.Cu")
		(net "DRIVE_A_19_PWR")
	)
	(segment
		(start 349.69069 -182.22849)
		(end 349.209106 -181.746906)
		(width 0.17145)
		(layer "F.Cu")
		(net "DRIVE_A_19_INS")
	)
	(segment
		(start 348.669102 -181.206902)
		(end 349.209106 -181.746906)
		(width 0.17145)
		(layer "F.Cu")
		(net "DRIVE_A_19_INS")
	)
	(segment
		(start 351.523808 -182.22849)
		(end 349.69069 -182.22849)
		(width 0.17145)
		(layer "F.Cu")
		(net "DRIVE_A_19_INS")
	)
	(segment
		(start 244.14988 -255.3716)
		(end 244.80012 -254.72136)
		(width 0.17145)
		(layer "F.Cu")
		(net "DRIVE_A_19_INS")
	)
	(segment
		(start 244.80012 -254.72136)
		(end 244.80012 -252.0696)
		(width 0.17145)
		(layer "F.Cu")
		(net "DRIVE_A_19_INS")
	)
	(segment
		(start 348.669102 -180.064918)
		(end 348.669102 -181.206902)
		(width 0.17145)
		(layer "F.Cu")
		(net "DRIVE_A_19_INS")
	)
	(via
		(at 351.523808 -182.22849)
		(size 0.5588)
		(drill 0.3048)
		(layers "F.Cu" "B.Cu")
		(net "DRIVE_A_19_INS")
	)
	(via
		(at 349.209106 -181.746906)
		(size 0.6604)
		(drill 0.3302)
		(layers "F.Cu" "B.Cu")
		(net "DRIVE_A_19_INS")
	)
	(via
		(at 244.14988 -255.3716)
		(size 0.5588)
		(drill 0.3048)
		(layers "F.Cu" "B.Cu")
		(net "DRIVE_A_19_INS")
	)
	(via
		(at 353.314 -236.8296)
		(size 0.5588)
		(drill 0.3048)
		(layers "F.Cu" "B.Cu")
		(net "DRIVE_A_19_INS")
	)
	(segment
		(start 294.048434 -228.553518)
		(end 311.373012 -228.553518)
		(width 0.13335)
		(layer "In2.Cu")
		(net "DRIVE_A_19_INS")
	)
	(segment
		(start 244.14988 -255.3716)
		(end 244.89156 -254.62992)
		(width 0.13335)
		(layer "In2.Cu")
		(net "DRIVE_A_19_INS")
	)
	(segment
		(start 285.37789 -237.224062)
		(end 294.048434 -228.553518)
		(width 0.13335)
		(layer "In2.Cu")
		(net "DRIVE_A_19_INS")
	)
	(segment
		(start 253.430532 -248.243598)
		(end 258.953508 -248.243598)
		(width 0.13335)
		(layer "In2.Cu")
		(net "DRIVE_A_19_INS")
	)
	(segment
		(start 277.423118 -237.224062)
		(end 285.37789 -237.224062)
		(width 0.13335)
		(layer "In2.Cu")
		(net "DRIVE_A_19_INS")
	)
	(segment
		(start 244.89156 -253.894336)
		(end 246.182896 -252.603)
		(width 0.13335)
		(layer "In2.Cu")
		(net "DRIVE_A_19_INS")
	)
	(segment
		(start 311.373012 -228.553518)
		(end 320.59753 -237.778036)
		(width 0.13335)
		(layer "In2.Cu")
		(net "DRIVE_A_19_INS")
	)
	(segment
		(start 244.89156 -254.62992)
		(end 244.89156 -253.894336)
		(width 0.13335)
		(layer "In2.Cu")
		(net "DRIVE_A_19_INS")
	)
	(segment
		(start 258.953508 -248.243598)
		(end 260.989826 -246.20728)
		(width 0.13335)
		(layer "In2.Cu")
		(net "DRIVE_A_19_INS")
	)
	(segment
		(start 246.182896 -252.603)
		(end 249.07113 -252.603)
		(width 0.13335)
		(layer "In2.Cu")
		(net "DRIVE_A_19_INS")
	)
	(segment
		(start 260.989826 -246.20728)
		(end 268.4399 -246.20728)
		(width 0.13335)
		(layer "In2.Cu")
		(net "DRIVE_A_19_INS")
	)
	(segment
		(start 268.4399 -246.20728)
		(end 277.423118 -237.224062)
		(width 0.13335)
		(layer "In2.Cu")
		(net "DRIVE_A_19_INS")
	)
	(segment
		(start 320.59753 -237.778036)
		(end 341.502746 -237.778036)
		(width 0.13335)
		(layer "In2.Cu")
		(net "DRIVE_A_19_INS")
	)
	(segment
		(start 341.502746 -237.778036)
		(end 342.451182 -236.8296)
		(width 0.13335)
		(layer "In2.Cu")
		(net "DRIVE_A_19_INS")
	)
	(segment
		(start 342.451182 -236.8296)
		(end 353.314 -236.8296)
		(width 0.13335)
		(layer "In2.Cu")
		(net "DRIVE_A_19_INS")
	)
	(segment
		(start 249.07113 -252.603)
		(end 253.430532 -248.243598)
		(width 0.13335)
		(layer "In2.Cu")
		(net "DRIVE_A_19_INS")
	)
	(segment
		(start 351.523808 -182.22849)
		(end 351.523808 -200.393808)
		(width 0.12065)
		(layer "In4.Cu")
		(net "DRIVE_A_19_INS")
	)
	(segment
		(start 354.544122 -235.599478)
		(end 353.314 -236.8296)
		(width 0.12065)
		(layer "In4.Cu")
		(net "DRIVE_A_19_INS")
	)
	(segment
		(start 351.523808 -200.393808)
		(end 354.544122 -203.414122)
		(width 0.12065)
		(layer "In4.Cu")
		(net "DRIVE_A_19_INS")
	)
	(segment
		(start 354.544122 -203.414122)
		(end 354.544122 -235.599478)
		(width 0.12065)
		(layer "In4.Cu")
		(net "DRIVE_A_19_INS")
	)
	(segment
		(start 276.55012 -273.991832)
		(end 276.55012 -275.5646)
		(width 0.17145)
		(layer "F.Cu")
		(net "DRIVE_A_19_FLT_LED")
	)
	(segment
		(start 342.865202 -130.876802)
		(end 343.789 -131.8006)
		(width 0.17145)
		(layer "F.Cu")
		(net "DRIVE_A_19_FLT_LED")
	)
	(segment
		(start 344.367612 -129.14757)
		(end 344.367612 -130.386836)
		(width 0.17145)
		(layer "F.Cu")
		(net "DRIVE_A_19_FLT_LED")
	)
	(segment
		(start 344.367612 -130.386836)
		(end 342.865202 -130.386836)
		(width 0.17145)
		(layer "F.Cu")
		(net "DRIVE_A_19_FLT_LED")
	)
	(segment
		(start 342.865202 -130.386836)
		(end 342.865202 -130.876802)
		(width 0.17145)
		(layer "F.Cu")
		(net "DRIVE_A_19_FLT_LED")
	)
	(segment
		(start 343.939876 -128.719834)
		(end 344.367612 -129.14757)
		(width 0.17145)
		(layer "F.Cu")
		(net "DRIVE_A_19_FLT_LED")
	)
	(segment
		(start 277.239476 -273.302476)
		(end 276.55012 -273.991832)
		(width 0.17145)
		(layer "F.Cu")
		(net "DRIVE_A_19_FLT_LED")
	)
	(via
		(at 277.239476 -273.302476)
		(size 0.5588)
		(drill 0.3048)
		(layers "F.Cu" "B.Cu")
		(net "DRIVE_A_19_FLT_LED")
	)
	(via
		(at 351.7392 -254.677164)
		(size 0.5588)
		(drill 0.3048)
		(layers "F.Cu" "B.Cu")
		(net "DRIVE_A_19_FLT_LED")
	)
	(via
		(at 343.789 -131.8006)
		(size 0.5588)
		(drill 0.3048)
		(layers "F.Cu" "B.Cu")
		(net "DRIVE_A_19_FLT_LED")
	)
	(via
		(at 344.367612 -130.386836)
		(size 0.6604)
		(drill 0.3302)
		(layers "F.Cu" "B.Cu")
		(net "DRIVE_A_19_FLT_LED")
	)
	(segment
		(start 281.739594 -268.297406)
		(end 308.143656 -268.297406)
		(width 0.13335)
		(layer "In2.Cu")
		(net "DRIVE_A_19_FLT_LED")
	)
	(segment
		(start 277.239476 -272.797524)
		(end 281.739594 -268.297406)
		(width 0.13335)
		(layer "In2.Cu")
		(net "DRIVE_A_19_FLT_LED")
	)
	(segment
		(start 277.239476 -273.302476)
		(end 277.239476 -272.797524)
		(width 0.13335)
		(layer "In2.Cu")
		(net "DRIVE_A_19_FLT_LED")
	)
	(segment
		(start 308.143656 -268.297406)
		(end 321.763898 -254.677164)
		(width 0.13335)
		(layer "In2.Cu")
		(net "DRIVE_A_19_FLT_LED")
	)
	(segment
		(start 321.763898 -254.677164)
		(end 351.7392 -254.677164)
		(width 0.13335)
		(layer "In2.Cu")
		(net "DRIVE_A_19_FLT_LED")
	)
	(segment
		(start 341.16645 -168.928796)
		(end 341.16645 -163.209478)
		(width 0.12065)
		(layer "In4.Cu")
		(net "DRIVE_A_19_FLT_LED")
	)
	(segment
		(start 350.277176 -181.67223)
		(end 342.613996 -174.00905)
		(width 0.12065)
		(layer "In4.Cu")
		(net "DRIVE_A_19_FLT_LED")
	)
	(segment
		(start 342.613996 -174.00905)
		(end 342.613996 -170.376342)
		(width 0.12065)
		(layer "In4.Cu")
		(net "DRIVE_A_19_FLT_LED")
	)
	(segment
		(start 351.739454 -202.387454)
		(end 350.277176 -200.925176)
		(width 0.12065)
		(layer "In4.Cu")
		(net "DRIVE_A_19_FLT_LED")
	)
	(segment
		(start 337.955636 -159.998664)
		(end 337.955636 -158.720282)
		(width 0.12065)
		(layer "In4.Cu")
		(net "DRIVE_A_19_FLT_LED")
	)
	(segment
		(start 337.452208 -138.137392)
		(end 343.789 -131.8006)
		(width 0.12065)
		(layer "In4.Cu")
		(net "DRIVE_A_19_FLT_LED")
	)
	(segment
		(start 351.739454 -202.850242)
		(end 351.739454 -202.387454)
		(width 0.12065)
		(layer "In4.Cu")
		(net "DRIVE_A_19_FLT_LED")
	)
	(segment
		(start 342.613996 -170.376342)
		(end 341.16645 -168.928796)
		(width 0.12065)
		(layer "In4.Cu")
		(net "DRIVE_A_19_FLT_LED")
	)
	(segment
		(start 351.7392 -254.677164)
		(end 351.7392 -202.850496)
		(width 0.12065)
		(layer "In4.Cu")
		(net "DRIVE_A_19_FLT_LED")
	)
	(segment
		(start 350.277176 -200.925176)
		(end 350.277176 -181.67223)
		(width 0.12065)
		(layer "In4.Cu")
		(net "DRIVE_A_19_FLT_LED")
	)
	(segment
		(start 351.7392 -202.850496)
		(end 351.739454 -202.850242)
		(width 0.12065)
		(layer "In4.Cu")
		(net "DRIVE_A_19_FLT_LED")
	)
	(segment
		(start 337.955636 -158.720282)
		(end 337.452208 -158.216854)
		(width 0.12065)
		(layer "In4.Cu")
		(net "DRIVE_A_19_FLT_LED")
	)
	(segment
		(start 341.16645 -163.209478)
		(end 337.955636 -159.998664)
		(width 0.12065)
		(layer "In4.Cu")
		(net "DRIVE_A_19_FLT_LED")
	)
	(segment
		(start 337.452208 -158.216854)
		(end 337.452208 -138.137392)
		(width 0.12065)
		(layer "In4.Cu")
		(net "DRIVE_A_19_FLT_LED")
	)
	(segment
		(start 339.8774 -132.1562)
		(end 339.3694 -131.6482)
		(width 0.17145)
		(layer "F.Cu")
		(net "DRIVE_A_19_ACT")
	)
	(segment
		(start 339.274404 -130.378962)
		(end 340.649306 -130.378962)
		(width 0.17145)
		(layer "F.Cu")
		(net "DRIVE_A_19_ACT")
	)
	(segment
		(start 340.649306 -130.378962)
		(end 340.680548 -130.410204)
		(width 0.17145)
		(layer "F.Cu")
		(net "DRIVE_A_19_ACT")
	)
	(segment
		(start 340.35619 -128.720088)
		(end 340.680548 -129.044446)
		(width 0.17145)
		(layer "F.Cu")
		(net "DRIVE_A_19_ACT")
	)
	(segment
		(start 339.3694 -130.473958)
		(end 339.274404 -130.378962)
		(width 0.17145)
		(layer "F.Cu")
		(net "DRIVE_A_19_ACT")
	)
	(segment
		(start 339.3694 -131.6482)
		(end 339.3694 -130.473958)
		(width 0.17145)
		(layer "F.Cu")
		(net "DRIVE_A_19_ACT")
	)
	(segment
		(start 340.680548 -129.044446)
		(end 340.680548 -130.410204)
		(width 0.17145)
		(layer "F.Cu")
		(net "DRIVE_A_19_ACT")
	)
	(via
		(at 352.679 -311.1246)
		(size 0.5588)
		(drill 0.3048)
		(layers "F.Cu" "B.Cu")
		(net "DRIVE_A_19_ACT")
	)
	(via
		(at 340.680548 -130.410204)
		(size 0.6604)
		(drill 0.3302)
		(layers "F.Cu" "B.Cu")
		(net "DRIVE_A_19_ACT")
	)
	(via
		(at 339.8774 -132.1562)
		(size 0.5588)
		(drill 0.3048)
		(layers "F.Cu" "B.Cu")
		(net "DRIVE_A_19_ACT")
	)
	(via
		(at 292.8112 -310.657748)
		(size 0.5588)
		(drill 0.3048)
		(layers "F.Cu" "B.Cu")
		(net "DRIVE_A_19_ACT")
	)
	(segment
		(start 323.402452 -310.657748)
		(end 292.8112 -310.657748)
		(width 0.13335)
		(layer "In2.Cu")
		(net "DRIVE_A_19_ACT")
	)
	(segment
		(start 352.679 -311.1246)
		(end 323.869304 -311.1246)
		(width 0.13335)
		(layer "In2.Cu")
		(net "DRIVE_A_19_ACT")
	)
	(segment
		(start 323.869304 -311.1246)
		(end 323.402452 -310.657748)
		(width 0.13335)
		(layer "In2.Cu")
		(net "DRIVE_A_19_ACT")
	)
	(segment
		(start 340.7537 -163.380674)
		(end 337.542886 -160.16986)
		(width 0.12065)
		(layer "In4.Cu")
		(net "DRIVE_A_19_ACT")
	)
	(segment
		(start 351.1804 -202.618848)
		(end 349.718376 -201.156824)
		(width 0.12065)
		(layer "In4.Cu")
		(net "DRIVE_A_19_ACT")
	)
	(segment
		(start 342.201246 -170.547538)
		(end 340.7537 -169.099992)
		(width 0.12065)
		(layer "In4.Cu")
		(net "DRIVE_A_19_ACT")
	)
	(segment
		(start 342.201246 -174.180246)
		(end 342.201246 -170.547538)
		(width 0.12065)
		(layer "In4.Cu")
		(net "DRIVE_A_19_ACT")
	)
	(segment
		(start 352.679 -311.1246)
		(end 352.679 -271.653)
		(width 0.12065)
		(layer "In4.Cu")
		(net "DRIVE_A_19_ACT")
	)
	(segment
		(start 349.718376 -181.697376)
		(end 342.201246 -174.180246)
		(width 0.12065)
		(layer "In4.Cu")
		(net "DRIVE_A_19_ACT")
	)
	(segment
		(start 336.893408 -158.242)
		(end 336.893408 -135.140192)
		(width 0.12065)
		(layer "In4.Cu")
		(net "DRIVE_A_19_ACT")
	)
	(segment
		(start 340.7537 -169.099992)
		(end 340.7537 -163.380674)
		(width 0.12065)
		(layer "In4.Cu")
		(net "DRIVE_A_19_ACT")
	)
	(segment
		(start 349.718376 -201.156824)
		(end 349.718376 -181.697376)
		(width 0.12065)
		(layer "In4.Cu")
		(net "DRIVE_A_19_ACT")
	)
	(segment
		(start 336.893408 -135.140192)
		(end 339.8774 -132.1562)
		(width 0.12065)
		(layer "In4.Cu")
		(net "DRIVE_A_19_ACT")
	)
	(segment
		(start 351.1804 -270.1544)
		(end 351.1804 -202.618848)
		(width 0.12065)
		(layer "In4.Cu")
		(net "DRIVE_A_19_ACT")
	)
	(segment
		(start 337.542886 -160.16986)
		(end 337.542886 -158.891478)
		(width 0.12065)
		(layer "In4.Cu")
		(net "DRIVE_A_19_ACT")
	)
	(segment
		(start 337.542886 -158.891478)
		(end 336.893408 -158.242)
		(width 0.12065)
		(layer "In4.Cu")
		(net "DRIVE_A_19_ACT")
	)
	(segment
		(start 352.679 -271.653)
		(end 351.1804 -270.1544)
		(width 0.12065)
		(layer "In4.Cu")
		(net "DRIVE_A_19_ACT")
	)
	(segment
		(start 282.83662 -310.905144)
		(end 283.576776 -311.6453)
		(width 0.13335)
		(layer "In9.Cu")
		(net "DRIVE_A_19_ACT")
	)
	(segment
		(start 291.217858 -310.657748)
		(end 292.8112 -310.657748)
		(width 0.13335)
		(layer "In9.Cu")
		(net "DRIVE_A_19_ACT")
	)
	(segment
		(start 290.230306 -311.6453)
		(end 291.217858 -310.657748)
		(width 0.13335)
		(layer "In9.Cu")
		(net "DRIVE_A_19_ACT")
	)
	(segment
		(start 283.576776 -311.6453)
		(end 290.230306 -311.6453)
		(width 0.13335)
		(layer "In9.Cu")
		(net "DRIVE_A_19_ACT")
	)
	(segment
		(start 245.766082 -237.136178)
		(end 245.41988 -236.789976)
		(width 0.17145)
		(layer "F.Cu")
		(net "DRIVE_A_18_PWR")
	)
	(segment
		(start 336.911442 -157.141418)
		(end 337.227418 -157.141418)
		(width 0.17145)
		(layer "F.Cu")
		(net "DRIVE_A_18_PWR")
	)
	(segment
		(start 245.41988 -236.789976)
		(end 245.41988 -234.1626)
		(width 0.17145)
		(layer "F.Cu")
		(net "DRIVE_A_18_PWR")
	)
	(segment
		(start 335.788 -157.141418)
		(end 336.911442 -157.141418)
		(width 0.17145)
		(layer "F.Cu")
		(net "DRIVE_A_18_PWR")
	)
	(segment
		(start 337.227418 -157.141418)
		(end 339.344 -159.258)
		(width 0.17145)
		(layer "F.Cu")
		(net "DRIVE_A_18_PWR")
	)
	(via
		(at 353.65817 -225.220784)
		(size 0.5588)
		(drill 0.3048)
		(layers "F.Cu" "B.Cu")
		(net "DRIVE_A_18_PWR")
	)
	(via
		(at 245.766082 -237.136178)
		(size 0.5588)
		(drill 0.3048)
		(layers "F.Cu" "B.Cu")
		(net "DRIVE_A_18_PWR")
	)
	(via
		(at 336.911442 -157.141418)
		(size 0.6604)
		(drill 0.3302)
		(layers "F.Cu" "B.Cu")
		(net "DRIVE_A_18_PWR")
	)
	(via
		(at 339.344 -159.258)
		(size 0.5588)
		(drill 0.3048)
		(layers "F.Cu" "B.Cu")
		(net "DRIVE_A_18_PWR")
	)
	(segment
		(start 316.437518 -215.574118)
		(end 326.371966 -225.508566)
		(width 0.13335)
		(layer "In2.Cu")
		(net "DRIVE_A_18_PWR")
	)
	(segment
		(start 353.370388 -225.508566)
		(end 353.65817 -225.220784)
		(width 0.13335)
		(layer "In2.Cu")
		(net "DRIVE_A_18_PWR")
	)
	(segment
		(start 258.176014 -233.680254)
		(end 261.675118 -230.18115)
		(width 0.13335)
		(layer "In2.Cu")
		(net "DRIVE_A_18_PWR")
	)
	(segment
		(start 245.766082 -237.136178)
		(end 245.41988 -236.789976)
		(width 0.13335)
		(layer "In2.Cu")
		(net "DRIVE_A_18_PWR")
	)
	(segment
		(start 264.083546 -228.008688)
		(end 267.271246 -228.008688)
		(width 0.13335)
		(layer "In2.Cu")
		(net "DRIVE_A_18_PWR")
	)
	(segment
		(start 261.675118 -230.18115)
		(end 261.911084 -230.18115)
		(width 0.13335)
		(layer "In2.Cu")
		(net "DRIVE_A_18_PWR")
	)
	(segment
		(start 261.911084 -230.18115)
		(end 264.083546 -228.008688)
		(width 0.13335)
		(layer "In2.Cu")
		(net "DRIVE_A_18_PWR")
	)
	(segment
		(start 267.271246 -228.008688)
		(end 279.705816 -215.574118)
		(width 0.13335)
		(layer "In2.Cu")
		(net "DRIVE_A_18_PWR")
	)
	(segment
		(start 246.65305 -233.680254)
		(end 258.176014 -233.680254)
		(width 0.13335)
		(layer "In2.Cu")
		(net "DRIVE_A_18_PWR")
	)
	(segment
		(start 279.705816 -215.574118)
		(end 316.437518 -215.574118)
		(width 0.13335)
		(layer "In2.Cu")
		(net "DRIVE_A_18_PWR")
	)
	(segment
		(start 245.41988 -236.789976)
		(end 245.41988 -234.913424)
		(width 0.13335)
		(layer "In2.Cu")
		(net "DRIVE_A_18_PWR")
	)
	(segment
		(start 245.41988 -234.913424)
		(end 246.65305 -233.680254)
		(width 0.13335)
		(layer "In2.Cu")
		(net "DRIVE_A_18_PWR")
	)
	(segment
		(start 326.371966 -225.508566)
		(end 353.370388 -225.508566)
		(width 0.13335)
		(layer "In2.Cu")
		(net "DRIVE_A_18_PWR")
	)
	(segment
		(start 341.5792 -168.3512)
		(end 343.382854 -170.154854)
		(width 0.12065)
		(layer "In4.Cu")
		(net "DRIVE_A_18_PWR")
	)
	(segment
		(start 339.344 -159.258)
		(end 339.344 -160.803082)
		(width 0.12065)
		(layer "In4.Cu")
		(net "DRIVE_A_18_PWR")
	)
	(segment
		(start 343.382854 -170.154854)
		(end 343.382854 -174.193962)
		(width 0.12065)
		(layer "In4.Cu")
		(net "DRIVE_A_18_PWR")
	)
	(segment
		(start 350.689926 -181.525926)
		(end 350.835976 -181.671976)
		(width 0.12065)
		(layer "In4.Cu")
		(net "DRIVE_A_18_PWR")
	)
	(segment
		(start 339.344 -160.803082)
		(end 341.5792 -163.038282)
		(width 0.12065)
		(layer "In4.Cu")
		(net "DRIVE_A_18_PWR")
	)
	(segment
		(start 341.5792 -163.038282)
		(end 341.5792 -168.3512)
		(width 0.12065)
		(layer "In4.Cu")
		(net "DRIVE_A_18_PWR")
	)
	(segment
		(start 343.382854 -174.193962)
		(end 350.689926 -181.501034)
		(width 0.12065)
		(layer "In4.Cu")
		(net "DRIVE_A_18_PWR")
	)
	(segment
		(start 350.689926 -181.501034)
		(end 350.689926 -181.525926)
		(width 0.12065)
		(layer "In4.Cu")
		(net "DRIVE_A_18_PWR")
	)
	(segment
		(start 350.835976 -200.693528)
		(end 352.425 -202.282552)
		(width 0.12065)
		(layer "In4.Cu")
		(net "DRIVE_A_18_PWR")
	)
	(segment
		(start 352.425 -202.282552)
		(end 352.425 -223.987614)
		(width 0.12065)
		(layer "In4.Cu")
		(net "DRIVE_A_18_PWR")
	)
	(segment
		(start 352.425 -223.987614)
		(end 353.65817 -225.220784)
		(width 0.12065)
		(layer "In4.Cu")
		(net "DRIVE_A_18_PWR")
	)
	(segment
		(start 350.835976 -181.671976)
		(end 350.835976 -200.693528)
		(width 0.12065)
		(layer "In4.Cu")
		(net "DRIVE_A_18_PWR")
	)
	(segment
		(start 317.9572 -181.8894)
		(end 317.66764 -181.59984)
		(width 0.17145)
		(layer "F.Cu")
		(net "DRIVE_A_18_INS")
	)
	(segment
		(start 244.14988 -252.0696)
		(end 244.14988 -254.4064)
		(width 0.17145)
		(layer "F.Cu")
		(net "DRIVE_A_18_INS")
	)
	(segment
		(start 317.119 -180.064918)
		(end 317.119 -181.0512)
		(width 0.17145)
		(layer "F.Cu")
		(net "DRIVE_A_18_INS")
	)
	(segment
		(start 317.119 -181.0512)
		(end 317.66764 -181.59984)
		(width 0.17145)
		(layer "F.Cu")
		(net "DRIVE_A_18_INS")
	)
	(segment
		(start 322.1736 -181.8894)
		(end 317.9572 -181.8894)
		(width 0.17145)
		(layer "F.Cu")
		(net "DRIVE_A_18_INS")
	)
	(via
		(at 322.1736 -181.8894)
		(size 0.5588)
		(drill 0.3048)
		(layers "F.Cu" "B.Cu")
		(net "DRIVE_A_18_INS")
	)
	(via
		(at 340.669626 -237.053628)
		(size 0.5588)
		(drill 0.3048)
		(layers "F.Cu" "B.Cu")
		(net "DRIVE_A_18_INS")
	)
	(via
		(at 244.14988 -254.4064)
		(size 0.5588)
		(drill 0.3048)
		(layers "F.Cu" "B.Cu")
		(net "DRIVE_A_18_INS")
	)
	(via
		(at 317.66764 -181.59984)
		(size 0.6604)
		(drill 0.3302)
		(layers "F.Cu" "B.Cu")
		(net "DRIVE_A_18_INS")
	)
	(segment
		(start 259.559298 -246.84736)
		(end 251.887228 -246.84736)
		(width 0.13335)
		(layer "In2.Cu")
		(net "DRIVE_A_18_INS")
	)
	(segment
		(start 244.14988 -253.845568)
		(end 244.14988 -254.4064)
		(width 0.13335)
		(layer "In2.Cu")
		(net "DRIVE_A_18_INS")
	)
	(segment
		(start 260.758178 -245.64848)
		(end 259.559298 -246.84736)
		(width 0.13335)
		(layer "In2.Cu")
		(net "DRIVE_A_18_INS")
	)
	(segment
		(start 249.573034 -250.832366)
		(end 248.3612 -252.0442)
		(width 0.13335)
		(layer "In2.Cu")
		(net "DRIVE_A_18_INS")
	)
	(segment
		(start 245.951248 -252.0442)
		(end 244.14988 -253.845568)
		(width 0.13335)
		(layer "In2.Cu")
		(net "DRIVE_A_18_INS")
	)
	(segment
		(start 277.19147 -236.665262)
		(end 268.208252 -245.64848)
		(width 0.13335)
		(layer "In2.Cu")
		(net "DRIVE_A_18_INS")
	)
	(segment
		(start 293.816786 -227.994718)
		(end 285.146242 -236.665262)
		(width 0.13335)
		(layer "In2.Cu")
		(net "DRIVE_A_18_INS")
	)
	(segment
		(start 320.820796 -237.210854)
		(end 311.60466 -227.994718)
		(width 0.13335)
		(layer "In2.Cu")
		(net "DRIVE_A_18_INS")
	)
	(segment
		(start 340.669626 -237.053628)
		(end 340.5124 -237.210854)
		(width 0.13335)
		(layer "In2.Cu")
		(net "DRIVE_A_18_INS")
	)
	(segment
		(start 249.573034 -249.161554)
		(end 249.573034 -250.832366)
		(width 0.13335)
		(layer "In2.Cu")
		(net "DRIVE_A_18_INS")
	)
	(segment
		(start 340.5124 -237.210854)
		(end 320.820796 -237.210854)
		(width 0.13335)
		(layer "In2.Cu")
		(net "DRIVE_A_18_INS")
	)
	(segment
		(start 311.60466 -227.994718)
		(end 293.816786 -227.994718)
		(width 0.13335)
		(layer "In2.Cu")
		(net "DRIVE_A_18_INS")
	)
	(segment
		(start 248.3612 -252.0442)
		(end 245.951248 -252.0442)
		(width 0.13335)
		(layer "In2.Cu")
		(net "DRIVE_A_18_INS")
	)
	(segment
		(start 268.208252 -245.64848)
		(end 260.758178 -245.64848)
		(width 0.13335)
		(layer "In2.Cu")
		(net "DRIVE_A_18_INS")
	)
	(segment
		(start 251.887228 -246.84736)
		(end 249.573034 -249.161554)
		(width 0.13335)
		(layer "In2.Cu")
		(net "DRIVE_A_18_INS")
	)
	(segment
		(start 285.146242 -236.665262)
		(end 277.19147 -236.665262)
		(width 0.13335)
		(layer "In2.Cu")
		(net "DRIVE_A_18_INS")
	)
	(segment
		(start 327.963276 -194.028822)
		(end 340.669626 -206.735172)
		(width 0.12065)
		(layer "In4.Cu")
		(net "DRIVE_A_18_INS")
	)
	(segment
		(start 322.1736 -181.8894)
		(end 322.1736 -186.045602)
		(width 0.12065)
		(layer "In4.Cu")
		(net "DRIVE_A_18_INS")
	)
	(segment
		(start 340.669626 -206.735172)
		(end 340.669626 -237.053628)
		(width 0.12065)
		(layer "In4.Cu")
		(net "DRIVE_A_18_INS")
	)
	(segment
		(start 327.963276 -191.835278)
		(end 327.963276 -194.028822)
		(width 0.12065)
		(layer "In4.Cu")
		(net "DRIVE_A_18_INS")
	)
	(segment
		(start 322.1736 -186.045602)
		(end 327.963276 -191.835278)
		(width 0.12065)
		(layer "In4.Cu")
		(net "DRIVE_A_18_INS")
	)
	(segment
		(start 277.2156 -272.0086)
		(end 277.2156 -272.5166)
		(width 0.17145)
		(layer "F.Cu")
		(net "DRIVE_A_18_FLT_LED")
	)
	(segment
		(start 319.466468 -128.7526)
		(end 319.894204 -129.180336)
		(width 0.17145)
		(layer "F.Cu")
		(net "DRIVE_A_18_FLT_LED")
	)
	(segment
		(start 318.391794 -131.471924)
		(end 318.391794 -130.419602)
		(width 0.17145)
		(layer "F.Cu")
		(net "DRIVE_A_18_FLT_LED")
	)
	(segment
		(start 319.894204 -129.180336)
		(end 319.894204 -130.419602)
		(width 0.17145)
		(layer "F.Cu")
		(net "DRIVE_A_18_FLT_LED")
	)
	(segment
		(start 318.391794 -130.419602)
		(end 319.894204 -130.419602)
		(width 0.17145)
		(layer "F.Cu")
		(net "DRIVE_A_18_FLT_LED")
	)
	(segment
		(start 275.89988 -273.83232)
		(end 275.89988 -275.5646)
		(width 0.17145)
		(layer "F.Cu")
		(net "DRIVE_A_18_FLT_LED")
	)
	(segment
		(start 277.2156 -272.5166)
		(end 275.89988 -273.83232)
		(width 0.17145)
		(layer "F.Cu")
		(net "DRIVE_A_18_FLT_LED")
	)
	(via
		(at 277.2156 -272.0086)
		(size 0.5588)
		(drill 0.3048)
		(layers "F.Cu" "B.Cu")
		(net "DRIVE_A_18_FLT_LED")
	)
	(via
		(at 314.9346 -260.096)
		(size 0.5588)
		(drill 0.3048)
		(layers "F.Cu" "B.Cu")
		(net "DRIVE_A_18_FLT_LED")
	)
	(via
		(at 318.391794 -131.471924)
		(size 0.5588)
		(drill 0.3048)
		(layers "F.Cu" "B.Cu")
		(net "DRIVE_A_18_FLT_LED")
	)
	(via
		(at 319.894204 -130.419602)
		(size 0.6604)
		(drill 0.3302)
		(layers "F.Cu" "B.Cu")
		(net "DRIVE_A_18_FLT_LED")
	)
	(segment
		(start 314.9346 -260.096)
		(end 314.9346 -260.5532)
		(width 0.13335)
		(layer "In2.Cu")
		(net "DRIVE_A_18_FLT_LED")
	)
	(segment
		(start 314.9346 -260.5532)
		(end 307.749194 -267.738606)
		(width 0.13335)
		(layer "In2.Cu")
		(net "DRIVE_A_18_FLT_LED")
	)
	(segment
		(start 307.749194 -267.738606)
		(end 281.485594 -267.738606)
		(width 0.13335)
		(layer "In2.Cu")
		(net "DRIVE_A_18_FLT_LED")
	)
	(segment
		(start 281.485594 -267.738606)
		(end 277.2156 -272.0086)
		(width 0.13335)
		(layer "In2.Cu")
		(net "DRIVE_A_18_FLT_LED")
	)
	(segment
		(start 316.430406 -170.202098)
		(end 314.259722 -172.372782)
		(width 0.12065)
		(layer "In4.Cu")
		(net "DRIVE_A_18_FLT_LED")
	)
	(segment
		(start 315.108082 -259.922518)
		(end 314.9346 -260.096)
		(width 0.12065)
		(layer "In4.Cu")
		(net "DRIVE_A_18_FLT_LED")
	)
	(segment
		(start 316.430406 -147.412456)
		(end 316.430406 -170.202098)
		(width 0.12065)
		(layer "In4.Cu")
		(net "DRIVE_A_18_FLT_LED")
	)
	(segment
		(start 314.259722 -238.313722)
		(end 315.108082 -239.162082)
		(width 0.12065)
		(layer "In4.Cu")
		(net "DRIVE_A_18_FLT_LED")
	)
	(segment
		(start 318.391794 -145.451068)
		(end 316.430406 -147.412456)
		(width 0.12065)
		(layer "In4.Cu")
		(net "DRIVE_A_18_FLT_LED")
	)
	(segment
		(start 318.391794 -131.471924)
		(end 318.391794 -145.451068)
		(width 0.12065)
		(layer "In4.Cu")
		(net "DRIVE_A_18_FLT_LED")
	)
	(segment
		(start 315.108082 -239.162082)
		(end 315.108082 -259.922518)
		(width 0.12065)
		(layer "In4.Cu")
		(net "DRIVE_A_18_FLT_LED")
	)
	(segment
		(start 314.259722 -172.372782)
		(end 314.259722 -238.313722)
		(width 0.12065)
		(layer "In4.Cu")
		(net "DRIVE_A_18_FLT_LED")
	)
	(segment
		(start 316.20714 -129.077212)
		(end 316.20714 -130.44297)
		(width 0.17145)
		(layer "F.Cu")
		(net "DRIVE_A_18_ACT")
	)
	(segment
		(start 314.832238 -130.44297)
		(end 314.800996 -130.411728)
		(width 0.17145)
		(layer "F.Cu")
		(net "DRIVE_A_18_ACT")
	)
	(segment
		(start 316.20714 -130.44297)
		(end 314.832238 -130.44297)
		(width 0.17145)
		(layer "F.Cu")
		(net "DRIVE_A_18_ACT")
	)
	(segment
		(start 314.800996 -133.135624)
		(end 314.800996 -130.411728)
		(width 0.17145)
		(layer "F.Cu")
		(net "DRIVE_A_18_ACT")
	)
	(segment
		(start 314.797948 -133.138672)
		(end 314.800996 -133.135624)
		(width 0.17145)
		(layer "F.Cu")
		(net "DRIVE_A_18_ACT")
	)
	(segment
		(start 315.882782 -128.752854)
		(end 316.20714 -129.077212)
		(width 0.17145)
		(layer "F.Cu")
		(net "DRIVE_A_18_ACT")
	)
	(via
		(at 306.146962 -311.811416)
		(size 0.5588)
		(drill 0.3048)
		(layers "F.Cu" "B.Cu")
		(net "DRIVE_A_18_ACT")
	)
	(via
		(at 314.797948 -133.138672)
		(size 0.5588)
		(drill 0.3048)
		(layers "F.Cu" "B.Cu")
		(net "DRIVE_A_18_ACT")
	)
	(via
		(at 316.20714 -130.44297)
		(size 0.6604)
		(drill 0.3302)
		(layers "F.Cu" "B.Cu")
		(net "DRIVE_A_18_ACT")
	)
	(segment
		(start 285.14294 -311.811416)
		(end 306.146962 -311.811416)
		(width 0.13335)
		(layer "In2.Cu")
		(net "DRIVE_A_18_ACT")
	)
	(segment
		(start 284.236668 -310.905144)
		(end 285.14294 -311.811416)
		(width 0.13335)
		(layer "In2.Cu")
		(net "DRIVE_A_18_ACT")
	)
	(segment
		(start 312.731404 -237.776004)
		(end 313.8424 -238.887)
		(width 0.12065)
		(layer "In4.Cu")
		(net "DRIVE_A_18_ACT")
	)
	(segment
		(start 313.8424 -238.887)
		(end 313.8424 -259.563108)
		(width 0.12065)
		(layer "In4.Cu")
		(net "DRIVE_A_18_ACT")
	)
	(segment
		(start 306.103528 -311.767982)
		(end 306.146962 -311.811416)
		(width 0.12065)
		(layer "In4.Cu")
		(net "DRIVE_A_18_ACT")
	)
	(segment
		(start 312.731404 -172.323252)
		(end 312.731404 -237.776004)
		(width 0.12065)
		(layer "In4.Cu")
		(net "DRIVE_A_18_ACT")
	)
	(segment
		(start 306.103528 -267.30198)
		(end 306.103528 -311.767982)
		(width 0.12065)
		(layer "In4.Cu")
		(net "DRIVE_A_18_ACT")
	)
	(segment
		(start 313.8424 -259.563108)
		(end 306.103528 -267.30198)
		(width 0.12065)
		(layer "In4.Cu")
		(net "DRIVE_A_18_ACT")
	)
	(segment
		(start 314.797948 -170.256708)
		(end 312.731404 -172.323252)
		(width 0.12065)
		(layer "In4.Cu")
		(net "DRIVE_A_18_ACT")
	)
	(segment
		(start 314.797948 -133.138672)
		(end 314.797948 -170.256708)
		(width 0.12065)
		(layer "In4.Cu")
		(net "DRIVE_A_18_ACT")
	)
	(segment
		(start 243.967762 -237.79099)
		(end 244.76964 -236.989112)
		(width 0.17145)
		(layer "F.Cu")
		(net "DRIVE_A_17_PWR")
	)
	(segment
		(start 181.1909 -159.871918)
		(end 182.0164 -159.871918)
		(width 0.17145)
		(layer "F.Cu")
		(net "DRIVE_A_17_PWR")
	)
	(segment
		(start 244.76964 -236.989112)
		(end 244.76964 -234.1626)
		(width 0.17145)
		(layer "F.Cu")
		(net "DRIVE_A_17_PWR")
	)
	(via
		(at 197.2056 -242.951)
		(size 0.5588)
		(drill 0.3048)
		(layers "F.Cu" "B.Cu")
		(net "DRIVE_A_17_PWR")
	)
	(via
		(at 182.0164 -159.871918)
		(size 0.5588)
		(drill 0.3048)
		(layers "F.Cu" "B.Cu")
		(net "DRIVE_A_17_PWR")
	)
	(via
		(at 243.967762 -237.79099)
		(size 0.5588)
		(drill 0.3048)
		(layers "F.Cu" "B.Cu")
		(net "DRIVE_A_17_PWR")
	)
	(segment
		(start 222.386144 -242.951)
		(end 224.672144 -240.665)
		(width 0.13335)
		(layer "In2.Cu")
		(net "DRIVE_A_17_PWR")
	)
	(segment
		(start 238.571278 -240.665)
		(end 241.445288 -237.79099)
		(width 0.13335)
		(layer "In2.Cu")
		(net "DRIVE_A_17_PWR")
	)
	(segment
		(start 241.445288 -237.79099)
		(end 243.967762 -237.79099)
		(width 0.13335)
		(layer "In2.Cu")
		(net "DRIVE_A_17_PWR")
	)
	(segment
		(start 197.2056 -242.951)
		(end 222.386144 -242.951)
		(width 0.13335)
		(layer "In2.Cu")
		(net "DRIVE_A_17_PWR")
	)
	(segment
		(start 224.672144 -240.665)
		(end 238.571278 -240.665)
		(width 0.13335)
		(layer "In2.Cu")
		(net "DRIVE_A_17_PWR")
	)
	(segment
		(start 183.121808 -161.73704)
		(end 181.7878 -163.071048)
		(width 0.12065)
		(layer "In4.Cu")
		(net "DRIVE_A_17_PWR")
	)
	(segment
		(start 181.7878 -181.6862)
		(end 188.1124 -188.0108)
		(width 0.12065)
		(layer "In4.Cu")
		(net "DRIVE_A_17_PWR")
	)
	(segment
		(start 182.0164 -159.871918)
		(end 183.121808 -160.977326)
		(width 0.12065)
		(layer "In4.Cu")
		(net "DRIVE_A_17_PWR")
	)
	(segment
		(start 188.1124 -192.458848)
		(end 197.2056 -201.552048)
		(width 0.12065)
		(layer "In4.Cu")
		(net "DRIVE_A_17_PWR")
	)
	(segment
		(start 197.2056 -201.552048)
		(end 197.2056 -242.951)
		(width 0.12065)
		(layer "In4.Cu")
		(net "DRIVE_A_17_PWR")
	)
	(segment
		(start 183.121808 -160.977326)
		(end 183.121808 -161.73704)
		(width 0.12065)
		(layer "In4.Cu")
		(net "DRIVE_A_17_PWR")
	)
	(segment
		(start 188.1124 -188.0108)
		(end 188.1124 -192.458848)
		(width 0.12065)
		(layer "In4.Cu")
		(net "DRIVE_A_17_PWR")
	)
	(segment
		(start 181.7878 -163.071048)
		(end 181.7878 -181.6862)
		(width 0.12065)
		(layer "In4.Cu")
		(net "DRIVE_A_17_PWR")
	)
	(segment
		(start 241.26317 -254.34163)
		(end 239.494822 -254.34163)
		(width 0.17145)
		(layer "F.Cu")
		(net "DRIVE_A_17_INS")
	)
	(segment
		(start 190.246 -169.164)
		(end 190.946786 -169.164)
		(width 0.17145)
		(layer "F.Cu")
		(net "DRIVE_A_17_INS")
	)
	(segment
		(start 243.49964 -253.04496)
		(end 242.8621 -253.6825)
		(width 0.17145)
		(layer "F.Cu")
		(net "DRIVE_A_17_INS")
	)
	(segment
		(start 243.49964 -252.0696)
		(end 243.49964 -253.04496)
		(width 0.17145)
		(layer "F.Cu")
		(net "DRIVE_A_17_INS")
	)
	(segment
		(start 239.494822 -254.34163)
		(end 239.187736 -254.34163)
		(width 0.17145)
		(layer "F.Cu")
		(net "DRIVE_A_17_INS")
	)
	(segment
		(start 242.8621 -253.6825)
		(end 241.9223 -253.6825)
		(width 0.17145)
		(layer "F.Cu")
		(net "DRIVE_A_17_INS")
	)
	(segment
		(start 239.187736 -254.34163)
		(end 238.644176 -254.88519)
		(width 0.17145)
		(layer "F.Cu")
		(net "DRIVE_A_17_INS")
	)
	(segment
		(start 241.9223 -253.6825)
		(end 241.26317 -254.34163)
		(width 0.17145)
		(layer "F.Cu")
		(net "DRIVE_A_17_INS")
	)
	(segment
		(start 190.946786 -169.164)
		(end 191.643 -169.860214)
		(width 0.17145)
		(layer "F.Cu")
		(net "DRIVE_A_17_INS")
	)
	(via
		(at 191.643 -169.860214)
		(size 0.5588)
		(drill 0.3048)
		(layers "F.Cu" "B.Cu")
		(net "DRIVE_A_17_INS")
	)
	(via
		(at 239.494822 -254.34163)
		(size 0.6604)
		(drill 0.3302)
		(layers "F.Cu" "B.Cu")
		(net "DRIVE_A_17_INS")
	)
	(via
		(at 238.644176 -254.88519)
		(size 0.5588)
		(drill 0.3048)
		(layers "F.Cu" "B.Cu")
		(net "DRIVE_A_17_INS")
	)
	(via
		(at 199.8472 -258.064)
		(size 0.5588)
		(drill 0.3048)
		(layers "F.Cu" "B.Cu")
		(net "DRIVE_A_17_INS")
	)
	(segment
		(start 232.323386 -258.064)
		(end 199.8472 -258.064)
		(width 0.13335)
		(layer "In2.Cu")
		(net "DRIVE_A_17_INS")
	)
	(segment
		(start 234.124754 -256.262632)
		(end 232.323386 -258.064)
		(width 0.13335)
		(layer "In2.Cu")
		(net "DRIVE_A_17_INS")
	)
	(segment
		(start 237.22457 -254.88519)
		(end 235.847128 -256.262632)
		(width 0.13335)
		(layer "In2.Cu")
		(net "DRIVE_A_17_INS")
	)
	(segment
		(start 238.644176 -254.88519)
		(end 237.22457 -254.88519)
		(width 0.13335)
		(layer "In2.Cu")
		(net "DRIVE_A_17_INS")
	)
	(segment
		(start 235.847128 -256.262632)
		(end 234.124754 -256.262632)
		(width 0.13335)
		(layer "In2.Cu")
		(net "DRIVE_A_17_INS")
	)
	(segment
		(start 192.659 -194.5132)
		(end 199.8472 -201.7014)
		(width 0.12065)
		(layer "In4.Cu")
		(net "DRIVE_A_17_INS")
	)
	(segment
		(start 199.8472 -201.7014)
		(end 199.8472 -258.064)
		(width 0.12065)
		(layer "In4.Cu")
		(net "DRIVE_A_17_INS")
	)
	(segment
		(start 192.659 -170.876214)
		(end 192.659 -194.5132)
		(width 0.12065)
		(layer "In4.Cu")
		(net "DRIVE_A_17_INS")
	)
	(segment
		(start 191.643 -169.860214)
		(end 192.659 -170.876214)
		(width 0.12065)
		(layer "In4.Cu")
		(net "DRIVE_A_17_INS")
	)
	(segment
		(start 163.197286 -131.32689)
		(end 163.155376 -131.28498)
		(width 0.17145)
		(layer "F.Cu")
		(net "DRIVE_A_17_FLT_LED")
	)
	(segment
		(start 163.102036 -130.185414)
		(end 163.102036 -131.23164)
		(width 0.17145)
		(layer "F.Cu")
		(net "DRIVE_A_17_FLT_LED")
	)
	(segment
		(start 163.102036 -128.656588)
		(end 163.102036 -130.185414)
		(width 0.17145)
		(layer "F.Cu")
		(net "DRIVE_A_17_FLT_LED")
	)
	(segment
		(start 163.197286 -132.249418)
		(end 163.197286 -131.32689)
		(width 0.17145)
		(layer "F.Cu")
		(net "DRIVE_A_17_FLT_LED")
	)
	(segment
		(start 163.102036 -131.23164)
		(end 163.155376 -131.28498)
		(width 0.17145)
		(layer "F.Cu")
		(net "DRIVE_A_17_FLT_LED")
	)
	(segment
		(start 163.103052 -128.655572)
		(end 163.102036 -128.656588)
		(width 0.17145)
		(layer "F.Cu")
		(net "DRIVE_A_17_FLT_LED")
	)
	(segment
		(start 275.24964 -275.5646)
		(end 275.24964 -277.5458)
		(width 0.17145)
		(layer "F.Cu")
		(net "DRIVE_A_17_FLT_LED")
	)
	(via
		(at 275.24964 -277.5458)
		(size 0.5588)
		(drill 0.3048)
		(layers "F.Cu" "B.Cu")
		(net "DRIVE_A_17_FLT_LED")
	)
	(via
		(at 163.197286 -132.249418)
		(size 0.5588)
		(drill 0.3048)
		(layers "F.Cu" "B.Cu")
		(net "DRIVE_A_17_FLT_LED")
	)
	(via
		(at 163.155376 -131.28498)
		(size 0.6604)
		(drill 0.3302)
		(layers "F.Cu" "B.Cu")
		(net "DRIVE_A_17_FLT_LED")
	)
	(via
		(at 161.747962 -296.637456)
		(size 0.5588)
		(drill 0.3048)
		(layers "F.Cu" "B.Cu")
		(net "DRIVE_A_17_FLT_LED")
	)
	(segment
		(start 242.599972 -292.092634)
		(end 198.035926 -292.092634)
		(width 0.13335)
		(layer "In2.Cu")
		(net "DRIVE_A_17_FLT_LED")
	)
	(segment
		(start 262.721344 -281.305)
		(end 261.781544 -282.2448)
		(width 0.13335)
		(layer "In2.Cu")
		(net "DRIVE_A_17_FLT_LED")
	)
	(segment
		(start 190.347854 -294.792146)
		(end 188.2902 -296.8498)
		(width 0.13335)
		(layer "In2.Cu")
		(net "DRIVE_A_17_FLT_LED")
	)
	(segment
		(start 195.336414 -294.792146)
		(end 190.347854 -294.792146)
		(width 0.13335)
		(layer "In2.Cu")
		(net "DRIVE_A_17_FLT_LED")
	)
	(segment
		(start 198.035926 -292.092634)
		(end 195.336414 -294.792146)
		(width 0.13335)
		(layer "In2.Cu")
		(net "DRIVE_A_17_FLT_LED")
	)
	(segment
		(start 162.315906 -297.2054)
		(end 161.747962 -296.637456)
		(width 0.13335)
		(layer "In2.Cu")
		(net "DRIVE_A_17_FLT_LED")
	)
	(segment
		(start 275.24964 -277.5458)
		(end 273.5072 -277.5458)
		(width 0.13335)
		(layer "In2.Cu")
		(net "DRIVE_A_17_FLT_LED")
	)
	(segment
		(start 248.295922 -290.703)
		(end 243.989606 -290.703)
		(width 0.13335)
		(layer "In2.Cu")
		(net "DRIVE_A_17_FLT_LED")
	)
	(segment
		(start 188.2902 -296.8498)
		(end 167.7162 -296.8498)
		(width 0.13335)
		(layer "In2.Cu")
		(net "DRIVE_A_17_FLT_LED")
	)
	(segment
		(start 256.754122 -282.2448)
		(end 248.295922 -290.703)
		(width 0.13335)
		(layer "In2.Cu")
		(net "DRIVE_A_17_FLT_LED")
	)
	(segment
		(start 167.3606 -297.2054)
		(end 162.315906 -297.2054)
		(width 0.13335)
		(layer "In2.Cu")
		(net "DRIVE_A_17_FLT_LED")
	)
	(segment
		(start 167.7162 -296.8498)
		(end 167.3606 -297.2054)
		(width 0.13335)
		(layer "In2.Cu")
		(net "DRIVE_A_17_FLT_LED")
	)
	(segment
		(start 261.781544 -282.2448)
		(end 256.754122 -282.2448)
		(width 0.13335)
		(layer "In2.Cu")
		(net "DRIVE_A_17_FLT_LED")
	)
	(segment
		(start 243.989606 -290.703)
		(end 242.599972 -292.092634)
		(width 0.13335)
		(layer "In2.Cu")
		(net "DRIVE_A_17_FLT_LED")
	)
	(segment
		(start 269.748 -281.305)
		(end 262.721344 -281.305)
		(width 0.13335)
		(layer "In2.Cu")
		(net "DRIVE_A_17_FLT_LED")
	)
	(segment
		(start 273.5072 -277.5458)
		(end 269.748 -281.305)
		(width 0.13335)
		(layer "In2.Cu")
		(net "DRIVE_A_17_FLT_LED")
	)
	(segment
		(start 180.5432 -136.118854)
		(end 180.5432 -159.361378)
		(width 0.12065)
		(layer "In4.Cu")
		(net "DRIVE_A_17_FLT_LED")
	)
	(segment
		(start 180.5432 -159.361378)
		(end 179.14874 -160.755838)
		(width 0.12065)
		(layer "In4.Cu")
		(net "DRIVE_A_17_FLT_LED")
	)
	(segment
		(start 173.609 -167.005)
		(end 168.021 -172.593)
		(width 0.12065)
		(layer "In4.Cu")
		(net "DRIVE_A_17_FLT_LED")
	)
	(segment
		(start 162.5346 -268.585696)
		(end 162.5346 -291.434012)
		(width 0.12065)
		(layer "In4.Cu")
		(net "DRIVE_A_17_FLT_LED")
	)
	(segment
		(start 161.748724 -292.219888)
		(end 161.748724 -296.636694)
		(width 0.12065)
		(layer "In4.Cu")
		(net "DRIVE_A_17_FLT_LED")
	)
	(segment
		(start 170.6372 -260.483096)
		(end 162.5346 -268.585696)
		(width 0.12065)
		(layer "In4.Cu")
		(net "DRIVE_A_17_FLT_LED")
	)
	(segment
		(start 175.360076 -160.755838)
		(end 173.609 -162.506914)
		(width 0.12065)
		(layer "In4.Cu")
		(net "DRIVE_A_17_FLT_LED")
	)
	(segment
		(start 173.609 -162.506914)
		(end 173.609 -167.005)
		(width 0.12065)
		(layer "In4.Cu")
		(net "DRIVE_A_17_FLT_LED")
	)
	(segment
		(start 176.673764 -132.249418)
		(end 180.5432 -136.118854)
		(width 0.12065)
		(layer "In4.Cu")
		(net "DRIVE_A_17_FLT_LED")
	)
	(segment
		(start 163.197286 -132.249418)
		(end 176.673764 -132.249418)
		(width 0.12065)
		(layer "In4.Cu")
		(net "DRIVE_A_17_FLT_LED")
	)
	(segment
		(start 168.021 -197.685152)
		(end 170.6372 -200.301352)
		(width 0.12065)
		(layer "In4.Cu")
		(net "DRIVE_A_17_FLT_LED")
	)
	(segment
		(start 162.5346 -291.434012)
		(end 161.748724 -292.219888)
		(width 0.12065)
		(layer "In4.Cu")
		(net "DRIVE_A_17_FLT_LED")
	)
	(segment
		(start 170.6372 -200.301352)
		(end 170.6372 -260.483096)
		(width 0.12065)
		(layer "In4.Cu")
		(net "DRIVE_A_17_FLT_LED")
	)
	(segment
		(start 161.748724 -296.636694)
		(end 161.747962 -296.637456)
		(width 0.12065)
		(layer "In4.Cu")
		(net "DRIVE_A_17_FLT_LED")
	)
	(segment
		(start 179.14874 -160.755838)
		(end 175.360076 -160.755838)
		(width 0.12065)
		(layer "In4.Cu")
		(net "DRIVE_A_17_FLT_LED")
	)
	(segment
		(start 168.021 -172.593)
		(end 168.021 -197.685152)
		(width 0.12065)
		(layer "In4.Cu")
		(net "DRIVE_A_17_FLT_LED")
	)
	(segment
		(start 159.488378 -130.184398)
		(end 159.487362 -130.183382)
		(width 0.17145)
		(layer "F.Cu")
		(net "DRIVE_A_17_ACT")
	)
	(segment
		(start 159.488378 -131.464558)
		(end 159.477202 -131.475734)
		(width 0.17145)
		(layer "F.Cu")
		(net "DRIVE_A_17_ACT")
	)
	(segment
		(start 159.477202 -131.475734)
		(end 159.477202 -132.588)
		(width 0.17145)
		(layer "F.Cu")
		(net "DRIVE_A_17_ACT")
	)
	(segment
		(start 159.487362 -130.183382)
		(end 159.487362 -128.66497)
		(width 0.17145)
		(layer "F.Cu")
		(net "DRIVE_A_17_ACT")
	)
	(segment
		(start 159.488378 -130.184398)
		(end 159.488378 -131.464558)
		(width 0.17145)
		(layer "F.Cu")
		(net "DRIVE_A_17_ACT")
	)
	(via
		(at 267.0302 -318.3382)
		(size 0.5588)
		(drill 0.3048)
		(layers "F.Cu" "B.Cu")
		(net "DRIVE_A_17_ACT")
	)
	(via
		(at 159.477202 -131.475734)
		(size 0.6604)
		(drill 0.3302)
		(layers "F.Cu" "B.Cu")
		(net "DRIVE_A_17_ACT")
	)
	(via
		(at 159.418528 -309.1942)
		(size 0.5588)
		(drill 0.3048)
		(layers "F.Cu" "B.Cu")
		(net "DRIVE_A_17_ACT")
	)
	(via
		(at 159.477202 -132.588)
		(size 0.5588)
		(drill 0.3048)
		(layers "F.Cu" "B.Cu")
		(net "DRIVE_A_17_ACT")
	)
	(segment
		(start 267.0302 -318.3382)
		(end 244.8814 -318.3382)
		(width 0.13335)
		(layer "In2.Cu")
		(net "DRIVE_A_17_ACT")
	)
	(segment
		(start 197.15861 -309.1942)
		(end 159.418528 -309.1942)
		(width 0.13335)
		(layer "In2.Cu")
		(net "DRIVE_A_17_ACT")
	)
	(segment
		(start 244.8814 -318.3382)
		(end 241.427 -314.8838)
		(width 0.13335)
		(layer "In2.Cu")
		(net "DRIVE_A_17_ACT")
	)
	(segment
		(start 202.84821 -314.8838)
		(end 197.15861 -309.1942)
		(width 0.13335)
		(layer "In2.Cu")
		(net "DRIVE_A_17_ACT")
	)
	(segment
		(start 241.427 -314.8838)
		(end 202.84821 -314.8838)
		(width 0.13335)
		(layer "In2.Cu")
		(net "DRIVE_A_17_ACT")
	)
	(segment
		(start 158.971996 -294.012874)
		(end 161.9758 -291.00907)
		(width 0.12065)
		(layer "In4.Cu")
		(net "DRIVE_A_17_ACT")
	)
	(segment
		(start 167.461946 -197.916546)
		(end 167.461946 -197.453758)
		(width 0.12065)
		(layer "In4.Cu")
		(net "DRIVE_A_17_ACT")
	)
	(segment
		(start 173.101 -162.430968)
		(end 175.18888 -160.343088)
		(width 0.12065)
		(layer "In4.Cu")
		(net "DRIVE_A_17_ACT")
	)
	(segment
		(start 173.101 -166.751)
		(end 173.101 -162.430968)
		(width 0.12065)
		(layer "In4.Cu")
		(net "DRIVE_A_17_ACT")
	)
	(segment
		(start 160.010602 -133.1214)
		(end 159.477202 -132.588)
		(width 0.12065)
		(layer "In4.Cu")
		(net "DRIVE_A_17_ACT")
	)
	(segment
		(start 167.4622 -172.3898)
		(end 173.101 -166.751)
		(width 0.12065)
		(layer "In4.Cu")
		(net "DRIVE_A_17_ACT")
	)
	(segment
		(start 167.4622 -197.453504)
		(end 167.4622 -172.3898)
		(width 0.12065)
		(layer "In4.Cu")
		(net "DRIVE_A_17_ACT")
	)
	(segment
		(start 161.9758 -268.354048)
		(end 170.0784 -260.251448)
		(width 0.12065)
		(layer "In4.Cu")
		(net "DRIVE_A_17_ACT")
	)
	(segment
		(start 179.9844 -159.336232)
		(end 179.9844 -136.350502)
		(width 0.12065)
		(layer "In4.Cu")
		(net "DRIVE_A_17_ACT")
	)
	(segment
		(start 170.0784 -260.251448)
		(end 170.0784 -200.533)
		(width 0.12065)
		(layer "In4.Cu")
		(net "DRIVE_A_17_ACT")
	)
	(segment
		(start 159.418528 -309.1942)
		(end 158.971996 -308.747668)
		(width 0.12065)
		(layer "In4.Cu")
		(net "DRIVE_A_17_ACT")
	)
	(segment
		(start 167.461946 -197.453758)
		(end 167.4622 -197.453504)
		(width 0.12065)
		(layer "In4.Cu")
		(net "DRIVE_A_17_ACT")
	)
	(segment
		(start 179.9844 -136.350502)
		(end 176.755298 -133.1214)
		(width 0.12065)
		(layer "In4.Cu")
		(net "DRIVE_A_17_ACT")
	)
	(segment
		(start 161.9758 -291.00907)
		(end 161.9758 -268.354048)
		(width 0.12065)
		(layer "In4.Cu")
		(net "DRIVE_A_17_ACT")
	)
	(segment
		(start 158.971996 -308.747668)
		(end 158.971996 -294.012874)
		(width 0.12065)
		(layer "In4.Cu")
		(net "DRIVE_A_17_ACT")
	)
	(segment
		(start 175.18888 -160.343088)
		(end 178.977544 -160.343088)
		(width 0.12065)
		(layer "In4.Cu")
		(net "DRIVE_A_17_ACT")
	)
	(segment
		(start 176.755298 -133.1214)
		(end 160.010602 -133.1214)
		(width 0.12065)
		(layer "In4.Cu")
		(net "DRIVE_A_17_ACT")
	)
	(segment
		(start 170.0784 -200.533)
		(end 167.461946 -197.916546)
		(width 0.12065)
		(layer "In4.Cu")
		(net "DRIVE_A_17_ACT")
	)
	(segment
		(start 178.977544 -160.343088)
		(end 179.9844 -159.336232)
		(width 0.12065)
		(layer "In4.Cu")
		(net "DRIVE_A_17_ACT")
	)
	(segment
		(start 273.0246 -318.3382)
		(end 267.0302 -318.3382)
		(width 0.13335)
		(layer "In9.Cu")
		(net "DRIVE_A_17_ACT")
	)
	(segment
		(start 277.5712 -313.7916)
		(end 273.0246 -318.3382)
		(width 0.13335)
		(layer "In9.Cu")
		(net "DRIVE_A_17_ACT")
	)
	(segment
		(start 280.750264 -313.7916)
		(end 277.5712 -313.7916)
		(width 0.13335)
		(layer "In9.Cu")
		(net "DRIVE_A_17_ACT")
	)
	(segment
		(start 281.836622 -312.705242)
		(end 280.750264 -313.7916)
		(width 0.13335)
		(layer "In9.Cu")
		(net "DRIVE_A_17_ACT")
	)
	(segment
		(start 244.1194 -234.1626)
		(end 244.1194 -236.63656)
		(width 0.17145)
		(layer "F.Cu")
		(net "DRIVE_A_16_PWR")
	)
	(segment
		(start 149.640798 -159.871918)
		(end 150.466298 -159.871918)
		(width 0.17145)
		(layer "F.Cu")
		(net "DRIVE_A_16_PWR")
	)
	(via
		(at 167.277796 -236.2454)
		(size 0.5588)
		(drill 0.3048)
		(layers "F.Cu" "B.Cu")
		(net "DRIVE_A_16_PWR")
	)
	(via
		(at 150.466298 -159.871918)
		(size 0.5588)
		(drill 0.3048)
		(layers "F.Cu" "B.Cu")
		(net "DRIVE_A_16_PWR")
	)
	(via
		(at 244.1194 -236.63656)
		(size 0.5588)
		(drill 0.3048)
		(layers "F.Cu" "B.Cu")
		(net "DRIVE_A_16_PWR")
	)
	(segment
		(start 241.797586 -236.63656)
		(end 238.327946 -240.1062)
		(width 0.13335)
		(layer "In2.Cu")
		(net "DRIVE_A_16_PWR")
	)
	(segment
		(start 238.327946 -240.1062)
		(end 224.440496 -240.1062)
		(width 0.13335)
		(layer "In2.Cu")
		(net "DRIVE_A_16_PWR")
	)
	(segment
		(start 222.71609 -241.830606)
		(end 196.624194 -241.830606)
		(width 0.13335)
		(layer "In2.Cu")
		(net "DRIVE_A_16_PWR")
	)
	(segment
		(start 196.624194 -241.830606)
		(end 193.4718 -244.983)
		(width 0.13335)
		(layer "In2.Cu")
		(net "DRIVE_A_16_PWR")
	)
	(segment
		(start 169.8244 -236.2454)
		(end 167.277796 -236.2454)
		(width 0.13335)
		(layer "In2.Cu")
		(net "DRIVE_A_16_PWR")
	)
	(segment
		(start 193.4718 -244.983)
		(end 178.562 -244.983)
		(width 0.13335)
		(layer "In2.Cu")
		(net "DRIVE_A_16_PWR")
	)
	(segment
		(start 244.1194 -236.63656)
		(end 241.797586 -236.63656)
		(width 0.13335)
		(layer "In2.Cu")
		(net "DRIVE_A_16_PWR")
	)
	(segment
		(start 224.440496 -240.1062)
		(end 222.71609 -241.830606)
		(width 0.13335)
		(layer "In2.Cu")
		(net "DRIVE_A_16_PWR")
	)
	(segment
		(start 178.562 -244.983)
		(end 169.8244 -236.2454)
		(width 0.13335)
		(layer "In2.Cu")
		(net "DRIVE_A_16_PWR")
	)
	(segment
		(start 162.437572 -188.472572)
		(end 162.437572 -195.672202)
		(width 0.12065)
		(layer "In4.Cu")
		(net "DRIVE_A_16_PWR")
	)
	(segment
		(start 167.5892 -235.933996)
		(end 167.277796 -236.2454)
		(width 0.12065)
		(layer "In4.Cu")
		(net "DRIVE_A_16_PWR")
	)
	(segment
		(start 150.466298 -159.871918)
		(end 149.8092 -160.529016)
		(width 0.12065)
		(layer "In4.Cu")
		(net "DRIVE_A_16_PWR")
	)
	(segment
		(start 161.1376 -178.9684)
		(end 161.1376 -187.1726)
		(width 0.12065)
		(layer "In4.Cu")
		(net "DRIVE_A_16_PWR")
	)
	(segment
		(start 161.1376 -187.1726)
		(end 162.437572 -188.472572)
		(width 0.12065)
		(layer "In4.Cu")
		(net "DRIVE_A_16_PWR")
	)
	(segment
		(start 149.8092 -160.529016)
		(end 149.8092 -163.5506)
		(width 0.12065)
		(layer "In4.Cu")
		(net "DRIVE_A_16_PWR")
	)
	(segment
		(start 150.241 -168.0718)
		(end 161.1376 -178.9684)
		(width 0.12065)
		(layer "In4.Cu")
		(net "DRIVE_A_16_PWR")
	)
	(segment
		(start 167.5892 -200.82383)
		(end 167.5892 -235.933996)
		(width 0.12065)
		(layer "In4.Cu")
		(net "DRIVE_A_16_PWR")
	)
	(segment
		(start 150.241 -163.9824)
		(end 150.241 -168.0718)
		(width 0.12065)
		(layer "In4.Cu")
		(net "DRIVE_A_16_PWR")
	)
	(segment
		(start 149.8092 -163.5506)
		(end 150.241 -163.9824)
		(width 0.12065)
		(layer "In4.Cu")
		(net "DRIVE_A_16_PWR")
	)
	(segment
		(start 162.437572 -195.672202)
		(end 167.5892 -200.82383)
		(width 0.12065)
		(layer "In4.Cu")
		(net "DRIVE_A_16_PWR")
	)
	(segment
		(start 242.8494 -252.8824)
		(end 242.8494 -252.0696)
		(width 0.17145)
		(layer "F.Cu")
		(net "DRIVE_A_16_INS")
	)
	(segment
		(start 242.6081 -253.1237)
		(end 242.8494 -252.8824)
		(width 0.17145)
		(layer "F.Cu")
		(net "DRIVE_A_16_INS")
	)
	(segment
		(start 241.28349 -253.1237)
		(end 242.6081 -253.1237)
		(width 0.17145)
		(layer "F.Cu")
		(net "DRIVE_A_16_INS")
	)
	(segment
		(start 240.730786 -253.676404)
		(end 241.28349 -253.1237)
		(width 0.17145)
		(layer "F.Cu")
		(net "DRIVE_A_16_INS")
	)
	(segment
		(start 163.140898 -181.5592)
		(end 163.140898 -180.064918)
		(width 0.17145)
		(layer "F.Cu")
		(net "DRIVE_A_16_INS")
	)
	(segment
		(start 163.140898 -182.833518)
		(end 163.140898 -181.5592)
		(width 0.17145)
		(layer "F.Cu")
		(net "DRIVE_A_16_INS")
	)
	(via
		(at 163.140898 -181.5592)
		(size 0.6604)
		(drill 0.3302)
		(layers "F.Cu" "B.Cu")
		(net "DRIVE_A_16_INS")
	)
	(via
		(at 168.6052 -258.6482)
		(size 0.5588)
		(drill 0.3048)
		(layers "F.Cu" "B.Cu")
		(net "DRIVE_A_16_INS")
	)
	(via
		(at 163.140898 -182.833518)
		(size 0.5588)
		(drill 0.3048)
		(layers "F.Cu" "B.Cu")
		(net "DRIVE_A_16_INS")
	)
	(via
		(at 240.730786 -253.676404)
		(size 0.5588)
		(drill 0.3048)
		(layers "F.Cu" "B.Cu")
		(net "DRIVE_A_16_INS")
	)
	(segment
		(start 169.062146 -258.191254)
		(end 168.6052 -258.6482)
		(width 0.13335)
		(layer "In2.Cu")
		(net "DRIVE_A_16_INS")
	)
	(segment
		(start 235.22813 -255.703832)
		(end 233.893106 -255.703832)
		(width 0.13335)
		(layer "In2.Cu")
		(net "DRIVE_A_16_INS")
	)
	(segment
		(start 197.741794 -258.191254)
		(end 169.062146 -258.191254)
		(width 0.13335)
		(layer "In2.Cu")
		(net "DRIVE_A_16_INS")
	)
	(segment
		(start 240.30432 -254.10287)
		(end 236.829092 -254.10287)
		(width 0.13335)
		(layer "In2.Cu")
		(net "DRIVE_A_16_INS")
	)
	(segment
		(start 240.730786 -253.676404)
		(end 240.30432 -254.10287)
		(width 0.13335)
		(layer "In2.Cu")
		(net "DRIVE_A_16_INS")
	)
	(segment
		(start 236.829092 -254.10287)
		(end 235.22813 -255.703832)
		(width 0.13335)
		(layer "In2.Cu")
		(net "DRIVE_A_16_INS")
	)
	(segment
		(start 233.893106 -255.703832)
		(end 232.183432 -257.413506)
		(width 0.13335)
		(layer "In2.Cu")
		(net "DRIVE_A_16_INS")
	)
	(segment
		(start 198.519542 -257.413506)
		(end 197.741794 -258.191254)
		(width 0.13335)
		(layer "In2.Cu")
		(net "DRIVE_A_16_INS")
	)
	(segment
		(start 232.183432 -257.413506)
		(end 198.519542 -257.413506)
		(width 0.13335)
		(layer "In2.Cu")
		(net "DRIVE_A_16_INS")
	)
	(segment
		(start 168.148 -200.592182)
		(end 168.148 -258.191)
		(width 0.12065)
		(layer "In4.Cu")
		(net "DRIVE_A_16_INS")
	)
	(segment
		(start 168.148 -258.191)
		(end 168.6052 -258.6482)
		(width 0.12065)
		(layer "In4.Cu")
		(net "DRIVE_A_16_INS")
	)
	(segment
		(start 163.140898 -182.833518)
		(end 163.140898 -195.58508)
		(width 0.12065)
		(layer "In4.Cu")
		(net "DRIVE_A_16_INS")
	)
	(segment
		(start 163.140898 -195.58508)
		(end 168.148 -200.592182)
		(width 0.12065)
		(layer "In4.Cu")
		(net "DRIVE_A_16_INS")
	)
	(segment
		(start 274.593812 -275.570188)
		(end 274.5994 -275.5646)
		(width 0.17145)
		(layer "F.Cu")
		(net "DRIVE_A_16_FLT_LED")
	)
	(segment
		(start 134.297674 -130.269996)
		(end 134.297674 -128.74117)
		(width 0.17145)
		(layer "F.Cu")
		(net "DRIVE_A_16_FLT_LED")
	)
	(segment
		(start 134.296658 -132.187696)
		(end 134.296658 -133.343142)
		(width 0.17145)
		(layer "F.Cu")
		(net "DRIVE_A_16_FLT_LED")
	)
	(segment
		(start 134.296658 -132.187696)
		(end 134.296658 -130.271012)
		(width 0.17145)
		(layer "F.Cu")
		(net "DRIVE_A_16_FLT_LED")
	)
	(segment
		(start 274.593812 -278.221948)
		(end 274.593812 -275.570188)
		(width 0.17145)
		(layer "F.Cu")
		(net "DRIVE_A_16_FLT_LED")
	)
	(segment
		(start 134.296658 -130.271012)
		(end 134.297674 -130.269996)
		(width 0.17145)
		(layer "F.Cu")
		(net "DRIVE_A_16_FLT_LED")
	)
	(via
		(at 274.593812 -278.221948)
		(size 0.5588)
		(drill 0.3048)
		(layers "F.Cu" "B.Cu")
		(net "DRIVE_A_16_FLT_LED")
	)
	(via
		(at 152.56256 -297.434)
		(size 0.5588)
		(drill 0.3048)
		(layers "F.Cu" "B.Cu")
		(net "DRIVE_A_16_FLT_LED")
	)
	(via
		(at 134.296658 -133.343142)
		(size 0.5588)
		(drill 0.3048)
		(layers "F.Cu" "B.Cu")
		(net "DRIVE_A_16_FLT_LED")
	)
	(via
		(at 134.296658 -132.187696)
		(size 0.6604)
		(drill 0.3302)
		(layers "F.Cu" "B.Cu")
		(net "DRIVE_A_16_FLT_LED")
	)
	(segment
		(start 195.568062 -295.350946)
		(end 190.551054 -295.350946)
		(width 0.13335)
		(layer "In2.Cu")
		(net "DRIVE_A_16_FLT_LED")
	)
	(segment
		(start 187.7568 -298.1452)
		(end 161.947098 -298.1452)
		(width 0.13335)
		(layer "In2.Cu")
		(net "DRIVE_A_16_FLT_LED")
	)
	(segment
		(start 269.9512 -281.8638)
		(end 262.952992 -281.8638)
		(width 0.13335)
		(layer "In2.Cu")
		(net "DRIVE_A_16_FLT_LED")
	)
	(segment
		(start 198.267574 -292.651434)
		(end 195.568062 -295.350946)
		(width 0.13335)
		(layer "In2.Cu")
		(net "DRIVE_A_16_FLT_LED")
	)
	(segment
		(start 262.013192 -282.8036)
		(end 256.98577 -282.8036)
		(width 0.13335)
		(layer "In2.Cu")
		(net "DRIVE_A_16_FLT_LED")
	)
	(segment
		(start 161.947098 -298.1452)
		(end 160.672018 -296.87012)
		(width 0.13335)
		(layer "In2.Cu")
		(net "DRIVE_A_16_FLT_LED")
	)
	(segment
		(start 242.83162 -292.651434)
		(end 198.267574 -292.651434)
		(width 0.13335)
		(layer "In2.Cu")
		(net "DRIVE_A_16_FLT_LED")
	)
	(segment
		(start 274.593812 -278.221948)
		(end 273.593052 -278.221948)
		(width 0.13335)
		(layer "In2.Cu")
		(net "DRIVE_A_16_FLT_LED")
	)
	(segment
		(start 273.593052 -278.221948)
		(end 269.9512 -281.8638)
		(width 0.13335)
		(layer "In2.Cu")
		(net "DRIVE_A_16_FLT_LED")
	)
	(segment
		(start 153.12644 -296.87012)
		(end 152.56256 -297.434)
		(width 0.13335)
		(layer "In2.Cu")
		(net "DRIVE_A_16_FLT_LED")
	)
	(segment
		(start 244.221254 -291.2618)
		(end 242.83162 -292.651434)
		(width 0.13335)
		(layer "In2.Cu")
		(net "DRIVE_A_16_FLT_LED")
	)
	(segment
		(start 248.52757 -291.2618)
		(end 244.221254 -291.2618)
		(width 0.13335)
		(layer "In2.Cu")
		(net "DRIVE_A_16_FLT_LED")
	)
	(segment
		(start 256.98577 -282.8036)
		(end 248.52757 -291.2618)
		(width 0.13335)
		(layer "In2.Cu")
		(net "DRIVE_A_16_FLT_LED")
	)
	(segment
		(start 262.952992 -281.8638)
		(end 262.013192 -282.8036)
		(width 0.13335)
		(layer "In2.Cu")
		(net "DRIVE_A_16_FLT_LED")
	)
	(segment
		(start 190.551054 -295.350946)
		(end 187.7568 -298.1452)
		(width 0.13335)
		(layer "In2.Cu")
		(net "DRIVE_A_16_FLT_LED")
	)
	(segment
		(start 160.672018 -296.87012)
		(end 153.12644 -296.87012)
		(width 0.13335)
		(layer "In2.Cu")
		(net "DRIVE_A_16_FLT_LED")
	)
	(segment
		(start 138.198098 -165.391338)
		(end 138.198098 -171.987464)
		(width 0.12065)
		(layer "In4.Cu")
		(net "DRIVE_A_16_FLT_LED")
	)
	(segment
		(start 129.752344 -146.129756)
		(end 129.752344 -156.945584)
		(width 0.12065)
		(layer "In4.Cu")
		(net "DRIVE_A_16_FLT_LED")
	)
	(segment
		(start 151.75611 -273.576288)
		(end 152.56256 -274.382738)
		(width 0.12065)
		(layer "In4.Cu")
		(net "DRIVE_A_16_FLT_LED")
	)
	(segment
		(start 138.198098 -171.987464)
		(end 151.75611 -185.545476)
		(width 0.12065)
		(layer "In4.Cu")
		(net "DRIVE_A_16_FLT_LED")
	)
	(segment
		(start 134.296658 -133.343142)
		(end 132.769102 -134.870698)
		(width 0.12065)
		(layer "In4.Cu")
		(net "DRIVE_A_16_FLT_LED")
	)
	(segment
		(start 152.56256 -274.382738)
		(end 152.56256 -297.434)
		(width 0.12065)
		(layer "In4.Cu")
		(net "DRIVE_A_16_FLT_LED")
	)
	(segment
		(start 132.769102 -134.870698)
		(end 132.769102 -143.112998)
		(width 0.12065)
		(layer "In4.Cu")
		(net "DRIVE_A_16_FLT_LED")
	)
	(segment
		(start 151.75611 -185.545476)
		(end 151.75611 -273.576288)
		(width 0.12065)
		(layer "In4.Cu")
		(net "DRIVE_A_16_FLT_LED")
	)
	(segment
		(start 132.769102 -143.112998)
		(end 129.752344 -146.129756)
		(width 0.12065)
		(layer "In4.Cu")
		(net "DRIVE_A_16_FLT_LED")
	)
	(segment
		(start 129.752344 -156.945584)
		(end 138.198098 -165.391338)
		(width 0.12065)
		(layer "In4.Cu")
		(net "DRIVE_A_16_FLT_LED")
	)
	(segment
		(start 130.683 -132.18668)
		(end 130.683 -133.215126)
		(width 0.17145)
		(layer "F.Cu")
		(net "DRIVE_A_16_ACT")
	)
	(segment
		(start 130.683 -132.18668)
		(end 130.683 -130.269996)
		(width 0.17145)
		(layer "F.Cu")
		(net "DRIVE_A_16_ACT")
	)
	(segment
		(start 130.681984 -130.26898)
		(end 130.681984 -128.750568)
		(width 0.17145)
		(layer "F.Cu")
		(net "DRIVE_A_16_ACT")
	)
	(segment
		(start 130.683 -130.269996)
		(end 130.681984 -130.26898)
		(width 0.17145)
		(layer "F.Cu")
		(net "DRIVE_A_16_ACT")
	)
	(via
		(at 150.4696 -308.471824)
		(size 0.5588)
		(drill 0.3048)
		(layers "F.Cu" "B.Cu")
		(net "DRIVE_A_16_ACT")
	)
	(via
		(at 130.683 -133.215126)
		(size 0.5588)
		(drill 0.3048)
		(layers "F.Cu" "B.Cu")
		(net "DRIVE_A_16_ACT")
	)
	(via
		(at 130.683 -132.18668)
		(size 0.6604)
		(drill 0.3302)
		(layers "F.Cu" "B.Cu")
		(net "DRIVE_A_16_ACT")
	)
	(segment
		(start 200.590658 -311.8358)
		(end 197.226682 -308.471824)
		(width 0.13335)
		(layer "In2.Cu")
		(net "DRIVE_A_16_ACT")
	)
	(segment
		(start 283.23667 -312.705242)
		(end 282.367228 -311.8358)
		(width 0.13335)
		(layer "In2.Cu")
		(net "DRIVE_A_16_ACT")
	)
	(segment
		(start 197.226682 -308.471824)
		(end 150.4696 -308.471824)
		(width 0.13335)
		(layer "In2.Cu")
		(net "DRIVE_A_16_ACT")
	)
	(segment
		(start 282.367228 -311.8358)
		(end 200.590658 -311.8358)
		(width 0.13335)
		(layer "In2.Cu")
		(net "DRIVE_A_16_ACT")
	)
	(segment
		(start 151.257 -273.9898)
		(end 151.257 -273.819874)
		(width 0.12065)
		(layer "In4.Cu")
		(net "DRIVE_A_16_ACT")
	)
	(segment
		(start 151.257 -273.819874)
		(end 151.336248 -273.740372)
		(width 0.12065)
		(layer "In4.Cu")
		(net "DRIVE_A_16_ACT")
	)
	(segment
		(start 137.639298 -165.416484)
		(end 129.339594 -157.11678)
		(width 0.12065)
		(layer "In4.Cu")
		(net "DRIVE_A_16_ACT")
	)
	(segment
		(start 151.336248 -273.740372)
		(end 151.34336 -273.73326)
		(width 0.12065)
		(layer "In4.Cu")
		(net "DRIVE_A_16_ACT")
	)
	(segment
		(start 130.683 -144.443196)
		(end 130.683 -133.215126)
		(width 0.12065)
		(layer "In4.Cu")
		(net "DRIVE_A_16_ACT")
	)
	(segment
		(start 149.948646 -191.44488)
		(end 149.948646 -184.650634)
		(width 0.12065)
		(layer "In4.Cu")
		(net "DRIVE_A_16_ACT")
	)
	(segment
		(start 129.339594 -145.786602)
		(end 130.683 -144.443196)
		(width 0.12065)
		(layer "In4.Cu")
		(net "DRIVE_A_16_ACT")
	)
	(segment
		(start 137.639298 -172.341286)
		(end 137.639298 -165.416484)
		(width 0.12065)
		(layer "In4.Cu")
		(net "DRIVE_A_16_ACT")
	)
	(segment
		(start 151.898096 -307.043328)
		(end 151.898096 -274.630896)
		(width 0.12065)
		(layer "In4.Cu")
		(net "DRIVE_A_16_ACT")
	)
	(segment
		(start 151.898096 -274.630896)
		(end 151.257 -273.9898)
		(width 0.12065)
		(layer "In4.Cu")
		(net "DRIVE_A_16_ACT")
	)
	(segment
		(start 151.34336 -192.839594)
		(end 149.948646 -191.44488)
		(width 0.12065)
		(layer "In4.Cu")
		(net "DRIVE_A_16_ACT")
	)
	(segment
		(start 150.4696 -308.471824)
		(end 151.898096 -307.043328)
		(width 0.12065)
		(layer "In4.Cu")
		(net "DRIVE_A_16_ACT")
	)
	(segment
		(start 149.948646 -184.650634)
		(end 137.639298 -172.341286)
		(width 0.12065)
		(layer "In4.Cu")
		(net "DRIVE_A_16_ACT")
	)
	(segment
		(start 129.339594 -157.11678)
		(end 129.339594 -145.786602)
		(width 0.12065)
		(layer "In4.Cu")
		(net "DRIVE_A_16_ACT")
	)
	(segment
		(start 151.34336 -273.73326)
		(end 151.34336 -192.839594)
		(width 0.12065)
		(layer "In4.Cu")
		(net "DRIVE_A_16_ACT")
	)
	(segment
		(start 233.0577 -237.424468)
		(end 232.24236 -236.609128)
		(width 0.17145)
		(layer "F.Cu")
		(net "DRIVE_A_15_PWR")
	)
	(segment
		(start 116.294662 -159.939228)
		(end 116.294662 -158.992824)
		(width 0.17145)
		(layer "F.Cu")
		(net "DRIVE_A_15_PWR")
	)
	(segment
		(start 116.294662 -158.992824)
		(end 116.294662 -158.011114)
		(width 0.17145)
		(layer "F.Cu")
		(net "DRIVE_A_15_PWR")
	)
	(segment
		(start 232.24236 -236.609128)
		(end 232.24236 -234.1626)
		(width 0.17145)
		(layer "F.Cu")
		(net "DRIVE_A_15_PWR")
	)
	(via
		(at 116.294662 -158.992824)
		(size 0.6604)
		(drill 0.3302)
		(layers "F.Cu" "B.Cu")
		(net "DRIVE_A_15_PWR")
	)
	(via
		(at 116.294662 -158.011114)
		(size 0.5588)
		(drill 0.3048)
		(layers "F.Cu" "B.Cu")
		(net "DRIVE_A_15_PWR")
	)
	(via
		(at 113.177828 -235.039408)
		(size 0.5588)
		(drill 0.3048)
		(layers "F.Cu" "B.Cu")
		(net "DRIVE_A_15_PWR")
	)
	(via
		(at 233.0577 -237.424468)
		(size 0.5588)
		(drill 0.3048)
		(layers "F.Cu" "B.Cu")
		(net "DRIVE_A_15_PWR")
	)
	(segment
		(start 222.252794 -240.713006)
		(end 223.9772 -238.9886)
		(width 0.13335)
		(layer "In2.Cu")
		(net "DRIVE_A_15_PWR")
	)
	(segment
		(start 196.160898 -240.713006)
		(end 222.252794 -240.713006)
		(width 0.13335)
		(layer "In2.Cu")
		(net "DRIVE_A_15_PWR")
	)
	(segment
		(start 179.025296 -243.8654)
		(end 193.008504 -243.8654)
		(width 0.13335)
		(layer "In2.Cu")
		(net "DRIVE_A_15_PWR")
	)
	(segment
		(start 229.6414 -238.9886)
		(end 231.205532 -237.424468)
		(width 0.13335)
		(layer "In2.Cu")
		(net "DRIVE_A_15_PWR")
	)
	(segment
		(start 113.177828 -235.039408)
		(end 170.199304 -235.039408)
		(width 0.13335)
		(layer "In2.Cu")
		(net "DRIVE_A_15_PWR")
	)
	(segment
		(start 170.199304 -235.039408)
		(end 179.025296 -243.8654)
		(width 0.13335)
		(layer "In2.Cu")
		(net "DRIVE_A_15_PWR")
	)
	(segment
		(start 223.9772 -238.9886)
		(end 229.6414 -238.9886)
		(width 0.13335)
		(layer "In2.Cu")
		(net "DRIVE_A_15_PWR")
	)
	(segment
		(start 231.205532 -237.424468)
		(end 233.0577 -237.424468)
		(width 0.13335)
		(layer "In2.Cu")
		(net "DRIVE_A_15_PWR")
	)
	(segment
		(start 193.008504 -243.8654)
		(end 196.160898 -240.713006)
		(width 0.13335)
		(layer "In2.Cu")
		(net "DRIVE_A_15_PWR")
	)
	(segment
		(start 120.1928 -173.530006)
		(end 120.1928 -164.308282)
		(width 0.12065)
		(layer "In4.Cu")
		(net "DRIVE_A_15_PWR")
	)
	(segment
		(start 112.93475 -231.149906)
		(end 109.379004 -227.59416)
		(width 0.12065)
		(layer "In4.Cu")
		(net "DRIVE_A_15_PWR")
	)
	(segment
		(start 113.177828 -235.039408)
		(end 112.93475 -234.79633)
		(width 0.12065)
		(layer "In4.Cu")
		(net "DRIVE_A_15_PWR")
	)
	(segment
		(start 112.93475 -234.79633)
		(end 112.93475 -231.149906)
		(width 0.12065)
		(layer "In4.Cu")
		(net "DRIVE_A_15_PWR")
	)
	(segment
		(start 109.379004 -227.59416)
		(end 109.379004 -184.343802)
		(width 0.12065)
		(layer "In4.Cu")
		(net "DRIVE_A_15_PWR")
	)
	(segment
		(start 109.379004 -184.343802)
		(end 120.1928 -173.530006)
		(width 0.12065)
		(layer "In4.Cu")
		(net "DRIVE_A_15_PWR")
	)
	(segment
		(start 120.1928 -164.308282)
		(end 116.294662 -160.410144)
		(width 0.12065)
		(layer "In4.Cu")
		(net "DRIVE_A_15_PWR")
	)
	(segment
		(start 116.294662 -160.410144)
		(end 116.294662 -158.011114)
		(width 0.12065)
		(layer "In4.Cu")
		(net "DRIVE_A_15_PWR")
	)
	(segment
		(start 130.328416 -182.116984)
		(end 130.81635 -181.62905)
		(width 0.17145)
		(layer "F.Cu")
		(net "DRIVE_A_15_INS")
	)
	(segment
		(start 233.592624 -253.686056)
		(end 232.87736 -252.970792)
		(width 0.17145)
		(layer "F.Cu")
		(net "DRIVE_A_15_INS")
	)
	(segment
		(start 232.87736 -252.970792)
		(end 232.87736 -251.8156)
		(width 0.17145)
		(layer "F.Cu")
		(net "DRIVE_A_15_INS")
	)
	(segment
		(start 131.590796 -180.854604)
		(end 130.81635 -181.62905)
		(width 0.17145)
		(layer "F.Cu")
		(net "DRIVE_A_15_INS")
	)
	(segment
		(start 129.538984 -182.116984)
		(end 130.328416 -182.116984)
		(width 0.17145)
		(layer "F.Cu")
		(net "DRIVE_A_15_INS")
	)
	(segment
		(start 131.590796 -180.064918)
		(end 131.590796 -180.854604)
		(width 0.17145)
		(layer "F.Cu")
		(net "DRIVE_A_15_INS")
	)
	(via
		(at 118.1608 -258.6228)
		(size 0.5588)
		(drill 0.3048)
		(layers "F.Cu" "B.Cu")
		(net "DRIVE_A_15_INS")
	)
	(via
		(at 233.592624 -253.686056)
		(size 0.5588)
		(drill 0.3048)
		(layers "F.Cu" "B.Cu")
		(net "DRIVE_A_15_INS")
	)
	(via
		(at 129.538984 -182.116984)
		(size 0.5588)
		(drill 0.3048)
		(layers "F.Cu" "B.Cu")
		(net "DRIVE_A_15_INS")
	)
	(via
		(at 130.81635 -181.62905)
		(size 0.6604)
		(drill 0.3302)
		(layers "F.Cu" "B.Cu")
		(net "DRIVE_A_15_INS")
	)
	(segment
		(start 200.80351 -256.829306)
		(end 198.313294 -256.829306)
		(width 0.13335)
		(layer "In2.Cu")
		(net "DRIVE_A_15_INS")
	)
	(segment
		(start 197.510146 -257.632454)
		(end 119.151146 -257.632454)
		(width 0.13335)
		(layer "In2.Cu")
		(net "DRIVE_A_15_INS")
	)
	(segment
		(start 231.776016 -256.829306)
		(end 201.276712 -256.829306)
		(width 0.13335)
		(layer "In2.Cu")
		(net "DRIVE_A_15_INS")
	)
	(segment
		(start 233.592624 -255.012698)
		(end 231.776016 -256.829306)
		(width 0.13335)
		(layer "In2.Cu")
		(net "DRIVE_A_15_INS")
	)
	(segment
		(start 233.592624 -253.686056)
		(end 233.592624 -255.012698)
		(width 0.13335)
		(layer "In2.Cu")
		(net "DRIVE_A_15_INS")
	)
	(segment
		(start 198.313294 -256.829306)
		(end 197.510146 -257.632454)
		(width 0.13335)
		(layer "In2.Cu")
		(net "DRIVE_A_15_INS")
	)
	(segment
		(start 201.276712 -256.829306)
		(end 201.276458 -256.82956)
		(width 0.13335)
		(layer "In2.Cu")
		(net "DRIVE_A_15_INS")
	)
	(segment
		(start 201.276458 -256.82956)
		(end 200.803764 -256.82956)
		(width 0.13335)
		(layer "In2.Cu")
		(net "DRIVE_A_15_INS")
	)
	(segment
		(start 119.151146 -257.632454)
		(end 118.1608 -258.6228)
		(width 0.13335)
		(layer "In2.Cu")
		(net "DRIVE_A_15_INS")
	)
	(segment
		(start 200.803764 -256.82956)
		(end 200.80351 -256.829306)
		(width 0.13335)
		(layer "In2.Cu")
		(net "DRIVE_A_15_INS")
	)
	(segment
		(start 110.9599 -227.647246)
		(end 115.024662 -231.712008)
		(width 0.12065)
		(layer "In4.Cu")
		(net "DRIVE_A_15_INS")
	)
	(segment
		(start 129.538984 -182.116984)
		(end 129.1082 -182.547768)
		(width 0.12065)
		(layer "In4.Cu")
		(net "DRIVE_A_15_INS")
	)
	(segment
		(start 129.1082 -188.051186)
		(end 110.9599 -206.199486)
		(width 0.12065)
		(layer "In4.Cu")
		(net "DRIVE_A_15_INS")
	)
	(segment
		(start 115.024662 -255.486662)
		(end 118.1608 -258.6228)
		(width 0.12065)
		(layer "In4.Cu")
		(net "DRIVE_A_15_INS")
	)
	(segment
		(start 115.024662 -231.712008)
		(end 115.024662 -255.486662)
		(width 0.12065)
		(layer "In4.Cu")
		(net "DRIVE_A_15_INS")
	)
	(segment
		(start 129.1082 -182.547768)
		(end 129.1082 -188.051186)
		(width 0.12065)
		(layer "In4.Cu")
		(net "DRIVE_A_15_INS")
	)
	(segment
		(start 110.9599 -206.199486)
		(end 110.9599 -227.647246)
		(width 0.12065)
		(layer "In4.Cu")
		(net "DRIVE_A_15_INS")
	)
	(segment
		(start 110.339886 -130.261614)
		(end 110.339886 -132.178298)
		(width 0.17145)
		(layer "F.Cu")
		(net "DRIVE_A_15_FLT_LED")
	)
	(segment
		(start 110.340902 -128.731772)
		(end 110.339886 -128.732788)
		(width 0.17145)
		(layer "F.Cu")
		(net "DRIVE_A_15_FLT_LED")
	)
	(segment
		(start 110.339886 -128.732788)
		(end 110.339886 -130.261614)
		(width 0.17145)
		(layer "F.Cu")
		(net "DRIVE_A_15_FLT_LED")
	)
	(segment
		(start 110.339886 -132.178298)
		(end 110.339886 -133.968744)
		(width 0.17145)
		(layer "F.Cu")
		(net "DRIVE_A_15_FLT_LED")
	)
	(segment
		(start 263.18464 -280.9494)
		(end 263.18464 -282.4226)
		(width 0.17145)
		(layer "F.Cu")
		(net "DRIVE_A_15_FLT_LED")
	)
	(via
		(at 110.339886 -133.968744)
		(size 0.5588)
		(drill 0.3048)
		(layers "F.Cu" "B.Cu")
		(net "DRIVE_A_15_FLT_LED")
	)
	(via
		(at 263.18464 -282.4226)
		(size 0.5588)
		(drill 0.3048)
		(layers "F.Cu" "B.Cu")
		(net "DRIVE_A_15_FLT_LED")
	)
	(via
		(at 112.1156 -297.0276)
		(size 0.5588)
		(drill 0.3048)
		(layers "F.Cu" "B.Cu")
		(net "DRIVE_A_15_FLT_LED")
	)
	(via
		(at 110.339886 -132.178298)
		(size 0.6604)
		(drill 0.3302)
		(layers "F.Cu" "B.Cu")
		(net "DRIVE_A_15_FLT_LED")
	)
	(segment
		(start 243.063268 -293.210234)
		(end 198.499222 -293.210234)
		(width 0.13335)
		(layer "In2.Cu")
		(net "DRIVE_A_15_FLT_LED")
	)
	(segment
		(start 128.764792 -298.087034)
		(end 122.663712 -298.087034)
		(width 0.13335)
		(layer "In2.Cu")
		(net "DRIVE_A_15_FLT_LED")
	)
	(segment
		(start 244.452902 -291.8206)
		(end 243.063268 -293.210234)
		(width 0.13335)
		(layer "In2.Cu")
		(net "DRIVE_A_15_FLT_LED")
	)
	(segment
		(start 152.502108 -298.163996)
		(end 151.17699 -296.838878)
		(width 0.13335)
		(layer "In2.Cu")
		(net "DRIVE_A_15_FLT_LED")
	)
	(segment
		(start 121.604278 -297.0276)
		(end 112.1156 -297.0276)
		(width 0.13335)
		(layer "In2.Cu")
		(net "DRIVE_A_15_FLT_LED")
	)
	(segment
		(start 257.217418 -283.3624)
		(end 248.759218 -291.8206)
		(width 0.13335)
		(layer "In2.Cu")
		(net "DRIVE_A_15_FLT_LED")
	)
	(segment
		(start 122.663712 -298.087034)
		(end 121.604278 -297.0276)
		(width 0.13335)
		(layer "In2.Cu")
		(net "DRIVE_A_15_FLT_LED")
	)
	(segment
		(start 248.759218 -291.8206)
		(end 244.452902 -291.8206)
		(width 0.13335)
		(layer "In2.Cu")
		(net "DRIVE_A_15_FLT_LED")
	)
	(segment
		(start 192.91935 -295.909746)
		(end 190.125096 -298.704)
		(width 0.13335)
		(layer "In2.Cu")
		(net "DRIVE_A_15_FLT_LED")
	)
	(segment
		(start 198.499222 -293.210234)
		(end 195.79971 -295.909746)
		(width 0.13335)
		(layer "In2.Cu")
		(net "DRIVE_A_15_FLT_LED")
	)
	(segment
		(start 161.71545 -298.704)
		(end 161.175446 -298.163996)
		(width 0.13335)
		(layer "In2.Cu")
		(net "DRIVE_A_15_FLT_LED")
	)
	(segment
		(start 190.125096 -298.704)
		(end 161.71545 -298.704)
		(width 0.13335)
		(layer "In2.Cu")
		(net "DRIVE_A_15_FLT_LED")
	)
	(segment
		(start 161.175446 -298.163996)
		(end 152.502108 -298.163996)
		(width 0.13335)
		(layer "In2.Cu")
		(net "DRIVE_A_15_FLT_LED")
	)
	(segment
		(start 262.24484 -283.3624)
		(end 257.217418 -283.3624)
		(width 0.13335)
		(layer "In2.Cu")
		(net "DRIVE_A_15_FLT_LED")
	)
	(segment
		(start 130.012948 -296.838878)
		(end 128.764792 -298.087034)
		(width 0.13335)
		(layer "In2.Cu")
		(net "DRIVE_A_15_FLT_LED")
	)
	(segment
		(start 195.79971 -295.909746)
		(end 192.91935 -295.909746)
		(width 0.13335)
		(layer "In2.Cu")
		(net "DRIVE_A_15_FLT_LED")
	)
	(segment
		(start 263.18464 -282.4226)
		(end 262.24484 -283.3624)
		(width 0.13335)
		(layer "In2.Cu")
		(net "DRIVE_A_15_FLT_LED")
	)
	(segment
		(start 151.17699 -296.838878)
		(end 130.012948 -296.838878)
		(width 0.13335)
		(layer "In2.Cu")
		(net "DRIVE_A_15_FLT_LED")
	)
	(segment
		(start 112.266984 -178.398678)
		(end 108.812584 -181.853078)
		(width 0.12065)
		(layer "In4.Cu")
		(net "DRIVE_A_15_FLT_LED")
	)
	(segment
		(start 113.3348 -295.8084)
		(end 112.1156 -297.0276)
		(width 0.12065)
		(layer "In4.Cu")
		(net "DRIVE_A_15_FLT_LED")
	)
	(segment
		(start 112.266984 -178.141884)
		(end 112.266984 -178.398678)
		(width 0.12065)
		(layer "In4.Cu")
		(net "DRIVE_A_15_FLT_LED")
	)
	(segment
		(start 112.413034 -177.995834)
		(end 112.266984 -178.141884)
		(width 0.12065)
		(layer "In4.Cu")
		(net "DRIVE_A_15_FLT_LED")
	)
	(segment
		(start 111.7473 -245.6561)
		(end 111.7473 -280.019252)
		(width 0.12065)
		(layer "In4.Cu")
		(net "DRIVE_A_15_FLT_LED")
	)
	(segment
		(start 112.820704 -281.092656)
		(end 112.820704 -286.99841)
		(width 0.12065)
		(layer "In4.Cu")
		(net "DRIVE_A_15_FLT_LED")
	)
	(segment
		(start 112.820704 -286.99841)
		(end 113.3348 -287.512506)
		(width 0.12065)
		(layer "In4.Cu")
		(net "DRIVE_A_15_FLT_LED")
	)
	(segment
		(start 108.812584 -227.611686)
		(end 112.522 -231.321102)
		(width 0.12065)
		(layer "In4.Cu")
		(net "DRIVE_A_15_FLT_LED")
	)
	(segment
		(start 111.7473 -280.019252)
		(end 112.820704 -281.092656)
		(width 0.12065)
		(layer "In4.Cu")
		(net "DRIVE_A_15_FLT_LED")
	)
	(segment
		(start 112.413034 -171.391834)
		(end 112.413034 -177.995834)
		(width 0.12065)
		(layer "In4.Cu")
		(net "DRIVE_A_15_FLT_LED")
	)
	(segment
		(start 110.339886 -133.968744)
		(end 107.272074 -137.036556)
		(width 0.12065)
		(layer "In4.Cu")
		(net "DRIVE_A_15_FLT_LED")
	)
	(segment
		(start 107.272074 -166.250874)
		(end 112.413034 -171.391834)
		(width 0.12065)
		(layer "In4.Cu")
		(net "DRIVE_A_15_FLT_LED")
	)
	(segment
		(start 112.522 -244.8814)
		(end 111.7473 -245.6561)
		(width 0.12065)
		(layer "In4.Cu")
		(net "DRIVE_A_15_FLT_LED")
	)
	(segment
		(start 112.522 -231.321102)
		(end 112.522 -244.8814)
		(width 0.12065)
		(layer "In4.Cu")
		(net "DRIVE_A_15_FLT_LED")
	)
	(segment
		(start 107.272074 -137.036556)
		(end 107.272074 -166.250874)
		(width 0.12065)
		(layer "In4.Cu")
		(net "DRIVE_A_15_FLT_LED")
	)
	(segment
		(start 113.3348 -287.512506)
		(end 113.3348 -295.8084)
		(width 0.12065)
		(layer "In4.Cu")
		(net "DRIVE_A_15_FLT_LED")
	)
	(segment
		(start 108.812584 -181.853078)
		(end 108.812584 -227.611686)
		(width 0.12065)
		(layer "In4.Cu")
		(net "DRIVE_A_15_FLT_LED")
	)
	(segment
		(start 106.726228 -132.177282)
		(end 106.726228 -133.967728)
		(width 0.17145)
		(layer "F.Cu")
		(net "DRIVE_A_15_ACT")
	)
	(segment
		(start 106.726228 -130.260598)
		(end 106.725212 -130.259582)
		(width 0.17145)
		(layer "F.Cu")
		(net "DRIVE_A_15_ACT")
	)
	(segment
		(start 106.725212 -130.259582)
		(end 106.725212 -128.74117)
		(width 0.17145)
		(layer "F.Cu")
		(net "DRIVE_A_15_ACT")
	)
	(segment
		(start 106.726228 -132.177282)
		(end 106.726228 -130.260598)
		(width 0.17145)
		(layer "F.Cu")
		(net "DRIVE_A_15_ACT")
	)
	(via
		(at 106.726228 -133.967728)
		(size 0.5588)
		(drill 0.3048)
		(layers "F.Cu" "B.Cu")
		(net "DRIVE_A_15_ACT")
	)
	(via
		(at 105.8926 -310.3372)
		(size 0.5588)
		(drill 0.3048)
		(layers "F.Cu" "B.Cu")
		(net "DRIVE_A_15_ACT")
	)
	(via
		(at 265.938 -319.706498)
		(size 0.5588)
		(drill 0.3048)
		(layers "F.Cu" "B.Cu")
		(net "DRIVE_A_15_ACT")
	)
	(via
		(at 106.726228 -132.177282)
		(size 0.6604)
		(drill 0.3302)
		(layers "F.Cu" "B.Cu")
		(net "DRIVE_A_15_ACT")
	)
	(segment
		(start 265.938 -319.706498)
		(end 265.934698 -319.7098)
		(width 0.13335)
		(layer "In2.Cu")
		(net "DRIVE_A_15_ACT")
	)
	(segment
		(start 265.934698 -319.7098)
		(end 244.442996 -319.7098)
		(width 0.13335)
		(layer "In2.Cu")
		(net "DRIVE_A_15_ACT")
	)
	(segment
		(start 240.896648 -316.163452)
		(end 190.585852 -316.163452)
		(width 0.13335)
		(layer "In2.Cu")
		(net "DRIVE_A_15_ACT")
	)
	(segment
		(start 190.585852 -316.163452)
		(end 184.7596 -310.3372)
		(width 0.13335)
		(layer "In2.Cu")
		(net "DRIVE_A_15_ACT")
	)
	(segment
		(start 244.442996 -319.7098)
		(end 240.896648 -316.163452)
		(width 0.13335)
		(layer "In2.Cu")
		(net "DRIVE_A_15_ACT")
	)
	(segment
		(start 184.7596 -310.3372)
		(end 105.8926 -310.3372)
		(width 0.13335)
		(layer "In2.Cu")
		(net "DRIVE_A_15_ACT")
	)
	(segment
		(start 108.399834 -181.681882)
		(end 108.399834 -228.302566)
		(width 0.12065)
		(layer "In4.Cu")
		(net "DRIVE_A_15_ACT")
	)
	(segment
		(start 111.854234 -178.227482)
		(end 108.399834 -181.681882)
		(width 0.12065)
		(layer "In4.Cu")
		(net "DRIVE_A_15_ACT")
	)
	(segment
		(start 111.9632 -231.865932)
		(end 111.9632 -234.2388)
		(width 0.12065)
		(layer "In4.Cu")
		(net "DRIVE_A_15_ACT")
	)
	(segment
		(start 108.399834 -228.302566)
		(end 111.9632 -231.865932)
		(width 0.12065)
		(layer "In4.Cu")
		(net "DRIVE_A_15_ACT")
	)
	(segment
		(start 111.1885 -286.156654)
		(end 112.522 -287.490154)
		(width 0.12065)
		(layer "In4.Cu")
		(net "DRIVE_A_15_ACT")
	)
	(segment
		(start 112.522 -294.8178)
		(end 105.88498 -301.45482)
		(width 0.12065)
		(layer "In4.Cu")
		(net "DRIVE_A_15_ACT")
	)
	(segment
		(start 105.88498 -310.32958)
		(end 105.8926 -310.3372)
		(width 0.12065)
		(layer "In4.Cu")
		(net "DRIVE_A_15_ACT")
	)
	(segment
		(start 106.726228 -133.967728)
		(end 106.726228 -166.495476)
		(width 0.12065)
		(layer "In4.Cu")
		(net "DRIVE_A_15_ACT")
	)
	(segment
		(start 112.522 -287.490154)
		(end 112.522 -294.8178)
		(width 0.12065)
		(layer "In4.Cu")
		(net "DRIVE_A_15_ACT")
	)
	(segment
		(start 111.854234 -171.623482)
		(end 111.854234 -178.227482)
		(width 0.12065)
		(layer "In4.Cu")
		(net "DRIVE_A_15_ACT")
	)
	(segment
		(start 111.1885 -235.0135)
		(end 111.1885 -286.156654)
		(width 0.12065)
		(layer "In4.Cu")
		(net "DRIVE_A_15_ACT")
	)
	(segment
		(start 105.88498 -301.45482)
		(end 105.88498 -310.32958)
		(width 0.12065)
		(layer "In4.Cu")
		(net "DRIVE_A_15_ACT")
	)
	(segment
		(start 106.726228 -166.495476)
		(end 111.854234 -171.623482)
		(width 0.12065)
		(layer "In4.Cu")
		(net "DRIVE_A_15_ACT")
	)
	(segment
		(start 111.9632 -234.2388)
		(end 111.1885 -235.0135)
		(width 0.12065)
		(layer "In4.Cu")
		(net "DRIVE_A_15_ACT")
	)
	(segment
		(start 277.0759 -315.3029)
		(end 272.672302 -319.706498)
		(width 0.13335)
		(layer "In9.Cu")
		(net "DRIVE_A_15_ACT")
	)
	(segment
		(start 282.83662 -314.505086)
		(end 282.038806 -315.3029)
		(width 0.13335)
		(layer "In9.Cu")
		(net "DRIVE_A_15_ACT")
	)
	(segment
		(start 272.672302 -319.706498)
		(end 265.938 -319.706498)
		(width 0.13335)
		(layer "In9.Cu")
		(net "DRIVE_A_15_ACT")
	)
	(segment
		(start 282.038806 -315.3029)
		(end 277.0759 -315.3029)
		(width 0.13335)
		(layer "In9.Cu")
		(net "DRIVE_A_15_ACT")
	)
	(segment
		(start 84.755228 -158.930594)
		(end 84.755228 -157.951932)
		(width 0.17145)
		(layer "F.Cu")
		(net "DRIVE_A_14_PWR")
	)
	(segment
		(start 232.715816 -238.397288)
		(end 231.59212 -237.273592)
		(width 0.17145)
		(layer "F.Cu")
		(net "DRIVE_A_14_PWR")
	)
	(segment
		(start 84.755228 -159.874966)
		(end 84.755228 -158.930594)
		(width 0.17145)
		(layer "F.Cu")
		(net "DRIVE_A_14_PWR")
	)
	(segment
		(start 231.59212 -237.273592)
		(end 231.59212 -234.1626)
		(width 0.17145)
		(layer "F.Cu")
		(net "DRIVE_A_14_PWR")
	)
	(via
		(at 84.755228 -157.951932)
		(size 0.5588)
		(drill 0.3048)
		(layers "F.Cu" "B.Cu")
		(net "DRIVE_A_14_PWR")
	)
	(via
		(at 84.755228 -158.930594)
		(size 0.6604)
		(drill 0.3302)
		(layers "F.Cu" "B.Cu")
		(net "DRIVE_A_14_PWR")
	)
	(via
		(at 85.1662 -235.4326)
		(size 0.5588)
		(drill 0.3048)
		(layers "F.Cu" "B.Cu")
		(net "DRIVE_A_14_PWR")
	)
	(via
		(at 232.715816 -238.397288)
		(size 0.5588)
		(drill 0.3048)
		(layers "F.Cu" "B.Cu")
		(net "DRIVE_A_14_PWR")
	)
	(segment
		(start 224.208848 -239.5474)
		(end 231.565704 -239.5474)
		(width 0.13335)
		(layer "In2.Cu")
		(net "DRIVE_A_14_PWR")
	)
	(segment
		(start 196.392546 -241.271806)
		(end 222.484442 -241.271806)
		(width 0.13335)
		(layer "In2.Cu")
		(net "DRIVE_A_14_PWR")
	)
	(segment
		(start 111.091472 -236.3724)
		(end 140.0302 -236.3724)
		(width 0.13335)
		(layer "In2.Cu")
		(net "DRIVE_A_14_PWR")
	)
	(segment
		(start 140.0302 -236.3724)
		(end 140.8938 -235.5088)
		(width 0.13335)
		(layer "In2.Cu")
		(net "DRIVE_A_14_PWR")
	)
	(segment
		(start 193.240152 -244.4242)
		(end 196.392546 -241.271806)
		(width 0.13335)
		(layer "In2.Cu")
		(net "DRIVE_A_14_PWR")
	)
	(segment
		(start 169.878248 -235.5088)
		(end 178.793648 -244.4242)
		(width 0.13335)
		(layer "In2.Cu")
		(net "DRIVE_A_14_PWR")
	)
	(segment
		(start 222.484442 -241.271806)
		(end 224.208848 -239.5474)
		(width 0.13335)
		(layer "In2.Cu")
		(net "DRIVE_A_14_PWR")
	)
	(segment
		(start 109.745272 -235.0262)
		(end 111.091472 -236.3724)
		(width 0.13335)
		(layer "In2.Cu")
		(net "DRIVE_A_14_PWR")
	)
	(segment
		(start 178.793648 -244.4242)
		(end 193.240152 -244.4242)
		(width 0.13335)
		(layer "In2.Cu")
		(net "DRIVE_A_14_PWR")
	)
	(segment
		(start 85.1662 -235.4326)
		(end 85.5726 -235.0262)
		(width 0.13335)
		(layer "In2.Cu")
		(net "DRIVE_A_14_PWR")
	)
	(segment
		(start 231.565704 -239.5474)
		(end 232.715816 -238.397288)
		(width 0.13335)
		(layer "In2.Cu")
		(net "DRIVE_A_14_PWR")
	)
	(segment
		(start 85.5726 -235.0262)
		(end 109.745272 -235.0262)
		(width 0.13335)
		(layer "In2.Cu")
		(net "DRIVE_A_14_PWR")
	)
	(segment
		(start 140.8938 -235.5088)
		(end 169.878248 -235.5088)
		(width 0.13335)
		(layer "In2.Cu")
		(net "DRIVE_A_14_PWR")
	)
	(segment
		(start 85.8266 -188.3664)
		(end 87.2236 -186.9694)
		(width 0.12065)
		(layer "In4.Cu")
		(net "DRIVE_A_14_PWR")
	)
	(segment
		(start 87.2236 -162.404552)
		(end 84.755228 -159.93618)
		(width 0.12065)
		(layer "In4.Cu")
		(net "DRIVE_A_14_PWR")
	)
	(segment
		(start 84.755228 -159.93618)
		(end 84.755228 -157.951932)
		(width 0.12065)
		(layer "In4.Cu")
		(net "DRIVE_A_14_PWR")
	)
	(segment
		(start 85.8266 -234.7722)
		(end 85.8266 -188.3664)
		(width 0.12065)
		(layer "In4.Cu")
		(net "DRIVE_A_14_PWR")
	)
	(segment
		(start 85.1662 -235.4326)
		(end 85.8266 -234.7722)
		(width 0.12065)
		(layer "In4.Cu")
		(net "DRIVE_A_14_PWR")
	)
	(segment
		(start 87.2236 -186.9694)
		(end 87.2236 -162.404552)
		(width 0.12065)
		(layer "In4.Cu")
		(net "DRIVE_A_14_PWR")
	)
	(segment
		(start 100.040948 -181.483)
		(end 100.040948 -180.064918)
		(width 0.17145)
		(layer "F.Cu")
		(net "DRIVE_A_14_INS")
	)
	(segment
		(start 100.040948 -182.858918)
		(end 100.040948 -181.483)
		(width 0.17145)
		(layer "F.Cu")
		(net "DRIVE_A_14_INS")
	)
	(segment
		(start 232.22712 -253.966726)
		(end 232.22712 -251.8156)
		(width 0.17145)
		(layer "F.Cu")
		(net "DRIVE_A_14_INS")
	)
	(segment
		(start 231.598978 -254.594868)
		(end 232.22712 -253.966726)
		(width 0.17145)
		(layer "F.Cu")
		(net "DRIVE_A_14_INS")
	)
	(via
		(at 100.040948 -181.483)
		(size 0.6604)
		(drill 0.3302)
		(layers "F.Cu" "B.Cu")
		(net "DRIVE_A_14_INS")
	)
	(via
		(at 103.802688 -256.041652)
		(size 0.5588)
		(drill 0.3048)
		(layers "F.Cu" "B.Cu")
		(net "DRIVE_A_14_INS")
	)
	(via
		(at 231.598978 -254.594868)
		(size 0.5588)
		(drill 0.3048)
		(layers "F.Cu" "B.Cu")
		(net "DRIVE_A_14_INS")
	)
	(via
		(at 100.040948 -182.858918)
		(size 0.5588)
		(drill 0.3048)
		(layers "F.Cu" "B.Cu")
		(net "DRIVE_A_14_INS")
	)
	(segment
		(start 197.485 -256.7178)
		(end 104.478836 -256.7178)
		(width 0.13335)
		(layer "In2.Cu")
		(net "DRIVE_A_14_INS")
	)
	(segment
		(start 231.598978 -254.594868)
		(end 231.8766 -254.87249)
		(width 0.13335)
		(layer "In2.Cu")
		(net "DRIVE_A_14_INS")
	)
	(segment
		(start 197.932548 -256.270252)
		(end 197.485 -256.7178)
		(width 0.13335)
		(layer "In2.Cu")
		(net "DRIVE_A_14_INS")
	)
	(segment
		(start 231.8766 -254.87249)
		(end 231.8766 -255.845564)
		(width 0.13335)
		(layer "In2.Cu")
		(net "DRIVE_A_14_INS")
	)
	(segment
		(start 104.478836 -256.7178)
		(end 103.802688 -256.041652)
		(width 0.13335)
		(layer "In2.Cu")
		(net "DRIVE_A_14_INS")
	)
	(segment
		(start 199.122538 -256.270506)
		(end 199.122284 -256.270252)
		(width 0.13335)
		(layer "In2.Cu")
		(net "DRIVE_A_14_INS")
	)
	(segment
		(start 231.451658 -256.270506)
		(end 199.122538 -256.270506)
		(width 0.13335)
		(layer "In2.Cu")
		(net "DRIVE_A_14_INS")
	)
	(segment
		(start 231.8766 -255.845564)
		(end 231.451658 -256.270506)
		(width 0.13335)
		(layer "In2.Cu")
		(net "DRIVE_A_14_INS")
	)
	(segment
		(start 199.122284 -256.270252)
		(end 197.932548 -256.270252)
		(width 0.13335)
		(layer "In2.Cu")
		(net "DRIVE_A_14_INS")
	)
	(segment
		(start 103.802688 -256.041652)
		(end 103.802688 -228.86416)
		(width 0.12065)
		(layer "In4.Cu")
		(net "DRIVE_A_14_INS")
	)
	(segment
		(start 100.040948 -184.6326)
		(end 100.040948 -182.858918)
		(width 0.12065)
		(layer "In4.Cu")
		(net "DRIVE_A_14_INS")
	)
	(segment
		(start 104.450134 -228.216714)
		(end 104.450134 -189.041786)
		(width 0.12065)
		(layer "In4.Cu")
		(net "DRIVE_A_14_INS")
	)
	(segment
		(start 104.450134 -189.041786)
		(end 100.040948 -184.6326)
		(width 0.12065)
		(layer "In4.Cu")
		(net "DRIVE_A_14_INS")
	)
	(segment
		(start 103.802688 -228.86416)
		(end 104.450134 -228.216714)
		(width 0.12065)
		(layer "In4.Cu")
		(net "DRIVE_A_14_INS")
	)
	(segment
		(start 78.805786 -132.187696)
		(end 78.805786 -130.271012)
		(width 0.17145)
		(layer "F.Cu")
		(net "DRIVE_A_14_FLT_LED")
	)
	(segment
		(start 78.806802 -130.269996)
		(end 78.805786 -130.271012)
		(width 0.17145)
		(layer "F.Cu")
		(net "DRIVE_A_14_FLT_LED")
	)
	(segment
		(start 78.805786 -132.187696)
		(end 78.805786 -133.978142)
		(width 0.17145)
		(layer "F.Cu")
		(net "DRIVE_A_14_FLT_LED")
	)
	(segment
		(start 78.806802 -128.74117)
		(end 78.806802 -130.269996)
		(width 0.17145)
		(layer "F.Cu")
		(net "DRIVE_A_14_FLT_LED")
	)
	(segment
		(start 264.48512 -283.8958)
		(end 263.83488 -283.24556)
		(width 0.17145)
		(layer "F.Cu")
		(net "DRIVE_A_14_FLT_LED")
	)
	(segment
		(start 263.83488 -283.24556)
		(end 263.83488 -280.9494)
		(width 0.17145)
		(layer "F.Cu")
		(net "DRIVE_A_14_FLT_LED")
	)
	(via
		(at 84.246466 -298.6532)
		(size 0.5588)
		(drill 0.3048)
		(layers "F.Cu" "B.Cu")
		(net "DRIVE_A_14_FLT_LED")
	)
	(via
		(at 78.805786 -132.187696)
		(size 0.6604)
		(drill 0.3302)
		(layers "F.Cu" "B.Cu")
		(net "DRIVE_A_14_FLT_LED")
	)
	(via
		(at 78.805786 -133.978142)
		(size 0.5588)
		(drill 0.3048)
		(layers "F.Cu" "B.Cu")
		(net "DRIVE_A_14_FLT_LED")
	)
	(via
		(at 264.48512 -283.8958)
		(size 0.5588)
		(drill 0.3048)
		(layers "F.Cu" "B.Cu")
		(net "DRIVE_A_14_FLT_LED")
	)
	(segment
		(start 152.038812 -299.281596)
		(end 150.713694 -297.956478)
		(width 0.13335)
		(layer "In2.Cu")
		(net "DRIVE_A_14_FLT_LED")
	)
	(segment
		(start 260.310884 -291.161978)
		(end 250.998736 -291.161978)
		(width 0.13335)
		(layer "In2.Cu")
		(net "DRIVE_A_14_FLT_LED")
	)
	(segment
		(start 263.8552 -284.52572)
		(end 263.8552 -287.617662)
		(width 0.13335)
		(layer "In2.Cu")
		(net "DRIVE_A_14_FLT_LED")
	)
	(segment
		(start 243.555266 -294.327834)
		(end 199.013318 -294.327834)
		(width 0.13335)
		(layer "In2.Cu")
		(net "DRIVE_A_14_FLT_LED")
	)
	(segment
		(start 250.998736 -291.161978)
		(end 249.222514 -292.9382)
		(width 0.13335)
		(layer "In2.Cu")
		(net "DRIVE_A_14_FLT_LED")
	)
	(segment
		(start 249.222514 -292.9382)
		(end 244.9449 -292.9382)
		(width 0.13335)
		(layer "In2.Cu")
		(net "DRIVE_A_14_FLT_LED")
	)
	(segment
		(start 196.313806 -297.027346)
		(end 193.382646 -297.027346)
		(width 0.13335)
		(layer "In2.Cu")
		(net "DRIVE_A_14_FLT_LED")
	)
	(segment
		(start 164.917374 -301.02048)
		(end 163.718494 -299.8216)
		(width 0.13335)
		(layer "In2.Cu")
		(net "DRIVE_A_14_FLT_LED")
	)
	(segment
		(start 110.588298 -298.037504)
		(end 103.830628 -298.037504)
		(width 0.13335)
		(layer "In2.Cu")
		(net "DRIVE_A_14_FLT_LED")
	)
	(segment
		(start 160.71215 -299.281596)
		(end 152.038812 -299.281596)
		(width 0.13335)
		(layer "In2.Cu")
		(net "DRIVE_A_14_FLT_LED")
	)
	(segment
		(start 161.252154 -299.8216)
		(end 160.71215 -299.281596)
		(width 0.13335)
		(layer "In2.Cu")
		(net "DRIVE_A_14_FLT_LED")
	)
	(segment
		(start 103.830628 -298.037504)
		(end 103.214932 -298.6532)
		(width 0.13335)
		(layer "In2.Cu")
		(net "DRIVE_A_14_FLT_LED")
	)
	(segment
		(start 189.389512 -301.02048)
		(end 164.917374 -301.02048)
		(width 0.13335)
		(layer "In2.Cu")
		(net "DRIVE_A_14_FLT_LED")
	)
	(segment
		(start 150.713694 -297.956478)
		(end 130.476244 -297.956478)
		(width 0.13335)
		(layer "In2.Cu")
		(net "DRIVE_A_14_FLT_LED")
	)
	(segment
		(start 163.718494 -299.8216)
		(end 161.252154 -299.8216)
		(width 0.13335)
		(layer "In2.Cu")
		(net "DRIVE_A_14_FLT_LED")
	)
	(segment
		(start 199.013318 -294.327834)
		(end 196.313806 -297.027346)
		(width 0.13335)
		(layer "In2.Cu")
		(net "DRIVE_A_14_FLT_LED")
	)
	(segment
		(start 244.9449 -292.9382)
		(end 243.555266 -294.327834)
		(width 0.13335)
		(layer "In2.Cu")
		(net "DRIVE_A_14_FLT_LED")
	)
	(segment
		(start 264.48512 -283.8958)
		(end 263.8552 -284.52572)
		(width 0.13335)
		(layer "In2.Cu")
		(net "DRIVE_A_14_FLT_LED")
	)
	(segment
		(start 263.8552 -287.617662)
		(end 260.310884 -291.161978)
		(width 0.13335)
		(layer "In2.Cu")
		(net "DRIVE_A_14_FLT_LED")
	)
	(segment
		(start 129.22758 -299.205142)
		(end 111.755936 -299.205142)
		(width 0.13335)
		(layer "In2.Cu")
		(net "DRIVE_A_14_FLT_LED")
	)
	(segment
		(start 103.214932 -298.6532)
		(end 84.246466 -298.6532)
		(width 0.13335)
		(layer "In2.Cu")
		(net "DRIVE_A_14_FLT_LED")
	)
	(segment
		(start 130.476244 -297.956478)
		(end 129.22758 -299.205142)
		(width 0.13335)
		(layer "In2.Cu")
		(net "DRIVE_A_14_FLT_LED")
	)
	(segment
		(start 111.755936 -299.205142)
		(end 110.588298 -298.037504)
		(width 0.13335)
		(layer "In2.Cu")
		(net "DRIVE_A_14_FLT_LED")
	)
	(segment
		(start 193.382646 -297.027346)
		(end 189.389512 -301.02048)
		(width 0.13335)
		(layer "In2.Cu")
		(net "DRIVE_A_14_FLT_LED")
	)
	(segment
		(start 79.0448 -182.0418)
		(end 79.0448 -278.638)
		(width 0.12065)
		(layer "In4.Cu")
		(net "DRIVE_A_14_FLT_LED")
	)
	(segment
		(start 80.8482 -180.2384)
		(end 79.0448 -182.0418)
		(width 0.12065)
		(layer "In4.Cu")
		(net "DRIVE_A_14_FLT_LED")
	)
	(segment
		(start 79.0448 -278.638)
		(end 80.80375 -280.39695)
		(width 0.12065)
		(layer "In4.Cu")
		(net "DRIVE_A_14_FLT_LED")
	)
	(segment
		(start 78.805786 -136.336786)
		(end 83.159854 -140.690854)
		(width 0.12065)
		(layer "In4.Cu")
		(net "DRIVE_A_14_FLT_LED")
	)
	(segment
		(start 83.159854 -159.205168)
		(end 80.8482 -161.516822)
		(width 0.12065)
		(layer "In4.Cu")
		(net "DRIVE_A_14_FLT_LED")
	)
	(segment
		(start 80.80375 -280.39695)
		(end 80.80375 -295.210484)
		(width 0.12065)
		(layer "In4.Cu")
		(net "DRIVE_A_14_FLT_LED")
	)
	(segment
		(start 78.805786 -133.978142)
		(end 78.805786 -136.336786)
		(width 0.12065)
		(layer "In4.Cu")
		(net "DRIVE_A_14_FLT_LED")
	)
	(segment
		(start 80.8482 -161.516822)
		(end 80.8482 -180.2384)
		(width 0.12065)
		(layer "In4.Cu")
		(net "DRIVE_A_14_FLT_LED")
	)
	(segment
		(start 83.159854 -140.690854)
		(end 83.159854 -159.205168)
		(width 0.12065)
		(layer "In4.Cu")
		(net "DRIVE_A_14_FLT_LED")
	)
	(segment
		(start 80.80375 -295.210484)
		(end 84.246466 -298.6532)
		(width 0.12065)
		(layer "In4.Cu")
		(net "DRIVE_A_14_FLT_LED")
	)
	(segment
		(start 75.192128 -132.18668)
		(end 75.192128 -133.977126)
		(width 0.17145)
		(layer "F.Cu")
		(net "DRIVE_A_14_ACT")
	)
	(segment
		(start 75.192128 -132.18668)
		(end 75.192128 -130.269996)
		(width 0.17145)
		(layer "F.Cu")
		(net "DRIVE_A_14_ACT")
	)
	(segment
		(start 75.192128 -130.269996)
		(end 75.191112 -130.26898)
		(width 0.17145)
		(layer "F.Cu")
		(net "DRIVE_A_14_ACT")
	)
	(segment
		(start 75.191112 -130.26898)
		(end 75.191112 -128.750568)
		(width 0.17145)
		(layer "F.Cu")
		(net "DRIVE_A_14_ACT")
	)
	(via
		(at 75.192128 -133.977126)
		(size 0.5588)
		(drill 0.3048)
		(layers "F.Cu" "B.Cu")
		(net "DRIVE_A_14_ACT")
	)
	(via
		(at 80.137 -309.0418)
		(size 0.5588)
		(drill 0.3048)
		(layers "F.Cu" "B.Cu")
		(net "DRIVE_A_14_ACT")
	)
	(via
		(at 75.192128 -132.18668)
		(size 0.6604)
		(drill 0.3302)
		(layers "F.Cu" "B.Cu")
		(net "DRIVE_A_14_ACT")
	)
	(segment
		(start 277.564596 -313.5884)
		(end 272.154396 -318.9986)
		(width 0.13335)
		(layer "In2.Cu")
		(net "DRIVE_A_14_ACT")
	)
	(segment
		(start 283.319982 -313.5884)
		(end 277.564596 -313.5884)
		(width 0.13335)
		(layer "In2.Cu")
		(net "DRIVE_A_14_ACT")
	)
	(segment
		(start 272.154396 -318.9986)
		(end 244.5766 -318.9986)
		(width 0.13335)
		(layer "In2.Cu")
		(net "DRIVE_A_14_ACT")
	)
	(segment
		(start 185.039 -309.7784)
		(end 157.734 -309.7784)
		(width 0.13335)
		(layer "In2.Cu")
		(net "DRIVE_A_14_ACT")
	)
	(segment
		(start 241.0206 -315.4426)
		(end 190.7032 -315.4426)
		(width 0.13335)
		(layer "In2.Cu")
		(net "DRIVE_A_14_ACT")
	)
	(segment
		(start 244.5766 -318.9986)
		(end 241.0206 -315.4426)
		(width 0.13335)
		(layer "In2.Cu")
		(net "DRIVE_A_14_ACT")
	)
	(segment
		(start 156.9974 -309.0418)
		(end 80.137 -309.0418)
		(width 0.13335)
		(layer "In2.Cu")
		(net "DRIVE_A_14_ACT")
	)
	(segment
		(start 284.236668 -314.505086)
		(end 283.319982 -313.5884)
		(width 0.13335)
		(layer "In2.Cu")
		(net "DRIVE_A_14_ACT")
	)
	(segment
		(start 190.7032 -315.4426)
		(end 185.039 -309.7784)
		(width 0.13335)
		(layer "In2.Cu")
		(net "DRIVE_A_14_ACT")
	)
	(segment
		(start 157.734 -309.7784)
		(end 156.9974 -309.0418)
		(width 0.13335)
		(layer "In2.Cu")
		(net "DRIVE_A_14_ACT")
	)
	(segment
		(start 81.712054 -159.86252)
		(end 80.2894 -161.285174)
		(width 0.12065)
		(layer "In4.Cu")
		(net "DRIVE_A_14_ACT")
	)
	(segment
		(start 80.161384 -280.545032)
		(end 80.161384 -309.017416)
		(width 0.12065)
		(layer "In4.Cu")
		(net "DRIVE_A_14_ACT")
	)
	(segment
		(start 75.192128 -133.977126)
		(end 81.712054 -140.497052)
		(width 0.12065)
		(layer "In4.Cu")
		(net "DRIVE_A_14_ACT")
	)
	(segment
		(start 80.2894 -180.006752)
		(end 78.485746 -181.810406)
		(width 0.12065)
		(layer "In4.Cu")
		(net "DRIVE_A_14_ACT")
	)
	(segment
		(start 80.2894 -161.285174)
		(end 80.2894 -180.006752)
		(width 0.12065)
		(layer "In4.Cu")
		(net "DRIVE_A_14_ACT")
	)
	(segment
		(start 80.161384 -309.017416)
		(end 80.137 -309.0418)
		(width 0.12065)
		(layer "In4.Cu")
		(net "DRIVE_A_14_ACT")
	)
	(segment
		(start 81.712054 -140.497052)
		(end 81.712054 -159.86252)
		(width 0.12065)
		(layer "In4.Cu")
		(net "DRIVE_A_14_ACT")
	)
	(segment
		(start 78.485746 -181.810406)
		(end 78.485746 -278.869394)
		(width 0.12065)
		(layer "In4.Cu")
		(net "DRIVE_A_14_ACT")
	)
	(segment
		(start 78.485746 -278.869394)
		(end 80.161384 -280.545032)
		(width 0.12065)
		(layer "In4.Cu")
		(net "DRIVE_A_14_ACT")
	)
	(segment
		(start 229.766876 -236.509814)
		(end 230.94188 -235.33481)
		(width 0.17145)
		(layer "F.Cu")
		(net "DRIVE_A_13_PWR")
	)
	(segment
		(start 230.94188 -235.33481)
		(end 230.94188 -234.1626)
		(width 0.17145)
		(layer "F.Cu")
		(net "DRIVE_A_13_PWR")
	)
	(segment
		(start 54.990746 -157.204918)
		(end 55.816246 -157.204918)
		(width 0.17145)
		(layer "F.Cu")
		(net "DRIVE_A_13_PWR")
	)
	(via
		(at 56.6674 -233.8324)
		(size 0.5588)
		(drill 0.3048)
		(layers "F.Cu" "B.Cu")
		(net "DRIVE_A_13_PWR")
	)
	(via
		(at 229.766876 -236.509814)
		(size 0.5588)
		(drill 0.3048)
		(layers "F.Cu" "B.Cu")
		(net "DRIVE_A_13_PWR")
	)
	(via
		(at 55.816246 -157.204918)
		(size 0.5588)
		(drill 0.3048)
		(layers "F.Cu" "B.Cu")
		(net "DRIVE_A_13_PWR")
	)
	(segment
		(start 221.789498 -239.595406)
		(end 223.513904 -237.871)
		(width 0.13335)
		(layer "In2.Cu")
		(net "DRIVE_A_13_PWR")
	)
	(segment
		(start 170.573192 -233.8324)
		(end 179.488592 -242.7478)
		(width 0.13335)
		(layer "In2.Cu")
		(net "DRIVE_A_13_PWR")
	)
	(segment
		(start 229.046024 -236.509814)
		(end 229.766876 -236.509814)
		(width 0.13335)
		(layer "In2.Cu")
		(net "DRIVE_A_13_PWR")
	)
	(segment
		(start 56.6674 -233.8324)
		(end 170.573192 -233.8324)
		(width 0.13335)
		(layer "In2.Cu")
		(net "DRIVE_A_13_PWR")
	)
	(segment
		(start 223.513904 -237.871)
		(end 227.684838 -237.871)
		(width 0.13335)
		(layer "In2.Cu")
		(net "DRIVE_A_13_PWR")
	)
	(segment
		(start 179.488592 -242.7478)
		(end 192.545208 -242.7478)
		(width 0.13335)
		(layer "In2.Cu")
		(net "DRIVE_A_13_PWR")
	)
	(segment
		(start 195.697602 -239.595406)
		(end 221.789498 -239.595406)
		(width 0.13335)
		(layer "In2.Cu")
		(net "DRIVE_A_13_PWR")
	)
	(segment
		(start 227.684838 -237.871)
		(end 229.046024 -236.509814)
		(width 0.13335)
		(layer "In2.Cu")
		(net "DRIVE_A_13_PWR")
	)
	(segment
		(start 192.545208 -242.7478)
		(end 195.697602 -239.595406)
		(width 0.13335)
		(layer "In2.Cu")
		(net "DRIVE_A_13_PWR")
	)
	(segment
		(start 56.6674 -233.8324)
		(end 55.243476 -232.408476)
		(width 0.12065)
		(layer "In4.Cu")
		(net "DRIVE_A_13_PWR")
	)
	(segment
		(start 55.243476 -232.408476)
		(end 55.243476 -165.735)
		(width 0.12065)
		(layer "In4.Cu")
		(net "DRIVE_A_13_PWR")
	)
	(segment
		(start 54.356 -158.665164)
		(end 55.816246 -157.204918)
		(width 0.12065)
		(layer "In4.Cu")
		(net "DRIVE_A_13_PWR")
	)
	(segment
		(start 54.356 -164.847524)
		(end 54.356 -158.665164)
		(width 0.12065)
		(layer "In4.Cu")
		(net "DRIVE_A_13_PWR")
	)
	(segment
		(start 55.243476 -165.735)
		(end 54.356 -164.847524)
		(width 0.12065)
		(layer "In4.Cu")
		(net "DRIVE_A_13_PWR")
	)
	(segment
		(start 68.490846 -180.064918)
		(end 68.490846 -180.937154)
		(width 0.17145)
		(layer "F.Cu")
		(net "DRIVE_A_13_INS")
	)
	(segment
		(start 65.6844 -181.737)
		(end 67.691 -181.737)
		(width 0.17145)
		(layer "F.Cu")
		(net "DRIVE_A_13_INS")
	)
	(segment
		(start 230.9368 -254.327406)
		(end 231.57688 -253.687326)
		(width 0.17145)
		(layer "F.Cu")
		(net "DRIVE_A_13_INS")
	)
	(segment
		(start 67.691 -181.737)
		(end 68.090034 -181.337966)
		(width 0.17145)
		(layer "F.Cu")
		(net "DRIVE_A_13_INS")
	)
	(segment
		(start 231.15016 -255.679702)
		(end 230.9368 -255.466342)
		(width 0.17145)
		(layer "F.Cu")
		(net "DRIVE_A_13_INS")
	)
	(segment
		(start 231.57688 -253.687326)
		(end 231.57688 -251.8156)
		(width 0.17145)
		(layer "F.Cu")
		(net "DRIVE_A_13_INS")
	)
	(segment
		(start 230.9368 -255.466342)
		(end 230.9368 -254.327406)
		(width 0.17145)
		(layer "F.Cu")
		(net "DRIVE_A_13_INS")
	)
	(segment
		(start 68.490846 -180.937154)
		(end 68.090034 -181.337966)
		(width 0.17145)
		(layer "F.Cu")
		(net "DRIVE_A_13_INS")
	)
	(via
		(at 231.15016 -255.679702)
		(size 0.5588)
		(drill 0.3048)
		(layers "F.Cu" "B.Cu")
		(net "DRIVE_A_13_INS")
	)
	(via
		(at 65.6844 -181.737)
		(size 0.5588)
		(drill 0.3048)
		(layers "F.Cu" "B.Cu")
		(net "DRIVE_A_13_INS")
	)
	(via
		(at 66.3194 -255.4478)
		(size 0.5588)
		(drill 0.3048)
		(layers "F.Cu" "B.Cu")
		(net "DRIVE_A_13_INS")
	)
	(via
		(at 68.090034 -181.337966)
		(size 0.6604)
		(drill 0.3302)
		(layers "F.Cu" "B.Cu")
		(net "DRIVE_A_13_INS")
	)
	(segment
		(start 231.128062 -255.7018)
		(end 199.354186 -255.7018)
		(width 0.13335)
		(layer "In2.Cu")
		(net "DRIVE_A_13_INS")
	)
	(segment
		(start 170.727624 -255.4478)
		(end 66.3194 -255.4478)
		(width 0.13335)
		(layer "In2.Cu")
		(net "DRIVE_A_13_INS")
	)
	(segment
		(start 199.354186 -255.7018)
		(end 199.353932 -255.701546)
		(width 0.13335)
		(layer "In2.Cu")
		(net "DRIVE_A_13_INS")
	)
	(segment
		(start 199.353932 -255.701546)
		(end 170.98137 -255.701546)
		(width 0.13335)
		(layer "In2.Cu")
		(net "DRIVE_A_13_INS")
	)
	(segment
		(start 170.98137 -255.701546)
		(end 170.727624 -255.4478)
		(width 0.13335)
		(layer "In2.Cu")
		(net "DRIVE_A_13_INS")
	)
	(segment
		(start 231.15016 -255.679702)
		(end 231.128062 -255.7018)
		(width 0.13335)
		(layer "In2.Cu")
		(net "DRIVE_A_13_INS")
	)
	(segment
		(start 65.6844 -191.659256)
		(end 65.455546 -191.88811)
		(width 0.12065)
		(layer "In4.Cu")
		(net "DRIVE_A_13_INS")
	)
	(segment
		(start 66.3194 -253.066296)
		(end 66.3194 -255.4478)
		(width 0.12065)
		(layer "In4.Cu")
		(net "DRIVE_A_13_INS")
	)
	(segment
		(start 65.6844 -181.737)
		(end 65.6844 -191.659256)
		(width 0.12065)
		(layer "In4.Cu")
		(net "DRIVE_A_13_INS")
	)
	(segment
		(start 65.455546 -252.202442)
		(end 66.3194 -253.066296)
		(width 0.12065)
		(layer "In4.Cu")
		(net "DRIVE_A_13_INS")
	)
	(segment
		(start 65.455546 -191.88811)
		(end 65.455546 -252.202442)
		(width 0.12065)
		(layer "In4.Cu")
		(net "DRIVE_A_13_INS")
	)
	(segment
		(start 47.266352 -130.271012)
		(end 47.267368 -130.269996)
		(width 0.17145)
		(layer "F.Cu")
		(net "DRIVE_A_13_FLT_LED")
	)
	(segment
		(start 47.266352 -132.187696)
		(end 47.266352 -133.978142)
		(width 0.17145)
		(layer "F.Cu")
		(net "DRIVE_A_13_FLT_LED")
	)
	(segment
		(start 264.48512 -280.9494)
		(end 264.48512 -282.9306)
		(width 0.17145)
		(layer "F.Cu")
		(net "DRIVE_A_13_FLT_LED")
	)
	(segment
		(start 47.266352 -132.187696)
		(end 47.266352 -130.271012)
		(width 0.17145)
		(layer "F.Cu")
		(net "DRIVE_A_13_FLT_LED")
	)
	(segment
		(start 47.267368 -130.269996)
		(end 47.267368 -128.74117)
		(width 0.17145)
		(layer "F.Cu")
		(net "DRIVE_A_13_FLT_LED")
	)
	(via
		(at 264.48512 -282.9306)
		(size 0.5588)
		(drill 0.3048)
		(layers "F.Cu" "B.Cu")
		(net "DRIVE_A_13_FLT_LED")
	)
	(via
		(at 47.266352 -133.978142)
		(size 0.5588)
		(drill 0.3048)
		(layers "F.Cu" "B.Cu")
		(net "DRIVE_A_13_FLT_LED")
	)
	(via
		(at 47.266352 -132.187696)
		(size 0.6604)
		(drill 0.3302)
		(layers "F.Cu" "B.Cu")
		(net "DRIVE_A_13_FLT_LED")
	)
	(via
		(at 9.359392 -298.0944)
		(size 0.5588)
		(drill 0.3048)
		(layers "F.Cu" "B.Cu")
		(net "DRIVE_A_13_FLT_LED")
	)
	(segment
		(start 262.5344 -288.148014)
		(end 260.079236 -290.603178)
		(width 0.13335)
		(layer "In2.Cu")
		(net "DRIVE_A_13_FLT_LED")
	)
	(segment
		(start 196.082158 -296.468546)
		(end 193.150998 -296.468546)
		(width 0.13335)
		(layer "In2.Cu")
		(net "DRIVE_A_13_FLT_LED")
	)
	(segment
		(start 37.20338 -298.0944)
		(end 9.359392 -298.0944)
		(width 0.13335)
		(layer "In2.Cu")
		(net "DRIVE_A_13_FLT_LED")
	)
	(segment
		(start 38.70198 -296.5958)
		(end 37.20338 -298.0944)
		(width 0.13335)
		(layer "In2.Cu")
		(net "DRIVE_A_13_FLT_LED")
	)
	(segment
		(start 94.8563 -296.5958)
		(end 38.70198 -296.5958)
		(width 0.13335)
		(layer "In2.Cu")
		(net "DRIVE_A_13_FLT_LED")
	)
	(segment
		(start 260.079236 -290.603178)
		(end 250.767088 -290.603178)
		(width 0.13335)
		(layer "In2.Cu")
		(net "DRIVE_A_13_FLT_LED")
	)
	(segment
		(start 152.27046 -298.722796)
		(end 150.945342 -297.397678)
		(width 0.13335)
		(layer "In2.Cu")
		(net "DRIVE_A_13_FLT_LED")
	)
	(segment
		(start 250.767088 -290.603178)
		(end 248.990866 -292.3794)
		(width 0.13335)
		(layer "In2.Cu")
		(net "DRIVE_A_13_FLT_LED")
	)
	(segment
		(start 264.48512 -282.9306)
		(end 262.5344 -284.88132)
		(width 0.13335)
		(layer "In2.Cu")
		(net "DRIVE_A_13_FLT_LED")
	)
	(segment
		(start 150.945342 -297.397678)
		(end 130.244596 -297.397678)
		(width 0.13335)
		(layer "In2.Cu")
		(net "DRIVE_A_13_FLT_LED")
	)
	(segment
		(start 96.2787 -298.0182)
		(end 94.8563 -296.5958)
		(width 0.13335)
		(layer "In2.Cu")
		(net "DRIVE_A_13_FLT_LED")
	)
	(segment
		(start 160.943798 -298.722796)
		(end 152.27046 -298.722796)
		(width 0.13335)
		(layer "In2.Cu")
		(net "DRIVE_A_13_FLT_LED")
	)
	(segment
		(start 262.5344 -284.88132)
		(end 262.5344 -288.148014)
		(width 0.13335)
		(layer "In2.Cu")
		(net "DRIVE_A_13_FLT_LED")
	)
	(segment
		(start 130.244596 -297.397678)
		(end 128.99644 -298.645834)
		(width 0.13335)
		(layer "In2.Cu")
		(net "DRIVE_A_13_FLT_LED")
	)
	(segment
		(start 111.987076 -298.645834)
		(end 110.819946 -297.478704)
		(width 0.13335)
		(layer "In2.Cu")
		(net "DRIVE_A_13_FLT_LED")
	)
	(segment
		(start 161.483802 -299.2628)
		(end 160.943798 -298.722796)
		(width 0.13335)
		(layer "In2.Cu")
		(net "DRIVE_A_13_FLT_LED")
	)
	(segment
		(start 193.150998 -296.468546)
		(end 190.356744 -299.2628)
		(width 0.13335)
		(layer "In2.Cu")
		(net "DRIVE_A_13_FLT_LED")
	)
	(segment
		(start 103.003604 -298.0182)
		(end 96.2787 -298.0182)
		(width 0.13335)
		(layer "In2.Cu")
		(net "DRIVE_A_13_FLT_LED")
	)
	(segment
		(start 198.78167 -293.769034)
		(end 196.082158 -296.468546)
		(width 0.13335)
		(layer "In2.Cu")
		(net "DRIVE_A_13_FLT_LED")
	)
	(segment
		(start 103.5431 -297.478704)
		(end 103.003604 -298.0182)
		(width 0.13335)
		(layer "In2.Cu")
		(net "DRIVE_A_13_FLT_LED")
	)
	(segment
		(start 248.990866 -292.3794)
		(end 244.713252 -292.3794)
		(width 0.13335)
		(layer "In2.Cu")
		(net "DRIVE_A_13_FLT_LED")
	)
	(segment
		(start 190.356744 -299.2628)
		(end 161.483802 -299.2628)
		(width 0.13335)
		(layer "In2.Cu")
		(net "DRIVE_A_13_FLT_LED")
	)
	(segment
		(start 243.323618 -293.769034)
		(end 198.78167 -293.769034)
		(width 0.13335)
		(layer "In2.Cu")
		(net "DRIVE_A_13_FLT_LED")
	)
	(segment
		(start 128.99644 -298.645834)
		(end 111.987076 -298.645834)
		(width 0.13335)
		(layer "In2.Cu")
		(net "DRIVE_A_13_FLT_LED")
	)
	(segment
		(start 244.713252 -292.3794)
		(end 243.323618 -293.769034)
		(width 0.13335)
		(layer "In2.Cu")
		(net "DRIVE_A_13_FLT_LED")
	)
	(segment
		(start 110.819946 -297.478704)
		(end 103.5431 -297.478704)
		(width 0.13335)
		(layer "In2.Cu")
		(net "DRIVE_A_13_FLT_LED")
	)
	(segment
		(start 5.663692 -213.251542)
		(end 5.663692 -136.373108)
		(width 0.12065)
		(layer "In4.Cu")
		(net "DRIVE_A_13_FLT_LED")
	)
	(segment
		(start 9.359392 -298.0944)
		(end 9.03097 -297.765978)
		(width 0.12065)
		(layer "In4.Cu")
		(net "DRIVE_A_13_FLT_LED")
	)
	(segment
		(start 13.932408 -221.520258)
		(end 5.663692 -213.251542)
		(width 0.12065)
		(layer "In4.Cu")
		(net "DRIVE_A_13_FLT_LED")
	)
	(segment
		(start 9.03097 -297.765978)
		(end 9.03097 -289.088068)
		(width 0.12065)
		(layer "In4.Cu")
		(net "DRIVE_A_13_FLT_LED")
	)
	(segment
		(start 8.90397 -288.961068)
		(end 8.90397 -260.825488)
		(width 0.12065)
		(layer "In4.Cu")
		(net "DRIVE_A_13_FLT_LED")
	)
	(segment
		(start 9.03097 -289.088068)
		(end 8.90397 -288.961068)
		(width 0.12065)
		(layer "In4.Cu")
		(net "DRIVE_A_13_FLT_LED")
	)
	(segment
		(start 45.532294 -135.7122)
		(end 47.266352 -133.978142)
		(width 0.12065)
		(layer "In4.Cu")
		(net "DRIVE_A_13_FLT_LED")
	)
	(segment
		(start 8.90397 -260.825488)
		(end 13.932408 -255.79705)
		(width 0.12065)
		(layer "In4.Cu")
		(net "DRIVE_A_13_FLT_LED")
	)
	(segment
		(start 5.663692 -136.373108)
		(end 6.3246 -135.7122)
		(width 0.12065)
		(layer "In4.Cu")
		(net "DRIVE_A_13_FLT_LED")
	)
	(segment
		(start 13.932408 -255.79705)
		(end 13.932408 -221.520258)
		(width 0.12065)
		(layer "In4.Cu")
		(net "DRIVE_A_13_FLT_LED")
	)
	(segment
		(start 6.3246 -135.7122)
		(end 45.532294 -135.7122)
		(width 0.12065)
		(layer "In4.Cu")
		(net "DRIVE_A_13_FLT_LED")
	)
	(segment
		(start 43.652694 -130.269996)
		(end 43.651678 -130.26898)
		(width 0.17145)
		(layer "F.Cu")
		(net "DRIVE_A_13_ACT")
	)
	(segment
		(start 43.652694 -132.18668)
		(end 43.652694 -133.977126)
		(width 0.17145)
		(layer "F.Cu")
		(net "DRIVE_A_13_ACT")
	)
	(segment
		(start 43.651678 -130.26898)
		(end 43.651678 -128.750568)
		(width 0.17145)
		(layer "F.Cu")
		(net "DRIVE_A_13_ACT")
	)
	(segment
		(start 43.652694 -132.18668)
		(end 43.652694 -130.269996)
		(width 0.17145)
		(layer "F.Cu")
		(net "DRIVE_A_13_ACT")
	)
	(via
		(at 43.652694 -133.977126)
		(size 0.5588)
		(drill 0.3048)
		(layers "F.Cu" "B.Cu")
		(net "DRIVE_A_13_ACT")
	)
	(via
		(at 43.652694 -132.18668)
		(size 0.6604)
		(drill 0.3302)
		(layers "F.Cu" "B.Cu")
		(net "DRIVE_A_13_ACT")
	)
	(via
		(at 10.01395 -311.4548)
		(size 0.5588)
		(drill 0.3048)
		(layers "F.Cu" "B.Cu")
		(net "DRIVE_A_13_ACT")
	)
	(segment
		(start 272.7706 -321.1322)
		(end 276.6568 -317.246)
		(width 0.13335)
		(layer "In2.Cu")
		(net "DRIVE_A_13_ACT")
	)
	(segment
		(start 190.122556 -317.281052)
		(end 240.293652 -317.281052)
		(width 0.13335)
		(layer "In2.Cu")
		(net "DRIVE_A_13_ACT")
	)
	(segment
		(start 184.296304 -311.4548)
		(end 190.122556 -317.281052)
		(width 0.13335)
		(layer "In2.Cu")
		(net "DRIVE_A_13_ACT")
	)
	(segment
		(start 276.6568 -317.246)
		(end 280.895806 -317.246)
		(width 0.13335)
		(layer "In2.Cu")
		(net "DRIVE_A_13_ACT")
	)
	(segment
		(start 10.01395 -311.4548)
		(end 184.296304 -311.4548)
		(width 0.13335)
		(layer "In2.Cu")
		(net "DRIVE_A_13_ACT")
	)
	(segment
		(start 240.293652 -317.281052)
		(end 244.1448 -321.1322)
		(width 0.13335)
		(layer "In2.Cu")
		(net "DRIVE_A_13_ACT")
	)
	(segment
		(start 244.1448 -321.1322)
		(end 272.7706 -321.1322)
		(width 0.13335)
		(layer "In2.Cu")
		(net "DRIVE_A_13_ACT")
	)
	(segment
		(start 280.895806 -317.246)
		(end 281.836622 -316.305184)
		(width 0.13335)
		(layer "In2.Cu")
		(net "DRIVE_A_13_ACT")
	)
	(segment
		(start 10.01395 -300.42104)
		(end 10.01395 -311.4548)
		(width 0.12065)
		(layer "In4.Cu")
		(net "DRIVE_A_13_ACT")
	)
	(segment
		(start 43.652694 -133.977126)
		(end 42.524426 -135.105394)
		(width 0.12065)
		(layer "In4.Cu")
		(net "DRIVE_A_13_ACT")
	)
	(segment
		(start 13.373608 -221.751906)
		(end 13.373608 -255.565402)
		(width 0.12065)
		(layer "In4.Cu")
		(net "DRIVE_A_13_ACT")
	)
	(segment
		(start 42.524426 -135.105394)
		(end 5.737606 -135.105394)
		(width 0.12065)
		(layer "In4.Cu")
		(net "DRIVE_A_13_ACT")
	)
	(segment
		(start 5.105146 -213.483444)
		(end 13.373608 -221.751906)
		(width 0.12065)
		(layer "In4.Cu")
		(net "DRIVE_A_13_ACT")
	)
	(segment
		(start 8.47217 -260.46684)
		(end 8.47217 -298.87926)
		(width 0.12065)
		(layer "In4.Cu")
		(net "DRIVE_A_13_ACT")
	)
	(segment
		(start 5.737606 -135.105394)
		(end 5.105146 -135.737854)
		(width 0.12065)
		(layer "In4.Cu")
		(net "DRIVE_A_13_ACT")
	)
	(segment
		(start 8.47217 -298.87926)
		(end 10.01395 -300.42104)
		(width 0.12065)
		(layer "In4.Cu")
		(net "DRIVE_A_13_ACT")
	)
	(segment
		(start 13.373608 -255.565402)
		(end 8.47217 -260.46684)
		(width 0.12065)
		(layer "In4.Cu")
		(net "DRIVE_A_13_ACT")
	)
	(segment
		(start 5.105146 -135.737854)
		(end 5.105146 -213.483444)
		(width 0.12065)
		(layer "In4.Cu")
		(net "DRIVE_A_13_ACT")
	)
	(segment
		(start 229.108 -237.0328)
		(end 229.108 -236.0676)
		(width 0.17145)
		(layer "F.Cu")
		(net "DRIVE_A_12_PWR")
	)
	(segment
		(start 230.29164 -234.88396)
		(end 230.29164 -234.1626)
		(width 0.17145)
		(layer "F.Cu")
		(net "DRIVE_A_12_PWR")
	)
	(segment
		(start 21.627084 -159.926274)
		(end 21.627084 -158.874714)
		(width 0.17145)
		(layer "F.Cu")
		(net "DRIVE_A_12_PWR")
	)
	(segment
		(start 229.108 -236.0676)
		(end 230.29164 -234.88396)
		(width 0.17145)
		(layer "F.Cu")
		(net "DRIVE_A_12_PWR")
	)
	(segment
		(start 229.455472 -237.380272)
		(end 229.108 -237.0328)
		(width 0.17145)
		(layer "F.Cu")
		(net "DRIVE_A_12_PWR")
	)
	(segment
		(start 21.627084 -158.874714)
		(end 21.627084 -157.895798)
		(width 0.17145)
		(layer "F.Cu")
		(net "DRIVE_A_12_PWR")
	)
	(via
		(at 21.627084 -157.895798)
		(size 0.5588)
		(drill 0.3048)
		(layers "F.Cu" "B.Cu")
		(net "DRIVE_A_12_PWR")
	)
	(via
		(at 50.7746 -234.4928)
		(size 0.5588)
		(drill 0.3048)
		(layers "F.Cu" "B.Cu")
		(net "DRIVE_A_12_PWR")
	)
	(via
		(at 229.455472 -237.380272)
		(size 0.5588)
		(drill 0.3048)
		(layers "F.Cu" "B.Cu")
		(net "DRIVE_A_12_PWR")
	)
	(via
		(at 21.627084 -158.874714)
		(size 0.6604)
		(drill 0.3302)
		(layers "F.Cu" "B.Cu")
		(net "DRIVE_A_12_PWR")
	)
	(segment
		(start 195.92925 -240.154206)
		(end 192.776856 -243.3066)
		(width 0.13335)
		(layer "In2.Cu")
		(net "DRIVE_A_12_PWR")
	)
	(segment
		(start 179.256944 -243.3066)
		(end 170.341544 -234.3912)
		(width 0.13335)
		(layer "In2.Cu")
		(net "DRIVE_A_12_PWR")
	)
	(segment
		(start 170.341544 -234.3912)
		(end 50.8762 -234.3912)
		(width 0.13335)
		(layer "In2.Cu")
		(net "DRIVE_A_12_PWR")
	)
	(segment
		(start 223.745552 -238.4298)
		(end 222.021146 -240.154206)
		(width 0.13335)
		(layer "In2.Cu")
		(net "DRIVE_A_12_PWR")
	)
	(segment
		(start 229.455472 -237.380272)
		(end 228.966268 -237.380272)
		(width 0.13335)
		(layer "In2.Cu")
		(net "DRIVE_A_12_PWR")
	)
	(segment
		(start 192.776856 -243.3066)
		(end 179.256944 -243.3066)
		(width 0.13335)
		(layer "In2.Cu")
		(net "DRIVE_A_12_PWR")
	)
	(segment
		(start 227.91674 -238.4298)
		(end 223.745552 -238.4298)
		(width 0.13335)
		(layer "In2.Cu")
		(net "DRIVE_A_12_PWR")
	)
	(segment
		(start 228.966268 -237.380272)
		(end 227.91674 -238.4298)
		(width 0.13335)
		(layer "In2.Cu")
		(net "DRIVE_A_12_PWR")
	)
	(segment
		(start 222.021146 -240.154206)
		(end 195.92925 -240.154206)
		(width 0.13335)
		(layer "In2.Cu")
		(net "DRIVE_A_12_PWR")
	)
	(segment
		(start 50.8762 -234.3912)
		(end 50.7746 -234.4928)
		(width 0.13335)
		(layer "In2.Cu")
		(net "DRIVE_A_12_PWR")
	)
	(segment
		(start 50.1904 -207.4672)
		(end 50.1904 -233.9086)
		(width 0.12065)
		(layer "In4.Cu")
		(net "DRIVE_A_12_PWR")
	)
	(segment
		(start 25.2984 -181.177946)
		(end 28.863798 -184.743344)
		(width 0.12065)
		(layer "In4.Cu")
		(net "DRIVE_A_12_PWR")
	)
	(segment
		(start 25.2984 -163.3474)
		(end 25.2984 -181.177946)
		(width 0.12065)
		(layer "In4.Cu")
		(net "DRIVE_A_12_PWR")
	)
	(segment
		(start 21.627084 -157.895798)
		(end 21.627084 -159.676084)
		(width 0.12065)
		(layer "In4.Cu")
		(net "DRIVE_A_12_PWR")
	)
	(segment
		(start 50.1904 -233.9086)
		(end 50.7746 -234.4928)
		(width 0.12065)
		(layer "In4.Cu")
		(net "DRIVE_A_12_PWR")
	)
	(segment
		(start 21.627084 -159.676084)
		(end 25.2984 -163.3474)
		(width 0.12065)
		(layer "In4.Cu")
		(net "DRIVE_A_12_PWR")
	)
	(segment
		(start 28.863798 -186.140598)
		(end 50.1904 -207.4672)
		(width 0.12065)
		(layer "In4.Cu")
		(net "DRIVE_A_12_PWR")
	)
	(segment
		(start 28.863798 -184.743344)
		(end 28.863798 -186.140598)
		(width 0.12065)
		(layer "In4.Cu")
		(net "DRIVE_A_12_PWR")
	)
	(segment
		(start 230.92664 -252.58776)
		(end 230.92664 -251.8156)
		(width 0.17145)
		(layer "F.Cu")
		(net "DRIVE_A_12_INS")
	)
	(segment
		(start 229.881176 -253.633224)
		(end 230.92664 -252.58776)
		(width 0.17145)
		(layer "F.Cu")
		(net "DRIVE_A_12_INS")
	)
	(segment
		(start 36.940998 -182.274718)
		(end 36.940998 -181.2798)
		(width 0.17145)
		(layer "F.Cu")
		(net "DRIVE_A_12_INS")
	)
	(segment
		(start 229.768654 -253.633224)
		(end 229.881176 -253.633224)
		(width 0.17145)
		(layer "F.Cu")
		(net "DRIVE_A_12_INS")
	)
	(segment
		(start 36.940998 -181.2798)
		(end 36.940998 -180.064918)
		(width 0.17145)
		(layer "F.Cu")
		(net "DRIVE_A_12_INS")
	)
	(via
		(at 36.940998 -182.274718)
		(size 0.5588)
		(drill 0.3048)
		(layers "F.Cu" "B.Cu")
		(net "DRIVE_A_12_INS")
	)
	(via
		(at 36.940998 -181.2798)
		(size 0.6604)
		(drill 0.3302)
		(layers "F.Cu" "B.Cu")
		(net "DRIVE_A_12_INS")
	)
	(via
		(at 229.768654 -253.633224)
		(size 0.5588)
		(drill 0.3048)
		(layers "F.Cu" "B.Cu")
		(net "DRIVE_A_12_INS")
	)
	(via
		(at 62.1284 -255.1684)
		(size 0.5588)
		(drill 0.3048)
		(layers "F.Cu" "B.Cu")
		(net "DRIVE_A_12_INS")
	)
	(segment
		(start 145.132552 -254.8128)
		(end 170.873928 -254.8128)
		(width 0.13335)
		(layer "In2.Cu")
		(net "DRIVE_A_12_INS")
	)
	(segment
		(start 112.671352 -254.6096)
		(end 112.849152 -254.7874)
		(width 0.13335)
		(layer "In2.Cu")
		(net "DRIVE_A_12_INS")
	)
	(segment
		(start 199.58558 -255.142746)
		(end 199.585834 -255.143)
		(width 0.13335)
		(layer "In2.Cu")
		(net "DRIVE_A_12_INS")
	)
	(segment
		(start 112.849152 -254.7874)
		(end 145.107152 -254.7874)
		(width 0.13335)
		(layer "In2.Cu")
		(net "DRIVE_A_12_INS")
	)
	(segment
		(start 62.1284 -255.1684)
		(end 62.6872 -254.6096)
		(width 0.13335)
		(layer "In2.Cu")
		(net "DRIVE_A_12_INS")
	)
	(segment
		(start 145.107152 -254.7874)
		(end 145.132552 -254.8128)
		(width 0.13335)
		(layer "In2.Cu")
		(net "DRIVE_A_12_INS")
	)
	(segment
		(start 229.652576 -253.633224)
		(end 229.768654 -253.633224)
		(width 0.13335)
		(layer "In2.Cu")
		(net "DRIVE_A_12_INS")
	)
	(segment
		(start 170.873928 -254.8128)
		(end 171.203874 -255.142746)
		(width 0.13335)
		(layer "In2.Cu")
		(net "DRIVE_A_12_INS")
	)
	(segment
		(start 171.203874 -255.142746)
		(end 199.58558 -255.142746)
		(width 0.13335)
		(layer "In2.Cu")
		(net "DRIVE_A_12_INS")
	)
	(segment
		(start 199.585834 -255.143)
		(end 228.1428 -255.143)
		(width 0.13335)
		(layer "In2.Cu")
		(net "DRIVE_A_12_INS")
	)
	(segment
		(start 228.1428 -255.143)
		(end 229.652576 -253.633224)
		(width 0.13335)
		(layer "In2.Cu")
		(net "DRIVE_A_12_INS")
	)
	(segment
		(start 62.6872 -254.6096)
		(end 112.671352 -254.6096)
		(width 0.13335)
		(layer "In2.Cu")
		(net "DRIVE_A_12_INS")
	)
	(segment
		(start 51.308 -232.616248)
		(end 63.017146 -244.325394)
		(width 0.12065)
		(layer "In4.Cu")
		(net "DRIVE_A_12_INS")
	)
	(segment
		(start 36.940998 -182.274718)
		(end 36.940998 -192.490598)
		(width 0.12065)
		(layer "In4.Cu")
		(net "DRIVE_A_12_INS")
	)
	(segment
		(start 51.308 -206.8576)
		(end 51.308 -232.616248)
		(width 0.12065)
		(layer "In4.Cu")
		(net "DRIVE_A_12_INS")
	)
	(segment
		(start 63.017146 -254.279654)
		(end 62.1284 -255.1684)
		(width 0.12065)
		(layer "In4.Cu")
		(net "DRIVE_A_12_INS")
	)
	(segment
		(start 36.940998 -192.490598)
		(end 51.308 -206.8576)
		(width 0.12065)
		(layer "In4.Cu")
		(net "DRIVE_A_12_INS")
	)
	(segment
		(start 63.017146 -244.325394)
		(end 63.017146 -254.279654)
		(width 0.12065)
		(layer "In4.Cu")
		(net "DRIVE_A_12_INS")
	)
	(segment
		(start 265.13536 -284.21076)
		(end 265.13536 -280.9494)
		(width 0.17145)
		(layer "F.Cu")
		(net "DRIVE_A_12_FLT_LED")
	)
	(segment
		(start 15.705836 -132.198364)
		(end 15.705836 -130.30708)
		(width 0.17145)
		(layer "F.Cu")
		(net "DRIVE_A_12_FLT_LED")
	)
	(segment
		(start 15.705836 -130.23088)
		(end 15.705836 -130.30708)
		(width 0.17145)
		(layer "F.Cu")
		(net "DRIVE_A_12_FLT_LED")
	)
	(segment
		(start 15.706852 -128.751838)
		(end 15.706852 -130.229864)
		(width 0.17145)
		(layer "F.Cu")
		(net "DRIVE_A_12_FLT_LED")
	)
	(segment
		(start 15.705836 -132.198364)
		(end 15.705836 -133.98881)
		(width 0.17145)
		(layer "F.Cu")
		(net "DRIVE_A_12_FLT_LED")
	)
	(segment
		(start 15.706852 -130.229864)
		(end 15.705836 -130.23088)
		(width 0.17145)
		(layer "F.Cu")
		(net "DRIVE_A_12_FLT_LED")
	)
	(segment
		(start 264.48512 -284.861)
		(end 265.13536 -284.21076)
		(width 0.17145)
		(layer "F.Cu")
		(net "DRIVE_A_12_FLT_LED")
	)
	(via
		(at 264.48512 -284.861)
		(size 0.5588)
		(drill 0.3048)
		(layers "F.Cu" "B.Cu")
		(net "DRIVE_A_12_FLT_LED")
	)
	(via
		(at 15.705836 -133.98881)
		(size 0.5588)
		(drill 0.3048)
		(layers "F.Cu" "B.Cu")
		(net "DRIVE_A_12_FLT_LED")
	)
	(via
		(at 5.006848 -298.7929)
		(size 0.5588)
		(drill 0.3048)
		(layers "F.Cu" "B.Cu")
		(net "DRIVE_A_12_FLT_LED")
	)
	(via
		(at 15.705836 -132.198364)
		(size 0.6604)
		(drill 0.3302)
		(layers "F.Cu" "B.Cu")
		(net "DRIVE_A_12_FLT_LED")
	)
	(segment
		(start 190.80734 -300.3931)
		(end 189.549024 -301.651416)
		(width 0.13335)
		(layer "In2.Cu")
		(net "DRIVE_A_12_FLT_LED")
	)
	(segment
		(start 120.779032 -299.76445)
		(end 117.548152 -299.76445)
		(width 0.13335)
		(layer "In2.Cu")
		(net "DRIVE_A_12_FLT_LED")
	)
	(segment
		(start 264.48512 -284.861)
		(end 264.48512 -287.77819)
		(width 0.13335)
		(layer "In2.Cu")
		(net "DRIVE_A_12_FLT_LED")
	)
	(segment
		(start 117.08384 -299.76445)
		(end 100.88245 -299.76445)
		(width 0.13335)
		(layer "In2.Cu")
		(net "DRIVE_A_12_FLT_LED")
	)
	(segment
		(start 163.689792 -300.583346)
		(end 152.550114 -300.583346)
		(width 0.13335)
		(layer "In2.Cu")
		(net "DRIVE_A_12_FLT_LED")
	)
	(segment
		(start 164.757862 -301.651416)
		(end 163.689792 -300.583346)
		(width 0.13335)
		(layer "In2.Cu")
		(net "DRIVE_A_12_FLT_LED")
	)
	(segment
		(start 260.542532 -291.720778)
		(end 251.230384 -291.720778)
		(width 0.13335)
		(layer "In2.Cu")
		(net "DRIVE_A_12_FLT_LED")
	)
	(segment
		(start 264.48512 -287.77819)
		(end 260.542532 -291.720778)
		(width 0.13335)
		(layer "In2.Cu")
		(net "DRIVE_A_12_FLT_LED")
	)
	(segment
		(start 117.547644 -299.763942)
		(end 117.084348 -299.763942)
		(width 0.13335)
		(layer "In2.Cu")
		(net "DRIVE_A_12_FLT_LED")
	)
	(segment
		(start 117.548152 -299.76445)
		(end 117.547644 -299.763942)
		(width 0.13335)
		(layer "In2.Cu")
		(net "DRIVE_A_12_FLT_LED")
	)
	(segment
		(start 123.3932 -300.609)
		(end 121.623582 -300.609)
		(width 0.13335)
		(layer "In2.Cu")
		(net "DRIVE_A_12_FLT_LED")
	)
	(segment
		(start 196.545454 -297.586146)
		(end 193.639694 -297.586146)
		(width 0.13335)
		(layer "In2.Cu")
		(net "DRIVE_A_12_FLT_LED")
	)
	(segment
		(start 8.6995 -298.7929)
		(end 5.006848 -298.7929)
		(width 0.13335)
		(layer "In2.Cu")
		(net "DRIVE_A_12_FLT_LED")
	)
	(segment
		(start 243.786914 -294.886634)
		(end 199.244966 -294.886634)
		(width 0.13335)
		(layer "In2.Cu")
		(net "DRIVE_A_12_FLT_LED")
	)
	(segment
		(start 189.549024 -301.651416)
		(end 164.757862 -301.651416)
		(width 0.13335)
		(layer "In2.Cu")
		(net "DRIVE_A_12_FLT_LED")
	)
	(segment
		(start 100.88245 -299.76445)
		(end 100.33 -299.212)
		(width 0.13335)
		(layer "In2.Cu")
		(net "DRIVE_A_12_FLT_LED")
	)
	(segment
		(start 199.244966 -294.886634)
		(end 196.545454 -297.586146)
		(width 0.13335)
		(layer "In2.Cu")
		(net "DRIVE_A_12_FLT_LED")
	)
	(segment
		(start 117.084348 -299.763942)
		(end 117.08384 -299.76445)
		(width 0.13335)
		(layer "In2.Cu")
		(net "DRIVE_A_12_FLT_LED")
	)
	(segment
		(start 124.238258 -299.763942)
		(end 123.3932 -300.609)
		(width 0.13335)
		(layer "In2.Cu")
		(net "DRIVE_A_12_FLT_LED")
	)
	(segment
		(start 245.176548 -293.497)
		(end 243.786914 -294.886634)
		(width 0.13335)
		(layer "In2.Cu")
		(net "DRIVE_A_12_FLT_LED")
	)
	(segment
		(start 251.230384 -291.720778)
		(end 249.454162 -293.497)
		(width 0.13335)
		(layer "In2.Cu")
		(net "DRIVE_A_12_FLT_LED")
	)
	(segment
		(start 121.623582 -300.609)
		(end 120.779032 -299.76445)
		(width 0.13335)
		(layer "In2.Cu")
		(net "DRIVE_A_12_FLT_LED")
	)
	(segment
		(start 9.1186 -299.212)
		(end 8.6995 -298.7929)
		(width 0.13335)
		(layer "In2.Cu")
		(net "DRIVE_A_12_FLT_LED")
	)
	(segment
		(start 100.33 -299.212)
		(end 9.1186 -299.212)
		(width 0.13335)
		(layer "In2.Cu")
		(net "DRIVE_A_12_FLT_LED")
	)
	(segment
		(start 193.639694 -297.586146)
		(end 190.83274 -300.3931)
		(width 0.13335)
		(layer "In2.Cu")
		(net "DRIVE_A_12_FLT_LED")
	)
	(segment
		(start 152.550114 -300.583346)
		(end 151.73071 -299.763942)
		(width 0.13335)
		(layer "In2.Cu")
		(net "DRIVE_A_12_FLT_LED")
	)
	(segment
		(start 190.83274 -300.3931)
		(end 190.80734 -300.3931)
		(width 0.13335)
		(layer "In2.Cu")
		(net "DRIVE_A_12_FLT_LED")
	)
	(segment
		(start 249.454162 -293.497)
		(end 245.176548 -293.497)
		(width 0.13335)
		(layer "In2.Cu")
		(net "DRIVE_A_12_FLT_LED")
	)
	(segment
		(start 151.73071 -299.763942)
		(end 124.238258 -299.763942)
		(width 0.13335)
		(layer "In2.Cu")
		(net "DRIVE_A_12_FLT_LED")
	)
	(segment
		(start 12.814808 -255.333754)
		(end 12.814808 -221.983554)
		(width 0.12065)
		(layer "In4.Cu")
		(net "DRIVE_A_12_FLT_LED")
	)
	(segment
		(start 5.505958 -134.546594)
		(end 15.148052 -134.546594)
		(width 0.12065)
		(layer "In4.Cu")
		(net "DRIVE_A_12_FLT_LED")
	)
	(segment
		(start 15.148052 -134.546594)
		(end 15.705836 -133.98881)
		(width 0.12065)
		(layer "In4.Cu")
		(net "DRIVE_A_12_FLT_LED")
	)
	(segment
		(start 4.546346 -135.506206)
		(end 5.505958 -134.546594)
		(width 0.12065)
		(layer "In4.Cu")
		(net "DRIVE_A_12_FLT_LED")
	)
	(segment
		(start 5.006848 -263.141714)
		(end 12.814808 -255.333754)
		(width 0.12065)
		(layer "In4.Cu")
		(net "DRIVE_A_12_FLT_LED")
	)
	(segment
		(start 4.546346 -213.715092)
		(end 4.546346 -135.506206)
		(width 0.12065)
		(layer "In4.Cu")
		(net "DRIVE_A_12_FLT_LED")
	)
	(segment
		(start 12.814808 -221.983554)
		(end 4.546346 -213.715092)
		(width 0.12065)
		(layer "In4.Cu")
		(net "DRIVE_A_12_FLT_LED")
	)
	(segment
		(start 5.006848 -298.7929)
		(end 5.006848 -263.141714)
		(width 0.12065)
		(layer "In4.Cu")
		(net "DRIVE_A_12_FLT_LED")
	)
	(segment
		(start 12.092178 -132.197348)
		(end 12.092178 -130.306064)
		(width 0.17145)
		(layer "F.Cu")
		(net "DRIVE_A_12_ACT")
	)
	(segment
		(start 12.091162 -130.305048)
		(end 12.092178 -130.306064)
		(width 0.17145)
		(layer "F.Cu")
		(net "DRIVE_A_12_ACT")
	)
	(segment
		(start 12.091162 -128.761236)
		(end 12.091162 -130.305048)
		(width 0.17145)
		(layer "F.Cu")
		(net "DRIVE_A_12_ACT")
	)
	(segment
		(start 12.092178 -132.197348)
		(end 12.092178 -133.987794)
		(width 0.17145)
		(layer "F.Cu")
		(net "DRIVE_A_12_ACT")
	)
	(via
		(at 12.092178 -133.987794)
		(size 0.5588)
		(drill 0.3048)
		(layers "F.Cu" "B.Cu")
		(net "DRIVE_A_12_ACT")
	)
	(via
		(at 12.092178 -132.197348)
		(size 0.6604)
		(drill 0.3302)
		(layers "F.Cu" "B.Cu")
		(net "DRIVE_A_12_ACT")
	)
	(via
		(at 8.001 -310.896)
		(size 0.5588)
		(drill 0.3048)
		(layers "F.Cu" "B.Cu")
		(net "DRIVE_A_12_ACT")
	)
	(segment
		(start 190.354204 -316.722252)
		(end 184.527952 -310.896)
		(width 0.13335)
		(layer "In2.Cu")
		(net "DRIVE_A_12_ACT")
	)
	(segment
		(start 184.527952 -310.896)
		(end 8.001 -310.896)
		(width 0.13335)
		(layer "In2.Cu")
		(net "DRIVE_A_12_ACT")
	)
	(segment
		(start 240.665 -316.722252)
		(end 190.354204 -316.722252)
		(width 0.13335)
		(layer "In2.Cu")
		(net "DRIVE_A_12_ACT")
	)
	(segment
		(start 283.23667 -316.305184)
		(end 282.297886 -315.3664)
		(width 0.13335)
		(layer "In2.Cu")
		(net "DRIVE_A_12_ACT")
	)
	(segment
		(start 282.297886 -315.3664)
		(end 277.01367 -315.3664)
		(width 0.13335)
		(layer "In2.Cu")
		(net "DRIVE_A_12_ACT")
	)
	(segment
		(start 277.01367 -315.3664)
		(end 271.80667 -320.5734)
		(width 0.13335)
		(layer "In2.Cu")
		(net "DRIVE_A_12_ACT")
	)
	(segment
		(start 244.516148 -320.5734)
		(end 240.665 -316.722252)
		(width 0.13335)
		(layer "In2.Cu")
		(net "DRIVE_A_12_ACT")
	)
	(segment
		(start 271.80667 -320.5734)
		(end 244.516148 -320.5734)
		(width 0.13335)
		(layer "In2.Cu")
		(net "DRIVE_A_12_ACT")
	)
	(segment
		(start 4.448048 -307.313584)
		(end 8.015732 -310.881268)
		(width 0.12065)
		(layer "In4.Cu")
		(net "DRIVE_A_12_ACT")
	)
	(segment
		(start 12.092178 -133.987794)
		(end 5.102606 -133.987794)
		(width 0.12065)
		(layer "In4.Cu")
		(net "DRIVE_A_12_ACT")
	)
	(segment
		(start 12.256008 -255.102106)
		(end 4.448048 -262.910066)
		(width 0.12065)
		(layer "In4.Cu")
		(net "DRIVE_A_12_ACT")
	)
	(segment
		(start 3.274314 -213.298786)
		(end 12.256008 -222.28048)
		(width 0.12065)
		(layer "In4.Cu")
		(net "DRIVE_A_12_ACT")
	)
	(segment
		(start 12.256008 -222.28048)
		(end 12.256008 -255.102106)
		(width 0.12065)
		(layer "In4.Cu")
		(net "DRIVE_A_12_ACT")
	)
	(segment
		(start 5.102606 -133.987794)
		(end 3.274314 -135.816086)
		(width 0.12065)
		(layer "In4.Cu")
		(net "DRIVE_A_12_ACT")
	)
	(segment
		(start 8.015732 -310.881268)
		(end 8.001 -310.896)
		(width 0.12065)
		(layer "In4.Cu")
		(net "DRIVE_A_12_ACT")
	)
	(segment
		(start 3.274314 -135.816086)
		(end 3.274314 -213.298786)
		(width 0.12065)
		(layer "In4.Cu")
		(net "DRIVE_A_12_ACT")
	)
	(segment
		(start 4.448048 -262.910066)
		(end 4.448048 -307.313584)
		(width 0.12065)
		(layer "In4.Cu")
		(net "DRIVE_A_12_ACT")
	)
	(segment
		(start 229.253034 -230.259636)
		(end 229.5906 -230.597202)
		(width 0.17145)
		(layer "F.Cu")
		(net "DRIVE_A_11_PWR")
	)
	(segment
		(start 229.5906 -231.81564)
		(end 229.6414 -231.86644)
		(width 0.17145)
		(layer "F.Cu")
		(net "DRIVE_A_11_PWR")
	)
	(segment
		(start 229.6414 -231.86644)
		(end 229.6414 -234.1626)
		(width 0.17145)
		(layer "F.Cu")
		(net "DRIVE_A_11_PWR")
	)
	(segment
		(start 475.529148 -268.903704)
		(end 475.529148 -268.078204)
		(width 0.17145)
		(layer "F.Cu")
		(net "DRIVE_A_11_PWR")
	)
	(segment
		(start 229.5906 -230.597202)
		(end 229.5906 -231.81564)
		(width 0.17145)
		(layer "F.Cu")
		(net "DRIVE_A_11_PWR")
	)
	(via
		(at 418.087302 -224.60077)
		(size 0.5588)
		(drill 0.3048)
		(layers "F.Cu" "B.Cu")
		(net "DRIVE_A_11_PWR")
	)
	(via
		(at 229.253034 -230.259636)
		(size 0.5588)
		(drill 0.3048)
		(layers "F.Cu" "B.Cu")
		(net "DRIVE_A_11_PWR")
	)
	(via
		(at 229.6414 -231.86644)
		(size 0.6604)
		(drill 0.3302)
		(layers "F.Cu" "B.Cu")
		(net "DRIVE_A_11_PWR")
	)
	(via
		(at 426.5422 -264.964926)
		(size 0.5588)
		(drill 0.3048)
		(layers "F.Cu" "B.Cu")
		(net "DRIVE_A_11_PWR")
	)
	(via
		(at 475.529148 -268.078204)
		(size 0.5588)
		(drill 0.3048)
		(layers "F.Cu" "B.Cu")
		(net "DRIVE_A_11_PWR")
	)
	(segment
		(start 278.315928 -212.221318)
		(end 317.929006 -212.221318)
		(width 0.13335)
		(layer "In2.Cu")
		(net "DRIVE_A_11_PWR")
	)
	(segment
		(start 426.5422 -264.964926)
		(end 427.438312 -264.068814)
		(width 0.13335)
		(layer "In2.Cu")
		(net "DRIVE_A_11_PWR")
	)
	(segment
		(start 231.813862 -224.522538)
		(end 266.014708 -224.522538)
		(width 0.13335)
		(layer "In2.Cu")
		(net "DRIVE_A_11_PWR")
	)
	(segment
		(start 266.014708 -224.522538)
		(end 278.315928 -212.221318)
		(width 0.13335)
		(layer "In2.Cu")
		(net "DRIVE_A_11_PWR")
	)
	(segment
		(start 317.929006 -212.221318)
		(end 327.398888 -221.6912)
		(width 0.13335)
		(layer "In2.Cu")
		(net "DRIVE_A_11_PWR")
	)
	(segment
		(start 367.1824 -221.6912)
		(end 369.6462 -224.155)
		(width 0.13335)
		(layer "In2.Cu")
		(net "DRIVE_A_11_PWR")
	)
	(segment
		(start 427.438312 -264.068814)
		(end 471.519758 -264.068814)
		(width 0.13335)
		(layer "In2.Cu")
		(net "DRIVE_A_11_PWR")
	)
	(segment
		(start 417.641532 -224.155)
		(end 418.087302 -224.60077)
		(width 0.13335)
		(layer "In2.Cu")
		(net "DRIVE_A_11_PWR")
	)
	(segment
		(start 369.6462 -224.155)
		(end 417.641532 -224.155)
		(width 0.13335)
		(layer "In2.Cu")
		(net "DRIVE_A_11_PWR")
	)
	(segment
		(start 327.398888 -221.6912)
		(end 367.1824 -221.6912)
		(width 0.13335)
		(layer "In2.Cu")
		(net "DRIVE_A_11_PWR")
	)
	(segment
		(start 229.253034 -227.083366)
		(end 231.813862 -224.522538)
		(width 0.13335)
		(layer "In2.Cu")
		(net "DRIVE_A_11_PWR")
	)
	(segment
		(start 471.519758 -264.068814)
		(end 475.529148 -268.078204)
		(width 0.13335)
		(layer "In2.Cu")
		(net "DRIVE_A_11_PWR")
	)
	(segment
		(start 229.253034 -230.259636)
		(end 229.253034 -227.083366)
		(width 0.13335)
		(layer "In2.Cu")
		(net "DRIVE_A_11_PWR")
	)
	(segment
		(start 418.087302 -224.60077)
		(end 423.156126 -229.669594)
		(width 0.12065)
		(layer "In4.Cu")
		(net "DRIVE_A_11_PWR")
	)
	(segment
		(start 423.156126 -229.669594)
		(end 423.156126 -261.578852)
		(width 0.12065)
		(layer "In4.Cu")
		(net "DRIVE_A_11_PWR")
	)
	(segment
		(start 423.156126 -261.578852)
		(end 426.5422 -264.964926)
		(width 0.12065)
		(layer "In4.Cu")
		(net "DRIVE_A_11_PWR")
	)
	(segment
		(start 231.019604 -249.649996)
		(end 230.2764 -250.3932)
		(width 0.17145)
		(layer "F.Cu")
		(net "DRIVE_A_11_INS")
	)
	(segment
		(start 479.382328 -266.766802)
		(end 479.400108 -266.749022)
		(width 0.17145)
		(layer "F.Cu")
		(net "DRIVE_A_11_INS")
	)
	(segment
		(start 231.095804 -249.649996)
		(end 231.019604 -249.649996)
		(width 0.17145)
		(layer "F.Cu")
		(net "DRIVE_A_11_INS")
	)
	(segment
		(start 479.382328 -267.773658)
		(end 479.382328 -266.766802)
		(width 0.17145)
		(layer "F.Cu")
		(net "DRIVE_A_11_INS")
	)
	(segment
		(start 230.2764 -250.3932)
		(end 230.2764 -251.8156)
		(width 0.17145)
		(layer "F.Cu")
		(net "DRIVE_A_11_INS")
	)
	(via
		(at 230.2764 -250.3932)
		(size 0.6604)
		(drill 0.3302)
		(layers "F.Cu" "B.Cu")
		(net "DRIVE_A_11_INS")
	)
	(via
		(at 479.400108 -266.749022)
		(size 0.5588)
		(drill 0.3048)
		(layers "F.Cu" "B.Cu")
		(net "DRIVE_A_11_INS")
	)
	(via
		(at 231.095804 -249.649996)
		(size 0.5588)
		(drill 0.3048)
		(layers "F.Cu" "B.Cu")
		(net "DRIVE_A_11_INS")
	)
	(via
		(at 462.163414 -234.061)
		(size 0.5588)
		(drill 0.3048)
		(layers "F.Cu" "B.Cu")
		(net "DRIVE_A_11_INS")
	)
	(segment
		(start 462.163414 -234.061)
		(end 324.300088 -234.061)
		(width 0.13335)
		(layer "In2.Cu")
		(net "DRIVE_A_11_INS")
	)
	(segment
		(start 273.29511 -233.147108)
		(end 271.213072 -235.229146)
		(width 0.13335)
		(layer "In2.Cu")
		(net "DRIVE_A_11_INS")
	)
	(segment
		(start 234.291378 -249.649996)
		(end 231.095804 -249.649996)
		(width 0.13335)
		(layer "In2.Cu")
		(net "DRIVE_A_11_INS")
	)
	(segment
		(start 269.68704 -235.229146)
		(end 263.361932 -241.554254)
		(width 0.13335)
		(layer "In2.Cu")
		(net "DRIVE_A_11_INS")
	)
	(segment
		(start 324.300088 -234.061)
		(end 314.303918 -224.06483)
		(width 0.13335)
		(layer "In2.Cu")
		(net "DRIVE_A_11_INS")
	)
	(segment
		(start 252.361446 -241.554254)
		(end 245.3767 -248.539)
		(width 0.13335)
		(layer "In2.Cu")
		(net "DRIVE_A_11_INS")
	)
	(segment
		(start 263.361932 -241.554254)
		(end 252.361446 -241.554254)
		(width 0.13335)
		(layer "In2.Cu")
		(net "DRIVE_A_11_INS")
	)
	(segment
		(start 314.303918 -224.06483)
		(end 292.831266 -224.06483)
		(width 0.13335)
		(layer "In2.Cu")
		(net "DRIVE_A_11_INS")
	)
	(segment
		(start 235.554774 -248.3866)
		(end 234.291378 -249.649996)
		(width 0.13335)
		(layer "In2.Cu")
		(net "DRIVE_A_11_INS")
	)
	(segment
		(start 240.157 -248.539)
		(end 240.0046 -248.3866)
		(width 0.13335)
		(layer "In2.Cu")
		(net "DRIVE_A_11_INS")
	)
	(segment
		(start 283.748988 -233.147108)
		(end 273.29511 -233.147108)
		(width 0.13335)
		(layer "In2.Cu")
		(net "DRIVE_A_11_INS")
	)
	(segment
		(start 292.831266 -224.06483)
		(end 283.748988 -233.147108)
		(width 0.13335)
		(layer "In2.Cu")
		(net "DRIVE_A_11_INS")
	)
	(segment
		(start 240.0046 -248.3866)
		(end 235.554774 -248.3866)
		(width 0.13335)
		(layer "In2.Cu")
		(net "DRIVE_A_11_INS")
	)
	(segment
		(start 245.3767 -248.539)
		(end 240.157 -248.539)
		(width 0.13335)
		(layer "In2.Cu")
		(net "DRIVE_A_11_INS")
	)
	(segment
		(start 271.213072 -235.229146)
		(end 269.68704 -235.229146)
		(width 0.13335)
		(layer "In2.Cu")
		(net "DRIVE_A_11_INS")
	)
	(segment
		(start 476.9866 -244.22989)
		(end 476.9866 -261.2898)
		(width 0.12065)
		(layer "In4.Cu")
		(net "DRIVE_A_11_INS")
	)
	(segment
		(start 466.81771 -234.061)
		(end 476.9866 -244.22989)
		(width 0.12065)
		(layer "In4.Cu")
		(net "DRIVE_A_11_INS")
	)
	(segment
		(start 476.9866 -261.2898)
		(end 479.400108 -263.703308)
		(width 0.12065)
		(layer "In4.Cu")
		(net "DRIVE_A_11_INS")
	)
	(segment
		(start 462.163414 -234.061)
		(end 466.81771 -234.061)
		(width 0.12065)
		(layer "In4.Cu")
		(net "DRIVE_A_11_INS")
	)
	(segment
		(start 479.400108 -263.703308)
		(end 479.400108 -266.749022)
		(width 0.12065)
		(layer "In4.Cu")
		(net "DRIVE_A_11_INS")
	)
	(segment
		(start 460.08163 -245.269004)
		(end 460.141574 -245.20906)
		(width 0.17145)
		(layer "F.Cu")
		(net "DRIVE_A_11_FLT_LED")
	)
	(segment
		(start 459.823058 -243.74094)
		(end 460.141574 -244.059456)
		(width 0.17145)
		(layer "F.Cu")
		(net "DRIVE_A_11_FLT_LED")
	)
	(segment
		(start 265.7856 -283.24556)
		(end 265.7856 -280.9494)
		(width 0.17145)
		(layer "F.Cu")
		(net "DRIVE_A_11_FLT_LED")
	)
	(segment
		(start 460.141574 -244.059456)
		(end 460.141574 -245.20906)
		(width 0.17145)
		(layer "F.Cu")
		(net "DRIVE_A_11_FLT_LED")
	)
	(segment
		(start 266.43584 -283.8958)
		(end 265.7856 -283.24556)
		(width 0.17145)
		(layer "F.Cu")
		(net "DRIVE_A_11_FLT_LED")
	)
	(segment
		(start 458.743558 -244.31244)
		(end 458.743558 -245.269004)
		(width 0.17145)
		(layer "F.Cu")
		(net "DRIVE_A_11_FLT_LED")
	)
	(segment
		(start 458.743558 -245.269004)
		(end 460.08163 -245.269004)
		(width 0.17145)
		(layer "F.Cu")
		(net "DRIVE_A_11_FLT_LED")
	)
	(via
		(at 266.43584 -283.8958)
		(size 0.5588)
		(drill 0.3048)
		(layers "F.Cu" "B.Cu")
		(net "DRIVE_A_11_FLT_LED")
	)
	(via
		(at 426.723048 -241.910108)
		(size 0.5588)
		(drill 0.3048)
		(layers "F.Cu" "B.Cu")
		(net "DRIVE_A_11_FLT_LED")
	)
	(via
		(at 458.743558 -244.31244)
		(size 0.5588)
		(drill 0.3048)
		(layers "F.Cu" "B.Cu")
		(net "DRIVE_A_11_FLT_LED")
	)
	(via
		(at 460.141574 -245.20906)
		(size 0.6604)
		(drill 0.3302)
		(layers "F.Cu" "B.Cu")
		(net "DRIVE_A_11_FLT_LED")
	)
	(via
		(at 426.742098 -260.091682)
		(size 0.5588)
		(drill 0.3048)
		(layers "F.Cu" "B.Cu")
		(net "DRIVE_A_11_FLT_LED")
	)
	(segment
		(start 426.71238 -260.061964)
		(end 324.769226 -260.061964)
		(width 0.13335)
		(layer "In2.Cu")
		(net "DRIVE_A_11_FLT_LED")
	)
	(segment
		(start 426.723048 -241.910108)
		(end 456.341226 -241.910108)
		(width 0.13335)
		(layer "In2.Cu")
		(net "DRIVE_A_11_FLT_LED")
	)
	(segment
		(start 284.6324 -275.6916)
		(end 280.797 -279.527)
		(width 0.13335)
		(layer "In2.Cu")
		(net "DRIVE_A_11_FLT_LED")
	)
	(segment
		(start 266.43584 -284.19044)
		(end 266.43584 -283.8958)
		(width 0.13335)
		(layer "In2.Cu")
		(net "DRIVE_A_11_FLT_LED")
	)
	(segment
		(start 272.8976 -285.0134)
		(end 267.2588 -285.0134)
		(width 0.13335)
		(layer "In2.Cu")
		(net "DRIVE_A_11_FLT_LED")
	)
	(segment
		(start 278.384 -279.527)
		(end 272.8976 -285.0134)
		(width 0.13335)
		(layer "In2.Cu")
		(net "DRIVE_A_11_FLT_LED")
	)
	(segment
		(start 267.2588 -285.0134)
		(end 266.43584 -284.19044)
		(width 0.13335)
		(layer "In2.Cu")
		(net "DRIVE_A_11_FLT_LED")
	)
	(segment
		(start 426.742098 -260.091682)
		(end 426.71238 -260.061964)
		(width 0.13335)
		(layer "In2.Cu")
		(net "DRIVE_A_11_FLT_LED")
	)
	(segment
		(start 280.797 -279.527)
		(end 278.384 -279.527)
		(width 0.13335)
		(layer "In2.Cu")
		(net "DRIVE_A_11_FLT_LED")
	)
	(segment
		(start 324.769226 -260.061964)
		(end 309.13959 -275.6916)
		(width 0.13335)
		(layer "In2.Cu")
		(net "DRIVE_A_11_FLT_LED")
	)
	(segment
		(start 309.13959 -275.6916)
		(end 284.6324 -275.6916)
		(width 0.13335)
		(layer "In2.Cu")
		(net "DRIVE_A_11_FLT_LED")
	)
	(segment
		(start 456.341226 -241.910108)
		(end 458.743558 -244.31244)
		(width 0.13335)
		(layer "In2.Cu")
		(net "DRIVE_A_11_FLT_LED")
	)
	(segment
		(start 426.723048 -241.910108)
		(end 426.742098 -241.929158)
		(width 0.12065)
		(layer "In4.Cu")
		(net "DRIVE_A_11_FLT_LED")
	)
	(segment
		(start 426.742098 -241.929158)
		(end 426.742098 -260.091682)
		(width 0.12065)
		(layer "In4.Cu")
		(net "DRIVE_A_11_FLT_LED")
	)
	(segment
		(start 456.212194 -243.675154)
		(end 456.212194 -244.67312)
		(width 0.17145)
		(layer "F.Cu")
		(net "DRIVE_A_11_ACT")
	)
	(segment
		(start 455.647552 -246.047006)
		(end 455.675746 -246.0752)
		(width 0.17145)
		(layer "F.Cu")
		(net "DRIVE_A_11_ACT")
	)
	(segment
		(start 456.212194 -244.67312)
		(end 455.870818 -245.014496)
		(width 0.17145)
		(layer "F.Cu")
		(net "DRIVE_A_11_ACT")
	)
	(segment
		(start 456.51801 -246.0752)
		(end 456.555602 -246.037608)
		(width 0.17145)
		(layer "F.Cu")
		(net "DRIVE_A_11_ACT")
	)
	(segment
		(start 455.870818 -245.014496)
		(end 455.647552 -245.237762)
		(width 0.17145)
		(layer "F.Cu")
		(net "DRIVE_A_11_ACT")
	)
	(segment
		(start 455.647552 -245.237762)
		(end 455.647552 -246.047006)
		(width 0.17145)
		(layer "F.Cu")
		(net "DRIVE_A_11_ACT")
	)
	(segment
		(start 455.675746 -246.0752)
		(end 456.51801 -246.0752)
		(width 0.17145)
		(layer "F.Cu")
		(net "DRIVE_A_11_ACT")
	)
	(via
		(at 456.555602 -246.037608)
		(size 0.5588)
		(drill 0.3048)
		(layers "F.Cu" "B.Cu")
		(net "DRIVE_A_11_ACT")
	)
	(via
		(at 455.870818 -245.014496)
		(size 0.6604)
		(drill 0.3302)
		(layers "F.Cu" "B.Cu")
		(net "DRIVE_A_11_ACT")
	)
	(via
		(at 435.622446 -313.436)
		(size 0.5588)
		(drill 0.3048)
		(layers "F.Cu" "B.Cu")
		(net "DRIVE_A_11_ACT")
	)
	(via
		(at 425.972224 -242.477544)
		(size 0.5588)
		(drill 0.3048)
		(layers "F.Cu" "B.Cu")
		(net "DRIVE_A_11_ACT")
	)
	(segment
		(start 325.427848 -313.0804)
		(end 433.197 -313.0804)
		(width 0.13335)
		(layer "In2.Cu")
		(net "DRIVE_A_11_ACT")
	)
	(segment
		(start 283.755592 -319.024)
		(end 319.484248 -319.024)
		(width 0.13335)
		(layer "In2.Cu")
		(net "DRIVE_A_11_ACT")
	)
	(segment
		(start 282.83662 -318.105028)
		(end 283.755592 -319.024)
		(width 0.13335)
		(layer "In2.Cu")
		(net "DRIVE_A_11_ACT")
	)
	(segment
		(start 452.995538 -242.477544)
		(end 456.555602 -246.037608)
		(width 0.13335)
		(layer "In2.Cu")
		(net "DRIVE_A_11_ACT")
	)
	(segment
		(start 319.484248 -319.024)
		(end 325.427848 -313.0804)
		(width 0.13335)
		(layer "In2.Cu")
		(net "DRIVE_A_11_ACT")
	)
	(segment
		(start 433.5526 -313.436)
		(end 435.622446 -313.436)
		(width 0.13335)
		(layer "In2.Cu")
		(net "DRIVE_A_11_ACT")
	)
	(segment
		(start 425.972224 -242.477544)
		(end 452.995538 -242.477544)
		(width 0.13335)
		(layer "In2.Cu")
		(net "DRIVE_A_11_ACT")
	)
	(segment
		(start 433.197 -313.0804)
		(end 433.5526 -313.436)
		(width 0.13335)
		(layer "In2.Cu")
		(net "DRIVE_A_11_ACT")
	)
	(segment
		(start 425.97197 -242.477798)
		(end 425.972224 -242.477544)
		(width 0.12065)
		(layer "In4.Cu")
		(net "DRIVE_A_11_ACT")
	)
	(segment
		(start 435.622446 -270.497046)
		(end 425.97197 -260.84657)
		(width 0.12065)
		(layer "In4.Cu")
		(net "DRIVE_A_11_ACT")
	)
	(segment
		(start 425.97197 -260.84657)
		(end 425.97197 -242.477798)
		(width 0.12065)
		(layer "In4.Cu")
		(net "DRIVE_A_11_ACT")
	)
	(segment
		(start 435.622446 -313.436)
		(end 435.622446 -270.497046)
		(width 0.12065)
		(layer "In4.Cu")
		(net "DRIVE_A_11_ACT")
	)
	(segment
		(start 461.0735 -272.090642)
		(end 460.2607 -272.090642)
		(width 0.17145)
		(layer "F.Cu")
		(net "DRIVE_A_10_PWR")
	)
	(segment
		(start 228.99116 -234.1626)
		(end 228.99116 -232.7148)
		(width 0.17145)
		(layer "F.Cu")
		(net "DRIVE_A_10_PWR")
	)
	(segment
		(start 228.99116 -231.304592)
		(end 228.99116 -232.7148)
		(width 0.17145)
		(layer "F.Cu")
		(net "DRIVE_A_10_PWR")
	)
	(segment
		(start 228.75621 -231.069642)
		(end 228.99116 -231.304592)
		(width 0.17145)
		(layer "F.Cu")
		(net "DRIVE_A_10_PWR")
	)
	(via
		(at 417.409376 -225.41357)
		(size 0.5588)
		(drill 0.3048)
		(layers "F.Cu" "B.Cu")
		(net "DRIVE_A_10_PWR")
	)
	(via
		(at 460.2607 -272.090642)
		(size 0.5588)
		(drill 0.3048)
		(layers "F.Cu" "B.Cu")
		(net "DRIVE_A_10_PWR")
	)
	(via
		(at 228.75621 -231.069642)
		(size 0.5588)
		(drill 0.3048)
		(layers "F.Cu" "B.Cu")
		(net "DRIVE_A_10_PWR")
	)
	(via
		(at 428.0154 -267.716)
		(size 0.5588)
		(drill 0.3048)
		(layers "F.Cu" "B.Cu")
		(net "DRIVE_A_10_PWR")
	)
	(via
		(at 228.99116 -232.7148)
		(size 0.6604)
		(drill 0.3302)
		(layers "F.Cu" "B.Cu")
		(net "DRIVE_A_10_PWR")
	)
	(segment
		(start 460.2607 -272.090642)
		(end 459.9686 -271.798542)
		(width 0.13335)
		(layer "In2.Cu")
		(net "DRIVE_A_10_PWR")
	)
	(segment
		(start 229.2096 -231.069642)
		(end 228.75621 -231.069642)
		(width 0.13335)
		(layer "In2.Cu")
		(net "DRIVE_A_10_PWR")
	)
	(segment
		(start 317.697358 -212.780118)
		(end 278.547576 -212.780118)
		(width 0.13335)
		(layer "In2.Cu")
		(net "DRIVE_A_10_PWR")
	)
	(segment
		(start 459.9686 -269.7988)
		(end 457.491338 -267.321538)
		(width 0.13335)
		(layer "In2.Cu")
		(net "DRIVE_A_10_PWR")
	)
	(segment
		(start 416.582606 -224.5868)
		(end 368.9604 -224.5868)
		(width 0.13335)
		(layer "In2.Cu")
		(net "DRIVE_A_10_PWR")
	)
	(segment
		(start 428.409862 -267.321538)
		(end 428.0154 -267.716)
		(width 0.13335)
		(layer "In2.Cu")
		(net "DRIVE_A_10_PWR")
	)
	(segment
		(start 266.246356 -225.081338)
		(end 232.120948 -225.081338)
		(width 0.13335)
		(layer "In2.Cu")
		(net "DRIVE_A_10_PWR")
	)
	(segment
		(start 327.42124 -222.504)
		(end 317.697358 -212.780118)
		(width 0.13335)
		(layer "In2.Cu")
		(net "DRIVE_A_10_PWR")
	)
	(segment
		(start 232.120948 -225.081338)
		(end 229.827836 -227.37445)
		(width 0.13335)
		(layer "In2.Cu")
		(net "DRIVE_A_10_PWR")
	)
	(segment
		(start 229.827836 -230.451406)
		(end 229.2096 -231.069642)
		(width 0.13335)
		(layer "In2.Cu")
		(net "DRIVE_A_10_PWR")
	)
	(segment
		(start 457.491338 -267.321538)
		(end 428.409862 -267.321538)
		(width 0.13335)
		(layer "In2.Cu")
		(net "DRIVE_A_10_PWR")
	)
	(segment
		(start 368.9604 -224.5868)
		(end 366.8776 -222.504)
		(width 0.13335)
		(layer "In2.Cu")
		(net "DRIVE_A_10_PWR")
	)
	(segment
		(start 366.8776 -222.504)
		(end 327.42124 -222.504)
		(width 0.13335)
		(layer "In2.Cu")
		(net "DRIVE_A_10_PWR")
	)
	(segment
		(start 278.547576 -212.780118)
		(end 266.246356 -225.081338)
		(width 0.13335)
		(layer "In2.Cu")
		(net "DRIVE_A_10_PWR")
	)
	(segment
		(start 459.9686 -271.798542)
		(end 459.9686 -269.7988)
		(width 0.13335)
		(layer "In2.Cu")
		(net "DRIVE_A_10_PWR")
	)
	(segment
		(start 417.409376 -225.41357)
		(end 416.582606 -224.5868)
		(width 0.13335)
		(layer "In2.Cu")
		(net "DRIVE_A_10_PWR")
	)
	(segment
		(start 229.827836 -227.37445)
		(end 229.827836 -230.451406)
		(width 0.13335)
		(layer "In2.Cu")
		(net "DRIVE_A_10_PWR")
	)
	(segment
		(start 417.409376 -225.41357)
		(end 422.4782 -230.482394)
		(width 0.12065)
		(layer "In4.Cu")
		(net "DRIVE_A_10_PWR")
	)
	(segment
		(start 422.4782 -230.482394)
		(end 422.4782 -262.1788)
		(width 0.12065)
		(layer "In4.Cu")
		(net "DRIVE_A_10_PWR")
	)
	(segment
		(start 422.4782 -262.1788)
		(end 428.0154 -267.716)
		(width 0.12065)
		(layer "In4.Cu")
		(net "DRIVE_A_10_PWR")
	)
	(segment
		(start 443.6618 -295.0972)
		(end 443.6618 -296.9768)
		(width 0.17145)
		(layer "F.Cu")
		(net "DRIVE_A_10_INS")
	)
	(segment
		(start 229.359714 -249.48642)
		(end 229.62616 -249.752866)
		(width 0.17145)
		(layer "F.Cu")
		(net "DRIVE_A_10_INS")
	)
	(segment
		(start 229.62616 -249.752866)
		(end 229.62616 -251.8156)
		(width 0.17145)
		(layer "F.Cu")
		(net "DRIVE_A_10_INS")
	)
	(segment
		(start 444.8556 -298.1706)
		(end 443.6618 -296.9768)
		(width 0.17145)
		(layer "F.Cu")
		(net "DRIVE_A_10_INS")
	)
	(via
		(at 443.6618 -296.9768)
		(size 0.6604)
		(drill 0.3302)
		(layers "F.Cu" "B.Cu")
		(net "DRIVE_A_10_INS")
	)
	(via
		(at 229.359714 -249.48642)
		(size 0.5588)
		(drill 0.3048)
		(layers "F.Cu" "B.Cu")
		(net "DRIVE_A_10_INS")
	)
	(via
		(at 444.8556 -298.1706)
		(size 0.5588)
		(drill 0.3048)
		(layers "F.Cu" "B.Cu")
		(net "DRIVE_A_10_INS")
	)
	(via
		(at 429.7934 -234.5944)
		(size 0.5588)
		(drill 0.3048)
		(layers "F.Cu" "B.Cu")
		(net "DRIVE_A_10_INS")
	)
	(segment
		(start 244.479064 -249.564144)
		(end 237.29823 -249.564144)
		(width 0.13335)
		(layer "In2.Cu")
		(net "DRIVE_A_10_INS")
	)
	(segment
		(start 269.918688 -235.787946)
		(end 263.59358 -242.113054)
		(width 0.13335)
		(layer "In2.Cu")
		(net "DRIVE_A_10_INS")
	)
	(segment
		(start 293.07409 -224.62363)
		(end 283.826458 -233.871262)
		(width 0.13335)
		(layer "In2.Cu")
		(net "DRIVE_A_10_INS")
	)
	(segment
		(start 245.457472 -249.248676)
		(end 244.794532 -249.248676)
		(width 0.13335)
		(layer "In2.Cu")
		(net "DRIVE_A_10_INS")
	)
	(segment
		(start 323.96684 -234.5944)
		(end 313.99607 -224.62363)
		(width 0.13335)
		(layer "In2.Cu")
		(net "DRIVE_A_10_INS")
	)
	(segment
		(start 263.59358 -242.113054)
		(end 252.593094 -242.113054)
		(width 0.13335)
		(layer "In2.Cu")
		(net "DRIVE_A_10_INS")
	)
	(segment
		(start 244.794532 -249.248676)
		(end 244.479064 -249.564144)
		(width 0.13335)
		(layer "In2.Cu")
		(net "DRIVE_A_10_INS")
	)
	(segment
		(start 236.398816 -250.463558)
		(end 230.336852 -250.463558)
		(width 0.13335)
		(layer "In2.Cu")
		(net "DRIVE_A_10_INS")
	)
	(segment
		(start 283.826458 -233.871262)
		(end 273.361404 -233.871262)
		(width 0.13335)
		(layer "In2.Cu")
		(net "DRIVE_A_10_INS")
	)
	(segment
		(start 237.29823 -249.564144)
		(end 236.398816 -250.463558)
		(width 0.13335)
		(layer "In2.Cu")
		(net "DRIVE_A_10_INS")
	)
	(segment
		(start 271.44472 -235.787946)
		(end 269.918688 -235.787946)
		(width 0.13335)
		(layer "In2.Cu")
		(net "DRIVE_A_10_INS")
	)
	(segment
		(start 252.593094 -242.113054)
		(end 245.457472 -249.248676)
		(width 0.13335)
		(layer "In2.Cu")
		(net "DRIVE_A_10_INS")
	)
	(segment
		(start 230.336852 -250.463558)
		(end 229.359714 -249.48642)
		(width 0.13335)
		(layer "In2.Cu")
		(net "DRIVE_A_10_INS")
	)
	(segment
		(start 429.7934 -234.5944)
		(end 323.96684 -234.5944)
		(width 0.13335)
		(layer "In2.Cu")
		(net "DRIVE_A_10_INS")
	)
	(segment
		(start 313.99607 -224.62363)
		(end 293.07409 -224.62363)
		(width 0.13335)
		(layer "In2.Cu")
		(net "DRIVE_A_10_INS")
	)
	(segment
		(start 273.361404 -233.871262)
		(end 271.44472 -235.787946)
		(width 0.13335)
		(layer "In2.Cu")
		(net "DRIVE_A_10_INS")
	)
	(segment
		(start 427.348904 -241.142266)
		(end 427.348904 -258.807966)
		(width 0.12065)
		(layer "In4.Cu")
		(net "DRIVE_A_10_INS")
	)
	(segment
		(start 439.516266 -270.975328)
		(end 439.516266 -280.947114)
		(width 0.12065)
		(layer "In4.Cu")
		(net "DRIVE_A_10_INS")
	)
	(segment
		(start 444.8556 -286.286448)
		(end 444.8556 -298.1706)
		(width 0.12065)
		(layer "In4.Cu")
		(net "DRIVE_A_10_INS")
	)
	(segment
		(start 427.348904 -258.807966)
		(end 439.516266 -270.975328)
		(width 0.12065)
		(layer "In4.Cu")
		(net "DRIVE_A_10_INS")
	)
	(segment
		(start 429.7934 -234.5944)
		(end 429.7934 -238.69777)
		(width 0.12065)
		(layer "In4.Cu")
		(net "DRIVE_A_10_INS")
	)
	(segment
		(start 429.7934 -238.69777)
		(end 427.348904 -241.142266)
		(width 0.12065)
		(layer "In4.Cu")
		(net "DRIVE_A_10_INS")
	)
	(segment
		(start 439.516266 -280.947114)
		(end 444.8556 -286.286448)
		(width 0.12065)
		(layer "In4.Cu")
		(net "DRIVE_A_10_INS")
	)
	(segment
		(start 449.247768 -246.10695)
		(end 448.933824 -246.420894)
		(width 0.17145)
		(layer "F.Cu")
		(net "DRIVE_A_10_FLT_LED")
	)
	(segment
		(start 266.43584 -280.9494)
		(end 266.43584 -282.9306)
		(width 0.17145)
		(layer "F.Cu")
		(net "DRIVE_A_10_FLT_LED")
	)
	(segment
		(start 447.899536 -246.174006)
		(end 448.146424 -246.420894)
		(width 0.17145)
		(layer "F.Cu")
		(net "DRIVE_A_10_FLT_LED")
	)
	(segment
		(start 447.899536 -244.85346)
		(end 447.899536 -245.302024)
		(width 0.17145)
		(layer "F.Cu")
		(net "DRIVE_A_10_FLT_LED")
	)
	(segment
		(start 448.98056 -243.772436)
		(end 447.899536 -244.85346)
		(width 0.17145)
		(layer "F.Cu")
		(net "DRIVE_A_10_FLT_LED")
	)
	(segment
		(start 447.899536 -245.302024)
		(end 447.899536 -246.174006)
		(width 0.17145)
		(layer "F.Cu")
		(net "DRIVE_A_10_FLT_LED")
	)
	(segment
		(start 448.933824 -246.420894)
		(end 448.146424 -246.420894)
		(width 0.17145)
		(layer "F.Cu")
		(net "DRIVE_A_10_FLT_LED")
	)
	(segment
		(start 449.247768 -245.382542)
		(end 449.247768 -246.10695)
		(width 0.17145)
		(layer "F.Cu")
		(net "DRIVE_A_10_FLT_LED")
	)
	(via
		(at 428.001938 -257.801364)
		(size 0.5588)
		(drill 0.3048)
		(layers "F.Cu" "B.Cu")
		(net "DRIVE_A_10_FLT_LED")
	)
	(via
		(at 448.146424 -246.420894)
		(size 0.6604)
		(drill 0.3302)
		(layers "F.Cu" "B.Cu")
		(net "DRIVE_A_10_FLT_LED")
	)
	(via
		(at 449.247768 -245.382542)
		(size 0.5588)
		(drill 0.3048)
		(layers "F.Cu" "B.Cu")
		(net "DRIVE_A_10_FLT_LED")
	)
	(via
		(at 266.43584 -282.9306)
		(size 0.5588)
		(drill 0.3048)
		(layers "F.Cu" "B.Cu")
		(net "DRIVE_A_10_FLT_LED")
	)
	(segment
		(start 449.247768 -245.382542)
		(end 447.232786 -243.36756)
		(width 0.17145)
		(layer "B.Cu")
		(net "DRIVE_A_10_FLT_LED")
	)
	(segment
		(start 440.224672 -243.36756)
		(end 439.396632 -244.1956)
		(width 0.17145)
		(layer "B.Cu")
		(net "DRIVE_A_10_FLT_LED")
	)
	(segment
		(start 439.396632 -244.1956)
		(end 430.4792 -244.1956)
		(width 0.17145)
		(layer "B.Cu")
		(net "DRIVE_A_10_FLT_LED")
	)
	(segment
		(start 447.232786 -243.36756)
		(end 440.224672 -243.36756)
		(width 0.17145)
		(layer "B.Cu")
		(net "DRIVE_A_10_FLT_LED")
	)
	(segment
		(start 430.4792 -244.1956)
		(end 428.001938 -246.672862)
		(width 0.17145)
		(layer "B.Cu")
		(net "DRIVE_A_10_FLT_LED")
	)
	(segment
		(start 428.001938 -246.672862)
		(end 428.001938 -257.801364)
		(width 0.17145)
		(layer "B.Cu")
		(net "DRIVE_A_10_FLT_LED")
	)
	(segment
		(start 279.744932 -278.924004)
		(end 283.536136 -275.1328)
		(width 0.13335)
		(layer "In2.Cu")
		(net "DRIVE_A_10_FLT_LED")
	)
	(segment
		(start 308.907942 -275.1328)
		(end 324.537578 -259.503164)
		(width 0.13335)
		(layer "In2.Cu")
		(net "DRIVE_A_10_FLT_LED")
	)
	(segment
		(start 267.17752 -283.89072)
		(end 267.17752 -284.14472)
		(width 0.13335)
		(layer "In2.Cu")
		(net "DRIVE_A_10_FLT_LED")
	)
	(segment
		(start 266.43584 -283.14904)
		(end 267.17752 -283.89072)
		(width 0.13335)
		(layer "In2.Cu")
		(net "DRIVE_A_10_FLT_LED")
	)
	(segment
		(start 277.970996 -278.924004)
		(end 279.744932 -278.924004)
		(width 0.13335)
		(layer "In2.Cu")
		(net "DRIVE_A_10_FLT_LED")
	)
	(segment
		(start 267.17752 -284.14472)
		(end 267.4874 -284.4546)
		(width 0.13335)
		(layer "In2.Cu")
		(net "DRIVE_A_10_FLT_LED")
	)
	(segment
		(start 283.536136 -275.1328)
		(end 308.907942 -275.1328)
		(width 0.13335)
		(layer "In2.Cu")
		(net "DRIVE_A_10_FLT_LED")
	)
	(segment
		(start 272.4404 -284.4546)
		(end 277.970996 -278.924004)
		(width 0.13335)
		(layer "In2.Cu")
		(net "DRIVE_A_10_FLT_LED")
	)
	(segment
		(start 324.537578 -259.503164)
		(end 426.300138 -259.503164)
		(width 0.13335)
		(layer "In2.Cu")
		(net "DRIVE_A_10_FLT_LED")
	)
	(segment
		(start 267.4874 -284.4546)
		(end 272.4404 -284.4546)
		(width 0.13335)
		(layer "In2.Cu")
		(net "DRIVE_A_10_FLT_LED")
	)
	(segment
		(start 426.300138 -259.503164)
		(end 428.001938 -257.801364)
		(width 0.13335)
		(layer "In2.Cu")
		(net "DRIVE_A_10_FLT_LED")
	)
	(segment
		(start 266.43584 -282.9306)
		(end 266.43584 -283.14904)
		(width 0.13335)
		(layer "In2.Cu")
		(net "DRIVE_A_10_FLT_LED")
	)
	(segment
		(start 444.293244 -245.278656)
		(end 444.293244 -244.84457)
		(width 0.17145)
		(layer "F.Cu")
		(net "DRIVE_A_10_ACT")
	)
	(segment
		(start 444.307468 -246.40413)
		(end 444.293244 -246.389906)
		(width 0.17145)
		(layer "F.Cu")
		(net "DRIVE_A_10_ACT")
	)
	(segment
		(start 444.293244 -244.84457)
		(end 445.375792 -243.762022)
		(width 0.17145)
		(layer "F.Cu")
		(net "DRIVE_A_10_ACT")
	)
	(segment
		(start 444.293244 -246.389906)
		(end 444.293244 -245.278656)
		(width 0.17145)
		(layer "F.Cu")
		(net "DRIVE_A_10_ACT")
	)
	(segment
		(start 445.572388 -246.40413)
		(end 444.307468 -246.40413)
		(width 0.17145)
		(layer "F.Cu")
		(net "DRIVE_A_10_ACT")
	)
	(segment
		(start 445.77254 -246.203978)
		(end 445.572388 -246.40413)
		(width 0.17145)
		(layer "F.Cu")
		(net "DRIVE_A_10_ACT")
	)
	(segment
		(start 445.77254 -245.43639)
		(end 445.77254 -246.203978)
		(width 0.17145)
		(layer "F.Cu")
		(net "DRIVE_A_10_ACT")
	)
	(via
		(at 434.496718 -312.782966)
		(size 0.5588)
		(drill 0.3048)
		(layers "F.Cu" "B.Cu")
		(net "DRIVE_A_10_ACT")
	)
	(via
		(at 445.77254 -245.43639)
		(size 0.5588)
		(drill 0.3048)
		(layers "F.Cu" "B.Cu")
		(net "DRIVE_A_10_ACT")
	)
	(via
		(at 444.307468 -246.40413)
		(size 0.6604)
		(drill 0.3302)
		(layers "F.Cu" "B.Cu")
		(net "DRIVE_A_10_ACT")
	)
	(via
		(at 425.402756 -244.342158)
		(size 0.5588)
		(drill 0.3048)
		(layers "F.Cu" "B.Cu")
		(net "DRIVE_A_10_ACT")
	)
	(segment
		(start 445.77254 -245.43639)
		(end 445.064642 -246.144288)
		(width 0.13335)
		(layer "In2.Cu")
		(net "DRIVE_A_10_ACT")
	)
	(segment
		(start 425.433236 -244.311678)
		(end 425.402756 -244.342158)
		(width 0.13335)
		(layer "In2.Cu")
		(net "DRIVE_A_10_ACT")
	)
	(segment
		(start 323.821552 -312.397648)
		(end 318.9478 -317.2714)
		(width 0.13335)
		(layer "In2.Cu")
		(net "DRIVE_A_10_ACT")
	)
	(segment
		(start 438.472326 -244.311678)
		(end 425.433236 -244.311678)
		(width 0.13335)
		(layer "In2.Cu")
		(net "DRIVE_A_10_ACT")
	)
	(segment
		(start 440.304936 -246.144288)
		(end 438.472326 -244.311678)
		(width 0.13335)
		(layer "In2.Cu")
		(net "DRIVE_A_10_ACT")
	)
	(segment
		(start 434.1114 -312.397648)
		(end 323.821552 -312.397648)
		(width 0.13335)
		(layer "In2.Cu")
		(net "DRIVE_A_10_ACT")
	)
	(segment
		(start 445.064642 -246.144288)
		(end 440.304936 -246.144288)
		(width 0.13335)
		(layer "In2.Cu")
		(net "DRIVE_A_10_ACT")
	)
	(segment
		(start 285.070296 -317.2714)
		(end 284.236668 -318.105028)
		(width 0.13335)
		(layer "In2.Cu")
		(net "DRIVE_A_10_ACT")
	)
	(segment
		(start 434.496718 -312.782966)
		(end 434.1114 -312.397648)
		(width 0.13335)
		(layer "In2.Cu")
		(net "DRIVE_A_10_ACT")
	)
	(segment
		(start 318.9478 -317.2714)
		(end 285.070296 -317.2714)
		(width 0.13335)
		(layer "In2.Cu")
		(net "DRIVE_A_10_ACT")
	)
	(segment
		(start 434.496718 -312.782966)
		(end 434.4924 -312.778648)
		(width 0.12065)
		(layer "In4.Cu")
		(net "DRIVE_A_10_ACT")
	)
	(segment
		(start 434.4924 -312.778648)
		(end 434.4924 -270.3322)
		(width 0.12065)
		(layer "In4.Cu")
		(net "DRIVE_A_10_ACT")
	)
	(segment
		(start 434.4924 -270.3322)
		(end 425.402756 -261.242556)
		(width 0.12065)
		(layer "In4.Cu")
		(net "DRIVE_A_10_ACT")
	)
	(segment
		(start 425.402756 -261.242556)
		(end 425.402756 -244.342158)
		(width 0.12065)
		(layer "In4.Cu")
		(net "DRIVE_A_10_ACT")
	)
	(segment
		(start 231.290876 -242.596924)
		(end 231.290876 -246.705628)
		(width 0.17145)
		(layer "F.Cu")
		(net "DRIVE_A_1_PWR")
	)
	(segment
		(start 231.1146 -248.587768)
		(end 231.240838 -248.714006)
		(width 0.17145)
		(layer "F.Cu")
		(net "DRIVE_A_1_PWR")
	)
	(segment
		(start 231.1146 -246.881904)
		(end 231.1146 -248.587768)
		(width 0.17145)
		(layer "F.Cu")
		(net "DRIVE_A_1_PWR")
	)
	(segment
		(start 54.990746 -274.871942)
		(end 55.816246 -274.871942)
		(width 0.17145)
		(layer "F.Cu")
		(net "DRIVE_A_1_PWR")
	)
	(segment
		(start 232.24236 -239.8014)
		(end 232.24236 -241.64544)
		(width 0.17145)
		(layer "F.Cu")
		(net "DRIVE_A_1_PWR")
	)
	(segment
		(start 231.290876 -246.705628)
		(end 231.1146 -246.881904)
		(width 0.17145)
		(layer "F.Cu")
		(net "DRIVE_A_1_PWR")
	)
	(segment
		(start 232.24236 -241.64544)
		(end 231.290876 -242.596924)
		(width 0.17145)
		(layer "F.Cu")
		(net "DRIVE_A_1_PWR")
	)
	(via
		(at 64.0334 -251.4854)
		(size 0.5588)
		(drill 0.3048)
		(layers "F.Cu" "B.Cu")
		(net "DRIVE_A_1_PWR")
	)
	(via
		(at 231.240838 -248.714006)
		(size 0.5588)
		(drill 0.3048)
		(layers "F.Cu" "B.Cu")
		(net "DRIVE_A_1_PWR")
	)
	(via
		(at 55.816246 -274.871942)
		(size 0.5588)
		(drill 0.3048)
		(layers "F.Cu" "B.Cu")
		(net "DRIVE_A_1_PWR")
	)
	(via
		(at 231.290876 -242.596924)
		(size 0.6604)
		(drill 0.3302)
		(layers "F.Cu" "B.Cu")
		(net "DRIVE_A_1_PWR")
	)
	(segment
		(start 64.880998 -252.332998)
		(end 64.0334 -251.4854)
		(width 0.13335)
		(layer "In2.Cu")
		(net "DRIVE_A_1_PWR")
	)
	(segment
		(start 229.109778 -245.3132)
		(end 226.9236 -245.3132)
		(width 0.13335)
		(layer "In2.Cu")
		(net "DRIVE_A_1_PWR")
	)
	(segment
		(start 219.35186 -251.84608)
		(end 218.899994 -252.297946)
		(width 0.13335)
		(layer "In2.Cu")
		(net "DRIVE_A_1_PWR")
	)
	(segment
		(start 171.914312 -251.8918)
		(end 141.836648 -251.8918)
		(width 0.13335)
		(layer "In2.Cu")
		(net "DRIVE_A_1_PWR")
	)
	(segment
		(start 141.836648 -251.8918)
		(end 141.39545 -252.332998)
		(width 0.13335)
		(layer "In2.Cu")
		(net "DRIVE_A_1_PWR")
	)
	(segment
		(start 231.240838 -248.714006)
		(end 230.659178 -248.132346)
		(width 0.13335)
		(layer "In2.Cu")
		(net "DRIVE_A_1_PWR")
	)
	(segment
		(start 230.659178 -246.8626)
		(end 229.109778 -245.3132)
		(width 0.13335)
		(layer "In2.Cu")
		(net "DRIVE_A_1_PWR")
	)
	(segment
		(start 172.320458 -252.297946)
		(end 171.914312 -251.8918)
		(width 0.13335)
		(layer "In2.Cu")
		(net "DRIVE_A_1_PWR")
	)
	(segment
		(start 141.39545 -252.332998)
		(end 64.880998 -252.332998)
		(width 0.13335)
		(layer "In2.Cu")
		(net "DRIVE_A_1_PWR")
	)
	(segment
		(start 230.659178 -248.132346)
		(end 230.659178 -246.8626)
		(width 0.13335)
		(layer "In2.Cu")
		(net "DRIVE_A_1_PWR")
	)
	(segment
		(start 218.899994 -252.297946)
		(end 172.320458 -252.297946)
		(width 0.13335)
		(layer "In2.Cu")
		(net "DRIVE_A_1_PWR")
	)
	(segment
		(start 226.9236 -245.3132)
		(end 220.39072 -251.84608)
		(width 0.13335)
		(layer "In2.Cu")
		(net "DRIVE_A_1_PWR")
	)
	(segment
		(start 220.39072 -251.84608)
		(end 219.35186 -251.84608)
		(width 0.13335)
		(layer "In2.Cu")
		(net "DRIVE_A_1_PWR")
	)
	(segment
		(start 57.99074 -272.697448)
		(end 55.816246 -274.871942)
		(width 0.12065)
		(layer "In4.Cu")
		(net "DRIVE_A_1_PWR")
	)
	(segment
		(start 62.658752 -272.697448)
		(end 57.99074 -272.697448)
		(width 0.12065)
		(layer "In4.Cu")
		(net "DRIVE_A_1_PWR")
	)
	(segment
		(start 64.0334 -271.3228)
		(end 62.658752 -272.697448)
		(width 0.12065)
		(layer "In4.Cu")
		(net "DRIVE_A_1_PWR")
	)
	(segment
		(start 64.0334 -251.4854)
		(end 64.0334 -271.3228)
		(width 0.12065)
		(layer "In4.Cu")
		(net "DRIVE_A_1_PWR")
	)
	(segment
		(start 232.87736 -259.19684)
		(end 232.87736 -257.4544)
		(width 0.17145)
		(layer "F.Cu")
		(net "DRIVE_A_1_INS")
	)
	(segment
		(start 231.299258 -260.774942)
		(end 232.87736 -259.19684)
		(width 0.17145)
		(layer "F.Cu")
		(net "DRIVE_A_1_INS")
	)
	(segment
		(start 233.623612 -266.008612)
		(end 231.299258 -263.684258)
		(width 0.17145)
		(layer "F.Cu")
		(net "DRIVE_A_1_INS")
	)
	(segment
		(start 68.490846 -296.080942)
		(end 68.490846 -295.064942)
		(width 0.17145)
		(layer "F.Cu")
		(net "DRIVE_A_1_INS")
	)
	(segment
		(start 231.299258 -263.684258)
		(end 231.299258 -260.774942)
		(width 0.17145)
		(layer "F.Cu")
		(net "DRIVE_A_1_INS")
	)
	(segment
		(start 234.3658 -266.7508)
		(end 233.623612 -266.008612)
		(width 0.17145)
		(layer "F.Cu")
		(net "DRIVE_A_1_INS")
	)
	(segment
		(start 233.971846 -269.855696)
		(end 234.3658 -269.461742)
		(width 0.17145)
		(layer "F.Cu")
		(net "DRIVE_A_1_INS")
	)
	(segment
		(start 234.3658 -269.461742)
		(end 234.3658 -266.7508)
		(width 0.17145)
		(layer "F.Cu")
		(net "DRIVE_A_1_INS")
	)
	(via
		(at 68.490846 -296.080942)
		(size 0.5588)
		(drill 0.3048)
		(layers "F.Cu" "B.Cu")
		(net "DRIVE_A_1_INS")
	)
	(via
		(at 233.623612 -266.008612)
		(size 0.6604)
		(drill 0.3302)
		(layers "F.Cu" "B.Cu")
		(net "DRIVE_A_1_INS")
	)
	(via
		(at 68.8594 -270.0528)
		(size 0.5588)
		(drill 0.3048)
		(layers "F.Cu" "B.Cu")
		(net "DRIVE_A_1_INS")
	)
	(via
		(at 233.971846 -269.855696)
		(size 0.5588)
		(drill 0.3048)
		(layers "F.Cu" "B.Cu")
		(net "DRIVE_A_1_INS")
	)
	(segment
		(start 167.381174 -277.869142)
		(end 160.107376 -270.595344)
		(width 0.13335)
		(layer "In2.Cu")
		(net "DRIVE_A_1_INS")
	)
	(segment
		(start 180.351176 -270.917416)
		(end 173.39945 -277.869142)
		(width 0.13335)
		(layer "In2.Cu")
		(net "DRIVE_A_1_INS")
	)
	(segment
		(start 118.657624 -270.595344)
		(end 118.26748 -270.2052)
		(width 0.13335)
		(layer "In2.Cu")
		(net "DRIVE_A_1_INS")
	)
	(segment
		(start 233.971846 -269.855696)
		(end 232.910126 -270.917416)
		(width 0.13335)
		(layer "In2.Cu")
		(net "DRIVE_A_1_INS")
	)
	(segment
		(start 110.0328 -270.2052)
		(end 109.5502 -270.6878)
		(width 0.13335)
		(layer "In2.Cu")
		(net "DRIVE_A_1_INS")
	)
	(segment
		(start 173.39945 -277.869142)
		(end 167.381174 -277.869142)
		(width 0.13335)
		(layer "In2.Cu")
		(net "DRIVE_A_1_INS")
	)
	(segment
		(start 109.5502 -270.6878)
		(end 69.4944 -270.6878)
		(width 0.13335)
		(layer "In2.Cu")
		(net "DRIVE_A_1_INS")
	)
	(segment
		(start 160.107376 -270.595344)
		(end 118.657624 -270.595344)
		(width 0.13335)
		(layer "In2.Cu")
		(net "DRIVE_A_1_INS")
	)
	(segment
		(start 232.910126 -270.917416)
		(end 180.351176 -270.917416)
		(width 0.13335)
		(layer "In2.Cu")
		(net "DRIVE_A_1_INS")
	)
	(segment
		(start 69.4944 -270.6878)
		(end 68.8594 -270.0528)
		(width 0.13335)
		(layer "In2.Cu")
		(net "DRIVE_A_1_INS")
	)
	(segment
		(start 118.26748 -270.2052)
		(end 110.0328 -270.2052)
		(width 0.13335)
		(layer "In2.Cu")
		(net "DRIVE_A_1_INS")
	)
	(segment
		(start 68.875656 -270.069056)
		(end 68.875656 -286.088836)
		(width 0.12065)
		(layer "In4.Cu")
		(net "DRIVE_A_1_INS")
	)
	(segment
		(start 68.8594 -270.0528)
		(end 68.875656 -270.069056)
		(width 0.12065)
		(layer "In4.Cu")
		(net "DRIVE_A_1_INS")
	)
	(segment
		(start 68.875656 -286.088836)
		(end 66.119248 -288.845244)
		(width 0.12065)
		(layer "In4.Cu")
		(net "DRIVE_A_1_INS")
	)
	(segment
		(start 66.119248 -293.709344)
		(end 68.490846 -296.080942)
		(width 0.12065)
		(layer "In4.Cu")
		(net "DRIVE_A_1_INS")
	)
	(segment
		(start 66.119248 -288.845244)
		(end 66.119248 -293.709344)
		(width 0.12065)
		(layer "In4.Cu")
		(net "DRIVE_A_1_INS")
	)
	(segment
		(start 35.654488 -187.953396)
		(end 35.654488 -189.299342)
		(width 0.17145)
		(layer "F.Cu")
		(net "DRIVE_A_1_FLT_LED")
	)
	(segment
		(start 35.654488 -189.299342)
		(end 35.652456 -189.301374)
		(width 0.17145)
		(layer "F.Cu")
		(net "DRIVE_A_1_FLT_LED")
	)
	(segment
		(start 35.652456 -189.301374)
		(end 35.652456 -190.450978)
		(width 0.17145)
		(layer "F.Cu")
		(net "DRIVE_A_1_FLT_LED")
	)
	(segment
		(start 263.18464 -275.3106)
		(end 263.18464 -277.2918)
		(width 0.17145)
		(layer "F.Cu")
		(net "DRIVE_A_1_FLT_LED")
	)
	(segment
		(start 37.07257 -187.962794)
		(end 35.663886 -187.962794)
		(width 0.17145)
		(layer "F.Cu")
		(net "DRIVE_A_1_FLT_LED")
	)
	(segment
		(start 35.663886 -187.962794)
		(end 35.654488 -187.953396)
		(width 0.17145)
		(layer "F.Cu")
		(net "DRIVE_A_1_FLT_LED")
	)
	(via
		(at 263.18464 -277.2918)
		(size 0.5588)
		(drill 0.3048)
		(layers "F.Cu" "B.Cu")
		(net "DRIVE_A_1_FLT_LED")
	)
	(via
		(at 35.652456 -190.450978)
		(size 0.5588)
		(drill 0.3048)
		(layers "F.Cu" "B.Cu")
		(net "DRIVE_A_1_FLT_LED")
	)
	(via
		(at 35.652456 -189.301374)
		(size 0.6604)
		(drill 0.3302)
		(layers "F.Cu" "B.Cu")
		(net "DRIVE_A_1_FLT_LED")
	)
	(via
		(at 49.5554 -278.5872)
		(size 0.5588)
		(drill 0.3048)
		(layers "F.Cu" "B.Cu")
		(net "DRIVE_A_1_FLT_LED")
	)
	(segment
		(start 184.169304 -281.991816)
		(end 176.503584 -281.991816)
		(width 0.13335)
		(layer "In2.Cu")
		(net "DRIVE_A_1_FLT_LED")
	)
	(segment
		(start 113.128552 -282.2194)
		(end 50.519584 -282.2194)
		(width 0.13335)
		(layer "In2.Cu")
		(net "DRIVE_A_1_FLT_LED")
	)
	(segment
		(start 256.964434 -277.2918)
		(end 247.203976 -287.052258)
		(width 0.13335)
		(layer "In2.Cu")
		(net "DRIVE_A_1_FLT_LED")
	)
	(segment
		(start 113.21161 -282.136342)
		(end 113.128552 -282.2194)
		(width 0.13335)
		(layer "In2.Cu")
		(net "DRIVE_A_1_FLT_LED")
	)
	(segment
		(start 154.124152 -285.201868)
		(end 151.058626 -282.136342)
		(width 0.13335)
		(layer "In2.Cu")
		(net "DRIVE_A_1_FLT_LED")
	)
	(segment
		(start 202.642216 -281.712416)
		(end 184.448704 -281.712416)
		(width 0.13335)
		(layer "In2.Cu")
		(net "DRIVE_A_1_FLT_LED")
	)
	(segment
		(start 49.5554 -281.255216)
		(end 49.5554 -278.5872)
		(width 0.13335)
		(layer "In2.Cu")
		(net "DRIVE_A_1_FLT_LED")
	)
	(segment
		(start 263.18464 -277.2918)
		(end 256.964434 -277.2918)
		(width 0.13335)
		(layer "In2.Cu")
		(net "DRIVE_A_1_FLT_LED")
	)
	(segment
		(start 176.503584 -281.991816)
		(end 173.293532 -285.201868)
		(width 0.13335)
		(layer "In2.Cu")
		(net "DRIVE_A_1_FLT_LED")
	)
	(segment
		(start 247.203976 -287.052258)
		(end 207.982058 -287.052258)
		(width 0.13335)
		(layer "In2.Cu")
		(net "DRIVE_A_1_FLT_LED")
	)
	(segment
		(start 207.982058 -287.052258)
		(end 202.642216 -281.712416)
		(width 0.13335)
		(layer "In2.Cu")
		(net "DRIVE_A_1_FLT_LED")
	)
	(segment
		(start 173.293532 -285.201868)
		(end 154.124152 -285.201868)
		(width 0.13335)
		(layer "In2.Cu")
		(net "DRIVE_A_1_FLT_LED")
	)
	(segment
		(start 151.058626 -282.136342)
		(end 113.21161 -282.136342)
		(width 0.13335)
		(layer "In2.Cu")
		(net "DRIVE_A_1_FLT_LED")
	)
	(segment
		(start 50.519584 -282.2194)
		(end 49.5554 -281.255216)
		(width 0.13335)
		(layer "In2.Cu")
		(net "DRIVE_A_1_FLT_LED")
	)
	(segment
		(start 184.448704 -281.712416)
		(end 184.169304 -281.991816)
		(width 0.13335)
		(layer "In2.Cu")
		(net "DRIVE_A_1_FLT_LED")
	)
	(segment
		(start 57.45607 -266.64793)
		(end 57.45607 -272.44167)
		(width 0.12065)
		(layer "In4.Cu")
		(net "DRIVE_A_1_FLT_LED")
	)
	(segment
		(start 57.45607 -272.44167)
		(end 52.841398 -277.056342)
		(width 0.12065)
		(layer "In4.Cu")
		(net "DRIVE_A_1_FLT_LED")
	)
	(segment
		(start 61.493146 -262.610854)
		(end 57.45607 -266.64793)
		(width 0.12065)
		(layer "In4.Cu")
		(net "DRIVE_A_1_FLT_LED")
	)
	(segment
		(start 52.841398 -277.056342)
		(end 50.400458 -277.056342)
		(width 0.12065)
		(layer "In4.Cu")
		(net "DRIVE_A_1_FLT_LED")
	)
	(segment
		(start 50.7492 -207.235552)
		(end 50.7492 -232.847896)
		(width 0.12065)
		(layer "In4.Cu")
		(net "DRIVE_A_1_FLT_LED")
	)
	(segment
		(start 61.493146 -243.591842)
		(end 61.493146 -262.610854)
		(width 0.12065)
		(layer "In4.Cu")
		(net "DRIVE_A_1_FLT_LED")
	)
	(segment
		(start 50.400458 -277.056342)
		(end 49.5554 -277.9014)
		(width 0.12065)
		(layer "In4.Cu")
		(net "DRIVE_A_1_FLT_LED")
	)
	(segment
		(start 35.652456 -190.450978)
		(end 35.652456 -192.138808)
		(width 0.12065)
		(layer "In4.Cu")
		(net "DRIVE_A_1_FLT_LED")
	)
	(segment
		(start 50.7492 -232.847896)
		(end 61.493146 -243.591842)
		(width 0.12065)
		(layer "In4.Cu")
		(net "DRIVE_A_1_FLT_LED")
	)
	(segment
		(start 49.5554 -277.9014)
		(end 49.5554 -278.5872)
		(width 0.12065)
		(layer "In4.Cu")
		(net "DRIVE_A_1_FLT_LED")
	)
	(segment
		(start 35.652456 -192.138808)
		(end 50.7492 -207.235552)
		(width 0.12065)
		(layer "In4.Cu")
		(net "DRIVE_A_1_FLT_LED")
	)
	(segment
		(start 38.164262 -182.585868)
		(end 38.164262 -181.44617)
		(width 0.17145)
		(layer "F.Cu")
		(net "DRIVE_A_1_ACT")
	)
	(segment
		(start 37.071554 -184.173114)
		(end 37.071554 -183.678576)
		(width 0.17145)
		(layer "F.Cu")
		(net "DRIVE_A_1_ACT")
	)
	(segment
		(start 37.071554 -183.678576)
		(end 38.164262 -182.585868)
		(width 0.17145)
		(layer "F.Cu")
		(net "DRIVE_A_1_ACT")
	)
	(segment
		(start 38.164262 -181.44617)
		(end 38.164262 -180.267102)
		(width 0.17145)
		(layer "F.Cu")
		(net "DRIVE_A_1_ACT")
	)
	(via
		(at 38.164262 -182.585868)
		(size 0.6604)
		(drill 0.3302)
		(layers "F.Cu" "B.Cu")
		(net "DRIVE_A_1_ACT")
	)
	(via
		(at 38.164262 -180.267102)
		(size 0.5588)
		(drill 0.3048)
		(layers "F.Cu" "B.Cu")
		(net "DRIVE_A_1_ACT")
	)
	(via
		(at 274.193 -324.1294)
		(size 0.5588)
		(drill 0.3048)
		(layers "F.Cu" "B.Cu")
		(net "DRIVE_A_1_ACT")
	)
	(via
		(at 71.0946 -337.3882)
		(size 0.5588)
		(drill 0.3048)
		(layers "F.Cu" "B.Cu")
		(net "DRIVE_A_1_ACT")
	)
	(segment
		(start 164.055552 -338.626196)
		(end 143.30172 -338.626196)
		(width 0.13335)
		(layer "In2.Cu")
		(net "DRIVE_A_1_ACT")
	)
	(segment
		(start 142.673324 -337.9978)
		(end 71.7042 -337.9978)
		(width 0.13335)
		(layer "In2.Cu")
		(net "DRIVE_A_1_ACT")
	)
	(segment
		(start 71.7042 -337.9978)
		(end 71.0946 -337.3882)
		(width 0.13335)
		(layer "In2.Cu")
		(net "DRIVE_A_1_ACT")
	)
	(segment
		(start 187.936124 -327.4568)
		(end 175.224948 -327.4568)
		(width 0.13335)
		(layer "In2.Cu")
		(net "DRIVE_A_1_ACT")
	)
	(segment
		(start 274.193 -324.1294)
		(end 191.263524 -324.1294)
		(width 0.13335)
		(layer "In2.Cu")
		(net "DRIVE_A_1_ACT")
	)
	(segment
		(start 175.224948 -327.4568)
		(end 164.055552 -338.626196)
		(width 0.13335)
		(layer "In2.Cu")
		(net "DRIVE_A_1_ACT")
	)
	(segment
		(start 143.30172 -338.626196)
		(end 142.673324 -337.9978)
		(width 0.13335)
		(layer "In2.Cu")
		(net "DRIVE_A_1_ACT")
	)
	(segment
		(start 191.263524 -324.1294)
		(end 187.936124 -327.4568)
		(width 0.13335)
		(layer "In2.Cu")
		(net "DRIVE_A_1_ACT")
	)
	(segment
		(start 63.323978 -310.246268)
		(end 71.0946 -318.01689)
		(width 0.12065)
		(layer "In4.Cu")
		(net "DRIVE_A_1_ACT")
	)
	(segment
		(start 64.896746 -252.43409)
		(end 65.659 -253.196344)
		(width 0.12065)
		(layer "In4.Cu")
		(net "DRIVE_A_1_ACT")
	)
	(segment
		(start 71.0946 -318.01689)
		(end 71.0946 -337.3882)
		(width 0.12065)
		(layer "In4.Cu")
		(net "DRIVE_A_1_ACT")
	)
	(segment
		(start 276.3012 -326.2376)
		(end 274.193 -324.1294)
		(width 0.12065)
		(layer "In4.Cu")
		(net "DRIVE_A_1_ACT")
	)
	(segment
		(start 52.705 -207.19034)
		(end 52.705 -233.2228)
		(width 0.12065)
		(layer "In4.Cu")
		(net "DRIVE_A_1_ACT")
	)
	(segment
		(start 38.164262 -192.649602)
		(end 52.705 -207.19034)
		(width 0.12065)
		(layer "In4.Cu")
		(net "DRIVE_A_1_ACT")
	)
	(segment
		(start 63.677546 -244.195346)
		(end 63.677546 -249.097546)
		(width 0.12065)
		(layer "In4.Cu")
		(net "DRIVE_A_1_ACT")
	)
	(segment
		(start 63.677546 -249.097546)
		(end 64.897 -250.317)
		(width 0.12065)
		(layer "In4.Cu")
		(net "DRIVE_A_1_ACT")
	)
	(segment
		(start 52.705 -233.2228)
		(end 63.677546 -244.195346)
		(width 0.12065)
		(layer "In4.Cu")
		(net "DRIVE_A_1_ACT")
	)
	(segment
		(start 64.896746 -251.04471)
		(end 64.896746 -252.43409)
		(width 0.12065)
		(layer "In4.Cu")
		(net "DRIVE_A_1_ACT")
	)
	(segment
		(start 280.968958 -326.2376)
		(end 276.3012 -326.2376)
		(width 0.12065)
		(layer "In4.Cu")
		(net "DRIVE_A_1_ACT")
	)
	(segment
		(start 65.659 -253.196344)
		(end 65.659 -273.304)
		(width 0.12065)
		(layer "In4.Cu")
		(net "DRIVE_A_1_ACT")
	)
	(segment
		(start 38.164262 -180.267102)
		(end 38.164262 -192.649602)
		(width 0.12065)
		(layer "In4.Cu")
		(net "DRIVE_A_1_ACT")
	)
	(segment
		(start 63.323978 -275.639022)
		(end 63.323978 -310.246268)
		(width 0.12065)
		(layer "In4.Cu")
		(net "DRIVE_A_1_ACT")
	)
	(segment
		(start 281.836622 -327.105264)
		(end 280.968958 -326.2376)
		(width 0.12065)
		(layer "In4.Cu")
		(net "DRIVE_A_1_ACT")
	)
	(segment
		(start 64.897 -250.317)
		(end 64.897 -251.044456)
		(width 0.12065)
		(layer "In4.Cu")
		(net "DRIVE_A_1_ACT")
	)
	(segment
		(start 65.659 -273.304)
		(end 63.323978 -275.639022)
		(width 0.12065)
		(layer "In4.Cu")
		(net "DRIVE_A_1_ACT")
	)
	(segment
		(start 64.897 -251.044456)
		(end 64.896746 -251.04471)
		(width 0.12065)
		(layer "In4.Cu")
		(net "DRIVE_A_1_ACT")
	)
	(segment
		(start 231.900476 -242.888516)
		(end 232.8926 -241.896392)
		(width 0.17145)
		(layer "F.Cu")
		(net "DRIVE_A_0_PWR")
	)
	(segment
		(start 231.900476 -245.833392)
		(end 231.900476 -242.888516)
		(width 0.17145)
		(layer "F.Cu")
		(net "DRIVE_A_0_PWR")
	)
	(segment
		(start 23.440898 -274.871942)
		(end 24.266398 -274.871942)
		(width 0.17145)
		(layer "F.Cu")
		(net "DRIVE_A_0_PWR")
	)
	(segment
		(start 232.8926 -241.896392)
		(end 232.8926 -239.8014)
		(width 0.17145)
		(layer "F.Cu")
		(net "DRIVE_A_0_PWR")
	)
	(segment
		(start 231.900476 -245.833392)
		(end 231.900476 -246.867934)
		(width 0.17145)
		(layer "F.Cu")
		(net "DRIVE_A_0_PWR")
	)
	(via
		(at 231.900476 -246.867934)
		(size 0.5588)
		(drill 0.3048)
		(layers "F.Cu" "B.Cu")
		(net "DRIVE_A_0_PWR")
	)
	(via
		(at 24.266398 -274.871942)
		(size 0.5588)
		(drill 0.3048)
		(layers "F.Cu" "B.Cu")
		(net "DRIVE_A_0_PWR")
	)
	(via
		(at 60.706 -250.3424)
		(size 0.5588)
		(drill 0.3048)
		(layers "F.Cu" "B.Cu")
		(net "DRIVE_A_0_PWR")
	)
	(via
		(at 231.900476 -245.833392)
		(size 0.6604)
		(drill 0.3302)
		(layers "F.Cu" "B.Cu")
		(net "DRIVE_A_0_PWR")
	)
	(segment
		(start 231.900476 -246.867934)
		(end 229.710742 -244.6782)
		(width 0.13335)
		(layer "In2.Cu")
		(net "DRIVE_A_0_PWR")
	)
	(segment
		(start 68.449952 -250.6472)
		(end 68.297552 -250.4948)
		(width 0.13335)
		(layer "In2.Cu")
		(net "DRIVE_A_0_PWR")
	)
	(segment
		(start 68.297552 -250.4948)
		(end 60.8584 -250.4948)
		(width 0.13335)
		(layer "In2.Cu")
		(net "DRIVE_A_0_PWR")
	)
	(segment
		(start 72.3138 -249.9106)
		(end 71.5772 -250.6472)
		(width 0.13335)
		(layer "In2.Cu")
		(net "DRIVE_A_0_PWR")
	)
	(segment
		(start 229.710742 -244.6782)
		(end 226.3394 -244.6782)
		(width 0.13335)
		(layer "In2.Cu")
		(net "DRIVE_A_0_PWR")
	)
	(segment
		(start 226.3394 -244.6782)
		(end 221.107 -249.9106)
		(width 0.13335)
		(layer "In2.Cu")
		(net "DRIVE_A_0_PWR")
	)
	(segment
		(start 71.5772 -250.6472)
		(end 68.449952 -250.6472)
		(width 0.13335)
		(layer "In2.Cu")
		(net "DRIVE_A_0_PWR")
	)
	(segment
		(start 221.107 -249.9106)
		(end 72.3138 -249.9106)
		(width 0.13335)
		(layer "In2.Cu")
		(net "DRIVE_A_0_PWR")
	)
	(segment
		(start 60.8584 -250.4948)
		(end 60.706 -250.3424)
		(width 0.13335)
		(layer "In2.Cu")
		(net "DRIVE_A_0_PWR")
	)
	(segment
		(start 60.833 -260.7818)
		(end 60.833 -250.4694)
		(width 0.12065)
		(layer "In4.Cu")
		(net "DRIVE_A_0_PWR")
	)
	(segment
		(start 24.266398 -274.871942)
		(end 24.8158 -274.32254)
		(width 0.12065)
		(layer "In4.Cu")
		(net "DRIVE_A_0_PWR")
	)
	(segment
		(start 24.8158 -265.6332)
		(end 27.1018 -263.3472)
		(width 0.12065)
		(layer "In4.Cu")
		(net "DRIVE_A_0_PWR")
	)
	(segment
		(start 60.833 -250.4694)
		(end 60.706 -250.3424)
		(width 0.12065)
		(layer "In4.Cu")
		(net "DRIVE_A_0_PWR")
	)
	(segment
		(start 27.1018 -263.3472)
		(end 58.2676 -263.3472)
		(width 0.12065)
		(layer "In4.Cu")
		(net "DRIVE_A_0_PWR")
	)
	(segment
		(start 58.2676 -263.3472)
		(end 60.833 -260.7818)
		(width 0.12065)
		(layer "In4.Cu")
		(net "DRIVE_A_0_PWR")
	)
	(segment
		(start 24.8158 -274.32254)
		(end 24.8158 -265.6332)
		(width 0.12065)
		(layer "In4.Cu")
		(net "DRIVE_A_0_PWR")
	)
	(segment
		(start 36.940998 -296.080942)
		(end 36.940998 -295.064942)
		(width 0.17145)
		(layer "F.Cu")
		(net "DRIVE_A_0_INS")
	)
	(segment
		(start 233.5276 -259.278882)
		(end 233.5276 -257.4544)
		(width 0.17145)
		(layer "F.Cu")
		(net "DRIVE_A_0_INS")
	)
	(segment
		(start 234.95 -266.065)
		(end 233.28122 -264.39622)
		(width 0.17145)
		(layer "F.Cu")
		(net "DRIVE_A_0_INS")
	)
	(segment
		(start 231.858058 -262.973058)
		(end 231.858058 -260.948424)
		(width 0.17145)
		(layer "F.Cu")
		(net "DRIVE_A_0_INS")
	)
	(segment
		(start 233.28122 -264.39622)
		(end 231.858058 -262.973058)
		(width 0.17145)
		(layer "F.Cu")
		(net "DRIVE_A_0_INS")
	)
	(segment
		(start 231.858058 -260.948424)
		(end 233.5276 -259.278882)
		(width 0.17145)
		(layer "F.Cu")
		(net "DRIVE_A_0_INS")
	)
	(segment
		(start 234.95 -270.042386)
		(end 234.95 -266.065)
		(width 0.17145)
		(layer "F.Cu")
		(net "DRIVE_A_0_INS")
	)
	(segment
		(start 233.87558 -271.116806)
		(end 234.95 -270.042386)
		(width 0.17145)
		(layer "F.Cu")
		(net "DRIVE_A_0_INS")
	)
	(via
		(at 36.940998 -296.080942)
		(size 0.5588)
		(drill 0.3048)
		(layers "F.Cu" "B.Cu")
		(net "DRIVE_A_0_INS")
	)
	(via
		(at 233.28122 -264.39622)
		(size 0.6604)
		(drill 0.3302)
		(layers "F.Cu" "B.Cu")
		(net "DRIVE_A_0_INS")
	)
	(via
		(at 37.6936 -276.0726)
		(size 0.5588)
		(drill 0.3048)
		(layers "F.Cu" "B.Cu")
		(net "DRIVE_A_0_INS")
	)
	(via
		(at 233.87558 -271.116806)
		(size 0.5588)
		(drill 0.3048)
		(layers "F.Cu" "B.Cu")
		(net "DRIVE_A_0_INS")
	)
	(segment
		(start 46.1264 -276.0726)
		(end 37.6936 -276.0726)
		(width 0.13335)
		(layer "In2.Cu")
		(net "DRIVE_A_0_INS")
	)
	(segment
		(start 69.262752 -271.2466)
		(end 68.729352 -270.7132)
		(width 0.13335)
		(layer "In2.Cu")
		(net "DRIVE_A_0_INS")
	)
	(segment
		(start 47.9044 -274.2946)
		(end 46.1264 -276.0726)
		(width 0.13335)
		(layer "In2.Cu")
		(net "DRIVE_A_0_INS")
	)
	(segment
		(start 79.1972 -271.9324)
		(end 75.6158 -271.9324)
		(width 0.13335)
		(layer "In2.Cu")
		(net "DRIVE_A_0_INS")
	)
	(segment
		(start 110.130844 -270.897604)
		(end 109.781848 -271.2466)
		(width 0.13335)
		(layer "In2.Cu")
		(net "DRIVE_A_0_INS")
	)
	(segment
		(start 118.169436 -270.897604)
		(end 110.130844 -270.897604)
		(width 0.13335)
		(layer "In2.Cu")
		(net "DRIVE_A_0_INS")
	)
	(segment
		(start 68.729352 -270.7132)
		(end 60.3758 -270.7132)
		(width 0.13335)
		(layer "In2.Cu")
		(net "DRIVE_A_0_INS")
	)
	(segment
		(start 60.3758 -270.7132)
		(end 56.7944 -274.2946)
		(width 0.13335)
		(layer "In2.Cu")
		(net "DRIVE_A_0_INS")
	)
	(segment
		(start 159.875982 -271.154398)
		(end 118.42623 -271.154398)
		(width 0.13335)
		(layer "In2.Cu")
		(net "DRIVE_A_0_INS")
	)
	(segment
		(start 233.51617 -271.476216)
		(end 180.582824 -271.476216)
		(width 0.13335)
		(layer "In2.Cu")
		(net "DRIVE_A_0_INS")
	)
	(segment
		(start 173.631098 -278.427942)
		(end 167.149526 -278.427942)
		(width 0.13335)
		(layer "In2.Cu")
		(net "DRIVE_A_0_INS")
	)
	(segment
		(start 79.883 -271.2466)
		(end 79.1972 -271.9324)
		(width 0.13335)
		(layer "In2.Cu")
		(net "DRIVE_A_0_INS")
	)
	(segment
		(start 233.87558 -271.116806)
		(end 233.51617 -271.476216)
		(width 0.13335)
		(layer "In2.Cu")
		(net "DRIVE_A_0_INS")
	)
	(segment
		(start 118.42623 -271.154398)
		(end 118.169436 -270.897604)
		(width 0.13335)
		(layer "In2.Cu")
		(net "DRIVE_A_0_INS")
	)
	(segment
		(start 109.781848 -271.2466)
		(end 79.883 -271.2466)
		(width 0.13335)
		(layer "In2.Cu")
		(net "DRIVE_A_0_INS")
	)
	(segment
		(start 180.582824 -271.476216)
		(end 173.631098 -278.427942)
		(width 0.13335)
		(layer "In2.Cu")
		(net "DRIVE_A_0_INS")
	)
	(segment
		(start 75.6158 -271.9324)
		(end 74.93 -271.2466)
		(width 0.13335)
		(layer "In2.Cu")
		(net "DRIVE_A_0_INS")
	)
	(segment
		(start 74.93 -271.2466)
		(end 69.262752 -271.2466)
		(width 0.13335)
		(layer "In2.Cu")
		(net "DRIVE_A_0_INS")
	)
	(segment
		(start 56.7944 -274.2946)
		(end 47.9044 -274.2946)
		(width 0.13335)
		(layer "In2.Cu")
		(net "DRIVE_A_0_INS")
	)
	(segment
		(start 167.149526 -278.427942)
		(end 159.875982 -271.154398)
		(width 0.13335)
		(layer "In2.Cu")
		(net "DRIVE_A_0_INS")
	)
	(segment
		(start 36.940998 -276.825202)
		(end 37.6936 -276.0726)
		(width 0.12065)
		(layer "In4.Cu")
		(net "DRIVE_A_0_INS")
	)
	(segment
		(start 36.940998 -296.080942)
		(end 36.940998 -276.825202)
		(width 0.12065)
		(layer "In4.Cu")
		(net "DRIVE_A_0_INS")
	)
	(segment
		(start 5.7404 -176.0474)
		(end 5.680964 -176.106836)
		(width 0.17145)
		(layer "F.Cu")
		(net "DRIVE_A_0_FLT_LED")
	)
	(segment
		(start 262.5344 -277.60676)
		(end 262.5344 -275.3106)
		(width 0.17145)
		(layer "F.Cu")
		(net "DRIVE_A_0_FLT_LED")
	)
	(segment
		(start 263.18464 -278.257)
		(end 262.5344 -277.60676)
		(width 0.17145)
		(layer "F.Cu")
		(net "DRIVE_A_0_FLT_LED")
	)
	(segment
		(start 6.98754 -175.980344)
		(end 6.98754 -174.859188)
		(width 0.17145)
		(layer "F.Cu")
		(net "DRIVE_A_0_FLT_LED")
	)
	(segment
		(start 5.680964 -176.106836)
		(end 5.680964 -177.631344)
		(width 0.17145)
		(layer "F.Cu")
		(net "DRIVE_A_0_FLT_LED")
	)
	(segment
		(start 6.995922 -175.988726)
		(end 6.98754 -175.980344)
		(width 0.17145)
		(layer "F.Cu")
		(net "DRIVE_A_0_FLT_LED")
	)
	(segment
		(start 5.799074 -175.988726)
		(end 5.7404 -176.0474)
		(width 0.17145)
		(layer "F.Cu")
		(net "DRIVE_A_0_FLT_LED")
	)
	(segment
		(start 6.995922 -175.988726)
		(end 5.799074 -175.988726)
		(width 0.17145)
		(layer "F.Cu")
		(net "DRIVE_A_0_FLT_LED")
	)
	(segment
		(start 5.680964 -177.631344)
		(end 5.921756 -177.872136)
		(width 0.17145)
		(layer "F.Cu")
		(net "DRIVE_A_0_FLT_LED")
	)
	(via
		(at 5.7404 -176.0474)
		(size 0.6604)
		(drill 0.3302)
		(layers "F.Cu" "B.Cu")
		(net "DRIVE_A_0_FLT_LED")
	)
	(via
		(at 9.98855 -287.3756)
		(size 0.5588)
		(drill 0.3048)
		(layers "F.Cu" "B.Cu")
		(net "DRIVE_A_0_FLT_LED")
	)
	(via
		(at 263.18464 -278.257)
		(size 0.5588)
		(drill 0.3048)
		(layers "F.Cu" "B.Cu")
		(net "DRIVE_A_0_FLT_LED")
	)
	(via
		(at 6.98754 -174.859188)
		(size 0.5588)
		(drill 0.3048)
		(layers "F.Cu" "B.Cu")
		(net "DRIVE_A_0_FLT_LED")
	)
	(segment
		(start 184.400952 -282.550616)
		(end 177.011584 -282.550616)
		(width 0.13335)
		(layer "In2.Cu")
		(net "DRIVE_A_0_FLT_LED")
	)
	(segment
		(start 184.680352 -282.271216)
		(end 184.400952 -282.550616)
		(width 0.13335)
		(layer "In2.Cu")
		(net "DRIVE_A_0_FLT_LED")
	)
	(segment
		(start 177.011584 -282.550616)
		(end 173.19625 -286.36595)
		(width 0.13335)
		(layer "In2.Cu")
		(net "DRIVE_A_0_FLT_LED")
	)
	(segment
		(start 262.93064 -278.511)
		(end 256.535682 -278.511)
		(width 0.13335)
		(layer "In2.Cu")
		(net "DRIVE_A_0_FLT_LED")
	)
	(segment
		(start 67.105022 -283.457142)
		(end 63.186564 -287.3756)
		(width 0.13335)
		(layer "In2.Cu")
		(net "DRIVE_A_0_FLT_LED")
	)
	(segment
		(start 202.410568 -282.271216)
		(end 184.680352 -282.271216)
		(width 0.13335)
		(layer "In2.Cu")
		(net "DRIVE_A_0_FLT_LED")
	)
	(segment
		(start 127.93345 -285.583884)
		(end 125.806708 -283.457142)
		(width 0.13335)
		(layer "In2.Cu")
		(net "DRIVE_A_0_FLT_LED")
	)
	(segment
		(start 137.883392 -285.583884)
		(end 127.93345 -285.583884)
		(width 0.13335)
		(layer "In2.Cu")
		(net "DRIVE_A_0_FLT_LED")
	)
	(segment
		(start 125.806708 -283.457142)
		(end 67.105022 -283.457142)
		(width 0.13335)
		(layer "In2.Cu")
		(net "DRIVE_A_0_FLT_LED")
	)
	(segment
		(start 207.75041 -287.611058)
		(end 202.410568 -282.271216)
		(width 0.13335)
		(layer "In2.Cu")
		(net "DRIVE_A_0_FLT_LED")
	)
	(segment
		(start 138.665458 -286.36595)
		(end 137.883392 -285.583884)
		(width 0.13335)
		(layer "In2.Cu")
		(net "DRIVE_A_0_FLT_LED")
	)
	(segment
		(start 63.186564 -287.3756)
		(end 9.98855 -287.3756)
		(width 0.13335)
		(layer "In2.Cu")
		(net "DRIVE_A_0_FLT_LED")
	)
	(segment
		(start 247.435624 -287.611058)
		(end 207.75041 -287.611058)
		(width 0.13335)
		(layer "In2.Cu")
		(net "DRIVE_A_0_FLT_LED")
	)
	(segment
		(start 263.18464 -278.257)
		(end 262.93064 -278.511)
		(width 0.13335)
		(layer "In2.Cu")
		(net "DRIVE_A_0_FLT_LED")
	)
	(segment
		(start 173.19625 -286.36595)
		(end 138.665458 -286.36595)
		(width 0.13335)
		(layer "In2.Cu")
		(net "DRIVE_A_0_FLT_LED")
	)
	(segment
		(start 256.535682 -278.511)
		(end 247.435624 -287.611058)
		(width 0.13335)
		(layer "In2.Cu")
		(net "DRIVE_A_0_FLT_LED")
	)
	(segment
		(start 9.98855 -287.3756)
		(end 9.98855 -261.321804)
		(width 0.12065)
		(layer "In4.Cu")
		(net "DRIVE_A_0_FLT_LED")
	)
	(segment
		(start 9.98855 -261.321804)
		(end 16.040608 -255.269746)
		(width 0.12065)
		(layer "In4.Cu")
		(net "DRIVE_A_0_FLT_LED")
	)
	(segment
		(start 7.5692 -179.6034)
		(end 6.98754 -179.02174)
		(width 0.12065)
		(layer "In4.Cu")
		(net "DRIVE_A_0_FLT_LED")
	)
	(segment
		(start 7.5692 -213.255352)
		(end 7.5692 -179.6034)
		(width 0.12065)
		(layer "In4.Cu")
		(net "DRIVE_A_0_FLT_LED")
	)
	(segment
		(start 16.040608 -255.269746)
		(end 16.040608 -221.72676)
		(width 0.12065)
		(layer "In4.Cu")
		(net "DRIVE_A_0_FLT_LED")
	)
	(segment
		(start 16.040608 -221.72676)
		(end 7.5692 -213.255352)
		(width 0.12065)
		(layer "In4.Cu")
		(net "DRIVE_A_0_FLT_LED")
	)
	(segment
		(start 6.98754 -179.02174)
		(end 6.98754 -174.859188)
		(width 0.12065)
		(layer "In4.Cu")
		(net "DRIVE_A_0_FLT_LED")
	)
	(segment
		(start 6.894322 -168.420034)
		(end 6.902704 -168.428416)
		(width 0.17145)
		(layer "F.Cu")
		(net "DRIVE_A_0_ACT")
	)
	(segment
		(start 6.902704 -168.428416)
		(end 6.902704 -169.549572)
		(width 0.17145)
		(layer "F.Cu")
		(net "DRIVE_A_0_ACT")
	)
	(segment
		(start 6.902704 -169.549572)
		(end 5.599684 -169.549572)
		(width 0.17145)
		(layer "F.Cu")
		(net "DRIVE_A_0_ACT")
	)
	(segment
		(start 5.599684 -169.549572)
		(end 5.587746 -169.537634)
		(width 0.17145)
		(layer "F.Cu")
		(net "DRIVE_A_0_ACT")
	)
	(segment
		(start 5.587746 -171.19219)
		(end 5.587746 -169.537634)
		(width 0.17145)
		(layer "F.Cu")
		(net "DRIVE_A_0_ACT")
	)
	(segment
		(start 5.828538 -171.432982)
		(end 5.587746 -171.19219)
		(width 0.17145)
		(layer "F.Cu")
		(net "DRIVE_A_0_ACT")
	)
	(via
		(at 11.561572 -339.436964)
		(size 0.5588)
		(drill 0.3048)
		(layers "F.Cu" "B.Cu")
		(net "DRIVE_A_0_ACT")
	)
	(via
		(at 6.894322 -168.420034)
		(size 0.5588)
		(drill 0.3048)
		(layers "F.Cu" "B.Cu")
		(net "DRIVE_A_0_ACT")
	)
	(via
		(at 5.587746 -169.537634)
		(size 0.6604)
		(drill 0.3302)
		(layers "F.Cu" "B.Cu")
		(net "DRIVE_A_0_ACT")
	)
	(segment
		(start 142.517876 -338.6328)
		(end 142.414244 -338.6328)
		(width 0.13335)
		(layer "In2.Cu")
		(net "DRIVE_A_0_ACT")
	)
	(segment
		(start 75.428856 -338.629752)
		(end 75.415902 -338.616798)
		(width 0.13335)
		(layer "In2.Cu")
		(net "DRIVE_A_0_ACT")
	)
	(segment
		(start 75.002898 -338.616798)
		(end 74.986896 -338.6328)
		(width 0.13335)
		(layer "In2.Cu")
		(net "DRIVE_A_0_ACT")
	)
	(segment
		(start 175.431196 -328.041)
		(end 164.305996 -339.1662)
		(width 0.13335)
		(layer "In2.Cu")
		(net "DRIVE_A_0_ACT")
	)
	(segment
		(start 142.411196 -338.629752)
		(end 75.428856 -338.629752)
		(width 0.13335)
		(layer "In2.Cu")
		(net "DRIVE_A_0_ACT")
	)
	(segment
		(start 74.986896 -338.6328)
		(end 72.9742 -338.6328)
		(width 0.13335)
		(layer "In2.Cu")
		(net "DRIVE_A_0_ACT")
	)
	(segment
		(start 142.414244 -338.6328)
		(end 142.411196 -338.629752)
		(width 0.13335)
		(layer "In2.Cu")
		(net "DRIVE_A_0_ACT")
	)
	(segment
		(start 164.305996 -339.1662)
		(end 143.051276 -339.1662)
		(width 0.13335)
		(layer "In2.Cu")
		(net "DRIVE_A_0_ACT")
	)
	(segment
		(start 282.300934 -328.041)
		(end 175.431196 -328.041)
		(width 0.13335)
		(layer "In2.Cu")
		(net "DRIVE_A_0_ACT")
	)
	(segment
		(start 13.094208 -340.9696)
		(end 11.561572 -339.436964)
		(width 0.13335)
		(layer "In2.Cu")
		(net "DRIVE_A_0_ACT")
	)
	(segment
		(start 75.415902 -338.616798)
		(end 75.002898 -338.616798)
		(width 0.13335)
		(layer "In2.Cu")
		(net "DRIVE_A_0_ACT")
	)
	(segment
		(start 72.9742 -338.6328)
		(end 70.6374 -340.9696)
		(width 0.13335)
		(layer "In2.Cu")
		(net "DRIVE_A_0_ACT")
	)
	(segment
		(start 143.051276 -339.1662)
		(end 142.517876 -338.6328)
		(width 0.13335)
		(layer "In2.Cu")
		(net "DRIVE_A_0_ACT")
	)
	(segment
		(start 70.6374 -340.9696)
		(end 13.094208 -340.9696)
		(width 0.13335)
		(layer "In2.Cu")
		(net "DRIVE_A_0_ACT")
	)
	(segment
		(start 283.23667 -327.105264)
		(end 282.300934 -328.041)
		(width 0.13335)
		(layer "In2.Cu")
		(net "DRIVE_A_0_ACT")
	)
	(segment
		(start 6.4008 -179.315872)
		(end 6.4008 -172.6692)
		(width 0.12065)
		(layer "In4.Cu")
		(net "DRIVE_A_0_ACT")
	)
	(segment
		(start 6.894322 -172.175678)
		(end 6.894322 -168.420034)
		(width 0.12065)
		(layer "In4.Cu")
		(net "DRIVE_A_0_ACT")
	)
	(segment
		(start 11.561572 -339.436964)
		(end 10.57275 -338.448142)
		(width 0.12065)
		(layer "In4.Cu")
		(net "DRIVE_A_0_ACT")
	)
	(segment
		(start 10.57275 -338.448142)
		(end 10.57275 -289.8394)
		(width 0.12065)
		(layer "In4.Cu")
		(net "DRIVE_A_0_ACT")
	)
	(segment
		(start 10.57275 -289.8394)
		(end 9.46277 -288.72942)
		(width 0.12065)
		(layer "In4.Cu")
		(net "DRIVE_A_0_ACT")
	)
	(segment
		(start 15.481808 -255.038098)
		(end 15.481808 -221.958408)
		(width 0.12065)
		(layer "In4.Cu")
		(net "DRIVE_A_0_ACT")
	)
	(segment
		(start 9.46277 -261.057136)
		(end 15.481808 -255.038098)
		(width 0.12065)
		(layer "In4.Cu")
		(net "DRIVE_A_0_ACT")
	)
	(segment
		(start 9.46277 -288.72942)
		(end 9.46277 -261.057136)
		(width 0.12065)
		(layer "In4.Cu")
		(net "DRIVE_A_0_ACT")
	)
	(segment
		(start 7.0104 -213.487)
		(end 7.0104 -179.925472)
		(width 0.12065)
		(layer "In4.Cu")
		(net "DRIVE_A_0_ACT")
	)
	(segment
		(start 6.4008 -172.6692)
		(end 6.894322 -172.175678)
		(width 0.12065)
		(layer "In4.Cu")
		(net "DRIVE_A_0_ACT")
	)
	(segment
		(start 15.481808 -221.958408)
		(end 7.0104 -213.487)
		(width 0.12065)
		(layer "In4.Cu")
		(net "DRIVE_A_0_ACT")
	)
	(segment
		(start 7.0104 -179.925472)
		(end 6.4008 -179.315872)
		(width 0.12065)
		(layer "In4.Cu")
		(net "DRIVE_A_0_ACT")
	)
	(segment
		(start 371.378734 -142.0749)
		(end 371.378734 -143.769334)
		(width 0.17145)
		(layer "F.Cu")
		(net "COMP_B_PGOOD")
	)
	(segment
		(start 374.5738 -145.3769)
		(end 373.5578 -145.3769)
		(width 0.17145)
		(layer "F.Cu")
		(net "COMP_B_PGOOD")
	)
	(segment
		(start 373.5578 -145.3769)
		(end 373.3165 -145.6182)
		(width 0.17145)
		(layer "F.Cu")
		(net "COMP_B_PGOOD")
	)
	(segment
		(start 373.3165 -145.6182)
		(end 372.0338 -145.6182)
		(width 0.17145)
		(layer "F.Cu")
		(net "COMP_B_PGOOD")
	)
	(segment
		(start 304.546 -75.1205)
		(end 304.546 -76.830936)
		(width 0.17145)
		(layer "F.Cu")
		(net "COMP_B_PGOOD")
	)
	(segment
		(start 339.303614 -31.33725)
		(end 339.303614 -30.05709)
		(width 0.17145)
		(layer "F.Cu")
		(net "COMP_B_PGOOD")
	)
	(segment
		(start 374.5738 -144.5514)
		(end 374.5738 -145.3769)
		(width 0.17145)
		(layer "F.Cu")
		(net "COMP_B_PGOOD")
	)
	(segment
		(start 371.734334 -144.124934)
		(end 372.0338 -144.4244)
		(width 0.17145)
		(layer "F.Cu")
		(net "COMP_B_PGOOD")
	)
	(segment
		(start 339.974174 -32.00781)
		(end 339.303614 -31.33725)
		(width 0.17145)
		(layer "F.Cu")
		(net "COMP_B_PGOOD")
	)
	(segment
		(start 372.0338 -144.4244)
		(end 372.0338 -145.6182)
		(width 0.17145)
		(layer "F.Cu")
		(net "COMP_B_PGOOD")
	)
	(segment
		(start 339.9536 -32.00781)
		(end 339.974174 -32.00781)
		(width 0.17145)
		(layer "F.Cu")
		(net "COMP_B_PGOOD")
	)
	(segment
		(start 371.378734 -143.769334)
		(end 371.734334 -144.124934)
		(width 0.17145)
		(layer "F.Cu")
		(net "COMP_B_PGOOD")
	)
	(segment
		(start 304.546 -76.830936)
		(end 305.26609 -77.551026)
		(width 0.17145)
		(layer "F.Cu")
		(net "COMP_B_PGOOD")
	)
	(via
		(at 305.26609 -77.551026)
		(size 0.5588)
		(drill 0.3048)
		(layers "F.Cu" "B.Cu")
		(net "COMP_B_PGOOD")
	)
	(via
		(at 371.734334 -144.124934)
		(size 0.6604)
		(drill 0.3302)
		(layers "F.Cu" "B.Cu")
		(net "COMP_B_PGOOD")
	)
	(via
		(at 362.626402 -42.426128)
		(size 0.5588)
		(drill 0.3048)
		(layers "F.Cu" "B.Cu")
		(net "COMP_B_PGOOD")
	)
	(via
		(at 339.9536 -32.00781)
		(size 0.5588)
		(drill 0.3048)
		(layers "F.Cu" "B.Cu")
		(net "COMP_B_PGOOD")
	)
	(via
		(at 374.5738 -144.5514)
		(size 0.5588)
		(drill 0.3048)
		(layers "F.Cu" "B.Cu")
		(net "COMP_B_PGOOD")
	)
	(via
		(at 363.704886 -91.264994)
		(size 0.5588)
		(drill 0.3048)
		(layers "F.Cu" "B.Cu")
		(net "COMP_B_PGOOD")
	)
	(segment
		(start 362.43641 -89.996518)
		(end 363.704886 -91.264994)
		(width 0.13335)
		(layer "In2.Cu")
		(net "COMP_B_PGOOD")
	)
	(segment
		(start 356.96017 -42.834306)
		(end 354.939092 -42.834306)
		(width 0.13335)
		(layer "In2.Cu")
		(net "COMP_B_PGOOD")
	)
	(segment
		(start 354.939092 -42.834306)
		(end 353.054666 -40.94988)
		(width 0.13335)
		(layer "In2.Cu")
		(net "COMP_B_PGOOD")
	)
	(segment
		(start 360.93273 -41.81602)
		(end 357.978456 -41.81602)
		(width 0.13335)
		(layer "In2.Cu")
		(net "COMP_B_PGOOD")
	)
	(segment
		(start 362.626402 -42.426128)
		(end 361.542838 -42.426128)
		(width 0.13335)
		(layer "In2.Cu")
		(net "COMP_B_PGOOD")
	)
	(segment
		(start 353.054666 -40.94988)
		(end 346.268802 -40.94988)
		(width 0.13335)
		(layer "In2.Cu")
		(net "COMP_B_PGOOD")
	)
	(segment
		(start 346.268802 -40.94988)
		(end 341.25789 -35.938968)
		(width 0.13335)
		(layer "In2.Cu")
		(net "COMP_B_PGOOD")
	)
	(segment
		(start 357.410004 -79.283814)
		(end 362.43641 -84.31022)
		(width 0.13335)
		(layer "In2.Cu")
		(net "COMP_B_PGOOD")
	)
	(segment
		(start 362.43641 -84.31022)
		(end 362.43641 -89.996518)
		(width 0.13335)
		(layer "In2.Cu")
		(net "COMP_B_PGOOD")
	)
	(segment
		(start 306.998878 -79.283814)
		(end 357.410004 -79.283814)
		(width 0.13335)
		(layer "In2.Cu")
		(net "COMP_B_PGOOD")
	)
	(segment
		(start 305.26609 -77.551026)
		(end 306.998878 -79.283814)
		(width 0.13335)
		(layer "In2.Cu")
		(net "COMP_B_PGOOD")
	)
	(segment
		(start 339.9536 -32.60852)
		(end 339.9536 -32.00781)
		(width 0.13335)
		(layer "In2.Cu")
		(net "COMP_B_PGOOD")
	)
	(segment
		(start 341.25789 -35.938968)
		(end 341.25789 -33.91281)
		(width 0.13335)
		(layer "In2.Cu")
		(net "COMP_B_PGOOD")
	)
	(segment
		(start 357.978456 -41.81602)
		(end 356.96017 -42.834306)
		(width 0.13335)
		(layer "In2.Cu")
		(net "COMP_B_PGOOD")
	)
	(segment
		(start 341.25789 -33.91281)
		(end 339.9536 -32.60852)
		(width 0.13335)
		(layer "In2.Cu")
		(net "COMP_B_PGOOD")
	)
	(segment
		(start 361.542838 -42.426128)
		(end 360.93273 -41.81602)
		(width 0.13335)
		(layer "In2.Cu")
		(net "COMP_B_PGOOD")
	)
	(segment
		(start 362.626402 -42.426128)
		(end 361.609894 -43.442636)
		(width 0.12065)
		(layer "In4.Cu")
		(net "COMP_B_PGOOD")
	)
	(segment
		(start 363.704886 -91.264994)
		(end 363.704886 -119.23395)
		(width 0.12065)
		(layer "In4.Cu")
		(net "COMP_B_PGOOD")
	)
	(segment
		(start 361.609894 -69.7484)
		(end 363.704886 -71.843392)
		(width 0.12065)
		(layer "In4.Cu")
		(net "COMP_B_PGOOD")
	)
	(segment
		(start 361.609894 -43.442636)
		(end 361.609894 -69.7484)
		(width 0.12065)
		(layer "In4.Cu")
		(net "COMP_B_PGOOD")
	)
	(segment
		(start 363.704886 -119.23395)
		(end 374.5738 -130.102864)
		(width 0.12065)
		(layer "In4.Cu")
		(net "COMP_B_PGOOD")
	)
	(segment
		(start 363.704886 -71.843392)
		(end 363.704886 -91.264994)
		(width 0.12065)
		(layer "In4.Cu")
		(net "COMP_B_PGOOD")
	)
	(segment
		(start 374.5738 -130.102864)
		(end 374.5738 -144.5514)
		(width 0.12065)
		(layer "In4.Cu")
		(net "COMP_B_PGOOD")
	)
	(segment
		(start 338.266786 -19.496786)
		(end 338.266786 -20.4216)
		(width 0.17145)
		(layer "F.Cu")
		(net "COMP_B_INS_N")
	)
	(segment
		(start 338.003134 -24.41829)
		(end 338.003134 -21.502624)
		(width 0.17145)
		(layer "F.Cu")
		(net "COMP_B_INS_N")
	)
	(segment
		(start 338.03717 -19.26717)
		(end 338.266786 -19.496786)
		(width 0.17145)
		(layer "F.Cu")
		(net "COMP_B_INS_N")
	)
	(segment
		(start 338.003134 -21.502624)
		(end 338.266786 -21.238972)
		(width 0.17145)
		(layer "F.Cu")
		(net "COMP_B_INS_N")
	)
	(segment
		(start 338.03717 -18.193766)
		(end 338.03717 -19.26717)
		(width 0.17145)
		(layer "F.Cu")
		(net "COMP_B_INS_N")
	)
	(segment
		(start 338.266786 -21.238972)
		(end 338.266786 -20.4216)
		(width 0.17145)
		(layer "F.Cu")
		(net "COMP_B_INS_N")
	)
	(via
		(at 338.266786 -20.4216)
		(size 0.6604)
		(drill 0.3302)
		(layers "F.Cu" "B.Cu")
		(net "COMP_B_INS_N")
	)
	(segment
		(start 265.756898 -109.157262)
		(end 264.863326 -109.157262)
		(width 0.17145)
		(layer "F.Cu")
		(net "COMP_B_EXP_B_SPARE_0")
	)
	(segment
		(start 264.863326 -109.157262)
		(end 264.20572 -109.814868)
		(width 0.17145)
		(layer "F.Cu")
		(net "COMP_B_EXP_B_SPARE_0")
	)
	(segment
		(start 264.20572 -109.814868)
		(end 264.20572 -111.12754)
		(width 0.17145)
		(layer "F.Cu")
		(net "COMP_B_EXP_B_SPARE_0")
	)
	(via
		(at 239.268 -191.2239)
		(size 0.5588)
		(drill 0.3048)
		(layers "F.Cu" "B.Cu")
		(net "COMP_B_EXP_B_SPARE_0")
	)
	(via
		(at 264.20572 -111.12754)
		(size 0.5588)
		(drill 0.3048)
		(layers "F.Cu" "B.Cu")
		(net "COMP_B_EXP_B_SPARE_0")
	)
	(segment
		(start 216.531952 -316.734444)
		(end 209.66176 -323.604636)
		(width 0.12065)
		(layer "In4.Cu")
		(net "COMP_B_EXP_B_SPARE_0")
	)
	(segment
		(start 214.5538 -410.2862)
		(end 215.267794 -411.000194)
		(width 0.12065)
		(layer "In4.Cu")
		(net "COMP_B_EXP_B_SPARE_0")
	)
	(segment
		(start 239.268 -191.2239)
		(end 232.65638 -191.2239)
		(width 0.12065)
		(layer "In4.Cu")
		(net "COMP_B_EXP_B_SPARE_0")
	)
	(segment
		(start 209.66176 -323.604636)
		(end 209.66176 -398.079722)
		(width 0.12065)
		(layer "In4.Cu")
		(net "COMP_B_EXP_B_SPARE_0")
	)
	(segment
		(start 216.531952 -207.348328)
		(end 216.531952 -316.734444)
		(width 0.12065)
		(layer "In4.Cu")
		(net "COMP_B_EXP_B_SPARE_0")
	)
	(segment
		(start 209.66176 -398.079722)
		(end 214.5538 -402.971762)
		(width 0.12065)
		(layer "In4.Cu")
		(net "COMP_B_EXP_B_SPARE_0")
	)
	(segment
		(start 232.65638 -191.2239)
		(end 216.531952 -207.348328)
		(width 0.12065)
		(layer "In4.Cu")
		(net "COMP_B_EXP_B_SPARE_0")
	)
	(segment
		(start 215.267794 -411.000194)
		(end 215.400128 -411.000194)
		(width 0.12065)
		(layer "In4.Cu")
		(net "COMP_B_EXP_B_SPARE_0")
	)
	(segment
		(start 214.5538 -402.971762)
		(end 214.5538 -410.2862)
		(width 0.12065)
		(layer "In4.Cu")
		(net "COMP_B_EXP_B_SPARE_0")
	)
	(segment
		(start 253.5555 -145.071846)
		(end 253.5555 -125.418596)
		(width 0.13335)
		(layer "In9.Cu")
		(net "COMP_B_EXP_B_SPARE_0")
	)
	(segment
		(start 243.68379 -154.943556)
		(end 253.5555 -145.071846)
		(width 0.13335)
		(layer "In9.Cu")
		(net "COMP_B_EXP_B_SPARE_0")
	)
	(segment
		(start 239.268 -187.43803)
		(end 243.68379 -183.02224)
		(width 0.13335)
		(layer "In9.Cu")
		(net "COMP_B_EXP_B_SPARE_0")
	)
	(segment
		(start 263.642094 -115.332002)
		(end 263.642094 -111.691166)
		(width 0.13335)
		(layer "In9.Cu")
		(net "COMP_B_EXP_B_SPARE_0")
	)
	(segment
		(start 243.68379 -183.02224)
		(end 243.68379 -154.943556)
		(width 0.13335)
		(layer "In9.Cu")
		(net "COMP_B_EXP_B_SPARE_0")
	)
	(segment
		(start 263.642094 -111.691166)
		(end 264.20572 -111.12754)
		(width 0.13335)
		(layer "In9.Cu")
		(net "COMP_B_EXP_B_SPARE_0")
	)
	(segment
		(start 239.268 -191.2239)
		(end 239.268 -187.43803)
		(width 0.13335)
		(layer "In9.Cu")
		(net "COMP_B_EXP_B_SPARE_0")
	)
	(segment
		(start 253.5555 -125.418596)
		(end 263.642094 -115.332002)
		(width 0.13335)
		(layer "In9.Cu")
		(net "COMP_B_EXP_B_SPARE_0")
	)
	(segment
		(start 302.3108 -74.3331)
		(end 302.3108 -73.378568)
		(width 0.17145)
		(layer "F.Cu")
		(net "COMP_B_BMC_B_SPARE_0")
	)
	(segment
		(start 302.3108 -73.378568)
		(end 302.3108 -72.395842)
		(width 0.17145)
		(layer "F.Cu")
		(net "COMP_B_BMC_B_SPARE_0")
	)
	(via
		(at 344.421714 -69.919088)
		(size 0.5588)
		(drill 0.3048)
		(layers "F.Cu" "B.Cu")
		(net "COMP_B_BMC_B_SPARE_0")
	)
	(via
		(at 302.3108 -73.378568)
		(size 0.6604)
		(drill 0.3302)
		(layers "F.Cu" "B.Cu")
		(net "COMP_B_BMC_B_SPARE_0")
	)
	(via
		(at 302.3108 -72.395842)
		(size 0.5588)
		(drill 0.3048)
		(layers "F.Cu" "B.Cu")
		(net "COMP_B_BMC_B_SPARE_0")
	)
	(segment
		(start 341.94496 -72.395842)
		(end 344.421714 -69.919088)
		(width 0.13335)
		(layer "In2.Cu")
		(net "COMP_B_BMC_B_SPARE_0")
	)
	(segment
		(start 302.3108 -72.395842)
		(end 341.94496 -72.395842)
		(width 0.13335)
		(layer "In2.Cu")
		(net "COMP_B_BMC_B_SPARE_0")
	)
	(segment
		(start 344.421714 -42.14114)
		(end 344.421714 -69.919088)
		(width 0.12065)
		(layer "In4.Cu")
		(net "COMP_B_BMC_B_SPARE_0")
	)
	(segment
		(start 355.149912 -28.150058)
		(end 353.4918 -29.80817)
		(width 0.12065)
		(layer "In4.Cu")
		(net "COMP_B_BMC_B_SPARE_0")
	)
	(segment
		(start 353.4918 -29.80817)
		(end 353.4918 -33.071054)
		(width 0.12065)
		(layer "In4.Cu")
		(net "COMP_B_BMC_B_SPARE_0")
	)
	(segment
		(start 353.4918 -33.071054)
		(end 344.421714 -42.14114)
		(width 0.12065)
		(layer "In4.Cu")
		(net "COMP_B_BMC_B_SPARE_0")
	)
	(segment
		(start 143.354552 -133.76656)
		(end 143.072866 -133.484874)
		(width 0.17145)
		(layer "F.Cu")
		(net "COMP_A_PGOOD")
	)
	(segment
		(start 140.532866 -132.926074)
		(end 140.532866 -132.100574)
		(width 0.17145)
		(layer "F.Cu")
		(net "COMP_A_PGOOD")
	)
	(segment
		(start 140.532866 -132.100574)
		(end 141.548866 -132.100574)
		(width 0.17145)
		(layer "F.Cu")
		(net "COMP_A_PGOOD")
	)
	(segment
		(start 143.727932 -135.402574)
		(end 143.727932 -134.13994)
		(width 0.17145)
		(layer "F.Cu")
		(net "COMP_A_PGOOD")
	)
	(segment
		(start 143.072866 -133.484874)
		(end 143.072866 -131.859274)
		(width 0.17145)
		(layer "F.Cu")
		(net "COMP_A_PGOOD")
	)
	(segment
		(start 141.790166 -131.859274)
		(end 143.072866 -131.859274)
		(width 0.17145)
		(layer "F.Cu")
		(net "COMP_A_PGOOD")
	)
	(segment
		(start 143.727932 -134.13994)
		(end 143.354552 -133.76656)
		(width 0.17145)
		(layer "F.Cu")
		(net "COMP_A_PGOOD")
	)
	(segment
		(start 85.760814 -27.86761)
		(end 85.760814 -29.18714)
		(width 0.17145)
		(layer "F.Cu")
		(net "COMP_A_PGOOD")
	)
	(segment
		(start 141.548866 -132.100574)
		(end 141.790166 -131.859274)
		(width 0.17145)
		(layer "F.Cu")
		(net "COMP_A_PGOOD")
	)
	(via
		(at 213.233 -129.159)
		(size 0.5588)
		(drill 0.3048)
		(layers "F.Cu" "B.Cu")
		(net "COMP_A_PGOOD")
	)
	(via
		(at 143.354552 -133.76656)
		(size 0.6604)
		(drill 0.3302)
		(layers "F.Cu" "B.Cu")
		(net "COMP_A_PGOOD")
	)
	(via
		(at 140.532866 -132.926074)
		(size 0.5588)
		(drill 0.3048)
		(layers "F.Cu" "B.Cu")
		(net "COMP_A_PGOOD")
	)
	(via
		(at 167.296084 -130.85572)
		(size 0.5588)
		(drill 0.3048)
		(layers "F.Cu" "B.Cu")
		(net "COMP_A_PGOOD")
	)
	(via
		(at 140.650468 -67.99707)
		(size 0.5588)
		(drill 0.3048)
		(layers "F.Cu" "B.Cu")
		(net "COMP_A_PGOOD")
	)
	(via
		(at 85.760814 -29.18714)
		(size 0.5588)
		(drill 0.3048)
		(layers "F.Cu" "B.Cu")
		(net "COMP_A_PGOOD")
	)
	(segment
		(start 167.296084 -130.85572)
		(end 165.843204 -129.40284)
		(width 0.17145)
		(layer "B.Cu")
		(net "COMP_A_PGOOD")
	)
	(segment
		(start 221.488 -124.3838)
		(end 216.7128 -129.159)
		(width 0.17145)
		(layer "B.Cu")
		(net "COMP_A_PGOOD")
	)
	(segment
		(start 144.56029 -129.40284)
		(end 141.037056 -132.926074)
		(width 0.17145)
		(layer "B.Cu")
		(net "COMP_A_PGOOD")
	)
	(segment
		(start 216.7128 -129.159)
		(end 213.233 -129.159)
		(width 0.17145)
		(layer "B.Cu")
		(net "COMP_A_PGOOD")
	)
	(segment
		(start 165.843204 -129.40284)
		(end 144.56029 -129.40284)
		(width 0.17145)
		(layer "B.Cu")
		(net "COMP_A_PGOOD")
	)
	(segment
		(start 141.037056 -132.926074)
		(end 140.532866 -132.926074)
		(width 0.17145)
		(layer "B.Cu")
		(net "COMP_A_PGOOD")
	)
	(segment
		(start 221.488 -123.8885)
		(end 221.488 -124.3838)
		(width 0.17145)
		(layer "B.Cu")
		(net "COMP_A_PGOOD")
	)
	(segment
		(start 86.765384 -32.5755)
		(end 85.760814 -31.57093)
		(width 0.13335)
		(layer "In2.Cu")
		(net "COMP_A_PGOOD")
	)
	(segment
		(start 140.650468 -67.99707)
		(end 126.032768 -67.99707)
		(width 0.13335)
		(layer "In2.Cu")
		(net "COMP_A_PGOOD")
	)
	(segment
		(start 126.032768 -67.99707)
		(end 115.877086 -57.841388)
		(width 0.13335)
		(layer "In2.Cu")
		(net "COMP_A_PGOOD")
	)
	(segment
		(start 213.233 -129.159)
		(end 168.992804 -129.159)
		(width 0.13335)
		(layer "In2.Cu")
		(net "COMP_A_PGOOD")
	)
	(segment
		(start 85.760814 -31.57093)
		(end 85.760814 -29.18714)
		(width 0.13335)
		(layer "In2.Cu")
		(net "COMP_A_PGOOD")
	)
	(segment
		(start 115.877086 -57.841388)
		(end 115.7097 -57.841388)
		(width 0.13335)
		(layer "In2.Cu")
		(net "COMP_A_PGOOD")
	)
	(segment
		(start 90.443812 -32.5755)
		(end 86.765384 -32.5755)
		(width 0.13335)
		(layer "In2.Cu")
		(net "COMP_A_PGOOD")
	)
	(segment
		(start 168.992804 -129.159)
		(end 167.296084 -130.85572)
		(width 0.13335)
		(layer "In2.Cu")
		(net "COMP_A_PGOOD")
	)
	(segment
		(start 115.7097 -57.841388)
		(end 90.443812 -32.5755)
		(width 0.13335)
		(layer "In2.Cu")
		(net "COMP_A_PGOOD")
	)
	(segment
		(start 141.025118 -130.590036)
		(end 141.025118 -130.182112)
		(width 0.12065)
		(layer "In4.Cu")
		(net "COMP_A_PGOOD")
	)
	(segment
		(start 141.025118 -130.182112)
		(end 140.650468 -129.807462)
		(width 0.12065)
		(layer "In4.Cu")
		(net "COMP_A_PGOOD")
	)
	(segment
		(start 140.532866 -132.926074)
		(end 140.650468 -132.808472)
		(width 0.12065)
		(layer "In4.Cu")
		(net "COMP_A_PGOOD")
	)
	(segment
		(start 140.650468 -132.808472)
		(end 140.650468 -130.964686)
		(width 0.12065)
		(layer "In4.Cu")
		(net "COMP_A_PGOOD")
	)
	(segment
		(start 140.650468 -130.964686)
		(end 141.025118 -130.590036)
		(width 0.12065)
		(layer "In4.Cu")
		(net "COMP_A_PGOOD")
	)
	(segment
		(start 140.650468 -129.807462)
		(end 140.650468 -67.99707)
		(width 0.12065)
		(layer "In4.Cu")
		(net "COMP_A_PGOOD")
	)
	(segment
		(start 84.460334 -22.22881)
		(end 84.460334 -19.705066)
		(width 0.17145)
		(layer "F.Cu")
		(net "COMP_A_INS_N")
	)
	(segment
		(start 84.460334 -19.705066)
		(end 85.284564 -18.880836)
		(width 0.17145)
		(layer "F.Cu")
		(net "COMP_A_INS_N")
	)
	(segment
		(start 85.284564 -18.880836)
		(end 86.098634 -18.066766)
		(width 0.17145)
		(layer "F.Cu")
		(net "COMP_A_INS_N")
	)
	(segment
		(start 86.098634 -18.066766)
		(end 86.098634 -17.59077)
		(width 0.17145)
		(layer "F.Cu")
		(net "COMP_A_INS_N")
	)
	(via
		(at 85.284564 -18.880836)
		(size 0.6604)
		(drill 0.3302)
		(layers "F.Cu" "B.Cu")
		(net "COMP_A_INS_N")
	)
	(segment
		(start 220.36532 -113.147348)
		(end 220.044518 -113.46815)
		(width 0.17145)
		(layer "F.Cu")
		(net "COMP_A_BMC_A_SPARE_0")
	)
	(segment
		(start 221.078806 -113.147348)
		(end 220.36532 -113.147348)
		(width 0.17145)
		(layer "F.Cu")
		(net "COMP_A_BMC_A_SPARE_0")
	)
	(segment
		(start 222.149416 -113.147348)
		(end 221.078806 -113.147348)
		(width 0.17145)
		(layer "F.Cu")
		(net "COMP_A_BMC_A_SPARE_0")
	)
	(via
		(at 221.078806 -113.147348)
		(size 0.6604)
		(drill 0.3302)
		(layers "F.Cu" "B.Cu")
		(net "COMP_A_BMC_A_SPARE_0")
	)
	(via
		(at 220.044518 -113.46815)
		(size 0.5588)
		(drill 0.3048)
		(layers "F.Cu" "B.Cu")
		(net "COMP_A_BMC_A_SPARE_0")
	)
	(via
		(at 106.3244 -113.147348)
		(size 0.5588)
		(drill 0.3048)
		(layers "F.Cu" "B.Cu")
		(net "COMP_A_BMC_A_SPARE_0")
	)
	(segment
		(start 106.3244 -113.147348)
		(end 210.850988 -113.147348)
		(width 0.13335)
		(layer "In2.Cu")
		(net "COMP_A_BMC_A_SPARE_0")
	)
	(segment
		(start 219.587318 -113.92535)
		(end 220.044518 -113.46815)
		(width 0.13335)
		(layer "In2.Cu")
		(net "COMP_A_BMC_A_SPARE_0")
	)
	(segment
		(start 210.850988 -113.147348)
		(end 211.62899 -113.92535)
		(width 0.13335)
		(layer "In2.Cu")
		(net "COMP_A_BMC_A_SPARE_0")
	)
	(segment
		(start 211.62899 -113.92535)
		(end 219.587318 -113.92535)
		(width 0.13335)
		(layer "In2.Cu")
		(net "COMP_A_BMC_A_SPARE_0")
	)
	(segment
		(start 106.3244 -87.87638)
		(end 106.3244 -113.147348)
		(width 0.12065)
		(layer "In4.Cu")
		(net "COMP_A_BMC_A_SPARE_0")
	)
	(segment
		(start 107.679744 -29.62021)
		(end 107.679744 -38.072568)
		(width 0.12065)
		(layer "In4.Cu")
		(net "COMP_A_BMC_A_SPARE_0")
	)
	(segment
		(start 109.149896 -28.150058)
		(end 107.679744 -29.62021)
		(width 0.12065)
		(layer "In4.Cu")
		(net "COMP_A_BMC_A_SPARE_0")
	)
	(segment
		(start 102.22611 -83.77809)
		(end 106.3244 -87.87638)
		(width 0.12065)
		(layer "In4.Cu")
		(net "COMP_A_BMC_A_SPARE_0")
	)
	(segment
		(start 102.22611 -43.526202)
		(end 102.22611 -83.77809)
		(width 0.12065)
		(layer "In4.Cu")
		(net "COMP_A_BMC_A_SPARE_0")
	)
	(segment
		(start 107.679744 -38.072568)
		(end 102.22611 -43.526202)
		(width 0.12065)
		(layer "In4.Cu")
		(net "COMP_A_BMC_A_SPARE_0")
	)
	(via
		(at 292.331394 -337.693)
		(size 0.5588)
		(drill 0.3048)
		(layers "F.Cu" "B.Cu")
		(net "BMC_B_EXP_B_SPARE_1")
	)
	(via
		(at 348.9198 -337.82)
		(size 0.5588)
		(drill 0.3048)
		(layers "F.Cu" "B.Cu")
		(net "BMC_B_EXP_B_SPARE_1")
	)
	(segment
		(start 348.097602 -338.642198)
		(end 293.280592 -338.642198)
		(width 0.13335)
		(layer "In2.Cu")
		(net "BMC_B_EXP_B_SPARE_1")
	)
	(segment
		(start 293.280592 -338.642198)
		(end 292.331394 -337.693)
		(width 0.13335)
		(layer "In2.Cu")
		(net "BMC_B_EXP_B_SPARE_1")
	)
	(segment
		(start 348.9198 -337.82)
		(end 348.097602 -338.642198)
		(width 0.13335)
		(layer "In2.Cu")
		(net "BMC_B_EXP_B_SPARE_1")
	)
	(segment
		(start 348.692724 -202.705716)
		(end 348.692724 -290.272724)
		(width 0.12065)
		(layer "In4.Cu")
		(net "BMC_B_EXP_B_SPARE_1")
	)
	(segment
		(start 335.092802 -162.749992)
		(end 335.092802 -168.990264)
		(width 0.12065)
		(layer "In4.Cu")
		(net "BMC_B_EXP_B_SPARE_1")
	)
	(segment
		(start 354.67163 -33.817814)
		(end 354.566474 -33.817814)
		(width 0.12065)
		(layer "In4.Cu")
		(net "BMC_B_EXP_B_SPARE_1")
	)
	(segment
		(start 338.645246 -177.196496)
		(end 343.252044 -181.803294)
		(width 0.12065)
		(layer "In4.Cu")
		(net "BMC_B_EXP_B_SPARE_1")
	)
	(segment
		(start 356.95001 -31.56839)
		(end 356.736904 -31.781496)
		(width 0.12065)
		(layer "In4.Cu")
		(net "BMC_B_EXP_B_SPARE_1")
	)
	(segment
		(start 338.645246 -172.542708)
		(end 338.645246 -177.196496)
		(width 0.12065)
		(layer "In4.Cu")
		(net "BMC_B_EXP_B_SPARE_1")
	)
	(segment
		(start 346.1639 -108.221272)
		(end 331.612748 -122.772424)
		(width 0.12065)
		(layer "In4.Cu")
		(net "BMC_B_EXP_B_SPARE_1")
	)
	(segment
		(start 350.5835 -292.1635)
		(end 350.5835 -336.1563)
		(width 0.12065)
		(layer "In4.Cu")
		(net "BMC_B_EXP_B_SPARE_1")
	)
	(segment
		(start 335.092802 -168.990264)
		(end 338.645246 -172.542708)
		(width 0.12065)
		(layer "In4.Cu")
		(net "BMC_B_EXP_B_SPARE_1")
	)
	(segment
		(start 346.1639 -42.220388)
		(end 346.1639 -108.221272)
		(width 0.12065)
		(layer "In4.Cu")
		(net "BMC_B_EXP_B_SPARE_1")
	)
	(segment
		(start 356.736904 -31.781496)
		(end 356.707948 -31.781496)
		(width 0.12065)
		(layer "In4.Cu")
		(net "BMC_B_EXP_B_SPARE_1")
	)
	(segment
		(start 343.252044 -197.265036)
		(end 348.692724 -202.705716)
		(width 0.12065)
		(layer "In4.Cu")
		(net "BMC_B_EXP_B_SPARE_1")
	)
	(segment
		(start 354.566474 -33.817814)
		(end 346.1639 -42.220388)
		(width 0.12065)
		(layer "In4.Cu")
		(net "BMC_B_EXP_B_SPARE_1")
	)
	(segment
		(start 348.692724 -290.272724)
		(end 350.5835 -292.1635)
		(width 0.12065)
		(layer "In4.Cu")
		(net "BMC_B_EXP_B_SPARE_1")
	)
	(segment
		(start 350.5835 -336.1563)
		(end 348.9198 -337.82)
		(width 0.12065)
		(layer "In4.Cu")
		(net "BMC_B_EXP_B_SPARE_1")
	)
	(segment
		(start 356.707948 -31.781496)
		(end 354.67163 -33.817814)
		(width 0.12065)
		(layer "In4.Cu")
		(net "BMC_B_EXP_B_SPARE_1")
	)
	(segment
		(start 331.612748 -122.772424)
		(end 331.612748 -159.269938)
		(width 0.12065)
		(layer "In4.Cu")
		(net "BMC_B_EXP_B_SPARE_1")
	)
	(segment
		(start 331.612748 -159.269938)
		(end 335.092802 -162.749992)
		(width 0.12065)
		(layer "In4.Cu")
		(net "BMC_B_EXP_B_SPARE_1")
	)
	(segment
		(start 356.95001 -30.550104)
		(end 356.95001 -31.56839)
		(width 0.12065)
		(layer "In4.Cu")
		(net "BMC_B_EXP_B_SPARE_1")
	)
	(segment
		(start 343.252044 -181.803294)
		(end 343.252044 -197.265036)
		(width 0.12065)
		(layer "In4.Cu")
		(net "BMC_B_EXP_B_SPARE_1")
	)
	(segment
		(start 239.771682 -351.418398)
		(end 248.39803 -351.418398)
		(width 0.12065)
		(layer "In7.Cu")
		(net "BMC_B_EXP_B_SPARE_1")
	)
	(segment
		(start 232.870502 -391.814304)
		(end 232.319068 -391.26287)
		(width 0.12065)
		(layer "In7.Cu")
		(net "BMC_B_EXP_B_SPARE_1")
	)
	(segment
		(start 234.597448 -377.898406)
		(end 234.597448 -356.592632)
		(width 0.12065)
		(layer "In7.Cu")
		(net "BMC_B_EXP_B_SPARE_1")
	)
	(segment
		(start 258.262882 -361.28325)
		(end 288.651442 -361.28325)
		(width 0.12065)
		(layer "In7.Cu")
		(net "BMC_B_EXP_B_SPARE_1")
	)
	(segment
		(start 292.331394 -357.603298)
		(end 292.331394 -337.693)
		(width 0.12065)
		(layer "In7.Cu")
		(net "BMC_B_EXP_B_SPARE_1")
	)
	(segment
		(start 288.651442 -361.28325)
		(end 292.331394 -357.603298)
		(width 0.12065)
		(layer "In7.Cu")
		(net "BMC_B_EXP_B_SPARE_1")
	)
	(segment
		(start 232.319068 -391.26287)
		(end 232.319068 -380.176786)
		(width 0.12065)
		(layer "In7.Cu")
		(net "BMC_B_EXP_B_SPARE_1")
	)
	(segment
		(start 231.599994 -418.200078)
		(end 235.611162 -414.18891)
		(width 0.12065)
		(layer "In7.Cu")
		(net "BMC_B_EXP_B_SPARE_1")
	)
	(segment
		(start 248.39803 -351.418398)
		(end 258.262882 -361.28325)
		(width 0.12065)
		(layer "In7.Cu")
		(net "BMC_B_EXP_B_SPARE_1")
	)
	(segment
		(start 232.319068 -380.176786)
		(end 234.597448 -377.898406)
		(width 0.12065)
		(layer "In7.Cu")
		(net "BMC_B_EXP_B_SPARE_1")
	)
	(segment
		(start 232.870502 -395.695678)
		(end 232.870502 -391.814304)
		(width 0.12065)
		(layer "In7.Cu")
		(net "BMC_B_EXP_B_SPARE_1")
	)
	(segment
		(start 235.611162 -398.436338)
		(end 232.870502 -395.695678)
		(width 0.12065)
		(layer "In7.Cu")
		(net "BMC_B_EXP_B_SPARE_1")
	)
	(segment
		(start 234.597448 -356.592632)
		(end 239.771682 -351.418398)
		(width 0.12065)
		(layer "In7.Cu")
		(net "BMC_B_EXP_B_SPARE_1")
	)
	(segment
		(start 235.611162 -414.18891)
		(end 235.611162 -398.436338)
		(width 0.12065)
		(layer "In7.Cu")
		(net "BMC_B_EXP_B_SPARE_1")
	)
	(via
		(at 293.243 -337.185)
		(size 0.5588)
		(drill 0.3048)
		(layers "F.Cu" "B.Cu")
		(net "BMC_B_EXP_B_SPARE_0")
	)
	(via
		(at 347.8784 -337.8454)
		(size 0.5588)
		(drill 0.3048)
		(layers "F.Cu" "B.Cu")
		(net "BMC_B_EXP_B_SPARE_0")
	)
	(segment
		(start 347.8784 -337.8454)
		(end 347.853 -337.82)
		(width 0.13335)
		(layer "In2.Cu")
		(net "BMC_B_EXP_B_SPARE_0")
	)
	(segment
		(start 293.878 -337.82)
		(end 293.243 -337.185)
		(width 0.13335)
		(layer "In2.Cu")
		(net "BMC_B_EXP_B_SPARE_0")
	)
	(segment
		(start 347.853 -337.82)
		(end 293.878 -337.82)
		(width 0.13335)
		(layer "In2.Cu")
		(net "BMC_B_EXP_B_SPARE_0")
	)
	(segment
		(start 342.839294 -182.057294)
		(end 342.839294 -197.436232)
		(width 0.12065)
		(layer "In4.Cu")
		(net "BMC_B_EXP_B_SPARE_0")
	)
	(segment
		(start 348.279974 -290.494974)
		(end 350.17075 -292.38575)
		(width 0.12065)
		(layer "In4.Cu")
		(net "BMC_B_EXP_B_SPARE_0")
	)
	(segment
		(start 338.162646 -172.644054)
		(end 338.162646 -177.380646)
		(width 0.12065)
		(layer "In4.Cu")
		(net "BMC_B_EXP_B_SPARE_0")
	)
	(segment
		(start 356.95001 -29.150056)
		(end 356.0064 -30.093666)
		(width 0.12065)
		(layer "In4.Cu")
		(net "BMC_B_EXP_B_SPARE_0")
	)
	(segment
		(start 338.162646 -177.380646)
		(end 342.839294 -182.057294)
		(width 0.12065)
		(layer "In4.Cu")
		(net "BMC_B_EXP_B_SPARE_0")
	)
	(segment
		(start 354.400104 -33.405064)
		(end 354.395278 -33.405064)
		(width 0.12065)
		(layer "In4.Cu")
		(net "BMC_B_EXP_B_SPARE_0")
	)
	(segment
		(start 345.75115 -108.050076)
		(end 331.019404 -122.781822)
		(width 0.12065)
		(layer "In4.Cu")
		(net "BMC_B_EXP_B_SPARE_0")
	)
	(segment
		(start 348.279974 -202.876912)
		(end 348.279974 -290.494974)
		(width 0.12065)
		(layer "In4.Cu")
		(net "BMC_B_EXP_B_SPARE_0")
	)
	(segment
		(start 350.17075 -292.38575)
		(end 350.17075 -335.55305)
		(width 0.12065)
		(layer "In4.Cu")
		(net "BMC_B_EXP_B_SPARE_0")
	)
	(segment
		(start 345.75115 -42.049192)
		(end 345.75115 -108.050076)
		(width 0.12065)
		(layer "In4.Cu")
		(net "BMC_B_EXP_B_SPARE_0")
	)
	(segment
		(start 356.0064 -31.798768)
		(end 354.400104 -33.405064)
		(width 0.12065)
		(layer "In4.Cu")
		(net "BMC_B_EXP_B_SPARE_0")
	)
	(segment
		(start 334.680052 -169.16146)
		(end 338.162646 -172.644054)
		(width 0.12065)
		(layer "In4.Cu")
		(net "BMC_B_EXP_B_SPARE_0")
	)
	(segment
		(start 350.17075 -335.55305)
		(end 347.8784 -337.8454)
		(width 0.12065)
		(layer "In4.Cu")
		(net "BMC_B_EXP_B_SPARE_0")
	)
	(segment
		(start 334.680052 -162.921188)
		(end 334.680052 -169.16146)
		(width 0.12065)
		(layer "In4.Cu")
		(net "BMC_B_EXP_B_SPARE_0")
	)
	(segment
		(start 354.395278 -33.405064)
		(end 345.75115 -42.049192)
		(width 0.12065)
		(layer "In4.Cu")
		(net "BMC_B_EXP_B_SPARE_0")
	)
	(segment
		(start 342.839294 -197.436232)
		(end 348.279974 -202.876912)
		(width 0.12065)
		(layer "In4.Cu")
		(net "BMC_B_EXP_B_SPARE_0")
	)
	(segment
		(start 331.019404 -159.26054)
		(end 334.680052 -162.921188)
		(width 0.12065)
		(layer "In4.Cu")
		(net "BMC_B_EXP_B_SPARE_0")
	)
	(segment
		(start 331.019404 -122.781822)
		(end 331.019404 -159.26054)
		(width 0.12065)
		(layer "In4.Cu")
		(net "BMC_B_EXP_B_SPARE_0")
	)
	(segment
		(start 356.0064 -30.093666)
		(end 356.0064 -31.798768)
		(width 0.12065)
		(layer "In4.Cu")
		(net "BMC_B_EXP_B_SPARE_0")
	)
	(segment
		(start 236.163358 -398.404588)
		(end 233.283252 -395.524482)
		(width 0.12065)
		(layer "In7.Cu")
		(net "BMC_B_EXP_B_SPARE_0")
	)
	(segment
		(start 235.010198 -378.069602)
		(end 235.010198 -356.763828)
		(width 0.12065)
		(layer "In7.Cu")
		(net "BMC_B_EXP_B_SPARE_0")
	)
	(segment
		(start 236.163358 -414.736788)
		(end 236.163358 -398.404588)
		(width 0.12065)
		(layer "In7.Cu")
		(net "BMC_B_EXP_B_SPARE_0")
	)
	(segment
		(start 231.599994 -419.300152)
		(end 236.163358 -414.736788)
		(width 0.12065)
		(layer "In7.Cu")
		(net "BMC_B_EXP_B_SPARE_0")
	)
	(segment
		(start 233.283252 -395.524482)
		(end 233.283252 -391.643108)
		(width 0.12065)
		(layer "In7.Cu")
		(net "BMC_B_EXP_B_SPARE_0")
	)
	(segment
		(start 232.731818 -391.091674)
		(end 232.731818 -380.347982)
		(width 0.12065)
		(layer "In7.Cu")
		(net "BMC_B_EXP_B_SPARE_0")
	)
	(segment
		(start 233.283252 -391.643108)
		(end 232.731818 -391.091674)
		(width 0.12065)
		(layer "In7.Cu")
		(net "BMC_B_EXP_B_SPARE_0")
	)
	(segment
		(start 292.845744 -337.582256)
		(end 293.243 -337.185)
		(width 0.12065)
		(layer "In7.Cu")
		(net "BMC_B_EXP_B_SPARE_0")
	)
	(segment
		(start 292.845744 -357.762556)
		(end 292.845744 -337.582256)
		(width 0.12065)
		(layer "In7.Cu")
		(net "BMC_B_EXP_B_SPARE_0")
	)
	(segment
		(start 258.091686 -361.696)
		(end 288.9123 -361.696)
		(width 0.12065)
		(layer "In7.Cu")
		(net "BMC_B_EXP_B_SPARE_0")
	)
	(segment
		(start 232.731818 -380.347982)
		(end 235.010198 -378.069602)
		(width 0.12065)
		(layer "In7.Cu")
		(net "BMC_B_EXP_B_SPARE_0")
	)
	(segment
		(start 248.226834 -351.831148)
		(end 258.091686 -361.696)
		(width 0.12065)
		(layer "In7.Cu")
		(net "BMC_B_EXP_B_SPARE_0")
	)
	(segment
		(start 288.9123 -361.696)
		(end 292.845744 -357.762556)
		(width 0.12065)
		(layer "In7.Cu")
		(net "BMC_B_EXP_B_SPARE_0")
	)
	(segment
		(start 235.010198 -356.763828)
		(end 239.942878 -351.831148)
		(width 0.12065)
		(layer "In7.Cu")
		(net "BMC_B_EXP_B_SPARE_0")
	)
	(segment
		(start 239.942878 -351.831148)
		(end 248.226834 -351.831148)
		(width 0.12065)
		(layer "In7.Cu")
		(net "BMC_B_EXP_B_SPARE_0")
	)
	(via
		(at 480.485704 -233.110786)
		(size 0.5588)
		(drill 0.3048)
		(layers "F.Cu" "B.Cu")
		(net "AGND_P5V_D")
	)
	(via
		(at 483.616 -237.109)
		(size 0.5588)
		(drill 0.3048)
		(layers "F.Cu" "B.Cu")
		(net "AGND_P5V_D")
	)
	(via
		(at 483.616 -235.966)
		(size 0.5588)
		(drill 0.3048)
		(layers "F.Cu" "B.Cu")
		(net "AGND_P5V_D")
	)
	(via
		(at 480.738942 -232.154984)
		(size 0.6096)
		(drill 0.3048)
		(layers "F.Cu" "B.Cu")
		(net "AGND_P5V_D")
	)
	(via
		(at 483.616 -234.95)
		(size 0.5588)
		(drill 0.3048)
		(layers "F.Cu" "B.Cu")
		(net "AGND_P5V_D")
	)
	(via
		(at 484.251 -226.9236)
		(size 0.5588)
		(drill 0.3048)
		(layers "F.Cu" "B.Cu")
		(net "AGND_P5V_D")
	)
	(via
		(at 478.663 -231.775)
		(size 0.5588)
		(drill 0.3048)
		(layers "F.Cu" "B.Cu")
		(net "AGND_P5V_D")
	)
	(segment
		(start 482.6635 -237.109)
		(end 483.616 -237.109)
		(width 0.508)
		(layer "B.Cu")
		(net "AGND_P5V_D")
	)
	(segment
		(start 478.663 -230.9495)
		(end 478.663 -231.775)
		(width 0.508)
		(layer "B.Cu")
		(net "AGND_P5V_D")
	)
	(segment
		(start 484.251 -226.1235)
		(end 484.251 -226.9236)
		(width 0.508)
		(layer "B.Cu")
		(net "AGND_P5V_D")
	)
	(segment
		(start 482.6635 -234.95)
		(end 483.616 -234.95)
		(width 0.508)
		(layer "B.Cu")
		(net "AGND_P5V_D")
	)
	(segment
		(start 482.6635 -235.966)
		(end 483.616 -235.966)
		(width 0.508)
		(layer "B.Cu")
		(net "AGND_P5V_D")
	)
	(via
		(at 445.049402 -258.01955)
		(size 0.6604)
		(drill 0.3302)
		(layers "F.Cu" "B.Cu")
		(net "AGND_P5V_C")
	)
	(via
		(at 445.9986 -257.7084)
		(size 0.5588)
		(drill 0.3048)
		(layers "F.Cu" "B.Cu")
		(net "AGND_P5V_C")
	)
	(via
		(at 44.974002 -150.32355)
		(size 0.6604)
		(drill 0.3302)
		(layers "F.Cu" "B.Cu")
		(net "AGND_P5V_B")
	)
	(via
		(at 45.9232 -150.0124)
		(size 0.5588)
		(drill 0.3048)
		(layers "F.Cu" "B.Cu")
		(net "AGND_P5V_B")
	)
	(via
		(at 28.9814 -254.6604)
		(size 0.5588)
		(drill 0.3048)
		(layers "F.Cu" "B.Cu")
		(net "AGND_P5V_A")
	)
	(via
		(at 28.032202 -254.97155)
		(size 0.6604)
		(drill 0.3302)
		(layers "F.Cu" "B.Cu")
		(net "AGND_P5V_A")
	)
	(segment
		(start 35.5854 -298.704)
		(end 35.584384 -298.705016)
		(width 0.17145)
		(layer "F.Cu")
		(net "ACT_HDD_0")
	)
	(segment
		(start 35.584384 -298.705016)
		(end 30.025086 -298.705016)
		(width 0.17145)
		(layer "F.Cu")
		(net "ACT_HDD_0")
	)
	(via
		(at 20.938998 -296.207942)
		(size 0.6604)
		(drill 0.3302)
		(layers "F.Cu" "B.Cu")
		(net "12V_PRE_0")
	)
	(segment
		(start 336.539078 -37.384736)
		(end 333.071724 -35.91941)
		(width 0.1651)
		(layer "F.Cu")
		(net "USB_COMP_B_DP")
	)
	(segment
		(start 353.27971 -31.786322)
		(end 340.700868 -36.770564)
		(width 0.1651)
		(layer "F.Cu")
		(net "USB_COMP_B_DP")
	)
	(segment
		(start 305.55438 -57.965848)
		(end 304.25009 -63.721234)
		(width 0.1651)
		(layer "F.Cu")
		(net "USB_COMP_B_DP")
	)
	(segment
		(start 288.98215 -105.087166)
		(end 288.97707 -105.090722)
		(width 0.1651)
		(layer "F.Cu")
		(net "USB_COMP_B_DP")
	)
	(segment
		(start 361.303824 -31.07309)
		(end 360.590592 -31.786322)
		(width 0.1651)
		(layer "F.Cu")
		(net "USB_COMP_B_DP")
	)
	(segment
		(start 306.856384 -52.220622)
		(end 305.55438 -57.965848)
		(width 0.1651)
		(layer "F.Cu")
		(net "USB_COMP_B_DP")
	)
	(segment
		(start 360.590592 -31.786322)
		(end 353.27971 -31.786322)
		(width 0.1651)
		(layer "F.Cu")
		(net "USB_COMP_B_DP")
	)
	(segment
		(start 338.620354 -37.07765)
		(end 336.539078 -37.384736)
		(width 0.1651)
		(layer "F.Cu")
		(net "USB_COMP_B_DP")
	)
	(segment
		(start 305.031648 -67.806824)
		(end 305.801522 -71.832216)
		(width 0.1651)
		(layer "F.Cu")
		(net "USB_COMP_B_DP")
	)
	(segment
		(start 306.566062 -75.82789)
		(end 304.882804 -83.257644)
		(width 0.1651)
		(layer "F.Cu")
		(net "USB_COMP_B_DP")
	)
	(segment
		(start 289.074606 -105.022904)
		(end 288.98215 -105.087166)
		(width 0.1651)
		(layer "F.Cu")
		(net "USB_COMP_B_DP")
	)
	(segment
		(start 361.303824 -29.36748)
		(end 361.303824 -31.07309)
		(width 0.1651)
		(layer "F.Cu")
		(net "USB_COMP_B_DP")
	)
	(segment
		(start 362.35005 -28.150058)
		(end 362.35005 -28.577032)
		(width 0.1651)
		(layer "F.Cu")
		(net "USB_COMP_B_DP")
	)
	(segment
		(start 305.801522 -71.832216)
		(end 306.566062 -75.82789)
		(width 0.1651)
		(layer "F.Cu")
		(net "USB_COMP_B_DP")
	)
	(segment
		(start 362.22305 -28.704032)
		(end 361.967272 -28.704032)
		(width 0.1651)
		(layer "F.Cu")
		(net "USB_COMP_B_DP")
	)
	(segment
		(start 288.97707 -105.090722)
		(end 285.712408 -107.353862)
		(width 0.1651)
		(layer "F.Cu")
		(net "USB_COMP_B_DP")
	)
	(segment
		(start 284.162246 -107.821984)
		(end 284.162246 -107.82935)
		(width 0.1651)
		(layer "F.Cu")
		(net "USB_COMP_B_DP")
	)
	(segment
		(start 284.376876 -107.526328)
		(end 284.162246 -107.821984)
		(width 0.1651)
		(layer "F.Cu")
		(net "USB_COMP_B_DP")
	)
	(segment
		(start 318.532256 -33.88233)
		(end 306.856384 -52.220622)
		(width 0.1651)
		(layer "F.Cu")
		(net "USB_COMP_B_DP")
	)
	(segment
		(start 285.712408 -107.353862)
		(end 284.71622 -107.353862)
		(width 0.1651)
		(layer "F.Cu")
		(net "USB_COMP_B_DP")
	)
	(segment
		(start 340.700868 -36.770564)
		(end 338.620354 -37.07765)
		(width 0.1651)
		(layer "F.Cu")
		(net "USB_COMP_B_DP")
	)
	(segment
		(start 283.971238 -107.860846)
		(end 283.249878 -107.499912)
		(width 0.1651)
		(layer "F.Cu")
		(net "USB_COMP_B_DP")
	)
	(segment
		(start 304.25009 -63.721234)
		(end 305.031648 -67.806824)
		(width 0.1651)
		(layer "F.Cu")
		(net "USB_COMP_B_DP")
	)
	(segment
		(start 289.172396 -104.955594)
		(end 289.074606 -105.022904)
		(width 0.1651)
		(layer "F.Cu")
		(net "USB_COMP_B_DP")
	)
	(segment
		(start 321.653662 -32.054546)
		(end 318.532256 -33.88233)
		(width 0.1651)
		(layer "F.Cu")
		(net "USB_COMP_B_DP")
	)
	(segment
		(start 330.114402 -32.054546)
		(end 321.653662 -32.054546)
		(width 0.1651)
		(layer "F.Cu")
		(net "USB_COMP_B_DP")
	)
	(segment
		(start 304.882804 -83.257644)
		(end 289.172396 -104.955594)
		(width 0.1651)
		(layer "F.Cu")
		(net "USB_COMP_B_DP")
	)
	(segment
		(start 333.071724 -35.91941)
		(end 330.114402 -32.054546)
		(width 0.1651)
		(layer "F.Cu")
		(net "USB_COMP_B_DP")
	)
	(arc
		(start 362.35005 -28.577032)
		(mid 362.312853 -28.666835)
		(end 362.22305 -28.704032)
		(width 0.1651)
		(layer "F.Cu")
		(net "USB_COMP_B_DP")
	)
	(arc
		(start 284.71622 -107.353862)
		(mid 284.525835 -107.399342)
		(end 284.376876 -107.526328)
		(width 0.1651)
		(layer "F.Cu")
		(net "USB_COMP_B_DP")
	)
	(arc
		(start 361.967272 -28.704032)
		(mid 361.498143 -28.898351)
		(end 361.303824 -29.36748)
		(width 0.1651)
		(layer "F.Cu")
		(net "USB_COMP_B_DP")
	)
	(arc
		(start 284.162246 -107.82935)
		(mid 284.071837 -107.876118)
		(end 283.971238 -107.860846)
		(width 0.1651)
		(layer "F.Cu")
		(net "USB_COMP_B_DP")
	)
	(segment
		(start 321.73291 -32.346646)
		(end 318.74079 -34.098738)
		(width 0.1651)
		(layer "F.Cu")
		(net "USB_COMP_B_DN")
	)
	(segment
		(start 318.74079 -34.098738)
		(end 307.130196 -52.334668)
		(width 0.1651)
		(layer "F.Cu")
		(net "USB_COMP_B_DN")
	)
	(segment
		(start 289.37966 -105.16743)
		(end 285.803848 -107.645962)
		(width 0.1651)
		(layer "F.Cu")
		(net "USB_COMP_B_DN")
	)
	(segment
		(start 284.454346 -107.91698)
		(end 284.454346 -107.917234)
		(width 0.1651)
		(layer "F.Cu")
		(net "USB_COMP_B_DN")
	)
	(segment
		(start 293.00297 -100.163376)
		(end 293.02837 -100.323142)
		(width 0.1651)
		(layer "F.Cu")
		(net "USB_COMP_B_DN")
	)
	(segment
		(start 293.293292 -99.76231)
		(end 293.00297 -100.163376)
		(width 0.1651)
		(layer "F.Cu")
		(net "USB_COMP_B_DN")
	)
	(segment
		(start 340.777068 -37.05479)
		(end 336.500724 -37.685726)
		(width 0.1651)
		(layer "F.Cu")
		(net "USB_COMP_B_DN")
	)
	(segment
		(start 361.595924 -31.194248)
		(end 360.71175 -32.078422)
		(width 0.1651)
		(layer "F.Cu")
		(net "USB_COMP_B_DN")
	)
	(segment
		(start 307.130196 -52.334668)
		(end 304.54854 -63.726314)
		(width 0.1651)
		(layer "F.Cu")
		(net "USB_COMP_B_DN")
	)
	(segment
		(start 362.35005 -29.550106)
		(end 362.35005 -29.123132)
		(width 0.1651)
		(layer "F.Cu")
		(net "USB_COMP_B_DN")
	)
	(segment
		(start 294.168068 -98.749104)
		(end 294.008302 -98.774758)
		(width 0.1651)
		(layer "F.Cu")
		(net "USB_COMP_B_DN")
	)
	(segment
		(start 293.453058 -99.736656)
		(end 293.293292 -99.76231)
		(width 0.1651)
		(layer "F.Cu")
		(net "USB_COMP_B_DN")
	)
	(segment
		(start 294.43299 -98.188526)
		(end 294.45839 -98.348038)
		(width 0.1651)
		(layer "F.Cu")
		(net "USB_COMP_B_DN")
	)
	(segment
		(start 329.969876 -32.346646)
		(end 321.73291 -32.346646)
		(width 0.1651)
		(layer "F.Cu")
		(net "USB_COMP_B_DN")
	)
	(segment
		(start 306.864512 -75.83297)
		(end 305.154584 -83.38058)
		(width 0.1651)
		(layer "F.Cu")
		(net "USB_COMP_B_DN")
	)
	(segment
		(start 292.738048 -100.724208)
		(end 292.578282 -100.749862)
		(width 0.1651)
		(layer "F.Cu")
		(net "USB_COMP_B_DN")
	)
	(segment
		(start 292.31336 -101.310694)
		(end 292.023038 -101.71176)
		(width 0.1651)
		(layer "F.Cu")
		(net "USB_COMP_B_DN")
	)
	(segment
		(start 284.528006 -108.138722)
		(end 285.249874 -108.49991)
		(width 0.1651)
		(layer "F.Cu")
		(net "USB_COMP_B_DN")
	)
	(segment
		(start 362.22305 -28.996132)
		(end 361.967272 -28.996132)
		(width 0.1651)
		(layer "F.Cu")
		(net "USB_COMP_B_DN")
	)
	(segment
		(start 294.008302 -98.774758)
		(end 293.71798 -99.175824)
		(width 0.1651)
		(layer "F.Cu")
		(net "USB_COMP_B_DN")
	)
	(segment
		(start 293.71798 -99.175824)
		(end 293.74338 -99.33559)
		(width 0.1651)
		(layer "F.Cu")
		(net "USB_COMP_B_DN")
	)
	(segment
		(start 336.500724 -37.685726)
		(end 332.886812 -36.158424)
		(width 0.1651)
		(layer "F.Cu")
		(net "USB_COMP_B_DN")
	)
	(segment
		(start 360.71175 -32.078422)
		(end 353.33559 -32.078422)
		(width 0.1651)
		(layer "F.Cu")
		(net "USB_COMP_B_DN")
	)
	(segment
		(start 361.595924 -29.36748)
		(end 361.595924 -31.194248)
		(width 0.1651)
		(layer "F.Cu")
		(net "USB_COMP_B_DN")
	)
	(segment
		(start 293.74338 -99.33559)
		(end 293.453058 -99.736656)
		(width 0.1651)
		(layer "F.Cu")
		(net "USB_COMP_B_DN")
	)
	(segment
		(start 353.33559 -32.078422)
		(end 340.777068 -37.05479)
		(width 0.1651)
		(layer "F.Cu")
		(net "USB_COMP_B_DN")
	)
	(segment
		(start 284.61335 -107.698286)
		(end 284.454346 -107.91698)
		(width 0.1651)
		(layer "F.Cu")
		(net "USB_COMP_B_DN")
	)
	(segment
		(start 291.863272 -101.737414)
		(end 289.37966 -105.16743)
		(width 0.1651)
		(layer "F.Cu")
		(net "USB_COMP_B_DN")
	)
	(segment
		(start 292.578282 -100.749862)
		(end 292.28796 -101.150928)
		(width 0.1651)
		(layer "F.Cu")
		(net "USB_COMP_B_DN")
	)
	(segment
		(start 293.02837 -100.323142)
		(end 292.738048 -100.724208)
		(width 0.1651)
		(layer "F.Cu")
		(net "USB_COMP_B_DN")
	)
	(segment
		(start 292.023038 -101.71176)
		(end 291.863272 -101.737414)
		(width 0.1651)
		(layer "F.Cu")
		(net "USB_COMP_B_DN")
	)
	(segment
		(start 292.28796 -101.150928)
		(end 292.31336 -101.310694)
		(width 0.1651)
		(layer "F.Cu")
		(net "USB_COMP_B_DN")
	)
	(segment
		(start 332.886812 -36.158424)
		(end 329.969876 -32.346646)
		(width 0.1651)
		(layer "F.Cu")
		(net "USB_COMP_B_DN")
	)
	(segment
		(start 294.45839 -98.348038)
		(end 294.168068 -98.749104)
		(width 0.1651)
		(layer "F.Cu")
		(net "USB_COMP_B_DN")
	)
	(segment
		(start 304.54854 -63.726314)
		(end 306.864512 -75.83297)
		(width 0.1651)
		(layer "F.Cu")
		(net "USB_COMP_B_DN")
	)
	(segment
		(start 285.803848 -107.645962)
		(end 284.71622 -107.645962)
		(width 0.1651)
		(layer "F.Cu")
		(net "USB_COMP_B_DN")
	)
	(segment
		(start 305.154584 -83.38058)
		(end 294.43299 -98.188526)
		(width 0.1651)
		(layer "F.Cu")
		(net "USB_COMP_B_DN")
	)
	(arc
		(start 361.967272 -28.996132)
		(mid 361.704689 -29.104897)
		(end 361.595924 -29.36748)
		(width 0.1651)
		(layer "F.Cu")
		(net "USB_COMP_B_DN")
	)
	(arc
		(start 284.454346 -107.917234)
		(mid 284.445304 -108.043233)
		(end 284.528006 -108.138722)
		(width 0.1651)
		(layer "F.Cu")
		(net "USB_COMP_B_DN")
	)
	(arc
		(start 284.71622 -107.645962)
		(mid 284.658466 -107.659724)
		(end 284.61335 -107.698286)
		(width 0.1651)
		(layer "F.Cu")
		(net "USB_COMP_B_DN")
	)
	(arc
		(start 362.35005 -29.123132)
		(mid 362.312853 -29.033329)
		(end 362.22305 -28.996132)
		(width 0.1651)
		(layer "F.Cu")
		(net "USB_COMP_B_DN")
	)
	(segment
		(start 240.549938 -107.499912)
		(end 241.271806 -107.8611)
		(width 0.1651)
		(layer "F.Cu")
		(net "USB_COMP_A_DP")
	)
	(segment
		(start 245.775734 -99.749864)
		(end 245.775988 -99.748848)
		(width 0.1651)
		(layer "F.Cu")
		(net "USB_COMP_A_DP")
	)
	(segment
		(start 245.34622 -101.644704)
		(end 245.346474 -101.643688)
		(width 0.1651)
		(layer "F.Cu")
		(net "USB_COMP_A_DP")
	)
	(segment
		(start 117.39626 -31.649924)
		(end 117.39626 -29.36748)
		(width 0.1651)
		(layer "F.Cu")
		(net "USB_COMP_A_DP")
	)
	(segment
		(start 169.220134 -34.047938)
		(end 156.67863 -31.580328)
		(width 0.1651)
		(layer "F.Cu")
		(net "USB_COMP_A_DP")
	)
	(segment
		(start 246.018304 -98.678238)
		(end 246.18188 -97.9551)
		(width 0.1651)
		(layer "F.Cu")
		(net "USB_COMP_A_DP")
	)
	(segment
		(start 245.593362 -95.967804)
		(end 245.093236 -95.55988)
		(width 0.1651)
		(layer "F.Cu")
		(net "USB_COMP_A_DP")
	)
	(segment
		(start 245.885462 -99.26574)
		(end 246.018558 -98.678238)
		(width 0.1651)
		(layer "F.Cu")
		(net "USB_COMP_A_DP")
	)
	(segment
		(start 242.151408 -109.866176)
		(end 242.838224 -109.866176)
		(width 0.1651)
		(layer "F.Cu")
		(net "USB_COMP_A_DP")
	)
	(segment
		(start 246.18188 -97.9551)
		(end 245.593362 -95.967804)
		(width 0.1651)
		(layer "F.Cu")
		(net "USB_COMP_A_DP")
	)
	(segment
		(start 116.350034 -28.577032)
		(end 116.350034 -28.150058)
		(width 0.1651)
		(layer "F.Cu")
		(net "USB_COMP_A_DP")
	)
	(segment
		(start 156.67863 -31.580328)
		(end 143.821912 -34.202878)
		(width 0.1651)
		(layer "F.Cu")
		(net "USB_COMP_A_DP")
	)
	(segment
		(start 241.240056 -108.955078)
		(end 241.24031 -108.955078)
		(width 0.1651)
		(layer "F.Cu")
		(net "USB_COMP_A_DP")
	)
	(segment
		(start 125.754892 -33.80613)
		(end 117.827552 -32.245808)
		(width 0.1651)
		(layer "F.Cu")
		(net "USB_COMP_A_DP")
	)
	(segment
		(start 245.615968 -100.454714)
		(end 245.775734 -99.749864)
		(width 0.1651)
		(layer "F.Cu")
		(net "USB_COMP_A_DP")
	)
	(segment
		(start 245.50624 -100.938838)
		(end 245.506494 -100.937822)
		(width 0.1651)
		(layer "F.Cu")
		(net "USB_COMP_A_DP")
	)
	(segment
		(start 246.018558 -98.678238)
		(end 246.018304 -98.678238)
		(width 0.1651)
		(layer "F.Cu")
		(net "USB_COMP_A_DP")
	)
	(segment
		(start 117.827806 -32.245808)
		(end 117.39626 -31.649924)
		(width 0.1651)
		(layer "F.Cu")
		(net "USB_COMP_A_DP")
	)
	(segment
		(start 245.506494 -100.937822)
		(end 245.615714 -100.45573)
		(width 0.1651)
		(layer "F.Cu")
		(net "USB_COMP_A_DP")
	)
	(segment
		(start 245.346474 -101.643688)
		(end 245.50624 -100.938838)
		(width 0.1651)
		(layer "F.Cu")
		(net "USB_COMP_A_DP")
	)
	(segment
		(start 241.24031 -108.955078)
		(end 242.151408 -109.866176)
		(width 0.1651)
		(layer "F.Cu")
		(net "USB_COMP_A_DP")
	)
	(segment
		(start 243.596922 -109.365034)
		(end 245.34622 -101.644704)
		(width 0.1651)
		(layer "F.Cu")
		(net "USB_COMP_A_DP")
	)
	(segment
		(start 232.342182 -90.561414)
		(end 200.693782 -40.907462)
		(width 0.1651)
		(layer "F.Cu")
		(net "USB_COMP_A_DP")
	)
	(segment
		(start 245.093236 -95.55988)
		(end 232.342182 -90.561414)
		(width 0.1651)
		(layer "F.Cu")
		(net "USB_COMP_A_DP")
	)
	(segment
		(start 241.345466 -108.082588)
		(end 241.21999 -108.255054)
		(width 0.1651)
		(layer "F.Cu")
		(net "USB_COMP_A_DP")
	)
	(segment
		(start 200.693782 -40.907462)
		(end 187.54471 -32.36849)
		(width 0.1651)
		(layer "F.Cu")
		(net "USB_COMP_A_DP")
	)
	(segment
		(start 187.54471 -32.36849)
		(end 182.409592 -31.357824)
		(width 0.1651)
		(layer "F.Cu")
		(net "USB_COMP_A_DP")
	)
	(segment
		(start 245.885208 -99.266756)
		(end 245.885462 -99.26574)
		(width 0.1651)
		(layer "F.Cu")
		(net "USB_COMP_A_DP")
	)
	(segment
		(start 242.838224 -109.866176)
		(end 243.596922 -109.365034)
		(width 0.1651)
		(layer "F.Cu")
		(net "USB_COMP_A_DP")
	)
	(segment
		(start 116.732812 -28.704032)
		(end 116.477034 -28.704032)
		(width 0.1651)
		(layer "F.Cu")
		(net "USB_COMP_A_DP")
	)
	(segment
		(start 117.827552 -32.245808)
		(end 117.827806 -32.245808)
		(width 0.1651)
		(layer "F.Cu")
		(net "USB_COMP_A_DP")
	)
	(segment
		(start 143.821912 -34.202878)
		(end 133.635242 -32.198818)
		(width 0.1651)
		(layer "F.Cu")
		(net "USB_COMP_A_DP")
	)
	(segment
		(start 133.635242 -32.198818)
		(end 125.754892 -33.80613)
		(width 0.1651)
		(layer "F.Cu")
		(net "USB_COMP_A_DP")
	)
	(segment
		(start 245.615714 -100.45573)
		(end 245.615968 -100.454714)
		(width 0.1651)
		(layer "F.Cu")
		(net "USB_COMP_A_DP")
	)
	(segment
		(start 182.409592 -31.357824)
		(end 169.220134 -34.047938)
		(width 0.1651)
		(layer "F.Cu")
		(net "USB_COMP_A_DP")
	)
	(segment
		(start 245.775988 -99.748848)
		(end 245.885208 -99.266756)
		(width 0.1651)
		(layer "F.Cu")
		(net "USB_COMP_A_DP")
	)
	(arc
		(start 241.271806 -107.8611)
		(mid 241.354508 -107.956589)
		(end 241.345466 -108.082588)
		(width 0.1651)
		(layer "F.Cu")
		(net "USB_COMP_A_DP")
	)
	(arc
		(start 117.39626 -29.36748)
		(mid 117.201941 -28.898351)
		(end 116.732812 -28.704032)
		(width 0.1651)
		(layer "F.Cu")
		(net "USB_COMP_A_DP")
	)
	(arc
		(start 241.21999 -108.255054)
		(mid 241.090989 -108.609042)
		(end 241.240056 -108.955078)
		(width 0.1651)
		(layer "F.Cu")
		(net "USB_COMP_A_DP")
	)
	(arc
		(start 116.477034 -28.704032)
		(mid 116.387231 -28.666835)
		(end 116.350034 -28.577032)
		(width 0.1651)
		(layer "F.Cu")
		(net "USB_COMP_A_DP")
	)
	(segment
		(start 229.525576 -86.68639)
		(end 226.795076 -82.40268)
		(width 0.1651)
		(layer "F.Cu")
		(net "USB_COMP_A_DN")
	)
	(segment
		(start 226.637342 -82.367628)
		(end 226.37115 -81.950052)
		(width 0.1651)
		(layer "F.Cu")
		(net "USB_COMP_A_DN")
	)
	(segment
		(start 242.212622 -94.744794)
		(end 242.064286 -94.80931)
		(width 0.1651)
		(layer "F.Cu")
		(net "USB_COMP_A_DN")
	)
	(segment
		(start 233.687112 -91.402662)
		(end 233.53903 -91.467432)
		(width 0.1651)
		(layer "F.Cu")
		(net "USB_COMP_A_DN")
	)
	(segment
		(start 231.880664 -90.381328)
		(end 231.72293 -90.346276)
		(width 0.1651)
		(layer "F.Cu")
		(net "USB_COMP_A_DN")
	)
	(segment
		(start 230.41229 -88.290146)
		(end 230.146098 -87.872316)
		(width 0.1651)
		(layer "F.Cu")
		(net "USB_COMP_A_DN")
	)
	(segment
		(start 182.410608 -31.655766)
		(end 169.22115 -34.34588)
		(width 0.1651)
		(layer "F.Cu")
		(net "USB_COMP_A_DN")
	)
	(segment
		(start 226.406202 -81.792318)
		(end 226.139756 -81.374488)
		(width 0.1651)
		(layer "F.Cu")
		(net "USB_COMP_A_DN")
	)
	(segment
		(start 241.447066 -108.748576)
		(end 242.272566 -109.574076)
		(width 0.1651)
		(layer "F.Cu")
		(net "USB_COMP_A_DN")
	)
	(segment
		(start 229.914704 -87.297006)
		(end 229.75697 -87.261954)
		(width 0.1651)
		(layer "F.Cu")
		(net "USB_COMP_A_DN")
	)
	(segment
		(start 245.084346 -100.95992)
		(end 245.221252 -100.87356)
		(width 0.1651)
		(layer "F.Cu")
		(net "USB_COMP_A_DN")
	)
	(segment
		(start 245.599966 -99.201478)
		(end 245.51386 -99.064826)
		(width 0.1651)
		(layer "F.Cu")
		(net "USB_COMP_A_DN")
	)
	(segment
		(start 243.199412 -95.254318)
		(end 242.738402 -95.073724)
		(width 0.1651)
		(layer "F.Cu")
		(net "USB_COMP_A_DN")
	)
	(segment
		(start 241.637566 -108.177838)
		(end 241.447066 -108.44022)
		(width 0.1651)
		(layer "F.Cu")
		(net "USB_COMP_A_DN")
	)
	(segment
		(start 234.674156 -91.91244)
		(end 234.212892 -91.731592)
		(width 0.1651)
		(layer "F.Cu")
		(net "USB_COMP_A_DN")
	)
	(segment
		(start 233.53903 -91.467432)
		(end 233.077766 -91.286584)
		(width 0.1651)
		(layer "F.Cu")
		(net "USB_COMP_A_DN")
	)
	(segment
		(start 235.957364 -92.292678)
		(end 235.809282 -92.357448)
		(width 0.1651)
		(layer "F.Cu")
		(net "USB_COMP_A_DN")
	)
	(segment
		(start 244.334538 -95.699326)
		(end 243.873528 -95.518478)
		(width 0.1651)
		(layer "F.Cu")
		(net "USB_COMP_A_DN")
	)
	(segment
		(start 244.943884 -95.815404)
		(end 244.482874 -95.634556)
		(width 0.1651)
		(layer "F.Cu")
		(net "USB_COMP_A_DN")
	)
	(segment
		(start 229.490778 -86.844378)
		(end 229.525576 -86.68639)
		(width 0.1651)
		(layer "F.Cu")
		(net "USB_COMP_A_DN")
	)
	(segment
		(start 142.814294 -34.302446)
		(end 136.153906 -32.99206)
		(width 0.1651)
		(layer "F.Cu")
		(net "USB_COMP_A_DN")
	)
	(segment
		(start 117.658388 -32.510476)
		(end 117.103906 -31.744412)
		(width 0.1651)
		(layer "F.Cu")
		(net "USB_COMP_A_DN")
	)
	(segment
		(start 225.750882 -80.764126)
		(end 208.376266 -53.504338)
		(width 0.1651)
		(layer "F.Cu")
		(net "USB_COMP_A_DN")
	)
	(segment
		(start 242.272566 -109.574076)
		(end 242.75034 -109.574076)
		(width 0.1651)
		(layer "F.Cu")
		(net "USB_COMP_A_DN")
	)
	(segment
		(start 200.481438 -41.118028)
		(end 187.43295 -32.644334)
		(width 0.1651)
		(layer "F.Cu")
		(net "USB_COMP_A_DN")
	)
	(segment
		(start 242.738402 -95.073724)
		(end 242.673632 -94.925388)
		(width 0.1651)
		(layer "F.Cu")
		(net "USB_COMP_A_DN")
	)
	(segment
		(start 230.146098 -87.872316)
		(end 230.180896 -87.714582)
		(width 0.1651)
		(layer "F.Cu")
		(net "USB_COMP_A_DN")
	)
	(segment
		(start 232.146856 -90.798904)
		(end 231.880664 -90.381328)
		(width 0.1651)
		(layer "F.Cu")
		(net "USB_COMP_A_DN")
	)
	(segment
		(start 117.10416 -29.817822)
		(end 117.10416 -29.36748)
		(width 0.1651)
		(layer "F.Cu")
		(net "USB_COMP_A_DN")
	)
	(segment
		(start 245.061232 -101.57968)
		(end 244.974872 -101.443028)
		(width 0.1651)
		(layer "F.Cu")
		(net "USB_COMP_A_DN")
	)
	(segment
		(start 241.603276 -94.628716)
		(end 241.538506 -94.480634)
		(width 0.1651)
		(layer "F.Cu")
		(net "USB_COMP_A_DN")
	)
	(segment
		(start 243.808758 -95.370396)
		(end 243.347748 -95.189802)
		(width 0.1651)
		(layer "F.Cu")
		(net "USB_COMP_A_DN")
	)
	(segment
		(start 241.637566 -108.170472)
		(end 241.637566 -108.177838)
		(width 0.1651)
		(layer "F.Cu")
		(net "USB_COMP_A_DN")
	)
	(segment
		(start 233.01325 -91.138502)
		(end 232.146856 -90.798904)
		(width 0.1651)
		(layer "F.Cu")
		(net "USB_COMP_A_DN")
	)
	(segment
		(start 234.148376 -91.58351)
		(end 233.687112 -91.402662)
		(width 0.1651)
		(layer "F.Cu")
		(net "USB_COMP_A_DN")
	)
	(segment
		(start 245.51386 -99.064826)
		(end 245.623334 -98.581718)
		(width 0.1651)
		(layer "F.Cu")
		(net "USB_COMP_A_DN")
	)
	(segment
		(start 226.37115 -81.950052)
		(end 226.406202 -81.792318)
		(width 0.1651)
		(layer "F.Cu")
		(net "USB_COMP_A_DN")
	)
	(segment
		(start 244.974872 -101.443028)
		(end 245.084346 -100.95992)
		(width 0.1651)
		(layer "F.Cu")
		(net "USB_COMP_A_DN")
	)
	(segment
		(start 226.139756 -81.374488)
		(end 225.982022 -81.33969)
		(width 0.1651)
		(layer "F.Cu")
		(net "USB_COMP_A_DN")
	)
	(segment
		(start 244.791738 -102.768654)
		(end 244.705632 -102.632002)
		(width 0.1651)
		(layer "F.Cu")
		(net "USB_COMP_A_DN")
	)
	(segment
		(start 234.212892 -91.731592)
		(end 234.148376 -91.58351)
		(width 0.1651)
		(layer "F.Cu")
		(net "USB_COMP_A_DN")
	)
	(segment
		(start 245.221252 -100.87356)
		(end 245.330726 -100.390706)
		(width 0.1651)
		(layer "F.Cu")
		(net "USB_COMP_A_DN")
	)
	(segment
		(start 208.376012 -53.504338)
		(end 204.428598 -47.310802)
		(width 0.1651)
		(layer "F.Cu")
		(net "USB_COMP_A_DN")
	)
	(segment
		(start 208.376266 -53.504338)
		(end 208.376012 -53.504338)
		(width 0.1651)
		(layer "F.Cu")
		(net "USB_COMP_A_DN")
	)
	(segment
		(start 229.75697 -87.261954)
		(end 229.490778 -86.844378)
		(width 0.1651)
		(layer "F.Cu")
		(net "USB_COMP_A_DN")
	)
	(segment
		(start 242.673632 -94.925388)
		(end 242.212622 -94.744794)
		(width 0.1651)
		(layer "F.Cu")
		(net "USB_COMP_A_DN")
	)
	(segment
		(start 245.490492 -99.684586)
		(end 245.599712 -99.202494)
		(width 0.1651)
		(layer "F.Cu")
		(net "USB_COMP_A_DN")
	)
	(segment
		(start 245.880128 -97.965006)
		(end 245.338854 -96.137222)
		(width 0.1651)
		(layer "F.Cu")
		(net "USB_COMP_A_DN")
	)
	(segment
		(start 169.22115 -34.34588)
		(end 156.679646 -31.87827)
		(width 0.1651)
		(layer "F.Cu")
		(net "USB_COMP_A_DN")
	)
	(segment
		(start 245.330726 -100.390706)
		(end 245.244366 -100.2538)
		(width 0.1651)
		(layer "F.Cu")
		(net "USB_COMP_A_DN")
	)
	(segment
		(start 243.873528 -95.518478)
		(end 243.808758 -95.370396)
		(width 0.1651)
		(layer "F.Cu")
		(net "USB_COMP_A_DN")
	)
	(segment
		(start 230.570024 -88.324944)
		(end 230.41229 -88.290146)
		(width 0.1651)
		(layer "F.Cu")
		(net "USB_COMP_A_DN")
	)
	(segment
		(start 240.929414 -94.364556)
		(end 240.46815 -94.183708)
		(width 0.1651)
		(layer "F.Cu")
		(net "USB_COMP_A_DN")
	)
	(segment
		(start 116.732812 -28.996132)
		(end 116.477034 -28.996132)
		(width 0.1651)
		(layer "F.Cu")
		(net "USB_COMP_A_DN")
	)
	(segment
		(start 231.456484 -89.9287)
		(end 231.491536 -89.770712)
		(width 0.1651)
		(layer "F.Cu")
		(net "USB_COMP_A_DN")
	)
	(segment
		(start 245.599712 -99.202494)
		(end 245.599966 -99.201478)
		(width 0.1651)
		(layer "F.Cu")
		(net "USB_COMP_A_DN")
	)
	(segment
		(start 235.348018 -92.1766)
		(end 235.283502 -92.028518)
		(width 0.1651)
		(layer "F.Cu")
		(net "USB_COMP_A_DN")
	)
	(segment
		(start 156.679646 -31.87827)
		(end 143.822928 -34.50082)
		(width 0.1651)
		(layer "F.Cu")
		(net "USB_COMP_A_DN")
	)
	(segment
		(start 234.822238 -91.84767)
		(end 234.674156 -91.91244)
		(width 0.1651)
		(layer "F.Cu")
		(net "USB_COMP_A_DN")
	)
	(segment
		(start 235.283502 -92.028518)
		(end 234.822238 -91.84767)
		(width 0.1651)
		(layer "F.Cu")
		(net "USB_COMP_A_DN")
	)
	(segment
		(start 204.428598 -47.310802)
		(end 200.481438 -41.118028)
		(width 0.1651)
		(layer "F.Cu")
		(net "USB_COMP_A_DN")
	)
	(segment
		(start 230.836216 -88.742774)
		(end 230.570024 -88.324944)
		(width 0.1651)
		(layer "F.Cu")
		(net "USB_COMP_A_DN")
	)
	(segment
		(start 143.822928 -34.50082)
		(end 142.814294 -34.302446)
		(width 0.1651)
		(layer "F.Cu")
		(net "USB_COMP_A_DN")
	)
	(segment
		(start 225.982022 -81.33969)
		(end 225.71583 -80.92186)
		(width 0.1651)
		(layer "F.Cu")
		(net "USB_COMP_A_DN")
	)
	(segment
		(start 133.636258 -32.49676)
		(end 125.755908 -34.104072)
		(width 0.1651)
		(layer "F.Cu")
		(net "USB_COMP_A_DN")
	)
	(segment
		(start 245.35384 -99.770946)
		(end 245.490492 -99.684586)
		(width 0.1651)
		(layer "F.Cu")
		(net "USB_COMP_A_DN")
	)
	(segment
		(start 243.337842 -109.185456)
		(end 243.338096 -109.18444)
		(width 0.1651)
		(layer "F.Cu")
		(net "USB_COMP_A_DN")
	)
	(segment
		(start 116.350034 -29.123132)
		(end 116.350034 -29.550106)
		(width 0.1651)
		(layer "F.Cu")
		(net "USB_COMP_A_DN")
	)
	(segment
		(start 244.951758 -102.062788)
		(end 245.061232 -101.57968)
		(width 0.1651)
		(layer "F.Cu")
		(net "USB_COMP_A_DN")
	)
	(segment
		(start 242.064286 -94.80931)
		(end 241.603276 -94.628716)
		(width 0.1651)
		(layer "F.Cu")
		(net "USB_COMP_A_DN")
	)
	(segment
		(start 231.225344 -89.353136)
		(end 231.06761 -89.318084)
		(width 0.1651)
		(layer "F.Cu")
		(net "USB_COMP_A_DN")
	)
	(segment
		(start 233.077766 -91.286584)
		(end 233.01325 -91.138502)
		(width 0.1651)
		(layer "F.Cu")
		(net "USB_COMP_A_DN")
	)
	(segment
		(start 230.801164 -88.900508)
		(end 230.836216 -88.742774)
		(width 0.1651)
		(layer "F.Cu")
		(net "USB_COMP_A_DN")
	)
	(segment
		(start 226.795076 -82.40268)
		(end 226.637342 -82.367628)
		(width 0.1651)
		(layer "F.Cu")
		(net "USB_COMP_A_DN")
	)
	(segment
		(start 245.623334 -98.581718)
		(end 245.759986 -98.495612)
		(width 0.1651)
		(layer "F.Cu")
		(net "USB_COMP_A_DN")
	)
	(segment
		(start 243.347748 -95.189802)
		(end 243.199412 -95.254318)
		(width 0.1651)
		(layer "F.Cu")
		(net "USB_COMP_A_DN")
	)
	(segment
		(start 244.705632 -102.632002)
		(end 244.815106 -102.148894)
		(width 0.1651)
		(layer "F.Cu")
		(net "USB_COMP_A_DN")
	)
	(segment
		(start 231.72293 -90.346276)
		(end 231.456484 -89.9287)
		(width 0.1651)
		(layer "F.Cu")
		(net "USB_COMP_A_DN")
	)
	(segment
		(start 245.338854 -96.137222)
		(end 244.943884 -95.815404)
		(width 0.1651)
		(layer "F.Cu")
		(net "USB_COMP_A_DN")
	)
	(segment
		(start 225.71583 -80.92186)
		(end 225.750882 -80.764126)
		(width 0.1651)
		(layer "F.Cu")
		(net "USB_COMP_A_DN")
	)
	(segment
		(start 241.538506 -94.480634)
		(end 241.077496 -94.299786)
		(width 0.1651)
		(layer "F.Cu")
		(net "USB_COMP_A_DN")
	)
	(segment
		(start 117.103906 -29.818076)
		(end 117.10416 -29.817822)
		(width 0.1651)
		(layer "F.Cu")
		(net "USB_COMP_A_DN")
	)
	(segment
		(start 235.809282 -92.357448)
		(end 235.348018 -92.1766)
		(width 0.1651)
		(layer "F.Cu")
		(net "USB_COMP_A_DN")
	)
	(segment
		(start 245.244366 -100.2538)
		(end 245.35384 -99.770946)
		(width 0.1651)
		(layer "F.Cu")
		(net "USB_COMP_A_DN")
	)
	(segment
		(start 245.759986 -98.495612)
		(end 245.880128 -97.965006)
		(width 0.1651)
		(layer "F.Cu")
		(net "USB_COMP_A_DN")
	)
	(segment
		(start 136.153906 -32.99206)
		(end 133.636258 -32.49676)
		(width 0.1651)
		(layer "F.Cu")
		(net "USB_COMP_A_DN")
	)
	(segment
		(start 240.40338 -94.035626)
		(end 235.957364 -92.292678)
		(width 0.1651)
		(layer "F.Cu")
		(net "USB_COMP_A_DN")
	)
	(segment
		(start 230.180896 -87.714582)
		(end 229.914704 -87.297006)
		(width 0.1651)
		(layer "F.Cu")
		(net "USB_COMP_A_DN")
	)
	(segment
		(start 242.75034 -109.574076)
		(end 243.337842 -109.185964)
		(width 0.1651)
		(layer "F.Cu")
		(net "USB_COMP_A_DN")
	)
	(segment
		(start 241.077496 -94.299786)
		(end 240.929414 -94.364556)
		(width 0.1651)
		(layer "F.Cu")
		(net "USB_COMP_A_DN")
	)
	(segment
		(start 231.491536 -89.770712)
		(end 231.225344 -89.353136)
		(width 0.1651)
		(layer "F.Cu")
		(net "USB_COMP_A_DN")
	)
	(segment
		(start 244.482874 -95.634556)
		(end 244.334538 -95.699326)
		(width 0.1651)
		(layer "F.Cu")
		(net "USB_COMP_A_DN")
	)
	(segment
		(start 117.103906 -31.744412)
		(end 117.103906 -29.818076)
		(width 0.1651)
		(layer "F.Cu")
		(net "USB_COMP_A_DN")
	)
	(segment
		(start 231.06761 -89.318084)
		(end 230.801164 -88.900508)
		(width 0.1651)
		(layer "F.Cu")
		(net "USB_COMP_A_DN")
	)
	(segment
		(start 244.815106 -102.148894)
		(end 244.951758 -102.062788)
		(width 0.1651)
		(layer "F.Cu")
		(net "USB_COMP_A_DN")
	)
	(segment
		(start 187.43295 -32.644334)
		(end 182.410608 -31.655766)
		(width 0.1651)
		(layer "F.Cu")
		(net "USB_COMP_A_DN")
	)
	(segment
		(start 243.337842 -109.185964)
		(end 243.337842 -109.185456)
		(width 0.1651)
		(layer "F.Cu")
		(net "USB_COMP_A_DN")
	)
	(segment
		(start 242.549934 -108.49991)
		(end 241.828574 -108.138976)
		(width 0.1651)
		(layer "F.Cu")
		(net "USB_COMP_A_DN")
	)
	(segment
		(start 240.46815 -94.183708)
		(end 240.40338 -94.035626)
		(width 0.1651)
		(layer "F.Cu")
		(net "USB_COMP_A_DN")
	)
	(segment
		(start 243.338096 -109.18444)
		(end 244.791738 -102.768654)
		(width 0.1651)
		(layer "F.Cu")
		(net "USB_COMP_A_DN")
	)
	(segment
		(start 125.755908 -34.104072)
		(end 117.658388 -32.510476)
		(width 0.1651)
		(layer "F.Cu")
		(net "USB_COMP_A_DN")
	)
	(arc
		(start 117.10416 -29.36748)
		(mid 116.995395 -29.104897)
		(end 116.732812 -28.996132)
		(width 0.1651)
		(layer "F.Cu")
		(net "USB_COMP_A_DN")
	)
	(arc
		(start 241.447066 -108.44022)
		(mid 241.383203 -108.594398)
		(end 241.447066 -108.748576)
		(width 0.1651)
		(layer "F.Cu")
		(net "USB_COMP_A_DN")
	)
	(arc
		(start 116.477034 -28.996132)
		(mid 116.387231 -29.033329)
		(end 116.350034 -29.123132)
		(width 0.1651)
		(layer "F.Cu")
		(net "USB_COMP_A_DN")
	)
	(arc
		(start 241.828574 -108.138976)
		(mid 241.727995 -108.123825)
		(end 241.637566 -108.170472)
		(width 0.1651)
		(layer "F.Cu")
		(net "USB_COMP_A_DN")
	)
	(segment
		(start 248.085102 31.074868)
		(end 248.085102 29.35478)
		(width 0.17145)
		(layer "F.Cu")
		(net "UART_IOC_A_TX")
	)
	(via
		(at 263.469628 -252.737112)
		(size 0.5588)
		(drill 0.3048)
		(layers "F.Cu" "B.Cu")
		(net "UART_IOC_A_TX")
	)
	(via
		(at 270.63065 -257.368294)
		(size 0.6096)
		(drill 0.3048)
		(layers "F.Cu" "B.Cu")
		(net "UART_IOC_A_TX")
	)
	(via
		(at 248.085102 29.35478)
		(size 0.5588)
		(drill 0.3048)
		(layers "F.Cu" "B.Cu")
		(net "UART_IOC_A_TX")
	)
	(segment
		(start 284.236668 -256.502408)
		(end 283.370782 -257.368294)
		(width 0.17145)
		(layer "B.Cu")
		(net "UART_IOC_A_TX")
	)
	(segment
		(start 266.300966 -257.368294)
		(end 270.63065 -257.368294)
		(width 0.17145)
		(layer "B.Cu")
		(net "UART_IOC_A_TX")
	)
	(segment
		(start 263.469628 -254.536956)
		(end 266.300966 -257.368294)
		(width 0.17145)
		(layer "B.Cu")
		(net "UART_IOC_A_TX")
	)
	(segment
		(start 263.469628 -252.737112)
		(end 263.469628 -254.536956)
		(width 0.17145)
		(layer "B.Cu")
		(net "UART_IOC_A_TX")
	)
	(segment
		(start 283.370782 -257.368294)
		(end 270.63065 -257.368294)
		(width 0.17145)
		(layer "B.Cu")
		(net "UART_IOC_A_TX")
	)
	(segment
		(start 263.911842 -202.896216)
		(end 263.911842 -132.521706)
		(width 0.12065)
		(layer "In4.Cu")
		(net "UART_IOC_A_TX")
	)
	(segment
		(start 262.640572 11.882882)
		(end 261.7343 12.789154)
		(width 0.12065)
		(layer "In4.Cu")
		(net "UART_IOC_A_TX")
	)
	(segment
		(start 265.012424 -238.201454)
		(end 271.02689 -232.186988)
		(width 0.12065)
		(layer "In4.Cu")
		(net "UART_IOC_A_TX")
	)
	(segment
		(start 263.659112 -18.612612)
		(end 263.659112 3.80238)
		(width 0.12065)
		(layer "In4.Cu")
		(net "UART_IOC_A_TX")
	)
	(segment
		(start 263.469628 -252.737112)
		(end 265.012424 -251.194316)
		(width 0.12065)
		(layer "In4.Cu")
		(net "UART_IOC_A_TX")
	)
	(segment
		(start 263.911842 -132.521706)
		(end 261.02945 -129.639314)
		(width 0.12065)
		(layer "In4.Cu")
		(net "UART_IOC_A_TX")
	)
	(segment
		(start 266.227814 -21.181314)
		(end 263.659112 -18.612612)
		(width 0.12065)
		(layer "In4.Cu")
		(net "UART_IOC_A_TX")
	)
	(segment
		(start 249.729498 27.710384)
		(end 248.085102 29.35478)
		(width 0.12065)
		(layer "In4.Cu")
		(net "UART_IOC_A_TX")
	)
	(segment
		(start 271.02689 -232.186988)
		(end 271.02689 -210.011264)
		(width 0.12065)
		(layer "In4.Cu")
		(net "UART_IOC_A_TX")
	)
	(segment
		(start 261.02945 -41.073578)
		(end 266.227814 -35.875214)
		(width 0.12065)
		(layer "In4.Cu")
		(net "UART_IOC_A_TX")
	)
	(segment
		(start 271.02689 -210.011264)
		(end 263.911842 -202.896216)
		(width 0.12065)
		(layer "In4.Cu")
		(net "UART_IOC_A_TX")
	)
	(segment
		(start 266.227814 -35.875214)
		(end 266.227814 -21.181314)
		(width 0.12065)
		(layer "In4.Cu")
		(net "UART_IOC_A_TX")
	)
	(segment
		(start 252.909324 27.710384)
		(end 249.729498 27.710384)
		(width 0.12065)
		(layer "In4.Cu")
		(net "UART_IOC_A_TX")
	)
	(segment
		(start 261.7343 18.885408)
		(end 252.909324 27.710384)
		(width 0.12065)
		(layer "In4.Cu")
		(net "UART_IOC_A_TX")
	)
	(segment
		(start 261.7343 12.789154)
		(end 261.7343 18.885408)
		(width 0.12065)
		(layer "In4.Cu")
		(net "UART_IOC_A_TX")
	)
	(segment
		(start 262.640572 4.82092)
		(end 262.640572 11.882882)
		(width 0.12065)
		(layer "In4.Cu")
		(net "UART_IOC_A_TX")
	)
	(segment
		(start 263.659112 3.80238)
		(end 262.640572 4.82092)
		(width 0.12065)
		(layer "In4.Cu")
		(net "UART_IOC_A_TX")
	)
	(segment
		(start 261.02945 -129.639314)
		(end 261.02945 -41.073578)
		(width 0.12065)
		(layer "In4.Cu")
		(net "UART_IOC_A_TX")
	)
	(segment
		(start 265.012424 -251.194316)
		(end 265.012424 -238.201454)
		(width 0.12065)
		(layer "In4.Cu")
		(net "UART_IOC_A_TX")
	)
	(segment
		(start 249.355102 29.340302)
		(end 249.355102 31.074868)
		(width 0.17145)
		(layer "F.Cu")
		(net "UART_IOC_A_RX")
	)
	(segment
		(start 249.3518 29.337)
		(end 249.355102 29.340302)
		(width 0.17145)
		(layer "F.Cu")
		(net "UART_IOC_A_RX")
	)
	(via
		(at 249.3518 29.337)
		(size 0.5588)
		(drill 0.3048)
		(layers "F.Cu" "B.Cu")
		(net "UART_IOC_A_RX")
	)
	(via
		(at 268.193774 -255.632712)
		(size 0.6096)
		(drill 0.3048)
		(layers "F.Cu" "B.Cu")
		(net "UART_IOC_A_RX")
	)
	(via
		(at 264.570464 -253.29515)
		(size 0.5588)
		(drill 0.3048)
		(layers "F.Cu" "B.Cu")
		(net "UART_IOC_A_RX")
	)
	(segment
		(start 264.570464 -253.29515)
		(end 266.908026 -255.632712)
		(width 0.17145)
		(layer "B.Cu")
		(net "UART_IOC_A_RX")
	)
	(segment
		(start 281.966924 -255.632712)
		(end 268.193774 -255.632712)
		(width 0.17145)
		(layer "B.Cu")
		(net "UART_IOC_A_RX")
	)
	(segment
		(start 282.83662 -256.502408)
		(end 281.966924 -255.632712)
		(width 0.17145)
		(layer "B.Cu")
		(net "UART_IOC_A_RX")
	)
	(segment
		(start 266.908026 -255.632712)
		(end 268.193774 -255.632712)
		(width 0.17145)
		(layer "B.Cu")
		(net "UART_IOC_A_RX")
	)
	(segment
		(start 261.6581 -41.334436)
		(end 267.180822 -35.811714)
		(width 0.12065)
		(layer "In4.Cu")
		(net "UART_IOC_A_RX")
	)
	(segment
		(start 264.540492 -202.635612)
		(end 264.540492 -132.147056)
		(width 0.12065)
		(layer "In4.Cu")
		(net "UART_IOC_A_RX")
	)
	(segment
		(start 264.540492 -132.147056)
		(end 261.6581 -129.264664)
		(width 0.12065)
		(layer "In4.Cu")
		(net "UART_IOC_A_RX")
	)
	(segment
		(start 271.65554 -209.75066)
		(end 264.540492 -202.635612)
		(width 0.12065)
		(layer "In4.Cu")
		(net "UART_IOC_A_RX")
	)
	(segment
		(start 267.180822 -35.811714)
		(end 267.180822 -20.916646)
		(width 0.12065)
		(layer "In4.Cu")
		(net "UART_IOC_A_RX")
	)
	(segment
		(start 253.169928 28.339034)
		(end 250.349766 28.339034)
		(width 0.12065)
		(layer "In4.Cu")
		(net "UART_IOC_A_RX")
	)
	(segment
		(start 265.82751 -252.038104)
		(end 265.82751 -238.275622)
		(width 0.12065)
		(layer "In4.Cu")
		(net "UART_IOC_A_RX")
	)
	(segment
		(start 263.269222 5.081524)
		(end 263.269222 12.143486)
		(width 0.12065)
		(layer "In4.Cu")
		(net "UART_IOC_A_RX")
	)
	(segment
		(start 262.36295 19.146012)
		(end 253.169928 28.339034)
		(width 0.12065)
		(layer "In4.Cu")
		(net "UART_IOC_A_RX")
	)
	(segment
		(start 264.570464 -253.29515)
		(end 265.82751 -252.038104)
		(width 0.12065)
		(layer "In4.Cu")
		(net "UART_IOC_A_RX")
	)
	(segment
		(start 271.65554 -232.447592)
		(end 271.65554 -209.75066)
		(width 0.12065)
		(layer "In4.Cu")
		(net "UART_IOC_A_RX")
	)
	(segment
		(start 250.349766 28.339034)
		(end 249.3518 29.337)
		(width 0.12065)
		(layer "In4.Cu")
		(net "UART_IOC_A_RX")
	)
	(segment
		(start 262.36295 13.049758)
		(end 262.36295 19.146012)
		(width 0.12065)
		(layer "In4.Cu")
		(net "UART_IOC_A_RX")
	)
	(segment
		(start 264.397744 3.953002)
		(end 263.269222 5.081524)
		(width 0.12065)
		(layer "In4.Cu")
		(net "UART_IOC_A_RX")
	)
	(segment
		(start 264.397744 -18.133568)
		(end 264.397744 3.953002)
		(width 0.12065)
		(layer "In4.Cu")
		(net "UART_IOC_A_RX")
	)
	(segment
		(start 265.82751 -238.275622)
		(end 271.65554 -232.447592)
		(width 0.12065)
		(layer "In4.Cu")
		(net "UART_IOC_A_RX")
	)
	(segment
		(start 261.6581 -129.264664)
		(end 261.6581 -41.334436)
		(width 0.12065)
		(layer "In4.Cu")
		(net "UART_IOC_A_RX")
	)
	(segment
		(start 263.269222 12.143486)
		(end 262.36295 13.049758)
		(width 0.12065)
		(layer "In4.Cu")
		(net "UART_IOC_A_RX")
	)
	(segment
		(start 267.180822 -20.916646)
		(end 264.397744 -18.133568)
		(width 0.12065)
		(layer "In4.Cu")
		(net "UART_IOC_A_RX")
	)
	(segment
		(start 274.755102 31.074868)
		(end 274.755102 29.35478)
		(width 0.17145)
		(layer "F.Cu")
		(net "UART_EXP_B_TX")
	)
	(via
		(at 198.68642 -336.21218)
		(size 0.5588)
		(drill 0.3048)
		(layers "F.Cu" "B.Cu")
		(net "UART_EXP_B_TX")
	)
	(via
		(at 272.2753 -115.135152)
		(size 0.5588)
		(drill 0.3048)
		(layers "F.Cu" "B.Cu")
		(net "UART_EXP_B_TX")
	)
	(via
		(at 274.755102 29.35478)
		(size 0.5588)
		(drill 0.3048)
		(layers "F.Cu" "B.Cu")
		(net "UART_EXP_B_TX")
	)
	(segment
		(start 271.065752 9.415526)
		(end 271.729962 10.079736)
		(width 0.12065)
		(layer "In4.Cu")
		(net "UART_EXP_B_TX")
	)
	(segment
		(start 272.2753 -88.913208)
		(end 272.2753 -20.659852)
		(width 0.12065)
		(layer "In4.Cu")
		(net "UART_EXP_B_TX")
	)
	(segment
		(start 272.2753 -20.659852)
		(end 271.065752 -19.450304)
		(width 0.12065)
		(layer "In4.Cu")
		(net "UART_EXP_B_TX")
	)
	(segment
		(start 275.907246 -107.657646)
		(end 275.907246 -92.545154)
		(width 0.12065)
		(layer "In4.Cu")
		(net "UART_EXP_B_TX")
	)
	(segment
		(start 275.907246 -92.545154)
		(end 272.2753 -88.913208)
		(width 0.12065)
		(layer "In4.Cu")
		(net "UART_EXP_B_TX")
	)
	(segment
		(start 273.776948 28.376372)
		(end 274.755102 29.354526)
		(width 0.12065)
		(layer "In4.Cu")
		(net "UART_EXP_B_TX")
	)
	(segment
		(start 273.776948 17.8562)
		(end 273.776948 28.376372)
		(width 0.12065)
		(layer "In4.Cu")
		(net "UART_EXP_B_TX")
	)
	(segment
		(start 271.729962 10.079736)
		(end 271.729962 15.809214)
		(width 0.12065)
		(layer "In4.Cu")
		(net "UART_EXP_B_TX")
	)
	(segment
		(start 274.755102 29.354526)
		(end 274.755102 29.35478)
		(width 0.12065)
		(layer "In4.Cu")
		(net "UART_EXP_B_TX")
	)
	(segment
		(start 271.065752 -19.450304)
		(end 271.065752 9.415526)
		(width 0.12065)
		(layer "In4.Cu")
		(net "UART_EXP_B_TX")
	)
	(segment
		(start 271.729962 15.809214)
		(end 273.776948 17.8562)
		(width 0.12065)
		(layer "In4.Cu")
		(net "UART_EXP_B_TX")
	)
	(segment
		(start 272.2753 -115.135152)
		(end 272.2753 -111.289592)
		(width 0.12065)
		(layer "In4.Cu")
		(net "UART_EXP_B_TX")
	)
	(segment
		(start 272.2753 -111.289592)
		(end 275.907246 -107.657646)
		(width 0.12065)
		(layer "In4.Cu")
		(net "UART_EXP_B_TX")
	)
	(segment
		(start 210.6676 -350.797622)
		(end 197.77964 -337.909662)
		(width 0.12065)
		(layer "In7.Cu")
		(net "UART_EXP_B_TX")
	)
	(segment
		(start 198.55942 -336.21218)
		(end 198.68642 -336.21218)
		(width 0.12065)
		(layer "In7.Cu")
		(net "UART_EXP_B_TX")
	)
	(segment
		(start 212.71865 -396.06093)
		(end 212.71865 -387.86054)
		(width 0.12065)
		(layer "In7.Cu")
		(net "UART_EXP_B_TX")
	)
	(segment
		(start 219.70492 -418.11702)
		(end 219.70492 -403.0472)
		(width 0.12065)
		(layer "In7.Cu")
		(net "UART_EXP_B_TX")
	)
	(segment
		(start 197.77964 -337.909662)
		(end 197.77964 -336.99196)
		(width 0.12065)
		(layer "In7.Cu")
		(net "UART_EXP_B_TX")
	)
	(segment
		(start 219.70492 -403.0472)
		(end 212.71865 -396.06093)
		(width 0.12065)
		(layer "In7.Cu")
		(net "UART_EXP_B_TX")
	)
	(segment
		(start 220.800168 -419.200076)
		(end 220.787976 -419.200076)
		(width 0.12065)
		(layer "In7.Cu")
		(net "UART_EXP_B_TX")
	)
	(segment
		(start 220.787976 -419.200076)
		(end 219.70492 -418.11702)
		(width 0.12065)
		(layer "In7.Cu")
		(net "UART_EXP_B_TX")
	)
	(segment
		(start 210.6676 -385.80949)
		(end 210.6676 -350.797622)
		(width 0.12065)
		(layer "In7.Cu")
		(net "UART_EXP_B_TX")
	)
	(segment
		(start 197.77964 -336.99196)
		(end 198.55942 -336.21218)
		(width 0.12065)
		(layer "In7.Cu")
		(net "UART_EXP_B_TX")
	)
	(segment
		(start 212.71865 -387.86054)
		(end 210.6676 -385.80949)
		(width 0.12065)
		(layer "In7.Cu")
		(net "UART_EXP_B_TX")
	)
	(segment
		(start 245.60784 -155.740608)
		(end 245.60784 -183.819292)
		(width 0.13335)
		(layer "In9.Cu")
		(net "UART_EXP_B_TX")
	)
	(segment
		(start 204.2541 -271.977866)
		(end 198.689468 -277.542498)
		(width 0.13335)
		(layer "In9.Cu")
		(net "UART_EXP_B_TX")
	)
	(segment
		(start 272.2753 -115.135152)
		(end 272.272252 -115.1382)
		(width 0.13335)
		(layer "In9.Cu")
		(net "UART_EXP_B_TX")
	)
	(segment
		(start 204.2541 -244.09654)
		(end 204.2541 -271.977866)
		(width 0.13335)
		(layer "In9.Cu")
		(net "UART_EXP_B_TX")
	)
	(segment
		(start 241.168936 -192.9892)
		(end 240.8682 -192.9892)
		(width 0.13335)
		(layer "In9.Cu")
		(net "UART_EXP_B_TX")
	)
	(segment
		(start 232.193846 -216.156794)
		(end 204.2541 -244.09654)
		(width 0.13335)
		(layer "In9.Cu")
		(net "UART_EXP_B_TX")
	)
	(segment
		(start 194.767962 -299.419264)
		(end 194.767962 -306.375054)
		(width 0.13335)
		(layer "In9.Cu")
		(net "UART_EXP_B_TX")
	)
	(segment
		(start 255.47955 -145.868898)
		(end 245.60784 -155.740608)
		(width 0.13335)
		(layer "In9.Cu")
		(net "UART_EXP_B_TX")
	)
	(segment
		(start 255.47955 -130.433572)
		(end 255.47955 -145.868898)
		(width 0.13335)
		(layer "In9.Cu")
		(net "UART_EXP_B_TX")
	)
	(segment
		(start 232.193846 -201.663554)
		(end 232.193846 -216.156794)
		(width 0.13335)
		(layer "In9.Cu")
		(net "UART_EXP_B_TX")
	)
	(segment
		(start 198.689468 -277.542498)
		(end 198.689468 -295.497758)
		(width 0.13335)
		(layer "In9.Cu")
		(net "UART_EXP_B_TX")
	)
	(segment
		(start 270.774922 -115.1382)
		(end 255.47955 -130.433572)
		(width 0.13335)
		(layer "In9.Cu")
		(net "UART_EXP_B_TX")
	)
	(segment
		(start 198.689468 -295.497758)
		(end 194.767962 -299.419264)
		(width 0.13335)
		(layer "In9.Cu")
		(net "UART_EXP_B_TX")
	)
	(segment
		(start 240.8682 -192.9892)
		(end 232.193846 -201.663554)
		(width 0.13335)
		(layer "In9.Cu")
		(net "UART_EXP_B_TX")
	)
	(segment
		(start 243.640356 -185.786776)
		(end 243.640356 -190.51778)
		(width 0.13335)
		(layer "In9.Cu")
		(net "UART_EXP_B_TX")
	)
	(segment
		(start 198.689468 -310.29656)
		(end 198.689468 -336.209132)
		(width 0.13335)
		(layer "In9.Cu")
		(net "UART_EXP_B_TX")
	)
	(segment
		(start 272.272252 -115.1382)
		(end 270.774922 -115.1382)
		(width 0.13335)
		(layer "In9.Cu")
		(net "UART_EXP_B_TX")
	)
	(segment
		(start 243.640356 -190.51778)
		(end 241.168936 -192.9892)
		(width 0.13335)
		(layer "In9.Cu")
		(net "UART_EXP_B_TX")
	)
	(segment
		(start 194.767962 -306.375054)
		(end 198.689468 -310.29656)
		(width 0.13335)
		(layer "In9.Cu")
		(net "UART_EXP_B_TX")
	)
	(segment
		(start 198.689468 -336.209132)
		(end 198.68642 -336.21218)
		(width 0.13335)
		(layer "In9.Cu")
		(net "UART_EXP_B_TX")
	)
	(segment
		(start 245.60784 -183.819292)
		(end 243.640356 -185.786776)
		(width 0.13335)
		(layer "In9.Cu")
		(net "UART_EXP_B_TX")
	)
	(segment
		(start 276.025102 31.074868)
		(end 276.025102 29.35478)
		(width 0.17145)
		(layer "F.Cu")
		(net "UART_EXP_B_RX")
	)
	(via
		(at 198.44766 -337.43646)
		(size 0.5588)
		(drill 0.3048)
		(layers "F.Cu" "B.Cu")
		(net "UART_EXP_B_RX")
	)
	(via
		(at 272.90395 -113.59515)
		(size 0.5588)
		(drill 0.3048)
		(layers "F.Cu" "B.Cu")
		(net "UART_EXP_B_RX")
	)
	(via
		(at 276.025102 29.35478)
		(size 0.5588)
		(drill 0.3048)
		(layers "F.Cu" "B.Cu")
		(net "UART_EXP_B_RX")
	)
	(segment
		(start 276.71395 -107.74045)
		(end 276.71395 -92.462604)
		(width 0.12065)
		(layer "In4.Cu")
		(net "UART_EXP_B_RX")
	)
	(segment
		(start 272.90395 -88.652604)
		(end 272.90395 -20.399248)
		(width 0.12065)
		(layer "In4.Cu")
		(net "UART_EXP_B_RX")
	)
	(segment
		(start 276.71395 -92.462604)
		(end 272.90395 -88.652604)
		(width 0.12065)
		(layer "In4.Cu")
		(net "UART_EXP_B_RX")
	)
	(segment
		(start 271.694402 -19.1897)
		(end 271.694402 7.813802)
		(width 0.12065)
		(layer "In4.Cu")
		(net "UART_EXP_B_RX")
	)
	(segment
		(start 273.548348 9.667748)
		(end 273.548348 13.59535)
		(width 0.12065)
		(layer "In4.Cu")
		(net "UART_EXP_B_RX")
	)
	(segment
		(start 273.548348 13.59535)
		(end 274.405598 14.4526)
		(width 0.12065)
		(layer "In4.Cu")
		(net "UART_EXP_B_RX")
	)
	(segment
		(start 271.694402 7.813802)
		(end 273.548348 9.667748)
		(width 0.12065)
		(layer "In4.Cu")
		(net "UART_EXP_B_RX")
	)
	(segment
		(start 272.90395 -20.399248)
		(end 271.694402 -19.1897)
		(width 0.12065)
		(layer "In4.Cu")
		(net "UART_EXP_B_RX")
	)
	(segment
		(start 274.405598 27.735276)
		(end 276.025102 29.35478)
		(width 0.12065)
		(layer "In4.Cu")
		(net "UART_EXP_B_RX")
	)
	(segment
		(start 272.90395 -111.55045)
		(end 276.71395 -107.74045)
		(width 0.12065)
		(layer "In4.Cu")
		(net "UART_EXP_B_RX")
	)
	(segment
		(start 274.405598 14.4526)
		(end 274.405598 27.735276)
		(width 0.12065)
		(layer "In4.Cu")
		(net "UART_EXP_B_RX")
	)
	(segment
		(start 272.90395 -113.59515)
		(end 272.90395 -111.55045)
		(width 0.12065)
		(layer "In4.Cu")
		(net "UART_EXP_B_RX")
	)
	(segment
		(start 220.18117 -417.18103)
		(end 220.18117 -403.244558)
		(width 0.12065)
		(layer "In7.Cu")
		(net "UART_EXP_B_RX")
	)
	(segment
		(start 213.3473 -387.599936)
		(end 211.6836 -385.936236)
		(width 0.12065)
		(layer "In7.Cu")
		(net "UART_EXP_B_RX")
	)
	(segment
		(start 220.181424 -403.244304)
		(end 220.181424 -402.850096)
		(width 0.12065)
		(layer "In7.Cu")
		(net "UART_EXP_B_RX")
	)
	(segment
		(start 220.800168 -417.800028)
		(end 220.18117 -417.18103)
		(width 0.12065)
		(layer "In7.Cu")
		(net "UART_EXP_B_RX")
	)
	(segment
		(start 198.44766 -337.568794)
		(end 198.44766 -337.43646)
		(width 0.12065)
		(layer "In7.Cu")
		(net "UART_EXP_B_RX")
	)
	(segment
		(start 211.6836 -385.936236)
		(end 211.6836 -350.804734)
		(width 0.12065)
		(layer "In7.Cu")
		(net "UART_EXP_B_RX")
	)
	(segment
		(start 220.18117 -402.849842)
		(end 220.18117 -402.571458)
		(width 0.12065)
		(layer "In7.Cu")
		(net "UART_EXP_B_RX")
	)
	(segment
		(start 220.181424 -402.850096)
		(end 220.18117 -402.849842)
		(width 0.12065)
		(layer "In7.Cu")
		(net "UART_EXP_B_RX")
	)
	(segment
		(start 213.3473 -395.737588)
		(end 213.3473 -387.599936)
		(width 0.12065)
		(layer "In7.Cu")
		(net "UART_EXP_B_RX")
	)
	(segment
		(start 211.6836 -350.804734)
		(end 198.44766 -337.568794)
		(width 0.12065)
		(layer "In7.Cu")
		(net "UART_EXP_B_RX")
	)
	(segment
		(start 220.18117 -402.571458)
		(end 213.3473 -395.737588)
		(width 0.12065)
		(layer "In7.Cu")
		(net "UART_EXP_B_RX")
	)
	(segment
		(start 220.18117 -403.244558)
		(end 220.181424 -403.244304)
		(width 0.12065)
		(layer "In7.Cu")
		(net "UART_EXP_B_RX")
	)
	(segment
		(start 244.96649 -183.553608)
		(end 244.96649 -155.474924)
		(width 0.13335)
		(layer "In9.Cu")
		(net "UART_EXP_B_RX")
	)
	(segment
		(start 231.4448 -200.678034)
		(end 240.5507 -191.572134)
		(width 0.13335)
		(layer "In9.Cu")
		(net "UART_EXP_B_RX")
	)
	(segment
		(start 254.8382 -145.603214)
		(end 254.8382 -130.167888)
		(width 0.13335)
		(layer "In9.Cu")
		(net "UART_EXP_B_RX")
	)
	(segment
		(start 254.8382 -130.167888)
		(end 271.410938 -113.59515)
		(width 0.13335)
		(layer "In9.Cu")
		(net "UART_EXP_B_RX")
	)
	(segment
		(start 198.026528 -310.848502)
		(end 193.77914 -306.601114)
		(width 0.13335)
		(layer "In9.Cu")
		(net "UART_EXP_B_RX")
	)
	(segment
		(start 193.77914 -306.601114)
		(end 193.77914 -299.038772)
		(width 0.13335)
		(layer "In9.Cu")
		(net "UART_EXP_B_RX")
	)
	(segment
		(start 271.410938 -113.59515)
		(end 272.90395 -113.59515)
		(width 0.13335)
		(layer "In9.Cu")
		(net "UART_EXP_B_RX")
	)
	(segment
		(start 198.026528 -277.298404)
		(end 203.61275 -271.712182)
		(width 0.13335)
		(layer "In9.Cu")
		(net "UART_EXP_B_RX")
	)
	(segment
		(start 193.77914 -299.038772)
		(end 198.026528 -294.791384)
		(width 0.13335)
		(layer "In9.Cu")
		(net "UART_EXP_B_RX")
	)
	(segment
		(start 198.026528 -294.791384)
		(end 198.026528 -277.298404)
		(width 0.13335)
		(layer "In9.Cu")
		(net "UART_EXP_B_RX")
	)
	(segment
		(start 198.026528 -337.022948)
		(end 198.026528 -310.848502)
		(width 0.13335)
		(layer "In9.Cu")
		(net "UART_EXP_B_RX")
	)
	(segment
		(start 203.61275 -243.27485)
		(end 231.4448 -215.4428)
		(width 0.13335)
		(layer "In9.Cu")
		(net "UART_EXP_B_RX")
	)
	(segment
		(start 231.4448 -215.4428)
		(end 231.4448 -200.678034)
		(width 0.13335)
		(layer "In9.Cu")
		(net "UART_EXP_B_RX")
	)
	(segment
		(start 240.5507 -191.572134)
		(end 240.5507 -187.969398)
		(width 0.13335)
		(layer "In9.Cu")
		(net "UART_EXP_B_RX")
	)
	(segment
		(start 244.96649 -155.474924)
		(end 254.8382 -145.603214)
		(width 0.13335)
		(layer "In9.Cu")
		(net "UART_EXP_B_RX")
	)
	(segment
		(start 240.5507 -187.969398)
		(end 244.96649 -183.553608)
		(width 0.13335)
		(layer "In9.Cu")
		(net "UART_EXP_B_RX")
	)
	(segment
		(start 198.44004 -337.43646)
		(end 198.026528 -337.022948)
		(width 0.13335)
		(layer "In9.Cu")
		(net "UART_EXP_B_RX")
	)
	(segment
		(start 198.44766 -337.43646)
		(end 198.44004 -337.43646)
		(width 0.13335)
		(layer "In9.Cu")
		(net "UART_EXP_B_RX")
	)
	(segment
		(start 203.61275 -271.712182)
		(end 203.61275 -243.27485)
		(width 0.13335)
		(layer "In9.Cu")
		(net "UART_EXP_B_RX")
	)
	(segment
		(start 256.82575 3.951986)
		(end 258.371086 3.951986)
		(width 0.17145)
		(layer "F.Cu")
		(net "UART_EXP_A_TX")
	)
	(segment
		(start 258.371086 3.951986)
		(end 259.355844 2.967228)
		(width 0.17145)
		(layer "F.Cu")
		(net "UART_EXP_A_TX")
	)
	(segment
		(start 244.275102 31.074868)
		(end 244.275102 28.782264)
		(width 0.17145)
		(layer "F.Cu")
		(net "UART_EXP_A_TX")
	)
	(segment
		(start 249.795538 23.261828)
		(end 249.795538 10.982198)
		(width 0.17145)
		(layer "F.Cu")
		(net "UART_EXP_A_TX")
	)
	(segment
		(start 244.275102 28.782264)
		(end 249.795538 23.261828)
		(width 0.17145)
		(layer "F.Cu")
		(net "UART_EXP_A_TX")
	)
	(segment
		(start 249.795538 10.982198)
		(end 256.82575 3.951986)
		(width 0.17145)
		(layer "F.Cu")
		(net "UART_EXP_A_TX")
	)
	(via
		(at 256.82575 3.951986)
		(size 0.6604)
		(drill 0.3302)
		(layers "F.Cu" "B.Cu")
		(net "UART_EXP_A_TX")
	)
	(via
		(at 259.355844 2.967228)
		(size 0.5588)
		(drill 0.3048)
		(layers "F.Cu" "B.Cu")
		(net "UART_EXP_A_TX")
	)
	(segment
		(start 253.977648 -303.660556)
		(end 253.977648 -292.202108)
		(width 0.12065)
		(layer "In4.Cu")
		(net "UART_EXP_A_TX")
	)
	(segment
		(start 259.355844 -17.992852)
		(end 259.355844 2.967228)
		(width 0.12065)
		(layer "In4.Cu")
		(net "UART_EXP_A_TX")
	)
	(segment
		(start 257.8862 -130.942334)
		(end 257.8862 -19.462496)
		(width 0.12065)
		(layer "In4.Cu")
		(net "UART_EXP_A_TX")
	)
	(segment
		(start 253.216664 -285.18231)
		(end 254.022098 -284.376876)
		(width 0.12065)
		(layer "In4.Cu")
		(net "UART_EXP_A_TX")
	)
	(segment
		(start 253.216664 -291.441124)
		(end 253.216664 -285.18231)
		(width 0.12065)
		(layer "In4.Cu")
		(net "UART_EXP_A_TX")
	)
	(segment
		(start 254.396748 -321.060826)
		(end 254.396748 -304.079656)
		(width 0.12065)
		(layer "In4.Cu")
		(net "UART_EXP_A_TX")
	)
	(segment
		(start 274.942046 -337.286346)
		(end 274.789646 -337.438746)
		(width 0.12065)
		(layer "In4.Cu")
		(net "UART_EXP_A_TX")
	)
	(segment
		(start 254.022098 -268.813788)
		(end 248.521982 -263.313672)
		(width 0.12065)
		(layer "In4.Cu")
		(net "UART_EXP_A_TX")
	)
	(segment
		(start 260.141974 -133.198108)
		(end 257.8862 -130.942334)
		(width 0.12065)
		(layer "In4.Cu")
		(net "UART_EXP_A_TX")
	)
	(segment
		(start 248.521982 -253.635256)
		(end 251.960126 -250.197112)
		(width 0.12065)
		(layer "In4.Cu")
		(net "UART_EXP_A_TX")
	)
	(segment
		(start 260.141974 -203.70927)
		(end 260.141974 -133.198108)
		(width 0.12065)
		(layer "In4.Cu")
		(net "UART_EXP_A_TX")
	)
	(segment
		(start 274.789646 -337.438746)
		(end 270.774668 -337.438746)
		(width 0.12065)
		(layer "In4.Cu")
		(net "UART_EXP_A_TX")
	)
	(segment
		(start 251.960126 -211.891118)
		(end 260.141974 -203.70927)
		(width 0.12065)
		(layer "In4.Cu")
		(net "UART_EXP_A_TX")
	)
	(segment
		(start 257.8862 -19.462496)
		(end 259.355844 -17.992852)
		(width 0.12065)
		(layer "In4.Cu")
		(net "UART_EXP_A_TX")
	)
	(segment
		(start 283.055568 -337.286346)
		(end 274.942046 -337.286346)
		(width 0.12065)
		(layer "In4.Cu")
		(net "UART_EXP_A_TX")
	)
	(segment
		(start 254.396748 -304.079656)
		(end 253.977648 -303.660556)
		(width 0.12065)
		(layer "In4.Cu")
		(net "UART_EXP_A_TX")
	)
	(segment
		(start 251.960126 -250.197112)
		(end 251.960126 -211.891118)
		(width 0.12065)
		(layer "In4.Cu")
		(net "UART_EXP_A_TX")
	)
	(segment
		(start 270.774668 -337.438746)
		(end 254.396748 -321.060826)
		(width 0.12065)
		(layer "In4.Cu")
		(net "UART_EXP_A_TX")
	)
	(segment
		(start 254.022098 -284.376876)
		(end 254.022098 -268.813788)
		(width 0.12065)
		(layer "In4.Cu")
		(net "UART_EXP_A_TX")
	)
	(segment
		(start 253.977648 -292.202108)
		(end 253.216664 -291.441124)
		(width 0.12065)
		(layer "In4.Cu")
		(net "UART_EXP_A_TX")
	)
	(segment
		(start 284.236668 -336.105246)
		(end 283.055568 -337.286346)
		(width 0.12065)
		(layer "In4.Cu")
		(net "UART_EXP_A_TX")
	)
	(segment
		(start 248.521982 -263.313672)
		(end 248.521982 -253.635256)
		(width 0.12065)
		(layer "In4.Cu")
		(net "UART_EXP_A_TX")
	)
	(segment
		(start 256.63652 5.20192)
		(end 258.542282 5.20192)
		(width 0.17145)
		(layer "F.Cu")
		(net "UART_EXP_A_RX")
	)
	(segment
		(start 258.542282 5.20192)
		(end 260.786118 2.958084)
		(width 0.17145)
		(layer "F.Cu")
		(net "UART_EXP_A_RX")
	)
	(segment
		(start 245.545102 28.4734)
		(end 250.474988 23.543514)
		(width 0.17145)
		(layer "F.Cu")
		(net "UART_EXP_A_RX")
	)
	(segment
		(start 250.474988 11.363452)
		(end 256.63652 5.20192)
		(width 0.17145)
		(layer "F.Cu")
		(net "UART_EXP_A_RX")
	)
	(segment
		(start 245.545102 31.074868)
		(end 245.545102 28.4734)
		(width 0.17145)
		(layer "F.Cu")
		(net "UART_EXP_A_RX")
	)
	(segment
		(start 250.474988 23.543514)
		(end 250.474988 11.363452)
		(width 0.17145)
		(layer "F.Cu")
		(net "UART_EXP_A_RX")
	)
	(via
		(at 256.63652 5.20192)
		(size 0.6604)
		(drill 0.3302)
		(layers "F.Cu" "B.Cu")
		(net "UART_EXP_A_RX")
	)
	(via
		(at 260.786118 2.958084)
		(size 0.5588)
		(drill 0.3048)
		(layers "F.Cu" "B.Cu")
		(net "UART_EXP_A_RX")
	)
	(segment
		(start 258.51485 -19.9136)
		(end 260.786118 -17.642332)
		(width 0.12065)
		(layer "In4.Cu")
		(net "UART_EXP_A_RX")
	)
	(segment
		(start 258.51485 -130.68173)
		(end 258.51485 -19.9136)
		(width 0.12065)
		(layer "In4.Cu")
		(net "UART_EXP_A_RX")
	)
	(segment
		(start 282.83662 -336.105246)
		(end 282.13177 -336.810096)
		(width 0.12065)
		(layer "In4.Cu")
		(net "UART_EXP_A_RX")
	)
	(segment
		(start 282.13177 -336.810096)
		(end 271.035272 -336.810096)
		(width 0.12065)
		(layer "In4.Cu")
		(net "UART_EXP_A_RX")
	)
	(segment
		(start 255.025398 -320.800222)
		(end 255.025398 -303.819052)
		(width 0.12065)
		(layer "In4.Cu")
		(net "UART_EXP_A_RX")
	)
	(segment
		(start 253.845314 -291.18052)
		(end 253.845314 -285.442914)
		(width 0.12065)
		(layer "In4.Cu")
		(net "UART_EXP_A_RX")
	)
	(segment
		(start 254.650748 -268.553184)
		(end 249.150632 -263.053068)
		(width 0.12065)
		(layer "In4.Cu")
		(net "UART_EXP_A_RX")
	)
	(segment
		(start 254.606298 -291.941504)
		(end 253.845314 -291.18052)
		(width 0.12065)
		(layer "In4.Cu")
		(net "UART_EXP_A_RX")
	)
	(segment
		(start 255.025398 -303.819052)
		(end 254.606298 -303.399952)
		(width 0.12065)
		(layer "In4.Cu")
		(net "UART_EXP_A_RX")
	)
	(segment
		(start 253.906528 -210.83397)
		(end 261.059422 -203.681076)
		(width 0.12065)
		(layer "In4.Cu")
		(net "UART_EXP_A_RX")
	)
	(segment
		(start 253.906528 -249.139964)
		(end 253.906528 -210.83397)
		(width 0.12065)
		(layer "In4.Cu")
		(net "UART_EXP_A_RX")
	)
	(segment
		(start 261.059422 -133.226302)
		(end 258.51485 -130.68173)
		(width 0.12065)
		(layer "In4.Cu")
		(net "UART_EXP_A_RX")
	)
	(segment
		(start 261.059422 -203.681076)
		(end 261.059422 -133.226302)
		(width 0.12065)
		(layer "In4.Cu")
		(net "UART_EXP_A_RX")
	)
	(segment
		(start 253.845314 -285.442914)
		(end 254.650748 -284.63748)
		(width 0.12065)
		(layer "In4.Cu")
		(net "UART_EXP_A_RX")
	)
	(segment
		(start 260.786118 -17.642332)
		(end 260.786118 2.958084)
		(width 0.12065)
		(layer "In4.Cu")
		(net "UART_EXP_A_RX")
	)
	(segment
		(start 271.035272 -336.810096)
		(end 255.025398 -320.800222)
		(width 0.12065)
		(layer "In4.Cu")
		(net "UART_EXP_A_RX")
	)
	(segment
		(start 254.606298 -303.399952)
		(end 254.606298 -291.941504)
		(width 0.12065)
		(layer "In4.Cu")
		(net "UART_EXP_A_RX")
	)
	(segment
		(start 254.650748 -284.63748)
		(end 254.650748 -268.553184)
		(width 0.12065)
		(layer "In4.Cu")
		(net "UART_EXP_A_RX")
	)
	(segment
		(start 249.150632 -253.89586)
		(end 253.906528 -249.139964)
		(width 0.12065)
		(layer "In4.Cu")
		(net "UART_EXP_A_RX")
	)
	(segment
		(start 249.150632 -263.053068)
		(end 249.150632 -253.89586)
		(width 0.12065)
		(layer "In4.Cu")
		(net "UART_EXP_A_RX")
	)
	(via
		(at 359.380028 -100.906834)
		(size 0.5588)
		(drill 0.3048)
		(layers "F.Cu" "B.Cu")
		(net "UART_COMP_B_TX")
	)
	(segment
		(start 285.074614 -105.649014)
		(end 284.074616 -104.649016)
		(width 0.13335)
		(layer "In2.Cu")
		(net "UART_COMP_B_TX")
	)
	(segment
		(start 359.380028 -100.906834)
		(end 351.969832 -100.906834)
		(width 0.13335)
		(layer "In2.Cu")
		(net "UART_COMP_B_TX")
	)
	(segment
		(start 284.074616 -104.649016)
		(end 282.499816 -104.649016)
		(width 0.13335)
		(layer "In2.Cu")
		(net "UART_COMP_B_TX")
	)
	(segment
		(start 287.751774 -106.3752)
		(end 287.025588 -105.649014)
		(width 0.13335)
		(layer "In2.Cu")
		(net "UART_COMP_B_TX")
	)
	(segment
		(start 351.969832 -100.906834)
		(end 346.501466 -106.3752)
		(width 0.13335)
		(layer "In2.Cu")
		(net "UART_COMP_B_TX")
	)
	(segment
		(start 281.648916 -105.499916)
		(end 280.75001 -105.499916)
		(width 0.13335)
		(layer "In2.Cu")
		(net "UART_COMP_B_TX")
	)
	(segment
		(start 287.025588 -105.649014)
		(end 285.074614 -105.649014)
		(width 0.13335)
		(layer "In2.Cu")
		(net "UART_COMP_B_TX")
	)
	(segment
		(start 282.499816 -104.649016)
		(end 281.648916 -105.499916)
		(width 0.13335)
		(layer "In2.Cu")
		(net "UART_COMP_B_TX")
	)
	(segment
		(start 346.501466 -106.3752)
		(end 287.751774 -106.3752)
		(width 0.13335)
		(layer "In2.Cu")
		(net "UART_COMP_B_TX")
	)
	(segment
		(start 364.149894 -25.689306)
		(end 362.998004 -26.841196)
		(width 0.12065)
		(layer "In4.Cu")
		(net "UART_COMP_B_TX")
	)
	(segment
		(start 359.380028 -42.832782)
		(end 359.380028 -100.906834)
		(width 0.12065)
		(layer "In4.Cu")
		(net "UART_COMP_B_TX")
	)
	(segment
		(start 362.631736 -39.581074)
		(end 359.380028 -42.832782)
		(width 0.12065)
		(layer "In4.Cu")
		(net "UART_COMP_B_TX")
	)
	(segment
		(start 362.631736 -32.46501)
		(end 362.631736 -39.581074)
		(width 0.12065)
		(layer "In4.Cu")
		(net "UART_COMP_B_TX")
	)
	(segment
		(start 362.998004 -26.841196)
		(end 362.998004 -32.098742)
		(width 0.12065)
		(layer "In4.Cu")
		(net "UART_COMP_B_TX")
	)
	(segment
		(start 364.149894 -25.550114)
		(end 364.149894 -25.689306)
		(width 0.12065)
		(layer "In4.Cu")
		(net "UART_COMP_B_TX")
	)
	(segment
		(start 362.998004 -32.098742)
		(end 362.631736 -32.46501)
		(width 0.12065)
		(layer "In4.Cu")
		(net "UART_COMP_B_TX")
	)
	(via
		(at 360.22915 -107.1118)
		(size 0.5588)
		(drill 0.3048)
		(layers "F.Cu" "B.Cu")
		(net "UART_COMP_B_RX")
	)
	(segment
		(start 286.438594 -107.6579)
		(end 286.131508 -107.350814)
		(width 0.13335)
		(layer "In2.Cu")
		(net "UART_COMP_B_RX")
	)
	(segment
		(start 359.68305 -107.6579)
		(end 286.438594 -107.6579)
		(width 0.13335)
		(layer "In2.Cu")
		(net "UART_COMP_B_RX")
	)
	(segment
		(start 284.897322 -107.350814)
		(end 284.046422 -106.499914)
		(width 0.13335)
		(layer "In2.Cu")
		(net "UART_COMP_B_RX")
	)
	(segment
		(start 284.046422 -106.499914)
		(end 278.750014 -106.499914)
		(width 0.13335)
		(layer "In2.Cu")
		(net "UART_COMP_B_RX")
	)
	(segment
		(start 286.131508 -107.350814)
		(end 284.897322 -107.350814)
		(width 0.13335)
		(layer "In2.Cu")
		(net "UART_COMP_B_RX")
	)
	(segment
		(start 360.22915 -107.1118)
		(end 359.68305 -107.6579)
		(width 0.13335)
		(layer "In2.Cu")
		(net "UART_COMP_B_RX")
	)
	(segment
		(start 363.506004 -39.59606)
		(end 360.22915 -42.872914)
		(width 0.12065)
		(layer "In4.Cu")
		(net "UART_COMP_B_RX")
	)
	(segment
		(start 360.22915 -42.872914)
		(end 360.22915 -107.1118)
		(width 0.12065)
		(layer "In4.Cu")
		(net "UART_COMP_B_RX")
	)
	(segment
		(start 363.506004 -27.594052)
		(end 363.506004 -39.59606)
		(width 0.12065)
		(layer "In4.Cu")
		(net "UART_COMP_B_RX")
	)
	(segment
		(start 364.149894 -26.950162)
		(end 363.506004 -27.594052)
		(width 0.12065)
		(layer "In4.Cu")
		(net "UART_COMP_B_RX")
	)
	(via
		(at 116.504466 -119.5578)
		(size 0.5588)
		(drill 0.3048)
		(layers "F.Cu" "B.Cu")
		(net "UART_COMP_A_TX")
	)
	(segment
		(start 229.693978 -113.89868)
		(end 229.693978 -115.365022)
		(width 0.13335)
		(layer "In2.Cu")
		(net "UART_COMP_A_TX")
	)
	(segment
		(start 117.10416 -118.958106)
		(end 116.504466 -119.5578)
		(width 0.13335)
		(layer "In2.Cu")
		(net "UART_COMP_A_TX")
	)
	(segment
		(start 221.76359 -123.29541)
		(end 185.270902 -123.29541)
		(width 0.13335)
		(layer "In2.Cu")
		(net "UART_COMP_A_TX")
	)
	(segment
		(start 233.3625 -110.230158)
		(end 229.693978 -113.89868)
		(width 0.13335)
		(layer "In2.Cu")
		(net "UART_COMP_A_TX")
	)
	(segment
		(start 233.3625 -107.98429)
		(end 233.3625 -110.230158)
		(width 0.13335)
		(layer "In2.Cu")
		(net "UART_COMP_A_TX")
	)
	(segment
		(start 229.693978 -115.365022)
		(end 221.76359 -123.29541)
		(width 0.13335)
		(layer "In2.Cu")
		(net "UART_COMP_A_TX")
	)
	(segment
		(start 235.846874 -105.499916)
		(end 233.3625 -107.98429)
		(width 0.13335)
		(layer "In2.Cu")
		(net "UART_COMP_A_TX")
	)
	(segment
		(start 238.05007 -105.499916)
		(end 235.846874 -105.499916)
		(width 0.13335)
		(layer "In2.Cu")
		(net "UART_COMP_A_TX")
	)
	(segment
		(start 180.933598 -118.958106)
		(end 117.10416 -118.958106)
		(width 0.13335)
		(layer "In2.Cu")
		(net "UART_COMP_A_TX")
	)
	(segment
		(start 185.270902 -123.29541)
		(end 180.933598 -118.958106)
		(width 0.13335)
		(layer "In2.Cu")
		(net "UART_COMP_A_TX")
	)
	(segment
		(start 117.009926 -26.690066)
		(end 117.009926 -31.31566)
		(width 0.12065)
		(layer "In4.Cu")
		(net "UART_COMP_A_TX")
	)
	(segment
		(start 116.501926 -88.897206)
		(end 116.501926 -119.55526)
		(width 0.12065)
		(layer "In4.Cu")
		(net "UART_COMP_A_TX")
	)
	(segment
		(start 116.501926 -119.55526)
		(end 116.504466 -119.5578)
		(width 0.12065)
		(layer "In4.Cu")
		(net "UART_COMP_A_TX")
	)
	(segment
		(start 109.138212 -81.533492)
		(end 116.501926 -88.897206)
		(width 0.12065)
		(layer "In4.Cu")
		(net "UART_COMP_A_TX")
	)
	(segment
		(start 109.138212 -45.70222)
		(end 109.138212 -55.579264)
		(width 0.12065)
		(layer "In4.Cu")
		(net "UART_COMP_A_TX")
	)
	(segment
		(start 116.689886 -31.6357)
		(end 116.689886 -38.150546)
		(width 0.12065)
		(layer "In4.Cu")
		(net "UART_COMP_A_TX")
	)
	(segment
		(start 109.127544 -55.589932)
		(end 109.127544 -55.997856)
		(width 0.12065)
		(layer "In4.Cu")
		(net "UART_COMP_A_TX")
	)
	(segment
		(start 117.009926 -31.31566)
		(end 116.689886 -31.6357)
		(width 0.12065)
		(layer "In4.Cu")
		(net "UART_COMP_A_TX")
	)
	(segment
		(start 118.149878 -25.550114)
		(end 117.009926 -26.690066)
		(width 0.12065)
		(layer "In4.Cu")
		(net "UART_COMP_A_TX")
	)
	(segment
		(start 109.138212 -56.008524)
		(end 109.138212 -81.533492)
		(width 0.12065)
		(layer "In4.Cu")
		(net "UART_COMP_A_TX")
	)
	(segment
		(start 109.127544 -55.997856)
		(end 109.138212 -56.008524)
		(width 0.12065)
		(layer "In4.Cu")
		(net "UART_COMP_A_TX")
	)
	(segment
		(start 116.689886 -38.150546)
		(end 109.138212 -45.70222)
		(width 0.12065)
		(layer "In4.Cu")
		(net "UART_COMP_A_TX")
	)
	(segment
		(start 109.138212 -55.579264)
		(end 109.127544 -55.589932)
		(width 0.12065)
		(layer "In4.Cu")
		(net "UART_COMP_A_TX")
	)
	(via
		(at 117.381782 -120.2182)
		(size 0.5588)
		(drill 0.3048)
		(layers "F.Cu" "B.Cu")
		(net "UART_COMP_A_RX")
	)
	(segment
		(start 234.00385 -108.435902)
		(end 234.00385 -110.495842)
		(width 0.13335)
		(layer "In2.Cu")
		(net "UART_COMP_A_RX")
	)
	(segment
		(start 230.335328 -114.164364)
		(end 230.335328 -115.638072)
		(width 0.13335)
		(layer "In2.Cu")
		(net "UART_COMP_A_RX")
	)
	(segment
		(start 235.939838 -106.499914)
		(end 234.00385 -108.435902)
		(width 0.13335)
		(layer "In2.Cu")
		(net "UART_COMP_A_RX")
	)
	(segment
		(start 234.00385 -110.495842)
		(end 230.335328 -114.164364)
		(width 0.13335)
		(layer "In2.Cu")
		(net "UART_COMP_A_RX")
	)
	(segment
		(start 184.584848 -123.95581)
		(end 180.847238 -120.2182)
		(width 0.13335)
		(layer "In2.Cu")
		(net "UART_COMP_A_RX")
	)
	(segment
		(start 236.050074 -106.499914)
		(end 235.939838 -106.499914)
		(width 0.13335)
		(layer "In2.Cu")
		(net "UART_COMP_A_RX")
	)
	(segment
		(start 222.01759 -123.95581)
		(end 184.584848 -123.95581)
		(width 0.13335)
		(layer "In2.Cu")
		(net "UART_COMP_A_RX")
	)
	(segment
		(start 180.847238 -120.2182)
		(end 117.381782 -120.2182)
		(width 0.13335)
		(layer "In2.Cu")
		(net "UART_COMP_A_RX")
	)
	(segment
		(start 230.335328 -115.638072)
		(end 222.01759 -123.95581)
		(width 0.13335)
		(layer "In2.Cu")
		(net "UART_COMP_A_RX")
	)
	(segment
		(start 117.381782 -88.31707)
		(end 117.381782 -120.2182)
		(width 0.12065)
		(layer "In4.Cu")
		(net "UART_COMP_A_RX")
	)
	(segment
		(start 117.486176 -27.613864)
		(end 117.486176 -31.88462)
		(width 0.12065)
		(layer "In4.Cu")
		(net "UART_COMP_A_RX")
	)
	(segment
		(start 117.318536 -32.05226)
		(end 117.318536 -38.459664)
		(width 0.12065)
		(layer "In4.Cu")
		(net "UART_COMP_A_RX")
	)
	(segment
		(start 117.486176 -31.88462)
		(end 117.318536 -32.05226)
		(width 0.12065)
		(layer "In4.Cu")
		(net "UART_COMP_A_RX")
	)
	(segment
		(start 118.149878 -26.950162)
		(end 117.486176 -27.613864)
		(width 0.12065)
		(layer "In4.Cu")
		(net "UART_COMP_A_RX")
	)
	(segment
		(start 110.443518 -81.378806)
		(end 117.381782 -88.31707)
		(width 0.12065)
		(layer "In4.Cu")
		(net "UART_COMP_A_RX")
	)
	(segment
		(start 117.318536 -38.459664)
		(end 110.443518 -45.334682)
		(width 0.12065)
		(layer "In4.Cu")
		(net "UART_COMP_A_RX")
	)
	(segment
		(start 110.443518 -45.334682)
		(end 110.443518 -81.378806)
		(width 0.12065)
		(layer "In4.Cu")
		(net "UART_COMP_A_RX")
	)
	(segment
		(start 341.904574 -28.72994)
		(end 341.904574 -30.05709)
		(width 0.17145)
		(layer "F.Cu")
		(net "SCC_B_TYPE_2")
	)
	(segment
		(start 342.554814 -28.0797)
		(end 341.904574 -28.72994)
		(width 0.17145)
		(layer "F.Cu")
		(net "SCC_B_TYPE_2")
	)
	(via
		(at 342.554814 -28.0797)
		(size 0.5588)
		(drill 0.3048)
		(layers "F.Cu" "B.Cu")
		(net "SCC_B_TYPE_2")
	)
	(via
		(at 340.0298 -195.961)
		(size 0.5588)
		(drill 0.3048)
		(layers "F.Cu" "B.Cu")
		(net "SCC_B_TYPE_2")
	)
	(via
		(at 227.838 -213.106)
		(size 0.5588)
		(drill 0.3048)
		(layers "F.Cu" "B.Cu")
		(net "SCC_B_TYPE_2")
	)
	(segment
		(start 339.418168 -197.283832)
		(end 337.880706 -198.821294)
		(width 0.13335)
		(layer "In2.Cu")
		(net "SCC_B_TYPE_2")
	)
	(segment
		(start 337.880706 -198.821294)
		(end 321.126866 -198.821294)
		(width 0.13335)
		(layer "In2.Cu")
		(net "SCC_B_TYPE_2")
	)
	(segment
		(start 321.126866 -198.821294)
		(end 316.671198 -203.276962)
		(width 0.13335)
		(layer "In2.Cu")
		(net "SCC_B_TYPE_2")
	)
	(segment
		(start 237.667038 -203.276962)
		(end 227.838 -213.106)
		(width 0.13335)
		(layer "In2.Cu")
		(net "SCC_B_TYPE_2")
	)
	(segment
		(start 316.671198 -203.276962)
		(end 237.667038 -203.276962)
		(width 0.13335)
		(layer "In2.Cu")
		(net "SCC_B_TYPE_2")
	)
	(segment
		(start 340.0298 -195.961)
		(end 339.418168 -196.572632)
		(width 0.13335)
		(layer "In2.Cu")
		(net "SCC_B_TYPE_2")
	)
	(segment
		(start 339.418168 -196.572632)
		(end 339.418168 -197.283832)
		(width 0.13335)
		(layer "In2.Cu")
		(net "SCC_B_TYPE_2")
	)
	(segment
		(start 218.931998 -393.463018)
		(end 218.931998 -385.55803)
		(width 0.12065)
		(layer "In4.Cu")
		(net "SCC_B_TYPE_2")
	)
	(segment
		(start 228.000052 -405.99995)
		(end 228.568504 -405.431498)
		(width 0.12065)
		(layer "In4.Cu")
		(net "SCC_B_TYPE_2")
	)
	(segment
		(start 341.84971 -39.582852)
		(end 344.461338 -36.971224)
		(width 0.12065)
		(layer "In4.Cu")
		(net "SCC_B_TYPE_2")
	)
	(segment
		(start 224.668842 -320.754756)
		(end 224.668842 -223.114616)
		(width 0.12065)
		(layer "In4.Cu")
		(net "SCC_B_TYPE_2")
	)
	(segment
		(start 224.668842 -223.114616)
		(end 227.822252 -219.961206)
		(width 0.12065)
		(layer "In4.Cu")
		(net "SCC_B_TYPE_2")
	)
	(segment
		(start 344.461338 -33.949132)
		(end 344.041476 -33.52927)
		(width 0.12065)
		(layer "In4.Cu")
		(net "SCC_B_TYPE_2")
	)
	(segment
		(start 218.582494 -380.915164)
		(end 218.582494 -379.356366)
		(width 0.12065)
		(layer "In4.Cu")
		(net "SCC_B_TYPE_2")
	)
	(segment
		(start 218.582494 -326.841104)
		(end 224.668842 -320.754756)
		(width 0.12065)
		(layer "In4.Cu")
		(net "SCC_B_TYPE_2")
	)
	(segment
		(start 328.45375 -121.54662)
		(end 343.185496 -106.814874)
		(width 0.12065)
		(layer "In4.Cu")
		(net "SCC_B_TYPE_2")
	)
	(segment
		(start 218.064842 -381.432816)
		(end 218.582494 -380.915164)
		(width 0.12065)
		(layer "In4.Cu")
		(net "SCC_B_TYPE_2")
	)
	(segment
		(start 218.064842 -384.690874)
		(end 218.064842 -381.432816)
		(width 0.12065)
		(layer "In4.Cu")
		(net "SCC_B_TYPE_2")
	)
	(segment
		(start 227.822252 -213.121748)
		(end 227.838 -213.106)
		(width 0.12065)
		(layer "In4.Cu")
		(net "SCC_B_TYPE_2")
	)
	(segment
		(start 218.582494 -379.356366)
		(end 218.977718 -378.961142)
		(width 0.12065)
		(layer "In4.Cu")
		(net "SCC_B_TYPE_2")
	)
	(segment
		(start 218.931998 -385.55803)
		(end 218.064842 -384.690874)
		(width 0.12065)
		(layer "In4.Cu")
		(net "SCC_B_TYPE_2")
	)
	(segment
		(start 344.041476 -29.566362)
		(end 342.554814 -28.0797)
		(width 0.12065)
		(layer "In4.Cu")
		(net "SCC_B_TYPE_2")
	)
	(segment
		(start 343.185496 -75.984608)
		(end 341.84971 -74.648822)
		(width 0.12065)
		(layer "In4.Cu")
		(net "SCC_B_TYPE_2")
	)
	(segment
		(start 218.977718 -378.553218)
		(end 218.582494 -378.157994)
		(width 0.12065)
		(layer "In4.Cu")
		(net "SCC_B_TYPE_2")
	)
	(segment
		(start 344.041476 -33.52927)
		(end 344.041476 -29.566362)
		(width 0.12065)
		(layer "In4.Cu")
		(net "SCC_B_TYPE_2")
	)
	(segment
		(start 218.977718 -378.961142)
		(end 218.977718 -378.553218)
		(width 0.12065)
		(layer "In4.Cu")
		(net "SCC_B_TYPE_2")
	)
	(segment
		(start 340.0298 -182.651908)
		(end 328.45375 -171.075858)
		(width 0.12065)
		(layer "In4.Cu")
		(net "SCC_B_TYPE_2")
	)
	(segment
		(start 218.582494 -378.157994)
		(end 218.582494 -326.841104)
		(width 0.12065)
		(layer "In4.Cu")
		(net "SCC_B_TYPE_2")
	)
	(segment
		(start 340.0298 -195.961)
		(end 340.0298 -182.651908)
		(width 0.12065)
		(layer "In4.Cu")
		(net "SCC_B_TYPE_2")
	)
	(segment
		(start 227.822252 -219.961206)
		(end 227.822252 -213.121748)
		(width 0.12065)
		(layer "In4.Cu")
		(net "SCC_B_TYPE_2")
	)
	(segment
		(start 344.461338 -36.971224)
		(end 344.461338 -33.949132)
		(width 0.12065)
		(layer "In4.Cu")
		(net "SCC_B_TYPE_2")
	)
	(segment
		(start 341.84971 -74.648822)
		(end 341.84971 -39.582852)
		(width 0.12065)
		(layer "In4.Cu")
		(net "SCC_B_TYPE_2")
	)
	(segment
		(start 343.185496 -106.814874)
		(end 343.185496 -75.984608)
		(width 0.12065)
		(layer "In4.Cu")
		(net "SCC_B_TYPE_2")
	)
	(segment
		(start 228.568504 -403.099524)
		(end 218.931998 -393.463018)
		(width 0.12065)
		(layer "In4.Cu")
		(net "SCC_B_TYPE_2")
	)
	(segment
		(start 328.45375 -171.075858)
		(end 328.45375 -121.54662)
		(width 0.12065)
		(layer "In4.Cu")
		(net "SCC_B_TYPE_2")
	)
	(segment
		(start 228.568504 -405.431498)
		(end 228.568504 -403.099524)
		(width 0.12065)
		(layer "In4.Cu")
		(net "SCC_B_TYPE_2")
	)
	(segment
		(start 342.554814 -29.129228)
		(end 342.554814 -30.05709)
		(width 0.17145)
		(layer "F.Cu")
		(net "SCC_B_TYPE_1")
	)
	(segment
		(start 343.097866 -28.586176)
		(end 342.554814 -29.129228)
		(width 0.17145)
		(layer "F.Cu")
		(net "SCC_B_TYPE_1")
	)
	(segment
		(start 343.097866 -27.049984)
		(end 343.097866 -28.586176)
		(width 0.17145)
		(layer "F.Cu")
		(net "SCC_B_TYPE_1")
	)
	(via
		(at 340.037166 -197.137274)
		(size 0.5588)
		(drill 0.3048)
		(layers "F.Cu" "B.Cu")
		(net "SCC_B_TYPE_1")
	)
	(via
		(at 343.097866 -27.049984)
		(size 0.5588)
		(drill 0.3048)
		(layers "F.Cu" "B.Cu")
		(net "SCC_B_TYPE_1")
	)
	(via
		(at 227.32111 -214.249)
		(size 0.5588)
		(drill 0.3048)
		(layers "F.Cu" "B.Cu")
		(net "SCC_B_TYPE_1")
	)
	(segment
		(start 338.191856 -199.246744)
		(end 340.037166 -197.401434)
		(width 0.13335)
		(layer "In2.Cu")
		(net "SCC_B_TYPE_1")
	)
	(segment
		(start 316.788038 -203.775564)
		(end 321.316858 -199.246744)
		(width 0.13335)
		(layer "In2.Cu")
		(net "SCC_B_TYPE_1")
	)
	(segment
		(start 227.32111 -214.249)
		(end 227.70211 -213.868)
		(width 0.13335)
		(layer "In2.Cu")
		(net "SCC_B_TYPE_1")
	)
	(segment
		(start 340.037166 -197.401434)
		(end 340.037166 -197.137274)
		(width 0.13335)
		(layer "In2.Cu")
		(net "SCC_B_TYPE_1")
	)
	(segment
		(start 227.70211 -213.868)
		(end 228.346 -213.868)
		(width 0.13335)
		(layer "In2.Cu")
		(net "SCC_B_TYPE_1")
	)
	(segment
		(start 238.438436 -203.775564)
		(end 316.788038 -203.775564)
		(width 0.13335)
		(layer "In2.Cu")
		(net "SCC_B_TYPE_1")
	)
	(segment
		(start 228.346 -213.868)
		(end 238.438436 -203.775564)
		(width 0.13335)
		(layer "In2.Cu")
		(net "SCC_B_TYPE_1")
	)
	(segment
		(start 321.316858 -199.246744)
		(end 338.191856 -199.246744)
		(width 0.13335)
		(layer "In2.Cu")
		(net "SCC_B_TYPE_1")
	)
	(segment
		(start 218.519248 -393.744196)
		(end 218.519248 -385.729226)
		(width 0.12065)
		(layer "In4.Cu")
		(net "SCC_B_TYPE_1")
	)
	(segment
		(start 340.037166 -197.137274)
		(end 340.522052 -196.652388)
		(width 0.12065)
		(layer "In4.Cu")
		(net "SCC_B_TYPE_1")
	)
	(segment
		(start 227.32111 -219.183204)
		(end 227.32111 -214.249)
		(width 0.12065)
		(layer "In4.Cu")
		(net "SCC_B_TYPE_1")
	)
	(segment
		(start 227.33635 -402.561298)
		(end 218.519248 -393.744196)
		(width 0.12065)
		(layer "In4.Cu")
		(net "SCC_B_TYPE_1")
	)
	(segment
		(start 216.92997 -325.939404)
		(end 223.264222 -319.605152)
		(width 0.12065)
		(layer "In4.Cu")
		(net "SCC_B_TYPE_1")
	)
	(segment
		(start 227.33635 -406.736296)
		(end 227.33635 -402.561298)
		(width 0.12065)
		(layer "In4.Cu")
		(net "SCC_B_TYPE_1")
	)
	(segment
		(start 328.8665 -170.904662)
		(end 328.8665 -121.717816)
		(width 0.12065)
		(layer "In4.Cu")
		(net "SCC_B_TYPE_1")
	)
	(segment
		(start 340.522052 -182.560214)
		(end 328.8665 -170.904662)
		(width 0.12065)
		(layer "In4.Cu")
		(net "SCC_B_TYPE_1")
	)
	(segment
		(start 223.320356 -319.548764)
		(end 223.320356 -223.183958)
		(width 0.12065)
		(layer "In4.Cu")
		(net "SCC_B_TYPE_1")
	)
	(segment
		(start 223.264222 -319.605152)
		(end 223.264222 -319.604898)
		(width 0.12065)
		(layer "In4.Cu")
		(net "SCC_B_TYPE_1")
	)
	(segment
		(start 343.598246 -106.98607)
		(end 343.598246 -75.813412)
		(width 0.12065)
		(layer "In4.Cu")
		(net "SCC_B_TYPE_1")
	)
	(segment
		(start 343.598246 -75.813412)
		(end 342.26246 -74.477626)
		(width 0.12065)
		(layer "In4.Cu")
		(net "SCC_B_TYPE_1")
	)
	(segment
		(start 342.26246 -39.754048)
		(end 344.874088 -37.14242)
		(width 0.12065)
		(layer "In4.Cu")
		(net "SCC_B_TYPE_1")
	)
	(segment
		(start 342.26246 -74.477626)
		(end 342.26246 -39.754048)
		(width 0.12065)
		(layer "In4.Cu")
		(net "SCC_B_TYPE_1")
	)
	(segment
		(start 340.522052 -196.652388)
		(end 340.522052 -182.560214)
		(width 0.12065)
		(layer "In4.Cu")
		(net "SCC_B_TYPE_1")
	)
	(segment
		(start 228.000052 -407.399998)
		(end 227.33635 -406.736296)
		(width 0.12065)
		(layer "In4.Cu")
		(net "SCC_B_TYPE_1")
	)
	(segment
		(start 344.454226 -33.358074)
		(end 344.454226 -28.406344)
		(width 0.12065)
		(layer "In4.Cu")
		(net "SCC_B_TYPE_1")
	)
	(segment
		(start 328.8665 -121.717816)
		(end 343.598246 -106.98607)
		(width 0.12065)
		(layer "In4.Cu")
		(net "SCC_B_TYPE_1")
	)
	(segment
		(start 344.874088 -37.14242)
		(end 344.874088 -33.777936)
		(width 0.12065)
		(layer "In4.Cu")
		(net "SCC_B_TYPE_1")
	)
	(segment
		(start 216.92997 -384.139948)
		(end 216.92997 -325.939404)
		(width 0.12065)
		(layer "In4.Cu")
		(net "SCC_B_TYPE_1")
	)
	(segment
		(start 344.454226 -28.406344)
		(end 343.097866 -27.049984)
		(width 0.12065)
		(layer "In4.Cu")
		(net "SCC_B_TYPE_1")
	)
	(segment
		(start 344.874088 -33.777936)
		(end 344.454226 -33.358074)
		(width 0.12065)
		(layer "In4.Cu")
		(net "SCC_B_TYPE_1")
	)
	(segment
		(start 218.519248 -385.729226)
		(end 216.92997 -384.139948)
		(width 0.12065)
		(layer "In4.Cu")
		(net "SCC_B_TYPE_1")
	)
	(segment
		(start 223.320356 -223.183958)
		(end 227.32111 -219.183204)
		(width 0.12065)
		(layer "In4.Cu")
		(net "SCC_B_TYPE_1")
	)
	(segment
		(start 223.264222 -319.604898)
		(end 223.320356 -319.548764)
		(width 0.12065)
		(layer "In4.Cu")
		(net "SCC_B_TYPE_1")
	)
	(segment
		(start 343.615518 -28.866592)
		(end 343.205054 -29.277056)
		(width 0.17145)
		(layer "F.Cu")
		(net "SCC_B_TYPE_0")
	)
	(segment
		(start 343.497154 -25.837896)
		(end 343.615518 -25.95626)
		(width 0.17145)
		(layer "F.Cu")
		(net "SCC_B_TYPE_0")
	)
	(segment
		(start 343.205054 -29.277056)
		(end 343.205054 -30.05709)
		(width 0.17145)
		(layer "F.Cu")
		(net "SCC_B_TYPE_0")
	)
	(segment
		(start 343.615518 -25.95626)
		(end 343.615518 -28.866592)
		(width 0.17145)
		(layer "F.Cu")
		(net "SCC_B_TYPE_0")
	)
	(via
		(at 226.3648 -212.9028)
		(size 0.5588)
		(drill 0.3048)
		(layers "F.Cu" "B.Cu")
		(net "SCC_B_TYPE_0")
	)
	(via
		(at 226.309428 -88.772492)
		(size 0.5588)
		(drill 0.3048)
		(layers "F.Cu" "B.Cu")
		(net "SCC_B_TYPE_0")
	)
	(via
		(at 343.497154 -25.837896)
		(size 0.5588)
		(drill 0.3048)
		(layers "F.Cu" "B.Cu")
		(net "SCC_B_TYPE_0")
	)
	(via
		(at 338.9122 -195.8848)
		(size 0.5588)
		(drill 0.3048)
		(layers "F.Cu" "B.Cu")
		(net "SCC_B_TYPE_0")
	)
	(segment
		(start 336.826606 -197.970394)
		(end 338.9122 -195.8848)
		(width 0.13335)
		(layer "In2.Cu")
		(net "SCC_B_TYPE_0")
	)
	(segment
		(start 226.3648 -212.9028)
		(end 236.841538 -202.426062)
		(width 0.13335)
		(layer "In2.Cu")
		(net "SCC_B_TYPE_0")
	)
	(segment
		(start 236.841538 -202.426062)
		(end 315.886338 -202.426062)
		(width 0.13335)
		(layer "In2.Cu")
		(net "SCC_B_TYPE_0")
	)
	(segment
		(start 226.309428 -88.772492)
		(end 229.06863 -88.772492)
		(width 0.13335)
		(layer "In2.Cu")
		(net "SCC_B_TYPE_0")
	)
	(segment
		(start 306.58689 -9.607804)
		(end 309.25135 -12.272264)
		(width 0.13335)
		(layer "In2.Cu")
		(net "SCC_B_TYPE_0")
	)
	(segment
		(start 249.828558 -13.382244)
		(end 262.339074 -0.871728)
		(width 0.13335)
		(layer "In2.Cu")
		(net "SCC_B_TYPE_0")
	)
	(segment
		(start 315.886338 -202.426062)
		(end 320.342006 -197.970394)
		(width 0.13335)
		(layer "In2.Cu")
		(net "SCC_B_TYPE_0")
	)
	(segment
		(start 262.339074 -0.871728)
		(end 285.839408 -0.871728)
		(width 0.13335)
		(layer "In2.Cu")
		(net "SCC_B_TYPE_0")
	)
	(segment
		(start 309.25135 -12.272264)
		(end 309.25135 -20.527264)
		(width 0.13335)
		(layer "In2.Cu")
		(net "SCC_B_TYPE_0")
	)
	(segment
		(start 233.031284 -92.735146)
		(end 246.207788 -92.735146)
		(width 0.13335)
		(layer "In2.Cu")
		(net "SCC_B_TYPE_0")
	)
	(segment
		(start 309.25135 -20.527264)
		(end 311.408318 -22.684232)
		(width 0.13335)
		(layer "In2.Cu")
		(net "SCC_B_TYPE_0")
	)
	(segment
		(start 249.828558 -89.114376)
		(end 249.828558 -13.382244)
		(width 0.13335)
		(layer "In2.Cu")
		(net "SCC_B_TYPE_0")
	)
	(segment
		(start 285.839408 -0.871728)
		(end 294.575484 -9.607804)
		(width 0.13335)
		(layer "In2.Cu")
		(net "SCC_B_TYPE_0")
	)
	(segment
		(start 337.746086 -22.684232)
		(end 337.995006 -22.933152)
		(width 0.13335)
		(layer "In2.Cu")
		(net "SCC_B_TYPE_0")
	)
	(segment
		(start 229.06863 -88.772492)
		(end 233.031284 -92.735146)
		(width 0.13335)
		(layer "In2.Cu")
		(net "SCC_B_TYPE_0")
	)
	(segment
		(start 341.332058 -23.6728)
		(end 343.497154 -25.837896)
		(width 0.13335)
		(layer "In2.Cu")
		(net "SCC_B_TYPE_0")
	)
	(segment
		(start 338.7344 -23.6728)
		(end 341.332058 -23.6728)
		(width 0.13335)
		(layer "In2.Cu")
		(net "SCC_B_TYPE_0")
	)
	(segment
		(start 337.995006 -22.933406)
		(end 338.7344 -23.6728)
		(width 0.13335)
		(layer "In2.Cu")
		(net "SCC_B_TYPE_0")
	)
	(segment
		(start 294.575484 -9.607804)
		(end 306.58689 -9.607804)
		(width 0.13335)
		(layer "In2.Cu")
		(net "SCC_B_TYPE_0")
	)
	(segment
		(start 246.207788 -92.735146)
		(end 249.828558 -89.114376)
		(width 0.13335)
		(layer "In2.Cu")
		(net "SCC_B_TYPE_0")
	)
	(segment
		(start 337.995006 -22.933152)
		(end 337.995006 -22.933406)
		(width 0.13335)
		(layer "In2.Cu")
		(net "SCC_B_TYPE_0")
	)
	(segment
		(start 320.342006 -197.970394)
		(end 336.826606 -197.970394)
		(width 0.13335)
		(layer "In2.Cu")
		(net "SCC_B_TYPE_0")
	)
	(segment
		(start 311.408318 -22.684232)
		(end 337.746086 -22.684232)
		(width 0.13335)
		(layer "In2.Cu")
		(net "SCC_B_TYPE_0")
	)
	(segment
		(start 342.359996 -106.472482)
		(end 342.359996 -76.327)
		(width 0.12065)
		(layer "In4.Cu")
		(net "SCC_B_TYPE_0")
	)
	(segment
		(start 342.359996 -76.327)
		(end 340.906608 -74.873612)
		(width 0.12065)
		(layer "In4.Cu")
		(net "SCC_B_TYPE_0")
	)
	(segment
		(start 216.51722 -384.311144)
		(end 216.51722 -325.768208)
		(width 0.12065)
		(layer "In4.Cu")
		(net "SCC_B_TYPE_0")
	)
	(segment
		(start 228.000052 -408.500072)
		(end 228.000052 -408.441652)
		(width 0.12065)
		(layer "In4.Cu")
		(net "SCC_B_TYPE_0")
	)
	(segment
		(start 327.604374 -152.724866)
		(end 326.940672 -152.061164)
		(width 0.12065)
		(layer "In4.Cu")
		(net "SCC_B_TYPE_0")
	)
	(segment
		(start 222.907606 -319.377568)
		(end 222.907606 -223.005142)
		(width 0.12065)
		(layer "In4.Cu")
		(net "SCC_B_TYPE_0")
	)
	(segment
		(start 326.940672 -152.061164)
		(end 326.940672 -149.330918)
		(width 0.12065)
		(layer "In4.Cu")
		(net "SCC_B_TYPE_0")
	)
	(segment
		(start 326.940672 -158.557976)
		(end 327.604374 -157.894274)
		(width 0.12065)
		(layer "In4.Cu")
		(net "SCC_B_TYPE_0")
	)
	(segment
		(start 342.062562 -27.272488)
		(end 343.497154 -25.837896)
		(width 0.12065)
		(layer "In4.Cu")
		(net "SCC_B_TYPE_0")
	)
	(segment
		(start 228.000052 -408.441652)
		(end 226.85502 -407.29662)
		(width 0.12065)
		(layer "In4.Cu")
		(net "SCC_B_TYPE_0")
	)
	(segment
		(start 216.51722 -325.768208)
		(end 222.851472 -319.433956)
		(width 0.12065)
		(layer "In4.Cu")
		(net "SCC_B_TYPE_0")
	)
	(segment
		(start 226.85502 -407.29662)
		(end 226.85502 -402.698712)
		(width 0.12065)
		(layer "In4.Cu")
		(net "SCC_B_TYPE_0")
	)
	(segment
		(start 327.62825 -121.204228)
		(end 342.359996 -106.472482)
		(width 0.12065)
		(layer "In4.Cu")
		(net "SCC_B_TYPE_0")
	)
	(segment
		(start 342.81745 -29.042614)
		(end 342.062562 -28.287726)
		(width 0.12065)
		(layer "In4.Cu")
		(net "SCC_B_TYPE_0")
	)
	(segment
		(start 226.387406 -217.86342)
		(end 226.336606 -217.81262)
		(width 0.12065)
		(layer "In4.Cu")
		(net "SCC_B_TYPE_0")
	)
	(segment
		(start 338.9122 -195.8848)
		(end 338.9122 -182.7022)
		(width 0.12065)
		(layer "In4.Cu")
		(net "SCC_B_TYPE_0")
	)
	(segment
		(start 327.604374 -157.894274)
		(end 327.604374 -152.724866)
		(width 0.12065)
		(layer "In4.Cu")
		(net "SCC_B_TYPE_0")
	)
	(segment
		(start 342.81745 -33.622742)
		(end 342.81745 -29.042614)
		(width 0.12065)
		(layer "In4.Cu")
		(net "SCC_B_TYPE_0")
	)
	(segment
		(start 222.851472 -319.433702)
		(end 222.907606 -319.377568)
		(width 0.12065)
		(layer "In4.Cu")
		(net "SCC_B_TYPE_0")
	)
	(segment
		(start 327.62825 -148.64334)
		(end 327.62825 -121.204228)
		(width 0.12065)
		(layer "In4.Cu")
		(net "SCC_B_TYPE_0")
	)
	(segment
		(start 338.9122 -182.7022)
		(end 326.940672 -170.730672)
		(width 0.12065)
		(layer "In4.Cu")
		(net "SCC_B_TYPE_0")
	)
	(segment
		(start 226.387406 -219.525342)
		(end 226.387406 -217.86342)
		(width 0.12065)
		(layer "In4.Cu")
		(net "SCC_B_TYPE_0")
	)
	(segment
		(start 343.635838 -36.424362)
		(end 343.635838 -34.44113)
		(width 0.12065)
		(layer "In4.Cu")
		(net "SCC_B_TYPE_0")
	)
	(segment
		(start 343.635838 -34.44113)
		(end 342.81745 -33.622742)
		(width 0.12065)
		(layer "In4.Cu")
		(net "SCC_B_TYPE_0")
	)
	(segment
		(start 340.906608 -39.153592)
		(end 343.635838 -36.424362)
		(width 0.12065)
		(layer "In4.Cu")
		(net "SCC_B_TYPE_0")
	)
	(segment
		(start 222.851472 -319.433956)
		(end 222.851472 -319.433702)
		(width 0.12065)
		(layer "In4.Cu")
		(net "SCC_B_TYPE_0")
	)
	(segment
		(start 226.85502 -402.698712)
		(end 218.106498 -393.95019)
		(width 0.12065)
		(layer "In4.Cu")
		(net "SCC_B_TYPE_0")
	)
	(segment
		(start 218.106498 -385.900422)
		(end 216.51722 -384.311144)
		(width 0.12065)
		(layer "In4.Cu")
		(net "SCC_B_TYPE_0")
	)
	(segment
		(start 222.907606 -223.005142)
		(end 226.387406 -219.525342)
		(width 0.12065)
		(layer "In4.Cu")
		(net "SCC_B_TYPE_0")
	)
	(segment
		(start 226.387406 -217.353896)
		(end 226.387406 -212.925406)
		(width 0.12065)
		(layer "In4.Cu")
		(net "SCC_B_TYPE_0")
	)
	(segment
		(start 226.336606 -217.81262)
		(end 226.336606 -217.404696)
		(width 0.12065)
		(layer "In4.Cu")
		(net "SCC_B_TYPE_0")
	)
	(segment
		(start 340.906608 -74.873612)
		(end 340.906608 -39.153592)
		(width 0.12065)
		(layer "In4.Cu")
		(net "SCC_B_TYPE_0")
	)
	(segment
		(start 326.940672 -170.730672)
		(end 326.940672 -158.557976)
		(width 0.12065)
		(layer "In4.Cu")
		(net "SCC_B_TYPE_0")
	)
	(segment
		(start 342.062562 -28.287726)
		(end 342.062562 -27.272488)
		(width 0.12065)
		(layer "In4.Cu")
		(net "SCC_B_TYPE_0")
	)
	(segment
		(start 226.336606 -217.404696)
		(end 226.387406 -217.353896)
		(width 0.12065)
		(layer "In4.Cu")
		(net "SCC_B_TYPE_0")
	)
	(segment
		(start 218.106498 -393.95019)
		(end 218.106498 -385.900422)
		(width 0.12065)
		(layer "In4.Cu")
		(net "SCC_B_TYPE_0")
	)
	(segment
		(start 326.940672 -149.330918)
		(end 327.62825 -148.64334)
		(width 0.12065)
		(layer "In4.Cu")
		(net "SCC_B_TYPE_0")
	)
	(segment
		(start 226.387406 -212.925406)
		(end 226.3648 -212.9028)
		(width 0.12065)
		(layer "In4.Cu")
		(net "SCC_B_TYPE_0")
	)
	(segment
		(start 186.69381 -30.444186)
		(end 223.021652 -66.772028)
		(width 0.12065)
		(layer "In7.Cu")
		(net "SCC_B_TYPE_0")
	)
	(segment
		(start 176.299622 -30.444186)
		(end 186.69381 -30.444186)
		(width 0.12065)
		(layer "In7.Cu")
		(net "SCC_B_TYPE_0")
	)
	(segment
		(start 115.68557 -25.21458)
		(end 115.68557 -31.533338)
		(width 0.12065)
		(layer "In7.Cu")
		(net "SCC_B_TYPE_0")
	)
	(segment
		(start 119.32285 -33.041336)
		(end 125.842522 -39.561008)
		(width 0.12065)
		(layer "In7.Cu")
		(net "SCC_B_TYPE_0")
	)
	(segment
		(start 125.842522 -39.561008)
		(end 143.011144 -39.561008)
		(width 0.12065)
		(layer "In7.Cu")
		(net "SCC_B_TYPE_0")
	)
	(segment
		(start 143.011144 -39.561008)
		(end 144.456404 -41.006268)
		(width 0.12065)
		(layer "In7.Cu")
		(net "SCC_B_TYPE_0")
	)
	(segment
		(start 223.021652 -66.772028)
		(end 223.021652 -83.22818)
		(width 0.12065)
		(layer "In7.Cu")
		(net "SCC_B_TYPE_0")
	)
	(segment
		(start 223.021652 -83.22818)
		(end 226.309428 -86.515956)
		(width 0.12065)
		(layer "In7.Cu")
		(net "SCC_B_TYPE_0")
	)
	(segment
		(start 174.027338 -28.171902)
		(end 176.299622 -30.444186)
		(width 0.12065)
		(layer "In7.Cu")
		(net "SCC_B_TYPE_0")
	)
	(segment
		(start 115.68557 -31.533338)
		(end 117.193568 -33.041336)
		(width 0.12065)
		(layer "In7.Cu")
		(net "SCC_B_TYPE_0")
	)
	(segment
		(start 226.309428 -86.515956)
		(end 226.309428 -88.772492)
		(width 0.12065)
		(layer "In7.Cu")
		(net "SCC_B_TYPE_0")
	)
	(segment
		(start 117.193568 -33.041336)
		(end 119.32285 -33.041336)
		(width 0.12065)
		(layer "In7.Cu")
		(net "SCC_B_TYPE_0")
	)
	(segment
		(start 144.456404 -41.006268)
		(end 155.885642 -41.006268)
		(width 0.12065)
		(layer "In7.Cu")
		(net "SCC_B_TYPE_0")
	)
	(segment
		(start 155.885642 -41.006268)
		(end 168.720008 -28.171902)
		(width 0.12065)
		(layer "In7.Cu")
		(net "SCC_B_TYPE_0")
	)
	(segment
		(start 168.720008 -28.171902)
		(end 174.027338 -28.171902)
		(width 0.12065)
		(layer "In7.Cu")
		(net "SCC_B_TYPE_0")
	)
	(segment
		(start 116.350034 -24.550116)
		(end 115.68557 -25.21458)
		(width 0.12065)
		(layer "In7.Cu")
		(net "SCC_B_TYPE_0")
	)
	(segment
		(start 89.012014 -22.22881)
		(end 89.012014 -24.082502)
		(width 0.17145)
		(layer "F.Cu")
		(net "SCC_B_INS_N")
	)
	(segment
		(start 255.994916 -256.92227)
		(end 255.994916 -257.79476)
		(width 0.17145)
		(layer "F.Cu")
		(net "SCC_B_INS_N")
	)
	(segment
		(start 89.012014 -24.082502)
		(end 89.259664 -24.330152)
		(width 0.17145)
		(layer "F.Cu")
		(net "SCC_B_INS_N")
	)
	(segment
		(start 256.415286 -256.5019)
		(end 255.994916 -256.92227)
		(width 0.17145)
		(layer "F.Cu")
		(net "SCC_B_INS_N")
	)
	(segment
		(start 342.554814 -24.41829)
		(end 342.554814 -22.153372)
		(width 0.17145)
		(layer "F.Cu")
		(net "SCC_B_INS_N")
	)
	(segment
		(start 342.554814 -22.153372)
		(end 342.554814 -21.164804)
		(width 0.17145)
		(layer "F.Cu")
		(net "SCC_B_INS_N")
	)
	(via
		(at 89.259664 -24.330152)
		(size 0.5588)
		(drill 0.3048)
		(layers "F.Cu" "B.Cu")
		(net "SCC_B_INS_N")
	)
	(via
		(at 342.554814 -21.164804)
		(size 0.5588)
		(drill 0.3048)
		(layers "F.Cu" "B.Cu")
		(net "SCC_B_INS_N")
	)
	(via
		(at 256.415286 -256.5019)
		(size 0.5588)
		(drill 0.3048)
		(layers "F.Cu" "B.Cu")
		(net "SCC_B_INS_N")
	)
	(via
		(at 325.018146 -248.007378)
		(size 0.5588)
		(drill 0.3048)
		(layers "F.Cu" "B.Cu")
		(net "SCC_B_INS_N")
	)
	(via
		(at 342.554814 -22.153372)
		(size 0.6604)
		(drill 0.3302)
		(layers "F.Cu" "B.Cu")
		(net "SCC_B_INS_N")
	)
	(segment
		(start 334.04937 -20.581874)
		(end 334.839564 -21.372068)
		(width 0.13335)
		(layer "In2.Cu")
		(net "SCC_B_INS_N")
	)
	(segment
		(start 286.015938 0.404876)
		(end 286.367982 0.404876)
		(width 0.13335)
		(layer "In2.Cu")
		(net "SCC_B_INS_N")
	)
	(segment
		(start 259.199634 -254.972566)
		(end 264.341864 -254.972566)
		(width 0.13335)
		(layer "In2.Cu")
		(net "SCC_B_INS_N")
	)
	(segment
		(start 317.94323 -248.007378)
		(end 325.018146 -248.007378)
		(width 0.13335)
		(layer "In2.Cu")
		(net "SCC_B_INS_N")
	)
	(segment
		(start 256.415286 -256.5019)
		(end 257.6703 -256.5019)
		(width 0.13335)
		(layer "In2.Cu")
		(net "SCC_B_INS_N")
	)
	(segment
		(start 179.49291 -57.732676)
		(end 179.49291 -76.443078)
		(width 0.13335)
		(layer "In2.Cu")
		(net "SCC_B_INS_N")
	)
	(segment
		(start 296.729912 -234.64012)
		(end 304.575972 -234.64012)
		(width 0.13335)
		(layer "In2.Cu")
		(net "SCC_B_INS_N")
	)
	(segment
		(start 89.259664 -24.330152)
		(end 89.873836 -24.330152)
		(width 0.13335)
		(layer "In2.Cu")
		(net "SCC_B_INS_N")
	)
	(segment
		(start 230.65867 -86.926674)
		(end 234.73664 -91.004644)
		(width 0.13335)
		(layer "In2.Cu")
		(net "SCC_B_INS_N")
	)
	(segment
		(start 338.465414 -21.04644)
		(end 338.465414 -21.046186)
		(width 0.13335)
		(layer "In2.Cu")
		(net "SCC_B_INS_N")
	)
	(segment
		(start 261.03199 0.404622)
		(end 286.015684 0.404622)
		(width 0.13335)
		(layer "In2.Cu")
		(net "SCC_B_INS_N")
	)
	(segment
		(start 276.278594 -247.123966)
		(end 284.246066 -247.123966)
		(width 0.13335)
		(layer "In2.Cu")
		(net "SCC_B_INS_N")
	)
	(segment
		(start 339.044534 -20.467066)
		(end 339.725 -20.467066)
		(width 0.13335)
		(layer "In2.Cu")
		(net "SCC_B_INS_N")
	)
	(segment
		(start 105.87736 -40.333676)
		(end 162.09391 -40.333676)
		(width 0.13335)
		(layer "In2.Cu")
		(net "SCC_B_INS_N")
	)
	(segment
		(start 310.5277 -18.556732)
		(end 312.303668 -20.3327)
		(width 0.13335)
		(layer "In2.Cu")
		(net "SCC_B_INS_N")
	)
	(segment
		(start 339.725 -20.467066)
		(end 340.422738 -21.164804)
		(width 0.13335)
		(layer "In2.Cu")
		(net "SCC_B_INS_N")
	)
	(segment
		(start 189.976506 -86.926674)
		(end 230.65867 -86.926674)
		(width 0.13335)
		(layer "In2.Cu")
		(net "SCC_B_INS_N")
	)
	(segment
		(start 310.5277 -11.743436)
		(end 310.5277 -18.556732)
		(width 0.13335)
		(layer "In2.Cu")
		(net "SCC_B_INS_N")
	)
	(segment
		(start 333.80045 -20.3327)
		(end 334.04937 -20.58162)
		(width 0.13335)
		(layer "In2.Cu")
		(net "SCC_B_INS_N")
	)
	(segment
		(start 264.341864 -254.972566)
		(end 266.94638 -252.36805)
		(width 0.13335)
		(layer "In2.Cu")
		(net "SCC_B_INS_N")
	)
	(segment
		(start 162.09391 -40.333676)
		(end 179.49291 -57.732676)
		(width 0.13335)
		(layer "In2.Cu")
		(net "SCC_B_INS_N")
	)
	(segment
		(start 295.104312 -8.331454)
		(end 307.115718 -8.331454)
		(width 0.13335)
		(layer "In2.Cu")
		(net "SCC_B_INS_N")
	)
	(segment
		(start 307.115718 -8.331454)
		(end 310.5277 -11.743436)
		(width 0.13335)
		(layer "In2.Cu")
		(net "SCC_B_INS_N")
	)
	(segment
		(start 234.73664 -91.004644)
		(end 245.720362 -91.004644)
		(width 0.13335)
		(layer "In2.Cu")
		(net "SCC_B_INS_N")
	)
	(segment
		(start 248.191782 -88.533224)
		(end 248.191782 -12.435586)
		(width 0.13335)
		(layer "In2.Cu")
		(net "SCC_B_INS_N")
	)
	(segment
		(start 286.015684 0.404622)
		(end 286.015938 0.404876)
		(width 0.13335)
		(layer "In2.Cu")
		(net "SCC_B_INS_N")
	)
	(segment
		(start 248.191782 -12.435586)
		(end 261.03199 0.404622)
		(width 0.13335)
		(layer "In2.Cu")
		(net "SCC_B_INS_N")
	)
	(segment
		(start 338.139532 -21.372068)
		(end 338.21624 -21.29536)
		(width 0.13335)
		(layer "In2.Cu")
		(net "SCC_B_INS_N")
	)
	(segment
		(start 338.216494 -21.29536)
		(end 338.465414 -21.04644)
		(width 0.13335)
		(layer "In2.Cu")
		(net "SCC_B_INS_N")
	)
	(segment
		(start 334.839564 -21.372068)
		(end 338.139532 -21.372068)
		(width 0.13335)
		(layer "In2.Cu")
		(net "SCC_B_INS_N")
	)
	(segment
		(start 266.94638 -252.36805)
		(end 271.03451 -252.36805)
		(width 0.13335)
		(layer "In2.Cu")
		(net "SCC_B_INS_N")
	)
	(segment
		(start 340.422738 -21.164804)
		(end 342.554814 -21.164804)
		(width 0.13335)
		(layer "In2.Cu")
		(net "SCC_B_INS_N")
	)
	(segment
		(start 338.21624 -21.29536)
		(end 338.216494 -21.29536)
		(width 0.13335)
		(layer "In2.Cu")
		(net "SCC_B_INS_N")
	)
	(segment
		(start 271.03451 -252.36805)
		(end 276.278594 -247.123966)
		(width 0.13335)
		(layer "In2.Cu")
		(net "SCC_B_INS_N")
	)
	(segment
		(start 179.49291 -76.443078)
		(end 189.976506 -86.926674)
		(width 0.13335)
		(layer "In2.Cu")
		(net "SCC_B_INS_N")
	)
	(segment
		(start 334.04937 -20.58162)
		(end 334.04937 -20.581874)
		(width 0.13335)
		(layer "In2.Cu")
		(net "SCC_B_INS_N")
	)
	(segment
		(start 284.246066 -247.123966)
		(end 296.729912 -234.64012)
		(width 0.13335)
		(layer "In2.Cu")
		(net "SCC_B_INS_N")
	)
	(segment
		(start 304.575972 -234.64012)
		(end 317.94323 -248.007378)
		(width 0.13335)
		(layer "In2.Cu")
		(net "SCC_B_INS_N")
	)
	(segment
		(start 312.303668 -20.3327)
		(end 333.80045 -20.3327)
		(width 0.13335)
		(layer "In2.Cu")
		(net "SCC_B_INS_N")
	)
	(segment
		(start 286.367982 0.404876)
		(end 295.104312 -8.331454)
		(width 0.13335)
		(layer "In2.Cu")
		(net "SCC_B_INS_N")
	)
	(segment
		(start 257.6703 -256.5019)
		(end 259.199634 -254.972566)
		(width 0.13335)
		(layer "In2.Cu")
		(net "SCC_B_INS_N")
	)
	(segment
		(start 338.465414 -21.046186)
		(end 339.044534 -20.467066)
		(width 0.13335)
		(layer "In2.Cu")
		(net "SCC_B_INS_N")
	)
	(segment
		(start 245.720362 -91.004644)
		(end 248.191782 -88.533224)
		(width 0.13335)
		(layer "In2.Cu")
		(net "SCC_B_INS_N")
	)
	(segment
		(start 89.873836 -24.330152)
		(end 105.87736 -40.333676)
		(width 0.13335)
		(layer "In2.Cu")
		(net "SCC_B_INS_N")
	)
	(segment
		(start 339.406484 -33.760156)
		(end 339.406484 -33.817306)
		(width 0.12065)
		(layer "In4.Cu")
		(net "SCC_B_INS_N")
	)
	(segment
		(start 321.0179 -202.65136)
		(end 322.388992 -204.022452)
		(width 0.12065)
		(layer "In4.Cu")
		(net "SCC_B_INS_N")
	)
	(segment
		(start 321.573398 -149.208744)
		(end 321.573398 -173.076108)
		(width 0.12065)
		(layer "In4.Cu")
		(net "SCC_B_INS_N")
	)
	(segment
		(start 339.20938 -36.141152)
		(end 337.822032 -37.5285)
		(width 0.12065)
		(layer "In4.Cu")
		(net "SCC_B_INS_N")
	)
	(segment
		(start 339.20938 -34.01441)
		(end 339.20938 -36.141152)
		(width 0.12065)
		(layer "In4.Cu")
		(net "SCC_B_INS_N")
	)
	(segment
		(start 322.388992 -221.398592)
		(end 325.018146 -224.027746)
		(width 0.12065)
		(layer "In4.Cu")
		(net "SCC_B_INS_N")
	)
	(segment
		(start 321.26809 -173.38167)
		(end 321.0179 -173.63186)
		(width 0.12065)
		(layer "In4.Cu")
		(net "SCC_B_INS_N")
	)
	(segment
		(start 321.0179 -173.63186)
		(end 321.0179 -202.65136)
		(width 0.12065)
		(layer "In4.Cu")
		(net "SCC_B_INS_N")
	)
	(segment
		(start 339.406738 -33.759902)
		(end 339.406484 -33.760156)
		(width 0.12065)
		(layer "In4.Cu")
		(net "SCC_B_INS_N")
	)
	(segment
		(start 331.928216 -66.82613)
		(end 331.928216 -68.8721)
		(width 0.12065)
		(layer "In4.Cu")
		(net "SCC_B_INS_N")
	)
	(segment
		(start 337.822032 -37.5285)
		(end 337.822032 -44.480734)
		(width 0.12065)
		(layer "In4.Cu")
		(net "SCC_B_INS_N")
	)
	(segment
		(start 336.838798 -51.959002)
		(end 333.0067 -55.7911)
		(width 0.12065)
		(layer "In4.Cu")
		(net "SCC_B_INS_N")
	)
	(segment
		(start 325.780654 -74.560938)
		(end 323.527674 -76.813918)
		(width 0.12065)
		(layer "In4.Cu")
		(net "SCC_B_INS_N")
	)
	(segment
		(start 336.838798 -45.463968)
		(end 336.838798 -51.959002)
		(width 0.12065)
		(layer "In4.Cu")
		(net "SCC_B_INS_N")
	)
	(segment
		(start 337.822032 -44.480734)
		(end 336.838798 -45.463968)
		(width 0.12065)
		(layer "In4.Cu")
		(net "SCC_B_INS_N")
	)
	(segment
		(start 326.239378 -74.560938)
		(end 325.780654 -74.560938)
		(width 0.12065)
		(layer "In4.Cu")
		(net "SCC_B_INS_N")
	)
	(segment
		(start 321.26809 -173.381416)
		(end 321.26809 -173.38167)
		(width 0.12065)
		(layer "In4.Cu")
		(net "SCC_B_INS_N")
	)
	(segment
		(start 323.527674 -77.272642)
		(end 323.106542 -77.693774)
		(width 0.12065)
		(layer "In4.Cu")
		(net "SCC_B_INS_N")
	)
	(segment
		(start 339.406484 -31.705804)
		(end 339.406738 -31.706058)
		(width 0.12065)
		(layer "In4.Cu")
		(net "SCC_B_INS_N")
	)
	(segment
		(start 323.106542 -147.6756)
		(end 321.573398 -149.208744)
		(width 0.12065)
		(layer "In4.Cu")
		(net "SCC_B_INS_N")
	)
	(segment
		(start 339.406738 -31.706058)
		(end 339.406738 -33.759902)
		(width 0.12065)
		(layer "In4.Cu")
		(net "SCC_B_INS_N")
	)
	(segment
		(start 333.0067 -55.7911)
		(end 333.0067 -65.747646)
		(width 0.12065)
		(layer "In4.Cu")
		(net "SCC_B_INS_N")
	)
	(segment
		(start 321.573398 -173.076108)
		(end 321.26809 -173.381416)
		(width 0.12065)
		(layer "In4.Cu")
		(net "SCC_B_INS_N")
	)
	(segment
		(start 333.0067 -65.747646)
		(end 331.928216 -66.82613)
		(width 0.12065)
		(layer "In4.Cu")
		(net "SCC_B_INS_N")
	)
	(segment
		(start 342.554814 -23.811738)
		(end 339.406484 -26.960068)
		(width 0.12065)
		(layer "In4.Cu")
		(net "SCC_B_INS_N")
	)
	(segment
		(start 322.388992 -204.022452)
		(end 322.388992 -221.398592)
		(width 0.12065)
		(layer "In4.Cu")
		(net "SCC_B_INS_N")
	)
	(segment
		(start 323.106542 -77.693774)
		(end 323.106542 -147.6756)
		(width 0.12065)
		(layer "In4.Cu")
		(net "SCC_B_INS_N")
	)
	(segment
		(start 323.527674 -76.813918)
		(end 323.527674 -77.272642)
		(width 0.12065)
		(layer "In4.Cu")
		(net "SCC_B_INS_N")
	)
	(segment
		(start 342.554814 -21.164804)
		(end 342.554814 -23.811738)
		(width 0.12065)
		(layer "In4.Cu")
		(net "SCC_B_INS_N")
	)
	(segment
		(start 325.018146 -224.027746)
		(end 325.018146 -248.007378)
		(width 0.12065)
		(layer "In4.Cu")
		(net "SCC_B_INS_N")
	)
	(segment
		(start 339.406484 -33.817306)
		(end 339.20938 -34.01441)
		(width 0.12065)
		(layer "In4.Cu")
		(net "SCC_B_INS_N")
	)
	(segment
		(start 339.406484 -26.960068)
		(end 339.406484 -31.705804)
		(width 0.12065)
		(layer "In4.Cu")
		(net "SCC_B_INS_N")
	)
	(segment
		(start 331.928216 -68.8721)
		(end 326.239378 -74.560938)
		(width 0.12065)
		(layer "In4.Cu")
		(net "SCC_B_INS_N")
	)
	(segment
		(start 253.142242 -267.536168)
		(end 253.259844 -267.418566)
		(width 0.13335)
		(layer "In9.Cu")
		(net "SCC_B_INS_N")
	)
	(segment
		(start 223.74987 -398.82445)
		(end 223.74987 -398.824196)
		(width 0.13335)
		(layer "In9.Cu")
		(net "SCC_B_INS_N")
	)
	(segment
		(start 256.415286 -257.3274)
		(end 256.415286 -256.5019)
		(width 0.13335)
		(layer "In9.Cu")
		(net "SCC_B_INS_N")
	)
	(segment
		(start 223.74987 -398.824196)
		(end 223.577404 -398.65173)
		(width 0.13335)
		(layer "In9.Cu")
		(net "SCC_B_INS_N")
	)
	(segment
		(start 253.142242 -282.784804)
		(end 253.142242 -267.536168)
		(width 0.13335)
		(layer "In9.Cu")
		(net "SCC_B_INS_N")
	)
	(segment
		(start 254.987044 -258.755642)
		(end 256.415286 -257.3274)
		(width 0.13335)
		(layer "In9.Cu")
		(net "SCC_B_INS_N")
	)
	(segment
		(start 228.000052 -409.600146)
		(end 227.321618 -408.921712)
		(width 0.13335)
		(layer "In9.Cu")
		(net "SCC_B_INS_N")
	)
	(segment
		(start 223.577404 -382.501902)
		(end 223.99625 -382.083056)
		(width 0.13335)
		(layer "In9.Cu")
		(net "SCC_B_INS_N")
	)
	(segment
		(start 229.574598 -364.869476)
		(end 229.574598 -335.778602)
		(width 0.13335)
		(layer "In9.Cu")
		(net "SCC_B_INS_N")
	)
	(segment
		(start 254.987044 -265.6332)
		(end 254.987044 -258.755642)
		(width 0.13335)
		(layer "In9.Cu")
		(net "SCC_B_INS_N")
	)
	(segment
		(start 229.574598 -335.778602)
		(end 239.899952 -325.453248)
		(width 0.13335)
		(layer "In9.Cu")
		(net "SCC_B_INS_N")
	)
	(segment
		(start 239.899952 -325.453248)
		(end 239.899952 -296.027094)
		(width 0.13335)
		(layer "In9.Cu")
		(net "SCC_B_INS_N")
	)
	(segment
		(start 223.99625 -380.652528)
		(end 223.960436 -380.616714)
		(width 0.13335)
		(layer "In9.Cu")
		(net "SCC_B_INS_N")
	)
	(segment
		(start 227.321618 -402.395944)
		(end 223.750124 -398.82445)
		(width 0.13335)
		(layer "In9.Cu")
		(net "SCC_B_INS_N")
	)
	(segment
		(start 223.750124 -398.82445)
		(end 223.74987 -398.82445)
		(width 0.13335)
		(layer "In9.Cu")
		(net "SCC_B_INS_N")
	)
	(segment
		(start 223.577404 -398.65173)
		(end 223.577404 -382.501902)
		(width 0.13335)
		(layer "In9.Cu")
		(net "SCC_B_INS_N")
	)
	(segment
		(start 253.259844 -267.3604)
		(end 254.987044 -265.6332)
		(width 0.13335)
		(layer "In9.Cu")
		(net "SCC_B_INS_N")
	)
	(segment
		(start 223.960436 -380.616714)
		(end 223.960436 -370.483638)
		(width 0.13335)
		(layer "In9.Cu")
		(net "SCC_B_INS_N")
	)
	(segment
		(start 239.899952 -296.027094)
		(end 253.142242 -282.784804)
		(width 0.13335)
		(layer "In9.Cu")
		(net "SCC_B_INS_N")
	)
	(segment
		(start 223.960436 -370.483638)
		(end 229.574598 -364.869476)
		(width 0.13335)
		(layer "In9.Cu")
		(net "SCC_B_INS_N")
	)
	(segment
		(start 253.259844 -267.418566)
		(end 253.259844 -267.3604)
		(width 0.13335)
		(layer "In9.Cu")
		(net "SCC_B_INS_N")
	)
	(segment
		(start 223.99625 -382.083056)
		(end 223.99625 -380.652528)
		(width 0.13335)
		(layer "In9.Cu")
		(net "SCC_B_INS_N")
	)
	(segment
		(start 227.321618 -408.921712)
		(end 227.321618 -402.395944)
		(width 0.13335)
		(layer "In9.Cu")
		(net "SCC_B_INS_N")
	)
	(segment
		(start 263.652 -336.350864)
		(end 264.755122 -336.350864)
		(width 0.17145)
		(layer "F.Cu")
		(net "SCC_A_TYPE_2")
	)
	(segment
		(start 262.335518 -336.392012)
		(end 262.335518 -336.7024)
		(width 0.17145)
		(layer "F.Cu")
		(net "SCC_A_TYPE_2")
	)
	(segment
		(start 262.376666 -336.350864)
		(end 262.335518 -336.392012)
		(width 0.17145)
		(layer "F.Cu")
		(net "SCC_A_TYPE_2")
	)
	(segment
		(start 263.652 -336.350864)
		(end 262.376666 -336.350864)
		(width 0.17145)
		(layer "F.Cu")
		(net "SCC_A_TYPE_2")
	)
	(segment
		(start 259.200142 -337.198716)
		(end 258.27609 -336.274664)
		(width 0.17145)
		(layer "F.Cu")
		(net "SCC_A_TYPE_2")
	)
	(segment
		(start 261.839202 -337.198716)
		(end 259.200142 -337.198716)
		(width 0.17145)
		(layer "F.Cu")
		(net "SCC_A_TYPE_2")
	)
	(segment
		(start 262.335518 -336.7024)
		(end 261.839202 -337.198716)
		(width 0.17145)
		(layer "F.Cu")
		(net "SCC_A_TYPE_2")
	)
	(segment
		(start 88.361774 -27.86761)
		(end 88.361774 -29.179774)
		(width 0.17145)
		(layer "F.Cu")
		(net "SCC_A_TYPE_2")
	)
	(via
		(at 75.2094 -339.1154)
		(size 0.5588)
		(drill 0.3048)
		(layers "F.Cu" "B.Cu")
		(net "SCC_A_TYPE_2")
	)
	(via
		(at 88.361774 -29.179774)
		(size 0.5588)
		(drill 0.3048)
		(layers "F.Cu" "B.Cu")
		(net "SCC_A_TYPE_2")
	)
	(via
		(at 264.755122 -336.350864)
		(size 0.5588)
		(drill 0.3048)
		(layers "F.Cu" "B.Cu")
		(net "SCC_A_TYPE_2")
	)
	(via
		(at 258.27609 -336.274664)
		(size 0.5588)
		(drill 0.3048)
		(layers "F.Cu" "B.Cu")
		(net "SCC_A_TYPE_2")
	)
	(via
		(at 263.652 -336.350864)
		(size 0.6604)
		(drill 0.3302)
		(layers "F.Cu" "B.Cu")
		(net "SCC_A_TYPE_2")
	)
	(segment
		(start 258.27609 -336.274664)
		(end 256.648204 -337.90255)
		(width 0.13335)
		(layer "In2.Cu")
		(net "SCC_A_TYPE_2")
	)
	(segment
		(start 75.269598 -339.055202)
		(end 75.2094 -339.1154)
		(width 0.13335)
		(layer "In2.Cu")
		(net "SCC_A_TYPE_2")
	)
	(segment
		(start 142.863316 -339.683598)
		(end 142.23492 -339.055202)
		(width 0.13335)
		(layer "In2.Cu")
		(net "SCC_A_TYPE_2")
	)
	(segment
		(start 219.474542 -333.926688)
		(end 214.173054 -328.6252)
		(width 0.13335)
		(layer "In2.Cu")
		(net "SCC_A_TYPE_2")
	)
	(segment
		(start 142.23492 -339.055202)
		(end 75.269598 -339.055202)
		(width 0.13335)
		(layer "In2.Cu")
		(net "SCC_A_TYPE_2")
	)
	(segment
		(start 219.474542 -333.926942)
		(end 219.474542 -333.926688)
		(width 0.13335)
		(layer "In2.Cu")
		(net "SCC_A_TYPE_2")
	)
	(segment
		(start 164.493956 -339.683598)
		(end 142.863316 -339.683598)
		(width 0.13335)
		(layer "In2.Cu")
		(net "SCC_A_TYPE_2")
	)
	(segment
		(start 175.552354 -328.6252)
		(end 164.493956 -339.683598)
		(width 0.13335)
		(layer "In2.Cu")
		(net "SCC_A_TYPE_2")
	)
	(segment
		(start 214.173054 -328.6252)
		(end 175.552354 -328.6252)
		(width 0.13335)
		(layer "In2.Cu")
		(net "SCC_A_TYPE_2")
	)
	(segment
		(start 223.45015 -337.90255)
		(end 219.474542 -333.926942)
		(width 0.13335)
		(layer "In2.Cu")
		(net "SCC_A_TYPE_2")
	)
	(segment
		(start 256.648204 -337.90255)
		(end 223.45015 -337.90255)
		(width 0.13335)
		(layer "In2.Cu")
		(net "SCC_A_TYPE_2")
	)
	(segment
		(start 273.740372 -344.793062)
		(end 265.298174 -336.350864)
		(width 0.12065)
		(layer "In4.Cu")
		(net "SCC_A_TYPE_2")
	)
	(segment
		(start 71.881238 -54.78907)
		(end 88.361774 -38.308534)
		(width 0.12065)
		(layer "In4.Cu")
		(net "SCC_A_TYPE_2")
	)
	(segment
		(start 76.191872 -182.387748)
		(end 77.53096 -181.04866)
		(width 0.12065)
		(layer "In4.Cu")
		(net "SCC_A_TYPE_2")
	)
	(segment
		(start 277.749 -347.5736)
		(end 274.968462 -344.793062)
		(width 0.12065)
		(layer "In4.Cu")
		(net "SCC_A_TYPE_2")
	)
	(segment
		(start 77.53096 -161.668714)
		(end 80.73136 -158.468314)
		(width 0.12065)
		(layer "In4.Cu")
		(net "SCC_A_TYPE_2")
	)
	(segment
		(start 76.191872 -190.493142)
		(end 76.191872 -182.387748)
		(width 0.12065)
		(layer "In4.Cu")
		(net "SCC_A_TYPE_2")
	)
	(segment
		(start 75.58405 -191.100964)
		(end 76.191872 -190.493142)
		(width 0.12065)
		(layer "In4.Cu")
		(net "SCC_A_TYPE_2")
	)
	(segment
		(start 80.73136 -158.468314)
		(end 80.73136 -140.989304)
		(width 0.12065)
		(layer "In4.Cu")
		(net "SCC_A_TYPE_2")
	)
	(segment
		(start 283.23667 -348.70517)
		(end 282.1051 -347.5736)
		(width 0.12065)
		(layer "In4.Cu")
		(net "SCC_A_TYPE_2")
	)
	(segment
		(start 88.361774 -38.308534)
		(end 88.361774 -29.179774)
		(width 0.12065)
		(layer "In4.Cu")
		(net "SCC_A_TYPE_2")
	)
	(segment
		(start 75.2094 -339.1154)
		(end 74.488802 -338.394802)
		(width 0.12065)
		(layer "In4.Cu")
		(net "SCC_A_TYPE_2")
	)
	(segment
		(start 74.488802 -306.352448)
		(end 74.74585 -306.0954)
		(width 0.12065)
		(layer "In4.Cu")
		(net "SCC_A_TYPE_2")
	)
	(segment
		(start 71.881238 -132.139182)
		(end 71.881238 -54.78907)
		(width 0.12065)
		(layer "In4.Cu")
		(net "SCC_A_TYPE_2")
	)
	(segment
		(start 77.53096 -181.04866)
		(end 77.53096 -161.668714)
		(width 0.12065)
		(layer "In4.Cu")
		(net "SCC_A_TYPE_2")
	)
	(segment
		(start 74.488802 -338.394802)
		(end 74.488802 -306.352448)
		(width 0.12065)
		(layer "In4.Cu")
		(net "SCC_A_TYPE_2")
	)
	(segment
		(start 75.58405 -274.428204)
		(end 75.58405 -191.100964)
		(width 0.12065)
		(layer "In4.Cu")
		(net "SCC_A_TYPE_2")
	)
	(segment
		(start 74.74585 -306.0954)
		(end 74.74585 -275.266404)
		(width 0.12065)
		(layer "In4.Cu")
		(net "SCC_A_TYPE_2")
	)
	(segment
		(start 265.298174 -336.350864)
		(end 264.755122 -336.350864)
		(width 0.12065)
		(layer "In4.Cu")
		(net "SCC_A_TYPE_2")
	)
	(segment
		(start 282.1051 -347.5736)
		(end 277.749 -347.5736)
		(width 0.12065)
		(layer "In4.Cu")
		(net "SCC_A_TYPE_2")
	)
	(segment
		(start 80.73136 -140.989304)
		(end 71.881238 -132.139182)
		(width 0.12065)
		(layer "In4.Cu")
		(net "SCC_A_TYPE_2")
	)
	(segment
		(start 74.74585 -275.266404)
		(end 75.58405 -274.428204)
		(width 0.12065)
		(layer "In4.Cu")
		(net "SCC_A_TYPE_2")
	)
	(segment
		(start 274.968462 -344.793062)
		(end 273.740372 -344.793062)
		(width 0.12065)
		(layer "In4.Cu")
		(net "SCC_A_TYPE_2")
	)
	(segment
		(start 89.012014 -27.86761)
		(end 89.012014 -29.855414)
		(width 0.17145)
		(layer "F.Cu")
		(net "SCC_A_TYPE_1")
	)
	(segment
		(start 263.7536 -341.037672)
		(end 264.780522 -341.037672)
		(width 0.17145)
		(layer "F.Cu")
		(net "SCC_A_TYPE_1")
	)
	(segment
		(start 260.3627 -342.037924)
		(end 261.401814 -342.037924)
		(width 0.17145)
		(layer "F.Cu")
		(net "SCC_A_TYPE_1")
	)
	(segment
		(start 261.401814 -342.037924)
		(end 262.402066 -341.037672)
		(width 0.17145)
		(layer "F.Cu")
		(net "SCC_A_TYPE_1")
	)
	(segment
		(start 263.7536 -341.037672)
		(end 262.402066 -341.037672)
		(width 0.17145)
		(layer "F.Cu")
		(net "SCC_A_TYPE_1")
	)
	(segment
		(start 258.234688 -339.909912)
		(end 260.3627 -342.037924)
		(width 0.17145)
		(layer "F.Cu")
		(net "SCC_A_TYPE_1")
	)
	(via
		(at 75.1586 -340.2838)
		(size 0.5588)
		(drill 0.3048)
		(layers "F.Cu" "B.Cu")
		(net "SCC_A_TYPE_1")
	)
	(via
		(at 264.780522 -341.037672)
		(size 0.5588)
		(drill 0.3048)
		(layers "F.Cu" "B.Cu")
		(net "SCC_A_TYPE_1")
	)
	(via
		(at 263.7536 -341.037672)
		(size 0.6604)
		(drill 0.3302)
		(layers "F.Cu" "B.Cu")
		(net "SCC_A_TYPE_1")
	)
	(via
		(at 89.012014 -29.855414)
		(size 0.5588)
		(drill 0.3048)
		(layers "F.Cu" "B.Cu")
		(net "SCC_A_TYPE_1")
	)
	(via
		(at 258.234688 -339.909912)
		(size 0.5588)
		(drill 0.3048)
		(layers "F.Cu" "B.Cu")
		(net "SCC_A_TYPE_1")
	)
	(segment
		(start 164.846508 -340.534498)
		(end 142.510764 -340.534498)
		(width 0.13335)
		(layer "In2.Cu")
		(net "SCC_A_TYPE_1")
	)
	(segment
		(start 258.234688 -339.909912)
		(end 257.160776 -338.836)
		(width 0.13335)
		(layer "In2.Cu")
		(net "SCC_A_TYPE_1")
	)
	(segment
		(start 222.8596 -338.836)
		(end 213.4997 -329.4761)
		(width 0.13335)
		(layer "In2.Cu")
		(net "SCC_A_TYPE_1")
	)
	(segment
		(start 132.432298 -339.906102)
		(end 132.106416 -340.231984)
		(width 0.13335)
		(layer "In2.Cu")
		(net "SCC_A_TYPE_1")
	)
	(segment
		(start 142.510764 -340.534498)
		(end 141.882368 -339.906102)
		(width 0.13335)
		(layer "In2.Cu")
		(net "SCC_A_TYPE_1")
	)
	(segment
		(start 75.210416 -340.231984)
		(end 75.1586 -340.2838)
		(width 0.13335)
		(layer "In2.Cu")
		(net "SCC_A_TYPE_1")
	)
	(segment
		(start 213.4997 -329.4761)
		(end 175.904906 -329.4761)
		(width 0.13335)
		(layer "In2.Cu")
		(net "SCC_A_TYPE_1")
	)
	(segment
		(start 175.904906 -329.4761)
		(end 164.846508 -340.534498)
		(width 0.13335)
		(layer "In2.Cu")
		(net "SCC_A_TYPE_1")
	)
	(segment
		(start 141.882368 -339.906102)
		(end 132.432298 -339.906102)
		(width 0.13335)
		(layer "In2.Cu")
		(net "SCC_A_TYPE_1")
	)
	(segment
		(start 257.160776 -338.836)
		(end 222.8596 -338.836)
		(width 0.13335)
		(layer "In2.Cu")
		(net "SCC_A_TYPE_1")
	)
	(segment
		(start 132.106416 -340.231984)
		(end 75.210416 -340.231984)
		(width 0.13335)
		(layer "In2.Cu")
		(net "SCC_A_TYPE_1")
	)
	(segment
		(start 81.14411 -140.818108)
		(end 72.73036 -132.404358)
		(width 0.12065)
		(layer "In4.Cu")
		(net "SCC_A_TYPE_1")
	)
	(segment
		(start 75.1586 -275.4376)
		(end 75.9968 -274.5994)
		(width 0.12065)
		(layer "In4.Cu")
		(net "SCC_A_TYPE_1")
	)
	(segment
		(start 276.5044 -349.8342)
		(end 273.5834 -346.9132)
		(width 0.12065)
		(layer "In4.Cu")
		(net "SCC_A_TYPE_1")
	)
	(segment
		(start 75.9968 -274.5994)
		(end 75.9968 -191.27216)
		(width 0.12065)
		(layer "In4.Cu")
		(net "SCC_A_TYPE_1")
	)
	(segment
		(start 73.024238 -54.230016)
		(end 89.012014 -38.24224)
		(width 0.12065)
		(layer "In4.Cu")
		(net "SCC_A_TYPE_1")
	)
	(segment
		(start 73.024238 -125.197362)
		(end 73.024238 -54.230016)
		(width 0.12065)
		(layer "In4.Cu")
		(net "SCC_A_TYPE_1")
	)
	(segment
		(start 75.701652 -337.677252)
		(end 75.1586 -337.1342)
		(width 0.12065)
		(layer "In4.Cu")
		(net "SCC_A_TYPE_1")
	)
	(segment
		(start 76.604622 -182.558944)
		(end 78.848966 -180.3146)
		(width 0.12065)
		(layer "In4.Cu")
		(net "SCC_A_TYPE_1")
	)
	(segment
		(start 75.9968 -191.27216)
		(end 76.604622 -190.664338)
		(width 0.12065)
		(layer "In4.Cu")
		(net "SCC_A_TYPE_1")
	)
	(segment
		(start 72.73036 -125.49124)
		(end 73.024238 -125.197362)
		(width 0.12065)
		(layer "In4.Cu")
		(net "SCC_A_TYPE_1")
	)
	(segment
		(start 89.012014 -38.24224)
		(end 89.012014 -29.855414)
		(width 0.12065)
		(layer "In4.Cu")
		(net "SCC_A_TYPE_1")
	)
	(segment
		(start 282.83662 -350.505268)
		(end 282.712668 -350.505268)
		(width 0.12065)
		(layer "In4.Cu")
		(net "SCC_A_TYPE_1")
	)
	(segment
		(start 267.072872 -341.037672)
		(end 264.780522 -341.037672)
		(width 0.12065)
		(layer "In4.Cu")
		(net "SCC_A_TYPE_1")
	)
	(segment
		(start 75.1586 -340.2838)
		(end 75.701652 -339.740748)
		(width 0.12065)
		(layer "In4.Cu")
		(net "SCC_A_TYPE_1")
	)
	(segment
		(start 273.5834 -346.9132)
		(end 272.9484 -346.9132)
		(width 0.12065)
		(layer "In4.Cu")
		(net "SCC_A_TYPE_1")
	)
	(segment
		(start 72.73036 -132.404358)
		(end 72.73036 -125.49124)
		(width 0.12065)
		(layer "In4.Cu")
		(net "SCC_A_TYPE_1")
	)
	(segment
		(start 78.848966 -161.191702)
		(end 81.14411 -158.896558)
		(width 0.12065)
		(layer "In4.Cu")
		(net "SCC_A_TYPE_1")
	)
	(segment
		(start 282.712668 -350.505268)
		(end 282.0416 -349.8342)
		(width 0.12065)
		(layer "In4.Cu")
		(net "SCC_A_TYPE_1")
	)
	(segment
		(start 282.0416 -349.8342)
		(end 276.5044 -349.8342)
		(width 0.12065)
		(layer "In4.Cu")
		(net "SCC_A_TYPE_1")
	)
	(segment
		(start 78.848966 -180.3146)
		(end 78.848966 -161.191702)
		(width 0.12065)
		(layer "In4.Cu")
		(net "SCC_A_TYPE_1")
	)
	(segment
		(start 75.701652 -339.740748)
		(end 75.701652 -337.677252)
		(width 0.12065)
		(layer "In4.Cu")
		(net "SCC_A_TYPE_1")
	)
	(segment
		(start 76.604622 -190.664338)
		(end 76.604622 -182.558944)
		(width 0.12065)
		(layer "In4.Cu")
		(net "SCC_A_TYPE_1")
	)
	(segment
		(start 81.14411 -158.896558)
		(end 81.14411 -140.818108)
		(width 0.12065)
		(layer "In4.Cu")
		(net "SCC_A_TYPE_1")
	)
	(segment
		(start 75.1586 -337.1342)
		(end 75.1586 -275.4376)
		(width 0.12065)
		(layer "In4.Cu")
		(net "SCC_A_TYPE_1")
	)
	(segment
		(start 272.9484 -346.9132)
		(end 267.072872 -341.037672)
		(width 0.12065)
		(layer "In4.Cu")
		(net "SCC_A_TYPE_1")
	)
	(segment
		(start 262.376666 -339.754464)
		(end 263.7028 -339.754464)
		(width 0.17145)
		(layer "F.Cu")
		(net "SCC_A_TYPE_0")
	)
	(segment
		(start 89.662254 -27.86761)
		(end 89.662254 -29.16301)
		(width 0.17145)
		(layer "F.Cu")
		(net "SCC_A_TYPE_0")
	)
	(segment
		(start 263.7028 -339.754464)
		(end 264.755122 -339.754464)
		(width 0.17145)
		(layer "F.Cu")
		(net "SCC_A_TYPE_0")
	)
	(via
		(at 89.662254 -29.16301)
		(size 0.5588)
		(drill 0.3048)
		(layers "F.Cu" "B.Cu")
		(net "SCC_A_TYPE_0")
	)
	(via
		(at 290.576 -332.74)
		(size 0.5588)
		(drill 0.3048)
		(layers "F.Cu" "B.Cu")
		(net "SCC_A_TYPE_0")
	)
	(via
		(at 264.755122 -339.754464)
		(size 0.5588)
		(drill 0.3048)
		(layers "F.Cu" "B.Cu")
		(net "SCC_A_TYPE_0")
	)
	(via
		(at 263.7028 -339.754464)
		(size 0.6604)
		(drill 0.3302)
		(layers "F.Cu" "B.Cu")
		(net "SCC_A_TYPE_0")
	)
	(via
		(at 350.9772 -337.7184)
		(size 0.5588)
		(drill 0.3048)
		(layers "F.Cu" "B.Cu")
		(net "SCC_A_TYPE_0")
	)
	(segment
		(start 332.20025 -24.7904)
		(end 330.944982 -23.535132)
		(width 0.13335)
		(layer "In2.Cu")
		(net "SCC_A_TYPE_0")
	)
	(segment
		(start 361.5944 -25.305766)
		(end 361.5944 -30.423866)
		(width 0.13335)
		(layer "In2.Cu")
		(net "SCC_A_TYPE_0")
	)
	(segment
		(start 292.0238 -332.74)
		(end 290.576 -332.74)
		(width 0.13335)
		(layer "In2.Cu")
		(net "SCC_A_TYPE_0")
	)
	(segment
		(start 311.029858 -23.535132)
		(end 308.40045 -20.905724)
		(width 0.13335)
		(layer "In2.Cu")
		(net "SCC_A_TYPE_0")
	)
	(segment
		(start 250.679458 -89.542366)
		(end 246.622062 -93.599762)
		(width 0.13335)
		(layer "In2.Cu")
		(net "SCC_A_TYPE_0")
	)
	(segment
		(start 167.8051 -61.003434)
		(end 163.792154 -56.990488)
		(width 0.13335)
		(layer "In2.Cu")
		(net "SCC_A_TYPE_0")
	)
	(segment
		(start 221.981776 -89.885012)
		(end 184.03062 -89.885012)
		(width 0.13335)
		(layer "In2.Cu")
		(net "SCC_A_TYPE_0")
	)
	(segment
		(start 246.622062 -93.599762)
		(end 231.26192 -93.599762)
		(width 0.13335)
		(layer "In2.Cu")
		(net "SCC_A_TYPE_0")
	)
	(segment
		(start 121.076466 -56.990488)
		(end 115.498372 -51.412394)
		(width 0.13335)
		(layer "In2.Cu")
		(net "SCC_A_TYPE_0")
	)
	(segment
		(start 308.40045 -12.624816)
		(end 306.253388 -10.477754)
		(width 0.13335)
		(layer "In2.Cu")
		(net "SCC_A_TYPE_0")
	)
	(segment
		(start 349.791782 -336.416396)
		(end 295.700196 -336.416396)
		(width 0.13335)
		(layer "In2.Cu")
		(net "SCC_A_TYPE_0")
	)
	(segment
		(start 167.8051 -73.659492)
		(end 167.8051 -61.003434)
		(width 0.13335)
		(layer "In2.Cu")
		(net "SCC_A_TYPE_0")
	)
	(segment
		(start 334.047592 -24.421846)
		(end 333.679038 -24.7904)
		(width 0.13335)
		(layer "In2.Cu")
		(net "SCC_A_TYPE_0")
	)
	(segment
		(start 163.792154 -56.990488)
		(end 121.076466 -56.990488)
		(width 0.13335)
		(layer "In2.Cu")
		(net "SCC_A_TYPE_0")
	)
	(segment
		(start 352.939096 -34.131504)
		(end 346.370402 -27.56281)
		(width 0.13335)
		(layer "In2.Cu")
		(net "SCC_A_TYPE_0")
	)
	(segment
		(start 221.992698 -89.87409)
		(end 221.981776 -89.885012)
		(width 0.13335)
		(layer "In2.Cu")
		(net "SCC_A_TYPE_0")
	)
	(segment
		(start 227.552758 -89.8906)
		(end 222.422212 -89.8906)
		(width 0.13335)
		(layer "In2.Cu")
		(net "SCC_A_TYPE_0")
	)
	(segment
		(start 112.616742 -51.412394)
		(end 91.101164 -29.896816)
		(width 0.13335)
		(layer "In2.Cu")
		(net "SCC_A_TYPE_0")
	)
	(segment
		(start 294.150796 -10.477754)
		(end 285.584392 -1.91135)
		(width 0.13335)
		(layer "In2.Cu")
		(net "SCC_A_TYPE_0")
	)
	(segment
		(start 333.679038 -24.7904)
		(end 332.20025 -24.7904)
		(width 0.13335)
		(layer "In2.Cu")
		(net "SCC_A_TYPE_0")
	)
	(segment
		(start 222.422212 -89.8906)
		(end 222.405702 -89.87409)
		(width 0.13335)
		(layer "In2.Cu")
		(net "SCC_A_TYPE_0")
	)
	(segment
		(start 357.886762 -34.131504)
		(end 352.939096 -34.131504)
		(width 0.13335)
		(layer "In2.Cu")
		(net "SCC_A_TYPE_0")
	)
	(segment
		(start 306.253388 -10.477754)
		(end 294.150796 -10.477754)
		(width 0.13335)
		(layer "In2.Cu")
		(net "SCC_A_TYPE_0")
	)
	(segment
		(start 342.281256 -27.56281)
		(end 340.51875 -25.800304)
		(width 0.13335)
		(layer "In2.Cu")
		(net "SCC_A_TYPE_0")
	)
	(segment
		(start 308.40045 -20.905724)
		(end 308.40045 -12.624816)
		(width 0.13335)
		(layer "In2.Cu")
		(net "SCC_A_TYPE_0")
	)
	(segment
		(start 115.498372 -51.412394)
		(end 112.616742 -51.412394)
		(width 0.13335)
		(layer "In2.Cu")
		(net "SCC_A_TYPE_0")
	)
	(segment
		(start 231.26192 -93.599762)
		(end 227.552758 -89.8906)
		(width 0.13335)
		(layer "In2.Cu")
		(net "SCC_A_TYPE_0")
	)
	(segment
		(start 350.9772 -337.7184)
		(end 350.9772 -337.601814)
		(width 0.13335)
		(layer "In2.Cu")
		(net "SCC_A_TYPE_0")
	)
	(segment
		(start 336.474562 -24.421846)
		(end 334.047592 -24.421846)
		(width 0.13335)
		(layer "In2.Cu")
		(net "SCC_A_TYPE_0")
	)
	(segment
		(start 338.913216 -25.800304)
		(end 338.912962 -25.800558)
		(width 0.13335)
		(layer "In2.Cu")
		(net "SCC_A_TYPE_0")
	)
	(segment
		(start 263.607042 -1.91135)
		(end 250.679458 -14.838934)
		(width 0.13335)
		(layer "In2.Cu")
		(net "SCC_A_TYPE_0")
	)
	(segment
		(start 250.679458 -14.838934)
		(end 250.679458 -89.542366)
		(width 0.13335)
		(layer "In2.Cu")
		(net "SCC_A_TYPE_0")
	)
	(segment
		(start 346.370402 -27.56281)
		(end 342.281256 -27.56281)
		(width 0.13335)
		(layer "In2.Cu")
		(net "SCC_A_TYPE_0")
	)
	(segment
		(start 184.03062 -89.885012)
		(end 167.8051 -73.659492)
		(width 0.13335)
		(layer "In2.Cu")
		(net "SCC_A_TYPE_0")
	)
	(segment
		(start 350.9772 -337.601814)
		(end 349.791782 -336.416396)
		(width 0.13335)
		(layer "In2.Cu")
		(net "SCC_A_TYPE_0")
	)
	(segment
		(start 91.101164 -29.896816)
		(end 90.39606 -29.896816)
		(width 0.13335)
		(layer "In2.Cu")
		(net "SCC_A_TYPE_0")
	)
	(segment
		(start 295.700196 -336.416396)
		(end 292.0238 -332.74)
		(width 0.13335)
		(layer "In2.Cu")
		(net "SCC_A_TYPE_0")
	)
	(segment
		(start 90.39606 -29.896816)
		(end 89.662254 -29.16301)
		(width 0.13335)
		(layer "In2.Cu")
		(net "SCC_A_TYPE_0")
	)
	(segment
		(start 285.584392 -1.91135)
		(end 263.607042 -1.91135)
		(width 0.13335)
		(layer "In2.Cu")
		(net "SCC_A_TYPE_0")
	)
	(segment
		(start 222.405702 -89.87409)
		(end 221.992698 -89.87409)
		(width 0.13335)
		(layer "In2.Cu")
		(net "SCC_A_TYPE_0")
	)
	(segment
		(start 337.853274 -25.800558)
		(end 336.474562 -24.421846)
		(width 0.13335)
		(layer "In2.Cu")
		(net "SCC_A_TYPE_0")
	)
	(segment
		(start 340.51875 -25.800304)
		(end 338.913216 -25.800304)
		(width 0.13335)
		(layer "In2.Cu")
		(net "SCC_A_TYPE_0")
	)
	(segment
		(start 362.35005 -24.550116)
		(end 361.5944 -25.305766)
		(width 0.13335)
		(layer "In2.Cu")
		(net "SCC_A_TYPE_0")
	)
	(segment
		(start 361.5944 -30.423866)
		(end 357.886762 -34.131504)
		(width 0.13335)
		(layer "In2.Cu")
		(net "SCC_A_TYPE_0")
	)
	(segment
		(start 338.912962 -25.800558)
		(end 337.853274 -25.800558)
		(width 0.13335)
		(layer "In2.Cu")
		(net "SCC_A_TYPE_0")
	)
	(segment
		(start 330.944982 -23.535132)
		(end 311.029858 -23.535132)
		(width 0.13335)
		(layer "In2.Cu")
		(net "SCC_A_TYPE_0")
	)
	(segment
		(start 350.5454 -106.507534)
		(end 335.010252 -122.042682)
		(width 0.12065)
		(layer "In4.Cu")
		(net "SCC_A_TYPE_0")
	)
	(segment
		(start 336.978752 -161.96818)
		(end 336.978752 -168.208452)
		(width 0.12065)
		(layer "In4.Cu")
		(net "SCC_A_TYPE_0")
	)
	(segment
		(start 336.978752 -168.208452)
		(end 340.531196 -171.760896)
		(width 0.12065)
		(layer "In4.Cu")
		(net "SCC_A_TYPE_0")
	)
	(segment
		(start 264.755122 -339.754464)
		(end 266.51712 -339.754464)
		(width 0.12065)
		(layer "In4.Cu")
		(net "SCC_A_TYPE_0")
	)
	(segment
		(start 276.7584 -349.3262)
		(end 283.0576 -349.3262)
		(width 0.12065)
		(layer "In4.Cu")
		(net "SCC_A_TYPE_0")
	)
	(segment
		(start 340.531196 -171.760896)
		(end 340.531196 -175.079406)
		(width 0.12065)
		(layer "In4.Cu")
		(net "SCC_A_TYPE_0")
	)
	(segment
		(start 350.5454 -49.703228)
		(end 350.5454 -106.507534)
		(width 0.12065)
		(layer "In4.Cu")
		(net "SCC_A_TYPE_0")
	)
	(segment
		(start 273.053556 -346.2909)
		(end 273.7231 -346.2909)
		(width 0.12065)
		(layer "In4.Cu")
		(net "SCC_A_TYPE_0")
	)
	(segment
		(start 289.56 -337.781392)
		(end 290.576 -336.765392)
		(width 0.12065)
		(layer "In4.Cu")
		(net "SCC_A_TYPE_0")
	)
	(segment
		(start 289.56 -348.361)
		(end 289.56 -337.781392)
		(width 0.12065)
		(layer "In4.Cu")
		(net "SCC_A_TYPE_0")
	)
	(segment
		(start 350.99625 -290.11245)
		(end 350.99625 -337.69935)
		(width 0.12065)
		(layer "In4.Cu")
		(net "SCC_A_TYPE_0")
	)
	(segment
		(start 284.240732 -350.505268)
		(end 285.115 -349.631)
		(width 0.12065)
		(layer "In4.Cu")
		(net "SCC_A_TYPE_0")
	)
	(segment
		(start 349.47987 -288.59607)
		(end 350.99625 -290.11245)
		(width 0.12065)
		(layer "In4.Cu")
		(net "SCC_A_TYPE_0")
	)
	(segment
		(start 290.576 -336.765392)
		(end 290.576 -332.74)
		(width 0.12065)
		(layer "In4.Cu")
		(net "SCC_A_TYPE_0")
	)
	(segment
		(start 288.29 -349.631)
		(end 289.56 -348.361)
		(width 0.12065)
		(layer "In4.Cu")
		(net "SCC_A_TYPE_0")
	)
	(segment
		(start 347.585538 -182.133748)
		(end 347.585538 -200.773538)
		(width 0.12065)
		(layer "In4.Cu")
		(net "SCC_A_TYPE_0")
	)
	(segment
		(start 340.531196 -175.079406)
		(end 347.585538 -182.133748)
		(width 0.12065)
		(layer "In4.Cu")
		(net "SCC_A_TYPE_0")
	)
	(segment
		(start 335.010252 -122.042682)
		(end 335.010252 -159.99968)
		(width 0.12065)
		(layer "In4.Cu")
		(net "SCC_A_TYPE_0")
	)
	(segment
		(start 284.236668 -350.505268)
		(end 284.240732 -350.505268)
		(width 0.12065)
		(layer "In4.Cu")
		(net "SCC_A_TYPE_0")
	)
	(segment
		(start 335.010252 -159.99968)
		(end 336.978752 -161.96818)
		(width 0.12065)
		(layer "In4.Cu")
		(net "SCC_A_TYPE_0")
	)
	(segment
		(start 361.238546 -25.66162)
		(end 361.238546 -39.010082)
		(width 0.12065)
		(layer "In4.Cu")
		(net "SCC_A_TYPE_0")
	)
	(segment
		(start 266.51712 -339.754464)
		(end 273.053556 -346.2909)
		(width 0.12065)
		(layer "In4.Cu")
		(net "SCC_A_TYPE_0")
	)
	(segment
		(start 349.47987 -202.66787)
		(end 349.47987 -288.59607)
		(width 0.12065)
		(layer "In4.Cu")
		(net "SCC_A_TYPE_0")
	)
	(segment
		(start 285.115 -349.631)
		(end 288.29 -349.631)
		(width 0.12065)
		(layer "In4.Cu")
		(net "SCC_A_TYPE_0")
	)
	(segment
		(start 273.7231 -346.2909)
		(end 276.7584 -349.3262)
		(width 0.12065)
		(layer "In4.Cu")
		(net "SCC_A_TYPE_0")
	)
	(segment
		(start 362.35005 -24.550116)
		(end 361.238546 -25.66162)
		(width 0.12065)
		(layer "In4.Cu")
		(net "SCC_A_TYPE_0")
	)
	(segment
		(start 283.0576 -349.3262)
		(end 284.236668 -350.505268)
		(width 0.12065)
		(layer "In4.Cu")
		(net "SCC_A_TYPE_0")
	)
	(segment
		(start 361.238546 -39.010082)
		(end 350.5454 -49.703228)
		(width 0.12065)
		(layer "In4.Cu")
		(net "SCC_A_TYPE_0")
	)
	(segment
		(start 350.99625 -337.69935)
		(end 350.9772 -337.7184)
		(width 0.12065)
		(layer "In4.Cu")
		(net "SCC_A_TYPE_0")
	)
	(segment
		(start 347.585538 -200.773538)
		(end 349.47987 -202.66787)
		(width 0.12065)
		(layer "In4.Cu")
		(net "SCC_A_TYPE_0")
	)
	(segment
		(start 265.321288 -344.049604)
		(end 264.677906 -344.049604)
		(width 0.17145)
		(layer "F.Cu")
		(net "SCC_A_SLOT_ID_1")
	)
	(segment
		(start 265.778488 -344.506804)
		(end 265.321288 -344.049604)
		(width 0.17145)
		(layer "F.Cu")
		(net "SCC_A_SLOT_ID_1")
	)
	(segment
		(start 263.683496 -344.049604)
		(end 264.677906 -344.049604)
		(width 0.17145)
		(layer "F.Cu")
		(net "SCC_A_SLOT_ID_1")
	)
	(via
		(at 264.677906 -344.049604)
		(size 0.6604)
		(drill 0.3302)
		(layers "F.Cu" "B.Cu")
		(net "SCC_A_SLOT_ID_1")
	)
	(via
		(at 265.778488 -344.506804)
		(size 0.5588)
		(drill 0.3048)
		(layers "F.Cu" "B.Cu")
		(net "SCC_A_SLOT_ID_1")
	)
	(segment
		(start 271.31137 -347.98)
		(end 267.838174 -344.506804)
		(width 0.12065)
		(layer "In4.Cu")
		(net "SCC_A_SLOT_ID_1")
	)
	(segment
		(start 267.838174 -344.506804)
		(end 265.778488 -344.506804)
		(width 0.12065)
		(layer "In4.Cu")
		(net "SCC_A_SLOT_ID_1")
	)
	(segment
		(start 281.836622 -352.305112)
		(end 281.775662 -352.305112)
		(width 0.12065)
		(layer "In4.Cu")
		(net "SCC_A_SLOT_ID_1")
	)
	(segment
		(start 272.981674 -347.98)
		(end 271.31137 -347.98)
		(width 0.12065)
		(layer "In4.Cu")
		(net "SCC_A_SLOT_ID_1")
	)
	(segment
		(start 281.775662 -352.305112)
		(end 281.10815 -351.6376)
		(width 0.12065)
		(layer "In4.Cu")
		(net "SCC_A_SLOT_ID_1")
	)
	(segment
		(start 281.10815 -351.6376)
		(end 276.639274 -351.6376)
		(width 0.12065)
		(layer "In4.Cu")
		(net "SCC_A_SLOT_ID_1")
	)
	(segment
		(start 276.639274 -351.6376)
		(end 272.981674 -347.98)
		(width 0.12065)
		(layer "In4.Cu")
		(net "SCC_A_SLOT_ID_1")
	)
	(segment
		(start 263.678162 -342.897968)
		(end 264.66165 -342.897968)
		(width 0.17145)
		(layer "F.Cu")
		(net "SCC_A_SLOT_ID_0")
	)
	(segment
		(start 264.66165 -342.897968)
		(end 266.255754 -342.897968)
		(width 0.17145)
		(layer "F.Cu")
		(net "SCC_A_SLOT_ID_0")
	)
	(via
		(at 264.66165 -342.897968)
		(size 0.6604)
		(drill 0.3302)
		(layers "F.Cu" "B.Cu")
		(net "SCC_A_SLOT_ID_0")
	)
	(via
		(at 266.255754 -342.897968)
		(size 0.5588)
		(drill 0.3048)
		(layers "F.Cu" "B.Cu")
		(net "SCC_A_SLOT_ID_0")
	)
	(segment
		(start 273.2278 -347.472)
		(end 271.530826 -347.472)
		(width 0.12065)
		(layer "In4.Cu")
		(net "SCC_A_SLOT_ID_0")
	)
	(segment
		(start 282.829 -351.155)
		(end 276.9108 -351.155)
		(width 0.12065)
		(layer "In4.Cu")
		(net "SCC_A_SLOT_ID_0")
	)
	(segment
		(start 266.956794 -342.897968)
		(end 266.255754 -342.897968)
		(width 0.12065)
		(layer "In4.Cu")
		(net "SCC_A_SLOT_ID_0")
	)
	(segment
		(start 283.23667 -352.305112)
		(end 283.23667 -351.56267)
		(width 0.12065)
		(layer "In4.Cu")
		(net "SCC_A_SLOT_ID_0")
	)
	(segment
		(start 276.9108 -351.155)
		(end 273.2278 -347.472)
		(width 0.12065)
		(layer "In4.Cu")
		(net "SCC_A_SLOT_ID_0")
	)
	(segment
		(start 271.530826 -347.472)
		(end 266.956794 -342.897968)
		(width 0.12065)
		(layer "In4.Cu")
		(net "SCC_A_SLOT_ID_0")
	)
	(segment
		(start 283.23667 -351.56267)
		(end 282.829 -351.155)
		(width 0.12065)
		(layer "In4.Cu")
		(net "SCC_A_SLOT_ID_0")
	)
	(segment
		(start 88.302338 -24.24811)
		(end 88.361774 -24.188674)
		(width 0.17145)
		(layer "F.Cu")
		(net "SCC_A_INS_N")
	)
	(segment
		(start 225.245168 -357.546656)
		(end 225.245168 -356.6414)
		(width 0.17145)
		(layer "F.Cu")
		(net "SCC_A_INS_N")
	)
	(segment
		(start 88.361774 -24.188674)
		(end 88.361774 -22.22881)
		(width 0.17145)
		(layer "F.Cu")
		(net "SCC_A_INS_N")
	)
	(segment
		(start 341.904574 -24.41829)
		(end 341.904574 -20.490434)
		(width 0.17145)
		(layer "F.Cu")
		(net "SCC_A_INS_N")
	)
	(segment
		(start 88.302338 -24.285956)
		(end 88.302338 -24.24811)
		(width 0.17145)
		(layer "F.Cu")
		(net "SCC_A_INS_N")
	)
	(via
		(at 323.27977 -288.872422)
		(size 0.5588)
		(drill 0.3048)
		(layers "F.Cu" "B.Cu")
		(net "SCC_A_INS_N")
	)
	(via
		(at 227.711 -340.8172)
		(size 0.5588)
		(drill 0.3048)
		(layers "F.Cu" "B.Cu")
		(net "SCC_A_INS_N")
	)
	(via
		(at 201.253344 -335.162398)
		(size 0.5588)
		(drill 0.3048)
		(layers "F.Cu" "B.Cu")
		(net "SCC_A_INS_N")
	)
	(via
		(at 203.717144 -295.717976)
		(size 0.5588)
		(drill 0.3048)
		(layers "F.Cu" "B.Cu")
		(net "SCC_A_INS_N")
	)
	(via
		(at 225.245168 -356.6414)
		(size 0.5588)
		(drill 0.3048)
		(layers "F.Cu" "B.Cu")
		(net "SCC_A_INS_N")
	)
	(via
		(at 88.302338 -24.285956)
		(size 0.5588)
		(drill 0.3048)
		(layers "F.Cu" "B.Cu")
		(net "SCC_A_INS_N")
	)
	(via
		(at 226.5172 -342.89111)
		(size 0.6096)
		(drill 0.3048)
		(layers "F.Cu" "B.Cu")
		(net "SCC_A_INS_N")
	)
	(via
		(at 341.904574 -20.490434)
		(size 0.5588)
		(drill 0.3048)
		(layers "F.Cu" "B.Cu")
		(net "SCC_A_INS_N")
	)
	(segment
		(start 225.245168 -352.985832)
		(end 226.5172 -351.7138)
		(width 0.17145)
		(layer "B.Cu")
		(net "SCC_A_INS_N")
	)
	(segment
		(start 226.5172 -351.7138)
		(end 226.5172 -342.89111)
		(width 0.17145)
		(layer "B.Cu")
		(net "SCC_A_INS_N")
	)
	(segment
		(start 226.5172 -342.011)
		(end 226.5172 -342.89111)
		(width 0.17145)
		(layer "B.Cu")
		(net "SCC_A_INS_N")
	)
	(segment
		(start 225.245168 -356.6414)
		(end 225.245168 -352.985832)
		(width 0.17145)
		(layer "B.Cu")
		(net "SCC_A_INS_N")
	)
	(segment
		(start 227.711 -340.8172)
		(end 226.5172 -342.011)
		(width 0.17145)
		(layer "B.Cu")
		(net "SCC_A_INS_N")
	)
	(segment
		(start 265.478768 -292.682168)
		(end 262.243824 -295.917112)
		(width 0.13335)
		(layer "In2.Cu")
		(net "SCC_A_INS_N")
	)
	(segment
		(start 174.075598 -48.327056)
		(end 175.279558 -49.531016)
		(width 0.13335)
		(layer "In2.Cu")
		(net "SCC_A_INS_N")
	)
	(segment
		(start 227.26142 -405.456898)
		(end 227.33635 -405.531828)
		(width 0.13335)
		(layer "In2.Cu")
		(net "SCC_A_INS_N")
	)
	(segment
		(start 183.506364 -74.562208)
		(end 183.506364 -77.154786)
		(width 0.13335)
		(layer "In2.Cu")
		(net "SCC_A_INS_N")
	)
	(segment
		(start 225.2599 -398.1069)
		(end 227.26142 -400.10842)
		(width 0.13335)
		(layer "In2.Cu")
		(net "SCC_A_INS_N")
	)
	(segment
		(start 206.054452 -295.717976)
		(end 203.717144 -295.717976)
		(width 0.13335)
		(layer "In2.Cu")
		(net "SCC_A_INS_N")
	)
	(segment
		(start 103.883714 -37.634926)
		(end 125.556518 -37.634926)
		(width 0.13335)
		(layer "In2.Cu")
		(net "SCC_A_INS_N")
	)
	(segment
		(start 88.302338 -24.285956)
		(end 88.302338 -24.24811)
		(width 0.13335)
		(layer "In2.Cu")
		(net "SCC_A_INS_N")
	)
	(segment
		(start 275.586698 -340.5505)
		(end 274.583398 -341.5538)
		(width 0.13335)
		(layer "In2.Cu")
		(net "SCC_A_INS_N")
	)
	(segment
		(start 88.872568 -23.67788)
		(end 89.926668 -23.67788)
		(width 0.13335)
		(layer "In2.Cu")
		(net "SCC_A_INS_N")
	)
	(segment
		(start 247.555258 -12.022582)
		(end 260.425692 0.847852)
		(width 0.13335)
		(layer "In2.Cu")
		(net "SCC_A_INS_N")
	)
	(segment
		(start 310.95315 -18.380456)
		(end 312.479944 -19.90725)
		(width 0.13335)
		(layer "In2.Cu")
		(net "SCC_A_INS_N")
	)
	(segment
		(start 285.25978 -292.682168)
		(end 265.478768 -292.682168)
		(width 0.13335)
		(layer "In2.Cu")
		(net "SCC_A_INS_N")
	)
	(segment
		(start 282.83662 -339.705188)
		(end 281.991308 -340.5505)
		(width 0.13335)
		(layer "In2.Cu")
		(net "SCC_A_INS_N")
	)
	(segment
		(start 252.640846 -295.917112)
		(end 250.01093 -298.547028)
		(width 0.13335)
		(layer "In2.Cu")
		(net "SCC_A_INS_N")
	)
	(segment
		(start 230.785924 -86.389972)
		(end 234.96143 -90.565478)
		(width 0.13335)
		(layer "In2.Cu")
		(net "SCC_A_INS_N")
	)
	(segment
		(start 340.810596 -20.516596)
		(end 340.836758 -20.490434)
		(width 0.13335)
		(layer "In2.Cu")
		(net "SCC_A_INS_N")
	)
	(segment
		(start 247.555258 -88.154002)
		(end 247.555258 -12.022582)
		(width 0.13335)
		(layer "In2.Cu")
		(net "SCC_A_INS_N")
	)
	(segment
		(start 340.376256 -20.516596)
		(end 340.810596 -20.516596)
		(width 0.13335)
		(layer "In2.Cu")
		(net "SCC_A_INS_N")
	)
	(segment
		(start 192.74155 -86.389972)
		(end 230.785924 -86.389972)
		(width 0.13335)
		(layer "In2.Cu")
		(net "SCC_A_INS_N")
	)
	(segment
		(start 88.302338 -24.24811)
		(end 88.872568 -23.67788)
		(width 0.13335)
		(layer "In2.Cu")
		(net "SCC_A_INS_N")
	)
	(segment
		(start 126.929388 -39.007796)
		(end 147.222718 -39.007796)
		(width 0.13335)
		(layer "In2.Cu")
		(net "SCC_A_INS_N")
	)
	(segment
		(start 323.250814 -288.843466)
		(end 289.098482 -288.843466)
		(width 0.13335)
		(layer "In2.Cu")
		(net "SCC_A_INS_N")
	)
	(segment
		(start 89.926668 -23.67788)
		(end 103.883714 -37.634926)
		(width 0.13335)
		(layer "In2.Cu")
		(net "SCC_A_INS_N")
	)
	(segment
		(start 334.119982 -19.90725)
		(end 335.082642 -20.86991)
		(width 0.13335)
		(layer "In2.Cu")
		(net "SCC_A_INS_N")
	)
	(segment
		(start 225.245168 -356.6414)
		(end 227.809806 -359.206038)
		(width 0.13335)
		(layer "In2.Cu")
		(net "SCC_A_INS_N")
	)
	(segment
		(start 227.33635 -405.531828)
		(end 227.33635 -410.04109)
		(width 0.13335)
		(layer "In2.Cu")
		(net "SCC_A_INS_N")
	)
	(segment
		(start 228.092 -341.1982)
		(end 227.711 -340.8172)
		(width 0.13335)
		(layer "In2.Cu")
		(net "SCC_A_INS_N")
	)
	(segment
		(start 147.222718 -39.007796)
		(end 148.595588 -37.634926)
		(width 0.13335)
		(layer "In2.Cu")
		(net "SCC_A_INS_N")
	)
	(segment
		(start 295.280588 -7.906004)
		(end 307.291994 -7.906004)
		(width 0.13335)
		(layer "In2.Cu")
		(net "SCC_A_INS_N")
	)
	(segment
		(start 215.783922 -340.1314)
		(end 210.83397 -335.181448)
		(width 0.13335)
		(layer "In2.Cu")
		(net "SCC_A_INS_N")
	)
	(segment
		(start 245.811802 -298.547028)
		(end 245.55577 -298.80306)
		(width 0.13335)
		(layer "In2.Cu")
		(net "SCC_A_INS_N")
	)
	(segment
		(start 125.556518 -37.634926)
		(end 126.929388 -39.007796)
		(width 0.13335)
		(layer "In2.Cu")
		(net "SCC_A_INS_N")
	)
	(segment
		(start 227.809806 -380.265178)
		(end 225.2599 -382.815084)
		(width 0.13335)
		(layer "In2.Cu")
		(net "SCC_A_INS_N")
	)
	(segment
		(start 310.95315 -11.56716)
		(end 310.95315 -18.380456)
		(width 0.13335)
		(layer "In2.Cu")
		(net "SCC_A_INS_N")
	)
	(segment
		(start 340.836758 -20.490434)
		(end 341.904574 -20.490434)
		(width 0.13335)
		(layer "In2.Cu")
		(net "SCC_A_INS_N")
	)
	(segment
		(start 274.583398 -341.5538)
		(end 257.300476 -341.5538)
		(width 0.13335)
		(layer "In2.Cu")
		(net "SCC_A_INS_N")
	)
	(segment
		(start 183.482234 -59.18835)
		(end 183.482234 -74.538078)
		(width 0.13335)
		(layer "In2.Cu")
		(net "SCC_A_INS_N")
	)
	(segment
		(start 257.300476 -341.5538)
		(end 256.944876 -341.1982)
		(width 0.13335)
		(layer "In2.Cu")
		(net "SCC_A_INS_N")
	)
	(segment
		(start 227.711 -340.8172)
		(end 227.0252 -340.1314)
		(width 0.13335)
		(layer "In2.Cu")
		(net "SCC_A_INS_N")
	)
	(segment
		(start 250.01093 -298.547028)
		(end 245.811802 -298.547028)
		(width 0.13335)
		(layer "In2.Cu")
		(net "SCC_A_INS_N")
	)
	(segment
		(start 175.279558 -49.531016)
		(end 175.279558 -50.985674)
		(width 0.13335)
		(layer "In2.Cu")
		(net "SCC_A_INS_N")
	)
	(segment
		(start 228.000052 -410.704792)
		(end 228.000052 -411.000194)
		(width 0.13335)
		(layer "In2.Cu")
		(net "SCC_A_INS_N")
	)
	(segment
		(start 148.595588 -37.634926)
		(end 160.92551 -37.634926)
		(width 0.13335)
		(layer "In2.Cu")
		(net "SCC_A_INS_N")
	)
	(segment
		(start 260.425692 0.847852)
		(end 286.526732 0.847852)
		(width 0.13335)
		(layer "In2.Cu")
		(net "SCC_A_INS_N")
	)
	(segment
		(start 209.139536 -298.80306)
		(end 206.054452 -295.717976)
		(width 0.13335)
		(layer "In2.Cu")
		(net "SCC_A_INS_N")
	)
	(segment
		(start 256.944876 -341.1982)
		(end 228.092 -341.1982)
		(width 0.13335)
		(layer "In2.Cu")
		(net "SCC_A_INS_N")
	)
	(segment
		(start 262.243824 -295.917112)
		(end 252.640846 -295.917112)
		(width 0.13335)
		(layer "In2.Cu")
		(net "SCC_A_INS_N")
	)
	(segment
		(start 281.991308 -340.5505)
		(end 275.586698 -340.5505)
		(width 0.13335)
		(layer "In2.Cu")
		(net "SCC_A_INS_N")
	)
	(segment
		(start 245.143782 -90.565478)
		(end 247.555258 -88.154002)
		(width 0.13335)
		(layer "In2.Cu")
		(net "SCC_A_INS_N")
	)
	(segment
		(start 201.253344 -335.181448)
		(end 201.253344 -335.162398)
		(width 0.13335)
		(layer "In2.Cu")
		(net "SCC_A_INS_N")
	)
	(segment
		(start 323.27977 -288.872422)
		(end 323.250814 -288.843466)
		(width 0.13335)
		(layer "In2.Cu")
		(net "SCC_A_INS_N")
	)
	(segment
		(start 183.482234 -74.538078)
		(end 183.506364 -74.562208)
		(width 0.13335)
		(layer "In2.Cu")
		(net "SCC_A_INS_N")
	)
	(segment
		(start 289.098482 -288.843466)
		(end 285.25978 -292.682168)
		(width 0.13335)
		(layer "In2.Cu")
		(net "SCC_A_INS_N")
	)
	(segment
		(start 175.279558 -50.985674)
		(end 183.482234 -59.18835)
		(width 0.13335)
		(layer "In2.Cu")
		(net "SCC_A_INS_N")
	)
	(segment
		(start 312.479944 -19.90725)
		(end 334.119982 -19.90725)
		(width 0.13335)
		(layer "In2.Cu")
		(net "SCC_A_INS_N")
	)
	(segment
		(start 338.868258 -20.041616)
		(end 339.901276 -20.041616)
		(width 0.13335)
		(layer "In2.Cu")
		(net "SCC_A_INS_N")
	)
	(segment
		(start 210.83397 -335.181448)
		(end 201.253344 -335.181448)
		(width 0.13335)
		(layer "In2.Cu")
		(net "SCC_A_INS_N")
	)
	(segment
		(start 227.26142 -400.10842)
		(end 227.26142 -405.456898)
		(width 0.13335)
		(layer "In2.Cu")
		(net "SCC_A_INS_N")
	)
	(segment
		(start 234.96143 -90.565478)
		(end 245.143782 -90.565478)
		(width 0.13335)
		(layer "In2.Cu")
		(net "SCC_A_INS_N")
	)
	(segment
		(start 286.526732 0.847852)
		(end 295.280588 -7.906004)
		(width 0.13335)
		(layer "In2.Cu")
		(net "SCC_A_INS_N")
	)
	(segment
		(start 227.0252 -340.1314)
		(end 215.783922 -340.1314)
		(width 0.13335)
		(layer "In2.Cu")
		(net "SCC_A_INS_N")
	)
	(segment
		(start 160.92551 -37.634926)
		(end 171.61764 -48.327056)
		(width 0.13335)
		(layer "In2.Cu")
		(net "SCC_A_INS_N")
	)
	(segment
		(start 245.55577 -298.80306)
		(end 209.139536 -298.80306)
		(width 0.13335)
		(layer "In2.Cu")
		(net "SCC_A_INS_N")
	)
	(segment
		(start 225.2599 -382.815084)
		(end 225.2599 -398.1069)
		(width 0.13335)
		(layer "In2.Cu")
		(net "SCC_A_INS_N")
	)
	(segment
		(start 338.039964 -20.86991)
		(end 338.868258 -20.041616)
		(width 0.13335)
		(layer "In2.Cu")
		(net "SCC_A_INS_N")
	)
	(segment
		(start 307.291994 -7.906004)
		(end 310.95315 -11.56716)
		(width 0.13335)
		(layer "In2.Cu")
		(net "SCC_A_INS_N")
	)
	(segment
		(start 171.61764 -48.327056)
		(end 174.075598 -48.327056)
		(width 0.13335)
		(layer "In2.Cu")
		(net "SCC_A_INS_N")
	)
	(segment
		(start 183.506364 -77.154786)
		(end 192.74155 -86.389972)
		(width 0.13335)
		(layer "In2.Cu")
		(net "SCC_A_INS_N")
	)
	(segment
		(start 339.901276 -20.041616)
		(end 340.376256 -20.516596)
		(width 0.13335)
		(layer "In2.Cu")
		(net "SCC_A_INS_N")
	)
	(segment
		(start 227.809806 -359.206038)
		(end 227.809806 -380.265178)
		(width 0.13335)
		(layer "In2.Cu")
		(net "SCC_A_INS_N")
	)
	(segment
		(start 227.33635 -410.04109)
		(end 228.000052 -410.704792)
		(width 0.13335)
		(layer "In2.Cu")
		(net "SCC_A_INS_N")
	)
	(segment
		(start 335.082642 -20.86991)
		(end 338.039964 -20.86991)
		(width 0.13335)
		(layer "In2.Cu")
		(net "SCC_A_INS_N")
	)
	(segment
		(start 321.160648 -149.005544)
		(end 322.693792 -147.4724)
		(width 0.12065)
		(layer "In4.Cu")
		(net "SCC_A_INS_N")
	)
	(segment
		(start 320.60515 -202.822556)
		(end 320.60515 -173.460664)
		(width 0.12065)
		(layer "In4.Cu")
		(net "SCC_A_INS_N")
	)
	(segment
		(start 338.993988 -31.877254)
		(end 338.993734 -31.877)
		(width 0.12065)
		(layer "In4.Cu")
		(net "SCC_A_INS_N")
	)
	(segment
		(start 320.85534 -173.210474)
		(end 320.85534 -173.21022)
		(width 0.12065)
		(layer "In4.Cu")
		(net "SCC_A_INS_N")
	)
	(segment
		(start 320.60515 -173.460664)
		(end 320.85534 -173.210474)
		(width 0.12065)
		(layer "In4.Cu")
		(net "SCC_A_INS_N")
	)
	(segment
		(start 320.85534 -173.21022)
		(end 321.160648 -172.904912)
		(width 0.12065)
		(layer "In4.Cu")
		(net "SCC_A_INS_N")
	)
	(segment
		(start 338.993734 -33.64611)
		(end 338.993734 -33.58896)
		(width 0.12065)
		(layer "In4.Cu")
		(net "SCC_A_INS_N")
	)
	(segment
		(start 325.609712 -74.147934)
		(end 326.068436 -74.147934)
		(width 0.12065)
		(layer "In4.Cu")
		(net "SCC_A_INS_N")
	)
	(segment
		(start 332.59395 -55.619904)
		(end 336.426048 -51.787806)
		(width 0.12065)
		(layer "In4.Cu")
		(net "SCC_A_INS_N")
	)
	(segment
		(start 336.426048 -51.787806)
		(end 336.426048 -45.195236)
		(width 0.12065)
		(layer "In4.Cu")
		(net "SCC_A_INS_N")
	)
	(segment
		(start 321.976242 -204.193648)
		(end 320.60515 -202.822556)
		(width 0.12065)
		(layer "In4.Cu")
		(net "SCC_A_INS_N")
	)
	(segment
		(start 321.976242 -221.570042)
		(end 321.976242 -204.193648)
		(width 0.12065)
		(layer "In4.Cu")
		(net "SCC_A_INS_N")
	)
	(segment
		(start 338.993734 -31.877)
		(end 338.993734 -26.704798)
		(width 0.12065)
		(layer "In4.Cu")
		(net "SCC_A_INS_N")
	)
	(segment
		(start 326.068436 -74.147934)
		(end 331.45603 -68.76034)
		(width 0.12065)
		(layer "In4.Cu")
		(net "SCC_A_INS_N")
	)
	(segment
		(start 338.993988 -33.588706)
		(end 338.993988 -31.877254)
		(width 0.12065)
		(layer "In4.Cu")
		(net "SCC_A_INS_N")
	)
	(segment
		(start 321.160648 -172.904912)
		(end 321.160648 -149.005544)
		(width 0.12065)
		(layer "In4.Cu")
		(net "SCC_A_INS_N")
	)
	(segment
		(start 322.693792 -147.4724)
		(end 322.693792 -77.522578)
		(width 0.12065)
		(layer "In4.Cu")
		(net "SCC_A_INS_N")
	)
	(segment
		(start 323.114924 -76.642722)
		(end 325.609712 -74.147934)
		(width 0.12065)
		(layer "In4.Cu")
		(net "SCC_A_INS_N")
	)
	(segment
		(start 324.193154 -268.246098)
		(end 324.193154 -223.786954)
		(width 0.12065)
		(layer "In4.Cu")
		(net "SCC_A_INS_N")
	)
	(segment
		(start 322.693792 -77.522578)
		(end 323.114924 -77.101446)
		(width 0.12065)
		(layer "In4.Cu")
		(net "SCC_A_INS_N")
	)
	(segment
		(start 323.27977 -269.159482)
		(end 324.193154 -268.246098)
		(width 0.12065)
		(layer "In4.Cu")
		(net "SCC_A_INS_N")
	)
	(segment
		(start 324.193154 -223.786954)
		(end 321.976242 -221.570042)
		(width 0.12065)
		(layer "In4.Cu")
		(net "SCC_A_INS_N")
	)
	(segment
		(start 337.906106 -35.938206)
		(end 337.906106 -34.733738)
		(width 0.12065)
		(layer "In4.Cu")
		(net "SCC_A_INS_N")
	)
	(segment
		(start 337.357466 -36.486846)
		(end 337.906106 -35.938206)
		(width 0.12065)
		(layer "In4.Cu")
		(net "SCC_A_INS_N")
	)
	(segment
		(start 332.59395 -65.57645)
		(end 332.59395 -55.619904)
		(width 0.12065)
		(layer "In4.Cu")
		(net "SCC_A_INS_N")
	)
	(segment
		(start 337.906106 -34.733738)
		(end 338.993734 -33.64611)
		(width 0.12065)
		(layer "In4.Cu")
		(net "SCC_A_INS_N")
	)
	(segment
		(start 323.114924 -77.101446)
		(end 323.114924 -76.642722)
		(width 0.12065)
		(layer "In4.Cu")
		(net "SCC_A_INS_N")
	)
	(segment
		(start 331.45603 -68.76034)
		(end 331.45603 -66.71437)
		(width 0.12065)
		(layer "In4.Cu")
		(net "SCC_A_INS_N")
	)
	(segment
		(start 341.904574 -23.793958)
		(end 341.904574 -20.490434)
		(width 0.12065)
		(layer "In4.Cu")
		(net "SCC_A_INS_N")
	)
	(segment
		(start 338.993734 -33.58896)
		(end 338.993988 -33.588706)
		(width 0.12065)
		(layer "In4.Cu")
		(net "SCC_A_INS_N")
	)
	(segment
		(start 336.426048 -45.195236)
		(end 337.357466 -44.263818)
		(width 0.12065)
		(layer "In4.Cu")
		(net "SCC_A_INS_N")
	)
	(segment
		(start 323.27977 -288.872422)
		(end 323.27977 -269.159482)
		(width 0.12065)
		(layer "In4.Cu")
		(net "SCC_A_INS_N")
	)
	(segment
		(start 338.993734 -26.704798)
		(end 341.904574 -23.793958)
		(width 0.12065)
		(layer "In4.Cu")
		(net "SCC_A_INS_N")
	)
	(segment
		(start 337.357466 -44.263818)
		(end 337.357466 -36.486846)
		(width 0.12065)
		(layer "In4.Cu")
		(net "SCC_A_INS_N")
	)
	(segment
		(start 331.45603 -66.71437)
		(end 332.59395 -65.57645)
		(width 0.12065)
		(layer "In4.Cu")
		(net "SCC_A_INS_N")
	)
	(segment
		(start 203.717144 -298.781724)
		(end 201.294238 -301.20463)
		(width 0.13335)
		(layer "In9.Cu")
		(net "SCC_A_INS_N")
	)
	(segment
		(start 201.294238 -301.20463)
		(end 201.294238 -335.162398)
		(width 0.13335)
		(layer "In9.Cu")
		(net "SCC_A_INS_N")
	)
	(segment
		(start 203.717144 -295.717976)
		(end 203.717144 -298.781724)
		(width 0.13335)
		(layer "In9.Cu")
		(net "SCC_A_INS_N")
	)
	(segment
		(start 201.294238 -335.162398)
		(end 201.253344 -335.162398)
		(width 0.13335)
		(layer "In9.Cu")
		(net "SCC_A_INS_N")
	)
	(segment
		(start 172.0977 -47.134526)
		(end 172.0723 -47.159926)
		(width 0.508)
		(layer "F.Cu")
		(net "P12V_A")
	)
	(segment
		(start 172.1485 -53.482494)
		(end 172.1485 -54.523894)
		(width 0.508)
		(layer "F.Cu")
		(net "P12V_A")
	)
	(segment
		(start 79.479648 -167.060118)
		(end 79.479648 -166.221918)
		(width 0.508)
		(layer "F.Cu")
		(net "P12V_A")
	)
	(segment
		(start 157.36824 -142.893796)
		(end 158.301944 -142.893796)
		(width 0.508)
		(layer "F.Cu")
		(net "P12V_A")
	)
	(segment
		(start 396.28445 -48.554894)
		(end 396.28445 -47.729394)
		(width 0.508)
		(layer "F.Cu")
		(net "P12V_A")
	)
	(segment
		(start 142.604998 -52.034694)
		(end 142.604998 -50.101246)
		(width 0.508)
		(layer "F.Cu")
		(net "P12V_A")
	)
	(segment
		(start 364.734602 -48.554894)
		(end 364.734602 -46.693582)
		(width 0.508)
		(layer "F.Cu")
		(net "P12V_A")
	)
	(segment
		(start 400.03095 -160.291018)
		(end 400.03095 -159.465518)
		(width 0.508)
		(layer "F.Cu")
		(net "P12V_A")
	)
	(segment
		(start 140.598398 -284.523942)
		(end 140.598398 -283.507942)
		(width 0.508)
		(layer "F.Cu")
		(net "P12V_A")
	)
	(segment
		(start 113.175542 -281.324304)
		(end 112.261904 -281.324304)
		(width 0.508)
		(layer "F.Cu")
		(net "P12V_A")
	)
	(segment
		(start 142.604998 -167.060118)
		(end 142.604998 -166.221918)
		(width 0.508)
		(layer "F.Cu")
		(net "P12V_A")
	)
	(segment
		(start 140.572998 -160.608518)
		(end 139.683998 -160.608518)
		(width 0.508)
		(layer "F.Cu")
		(net "P12V_A")
	)
	(segment
		(start 153.105866 -140.292074)
		(end 152.153366 -140.292074)
		(width 0.508)
		(layer "F.Cu")
		(net "P12V_A")
	)
	(segment
		(start 222.634556 -384.796792)
		(end 222.634556 -385.867656)
		(width 0.508)
		(layer "F.Cu")
		(net "P12V_A")
	)
	(segment
		(start 77.447648 -275.633942)
		(end 76.537058 -275.633942)
		(width 0.508)
		(layer "F.Cu")
		(net "P12V_A")
	)
	(segment
		(start 468.354918 -166.501318)
		(end 469.265 -167.4114)
		(width 0.508)
		(layer "F.Cu")
		(net "P12V_A")
	)
	(segment
		(start 132.201666 -143.437102)
		(end 132.75183 -143.437102)
		(width 0.508)
		(layer "F.Cu")
		(net "P12V_A")
	)
	(segment
		(start 132.864352 -143.32458)
		(end 133.89483 -143.32458)
		(width 0.508)
		(layer "F.Cu")
		(net "P12V_A")
	)
	(segment
		(start 47.929546 -52.060094)
		(end 47.929546 -50.942494)
		(width 0.508)
		(layer "F.Cu")
		(net "P12V_A")
	)
	(segment
		(start 45.948346 -53.482494)
		(end 45.948346 -54.523894)
		(width 0.508)
		(layer "F.Cu")
		(net "P12V_A")
	)
	(segment
		(start 463.1309 -275.291042)
		(end 463.1309 -274.490942)
		(width 0.508)
		(layer "F.Cu")
		(net "P12V_A")
	)
	(segment
		(start 400.03095 -275.316442)
		(end 400.03095 -274.490942)
		(width 0.508)
		(layer "F.Cu")
		(net "P12V_A")
	)
	(segment
		(start 427.834552 -278.554942)
		(end 427.834552 -277.297642)
		(width 0.508)
		(layer "F.Cu")
		(net "P12V_A")
	)
	(segment
		(start 468.355426 -52.314094)
		(end 469.498426 -53.457094)
		(width 0.508)
		(layer "F.Cu")
		(net "P12V_A")
	)
	(segment
		(start 463.1309 -45.290994)
		(end 463.1309 -44.490894)
		(width 0.508)
		(layer "F.Cu")
		(net "P12V_A")
	)
	(segment
		(start 431.581052 -160.291018)
		(end 431.581052 -159.490918)
		(width 0.508)
		(layer "F.Cu")
		(net "P12V_A")
	)
	(segment
		(start 459.3844 -48.554894)
		(end 459.3844 -47.729394)
		(width 0.508)
		(layer "F.Cu")
		(net "P12V_A")
	)
	(segment
		(start 77.498448 -168.482518)
		(end 77.498448 -169.523918)
		(width 0.508)
		(layer "F.Cu")
		(net "P12V_A")
	)
	(segment
		(start 14.398498 -283.482542)
		(end 14.398498 -284.523942)
		(width 0.508)
		(layer "F.Cu")
		(net "P12V_A")
	)
	(segment
		(start 109.022896 -45.633894)
		(end 109.022896 -44.7802)
		(width 0.508)
		(layer "F.Cu")
		(net "P12V_A")
	)
	(segment
		(start 111.054896 -167.085518)
		(end 111.054896 -166.221918)
		(width 0.508)
		(layer "F.Cu")
		(net "P12V_A")
	)
	(segment
		(start 47.853346 -281.018742)
		(end 47.853346 -280.129742)
		(width 0.508)
		(layer "F.Cu")
		(net "P12V_A")
	)
	(segment
		(start 222.634556 -385.867656)
		(end 221.477332 -387.02488)
		(width 0.508)
		(layer "F.Cu")
		(net "P12V_A")
	)
	(segment
		(start 33.798002 -256.40665)
		(end 33.798002 -257.23215)
		(width 0.508)
		(layer "F.Cu")
		(net "P12V_A")
	)
	(segment
		(start 459.3844 -163.554918)
		(end 459.3844 -162.729418)
		(width 0.508)
		(layer "F.Cu")
		(net "P12V_A")
	)
	(segment
		(start 109.048296 -53.482494)
		(end 109.048296 -54.523894)
		(width 0.508)
		(layer "F.Cu")
		(net "P12V_A")
	)
	(segment
		(start 111.029496 -52.085494)
		(end 111.029496 -51.221894)
		(width 0.508)
		(layer "F.Cu")
		(net "P12V_A")
	)
	(segment
		(start 52.3875 -165.1)
		(end 53.34 -165.1)
		(width 0.508)
		(layer "F.Cu")
		(net "P12V_A")
	)
	(segment
		(start 157.36824 -138.989054)
		(end 157.36824 -141.014196)
		(width 0.508)
		(layer "F.Cu")
		(net "P12V_A")
	)
	(segment
		(start 466.586062 -280.261314)
		(end 467.469982 -280.261314)
		(width 0.508)
		(layer "F.Cu")
		(net "P12V_A")
	)
	(segment
		(start 460.803498 -278.554942)
		(end 461.275684 -279.027128)
		(width 0.508)
		(layer "F.Cu")
		(net "P12V_A")
	)
	(segment
		(start 333.1845 -278.554942)
		(end 333.1845 -277.729442)
		(width 0.508)
		(layer "F.Cu")
		(net "P12V_A")
	)
	(segment
		(start 336.931 -160.291018)
		(end 336.931 -159.490918)
		(width 0.508)
		(layer "F.Cu")
		(net "P12V_A")
	)
	(segment
		(start 468.354918 -165.145974)
		(end 468.354918 -166.501318)
		(width 0.508)
		(layer "F.Cu")
		(net "P12V_A")
	)
	(segment
		(start 140.598398 -54.523894)
		(end 140.598398 -53.507894)
		(width 0.508)
		(layer "F.Cu")
		(net "P12V_A")
	)
	(segment
		(start 241.3762 -381.7493)
		(end 241.3762 -380.873)
		(width 0.508)
		(layer "F.Cu")
		(net "P12V_A")
	)
	(segment
		(start 45.897546 -45.633894)
		(end 45.059346 -45.633894)
		(width 0.508)
		(layer "F.Cu")
		(net "P12V_A")
	)
	(segment
		(start 469.498426 -53.457094)
		(end 469.498426 -54.523894)
		(width 0.508)
		(layer "F.Cu")
		(net "P12V_A")
	)
	(segment
		(start 336.9056 -45.290994)
		(end 337.22183 -45.290994)
		(width 0.508)
		(layer "F.Cu")
		(net "P12V_A")
	)
	(segment
		(start 47.027846 -157.839918)
		(end 47.027846 -156.959046)
		(width 0.508)
		(layer "F.Cu")
		(net "P12V_A")
	)
	(segment
		(start 140.547598 -45.608494)
		(end 140.547598 -45.845222)
		(width 0.508)
		(layer "F.Cu")
		(net "P12V_A")
	)
	(segment
		(start 394.610336 -287.597342)
		(end 395.282674 -288.26968)
		(width 0.508)
		(layer "F.Cu")
		(net "P12V_A")
	)
	(segment
		(start 140.547598 -45.845222)
		(end 138.686286 -47.706534)
		(width 0.508)
		(layer "F.Cu")
		(net "P12V_A")
	)
	(segment
		(start 174.0535 -280.993342)
		(end 174.0535 -280.129742)
		(width 0.508)
		(layer "F.Cu")
		(net "P12V_A")
	)
	(segment
		(start 171.9961 -277.6474)
		(end 171.9961 -278.3967)
		(width 0.508)
		(layer "F.Cu")
		(net "P12V_A")
	)
	(segment
		(start 142.579598 -282.060142)
		(end 142.579598 -281.221942)
		(width 0.508)
		(layer "F.Cu")
		(net "P12V_A")
	)
	(segment
		(start 174.1297 -167.110918)
		(end 174.1297 -166.221918)
		(width 0.508)
		(layer "F.Cu")
		(net "P12V_A")
	)
	(segment
		(start 431.581052 -275.291042)
		(end 431.581052 -274.465542)
		(width 0.508)
		(layer "F.Cu")
		(net "P12V_A")
	)
	(segment
		(start 333.1845 -48.554894)
		(end 333.1845 -47.729394)
		(width 0.508)
		(layer "F.Cu")
		(net "P12V_A")
	)
	(segment
		(start 336.931 -275.291042)
		(end 336.931 -274.490942)
		(width 0.508)
		(layer "F.Cu")
		(net "P12V_A")
	)
	(segment
		(start 333.1845 -163.554918)
		(end 333.1845 -162.729418)
		(width 0.508)
		(layer "F.Cu")
		(net "P12V_A")
	)
	(segment
		(start 79.479648 -282.085542)
		(end 79.479648 -281.132026)
		(width 0.508)
		(layer "F.Cu")
		(net "P12V_A")
	)
	(segment
		(start 14.373098 -160.608518)
		(end 13.484098 -160.608518)
		(width 0.508)
		(layer "F.Cu")
		(net "P12V_A")
	)
	(segment
		(start 140.572998 -275.633942)
		(end 139.642342 -275.633942)
		(width 0.508)
		(layer "F.Cu")
		(net "P12V_A")
	)
	(segment
		(start 394.35405 -287.597342)
		(end 394.610336 -287.597342)
		(width 0.508)
		(layer "F.Cu")
		(net "P12V_A")
	)
	(segment
		(start 174.1297 -52.110894)
		(end 174.1297 -50.747422)
		(width 0.508)
		(layer "F.Cu")
		(net "P12V_A")
	)
	(segment
		(start 471.510614 -277.998936)
		(end 471.943684 -277.565866)
		(width 0.508)
		(layer "F.Cu")
		(net "P12V_A")
	)
	(segment
		(start 471.510614 -279.091898)
		(end 471.510614 -277.998936)
		(width 0.508)
		(layer "F.Cu")
		(net "P12V_A")
	)
	(segment
		(start 79.479648 -281.132026)
		(end 79.560928 -281.050746)
		(width 0.508)
		(layer "F.Cu")
		(net "P12V_A")
	)
	(segment
		(start 77.447648 -45.633894)
		(end 76.609448 -45.633894)
		(width 0.508)
		(layer "F.Cu")
		(net "P12V_A")
	)
	(segment
		(start 132.75183 -143.437102)
		(end 132.864352 -143.32458)
		(width 0.508)
		(layer "F.Cu")
		(net "P12V_A")
	)
	(segment
		(start 234.315 -380.9238)
		(end 234.315 -381.7493)
		(width 0.508)
		(layer "F.Cu")
		(net "P12V_A")
	)
	(segment
		(start 395.01445 -164.062918)
		(end 395.01445 -163.237418)
		(width 0.508)
		(layer "F.Cu")
		(net "P12V_A")
	)
	(segment
		(start 77.473048 -160.633918)
		(end 76.609448 -160.633918)
		(width 0.508)
		(layer "F.Cu")
		(net "P12V_A")
	)
	(segment
		(start 400.03095 -45.290994)
		(end 400.03095 -44.465494)
		(width 0.508)
		(layer "F.Cu")
		(net "P12V_A")
	)
	(segment
		(start 14.347698 -275.608542)
		(end 13.468858 -275.608542)
		(width 0.508)
		(layer "F.Cu")
		(net "P12V_A")
	)
	(segment
		(start 469.498426 -167.644826)
		(end 469.498426 -168.482518)
		(width 0.508)
		(layer "F.Cu")
		(net "P12V_A")
	)
	(segment
		(start 471.479626 -167.085518)
		(end 471.479626 -166.221918)
		(width 0.508)
		(layer "F.Cu")
		(net "P12V_A")
	)
	(segment
		(start 427.834552 -48.554894)
		(end 427.834552 -47.729394)
		(width 0.508)
		(layer "F.Cu")
		(net "P12V_A")
	)
	(segment
		(start 427.834552 -163.554918)
		(end 427.834552 -162.134296)
		(width 0.508)
		(layer "F.Cu")
		(net "P12V_A")
	)
	(segment
		(start 128.199896 -282.085542)
		(end 128.199896 -281.196542)
		(width 0.508)
		(layer "F.Cu")
		(net "P12V_A")
	)
	(segment
		(start 14.398498 -168.482518)
		(end 14.398498 -169.523918)
		(width 0.508)
		(layer "F.Cu")
		(net "P12V_A")
	)
	(segment
		(start 16.379698 -167.110918)
		(end 16.379698 -166.221918)
		(width 0.508)
		(layer "F.Cu")
		(net "P12V_A")
	)
	(segment
		(start 337.22183 -45.290994)
		(end 338.024978 -46.094142)
		(width 0.508)
		(layer "F.Cu")
		(net "P12V_A")
	)
	(segment
		(start 364.734602 -163.554918)
		(end 364.734602 -162.729418)
		(width 0.508)
		(layer "F.Cu")
		(net "P12V_A")
	)
	(segment
		(start 463.1309 -160.291018)
		(end 463.1309 -159.490918)
		(width 0.508)
		(layer "F.Cu")
		(net "P12V_A")
	)
	(segment
		(start 14.373098 -45.608494)
		(end 13.484098 -45.608494)
		(width 0.508)
		(layer "F.Cu")
		(net "P12V_A")
	)
	(segment
		(start 133.89483 -144.449038)
		(end 133.903466 -144.457674)
		(width 0.508)
		(layer "F.Cu")
		(net "P12V_A")
	)
	(segment
		(start 114.280696 -282.695142)
		(end 114.280696 -283.736542)
		(width 0.508)
		(layer "F.Cu")
		(net "P12V_A")
	)
	(segment
		(start 364.734602 -278.554942)
		(end 365.6965 -278.554942)
		(width 0.508)
		(layer "F.Cu")
		(net "P12V_A")
	)
	(segment
		(start 469.265 -167.4114)
		(end 469.498426 -167.644826)
		(width 0.508)
		(layer "F.Cu")
		(net "P12V_A")
	)
	(segment
		(start 468.354918 -50.14595)
		(end 468.355426 -50.14595)
		(width 0.508)
		(layer "F.Cu")
		(net "P12V_A")
	)
	(segment
		(start 368.481102 -160.291018)
		(end 368.481102 -159.465518)
		(width 0.508)
		(layer "F.Cu")
		(net "P12V_A")
	)
	(segment
		(start 114.280696 -282.695142)
		(end 113.443258 -282.695142)
		(width 0.508)
		(layer "F.Cu")
		(net "P12V_A")
	)
	(segment
		(start 368.481102 -275.291042)
		(end 368.481102 -274.490942)
		(width 0.508)
		(layer "F.Cu")
		(net "P12V_A")
	)
	(segment
		(start 471.479626 -52.060094)
		(end 471.479626 -51.221894)
		(width 0.508)
		(layer "F.Cu")
		(net "P12V_A")
	)
	(segment
		(start 468.355426 -50.14595)
		(end 468.355426 -52.314094)
		(width 0.508)
		(layer "F.Cu")
		(net "P12V_A")
	)
	(segment
		(start 14.398498 -53.482494)
		(end 14.398498 -54.523894)
		(width 0.508)
		(layer "F.Cu")
		(net "P12V_A")
	)
	(segment
		(start 109.022896 -160.608518)
		(end 108.159296 -160.608518)
		(width 0.508)
		(layer "F.Cu")
		(net "P12V_A")
	)
	(segment
		(start 109.048296 -168.482518)
		(end 109.048296 -169.523918)
		(width 0.508)
		(layer "F.Cu")
		(net "P12V_A")
	)
	(segment
		(start 368.481102 -45.290994)
		(end 368.481102 -43.954446)
		(width 0.508)
		(layer "F.Cu")
		(net "P12V_A")
	)
	(segment
		(start 140.598398 -169.523918)
		(end 140.598398 -168.507918)
		(width 0.508)
		(layer "F.Cu")
		(net "P12V_A")
	)
	(segment
		(start 459.3844 -278.554942)
		(end 460.803498 -278.554942)
		(width 0.508)
		(layer "F.Cu")
		(net "P12V_A")
	)
	(segment
		(start 16.379698 -282.110942)
		(end 16.379698 -281.221942)
		(width 0.508)
		(layer "F.Cu")
		(net "P12V_A")
	)
	(segment
		(start 77.498448 -283.482542)
		(end 77.498448 -284.523942)
		(width 0.508)
		(layer "F.Cu")
		(net "P12V_A")
	)
	(segment
		(start 45.968158 -278.089106)
		(end 44.98467 -278.089106)
		(width 0.508)
		(layer "F.Cu")
		(net "P12V_A")
	)
	(segment
		(start 239.268 -381.7493)
		(end 239.268 -380.873)
		(width 0.508)
		(layer "F.Cu")
		(net "P12V_A")
	)
	(segment
		(start 50.739802 -151.75865)
		(end 50.739802 -152.58415)
		(width 0.508)
		(layer "F.Cu")
		(net "P12V_A")
	)
	(segment
		(start 133.89483 -143.32458)
		(end 133.89483 -144.449038)
		(width 0.508)
		(layer "F.Cu")
		(net "P12V_A")
	)
	(segment
		(start 79.479648 -52.085494)
		(end 79.479648 -51.221894)
		(width 0.508)
		(layer "F.Cu")
		(net "P12V_A")
	)
	(segment
		(start 77.498448 -53.482494)
		(end 77.498448 -54.523894)
		(width 0.508)
		(layer "F.Cu")
		(net "P12V_A")
	)
	(segment
		(start 172.0977 -45.608494)
		(end 172.0977 -47.134526)
		(width 0.508)
		(layer "F.Cu")
		(net "P12V_A")
	)
	(segment
		(start 469.498426 -168.482518)
		(end 469.498426 -169.523918)
		(width 0.508)
		(layer "F.Cu")
		(net "P12V_A")
	)
	(segment
		(start 16.379698 -52.136294)
		(end 16.379698 -51.247294)
		(width 0.508)
		(layer "F.Cu")
		(net "P12V_A")
	)
	(segment
		(start 174.1297 -50.747422)
		(end 174.0535 -50.671222)
		(width 0.508)
		(layer "F.Cu")
		(net "P12V_A")
	)
	(segment
		(start 171.9961 -278.3967)
		(end 171.3738 -279.019)
		(width 0.508)
		(layer "F.Cu")
		(net "P12V_A")
	)
	(segment
		(start 450.815202 -259.45465)
		(end 450.815202 -260.28015)
		(width 0.508)
		(layer "F.Cu")
		(net "P12V_A")
	)
	(segment
		(start 431.581052 -45.290994)
		(end 431.581052 -44.465494)
		(width 0.508)
		(layer "F.Cu")
		(net "P12V_A")
	)
	(segment
		(start 173.228 -160.506918)
		(end 173.228 -159.626046)
		(width 0.508)
		(layer "F.Cu")
		(net "P12V_A")
	)
	(via
		(at 158.301944 -142.893796)
		(size 0.5588)
		(drill 0.3048)
		(layers "F.Cu" "B.Cu")
		(net "P12V_A")
	)
	(via
		(at 176.634902 -154.72537)
		(size 0.7112)
		(drill 0.4064)
		(layers "F.Cu" "B.Cu")
		(net "P12V_A")
	)
	(via
		(at 254.2286 -373.927878)
		(size 0.8636)
		(drill 0.508)
		(layers "F.Cu" "B.Cu")
		(net "P12V_A")
	)
	(via
		(at 459.3844 -162.729418)
		(size 0.5588)
		(drill 0.3048)
		(layers "F.Cu" "B.Cu")
		(net "P12V_A")
	)
	(via
		(at 271.0688 -373.9134)
		(size 0.8636)
		(drill 0.508)
		(layers "F.Cu" "B.Cu")
		(net "P12V_A")
	)
	(via
		(at 203.7334 -313.2582)
		(size 0.5588)
		(drill 0.3048)
		(layers "F.Cu" "B.Cu")
		(net "P12V_A")
	)
	(via
		(at 142.579598 -281.221942)
		(size 0.5588)
		(drill 0.3048)
		(layers "F.Cu" "B.Cu")
		(net "P12V_A")
	)
	(via
		(at 280.783538 -239.831118)
		(size 0.5588)
		(drill 0.3048)
		(layers "F.Cu" "B.Cu")
		(net "P12V_A")
	)
	(via
		(at 368.862102 -172.825918)
		(size 0.5588)
		(drill 0.3048)
		(layers "F.Cu" "B.Cu")
		(net "P12V_A")
	)
	(via
		(at 333.1845 -162.729418)
		(size 0.5588)
		(drill 0.3048)
		(layers "F.Cu" "B.Cu")
		(net "P12V_A")
	)
	(via
		(at 469.99398 -243.900706)
		(size 0.7112)
		(drill 0.4064)
		(layers "F.Cu" "B.Cu")
		(net "P12V_A")
	)
	(via
		(at 76.926948 -170.793918)
		(size 0.5588)
		(drill 0.3048)
		(layers "F.Cu" "B.Cu")
		(net "P12V_A")
	)
	(via
		(at 337.312 -172.825918)
		(size 0.5588)
		(drill 0.3048)
		(layers "F.Cu" "B.Cu")
		(net "P12V_A")
	)
	(via
		(at 460.9719 -172.825918)
		(size 0.5588)
		(drill 0.3048)
		(layers "F.Cu" "B.Cu")
		(net "P12V_A")
	)
	(via
		(at 407.26995 -279.41016)
		(size 0.5588)
		(drill 0.3048)
		(layers "F.Cu" "B.Cu")
		(net "P12V_A")
	)
	(via
		(at 255.3716 -371.641878)
		(size 0.8636)
		(drill 0.508)
		(layers "F.Cu" "B.Cu")
		(net "P12V_A")
	)
	(via
		(at 153.105866 -140.292074)
		(size 0.5588)
		(drill 0.3048)
		(layers "F.Cu" "B.Cu")
		(net "P12V_A")
	)
	(via
		(at 400.03095 -159.465518)
		(size 0.5588)
		(drill 0.3048)
		(layers "F.Cu" "B.Cu")
		(net "P12V_A")
	)
	(via
		(at 30.419802 -139.88415)
		(size 0.7112)
		(drill 0.4064)
		(layers "F.Cu" "B.Cu")
		(net "P12V_A")
	)
	(via
		(at 269.9258 -372.7704)
		(size 0.8636)
		(drill 0.508)
		(layers "F.Cu" "B.Cu")
		(net "P12V_A")
	)
	(via
		(at 31.562802 -138.74115)
		(size 0.7112)
		(drill 0.4064)
		(layers "F.Cu" "B.Cu")
		(net "P12V_A")
	)
	(via
		(at 431.962052 -287.444942)
		(size 0.5588)
		(drill 0.3048)
		(layers "F.Cu" "B.Cu")
		(net "P12V_A")
	)
	(via
		(at 405.99995 -280.01976)
		(size 0.5588)
		(drill 0.3048)
		(layers "F.Cu" "B.Cu")
		(net "P12V_A")
	)
	(via
		(at 194.341496 -219.478606)
		(size 0.5588)
		(drill 0.3048)
		(layers "F.Cu" "B.Cu")
		(net "P12V_A")
	)
	(via
		(at 177.701702 -154.72537)
		(size 0.7112)
		(drill 0.4064)
		(layers "F.Cu" "B.Cu")
		(net "P12V_A")
	)
	(via
		(at 334.425798 -57.548272)
		(size 0.5588)
		(drill 0.3048)
		(layers "F.Cu" "B.Cu")
		(net "P12V_A")
	)
	(via
		(at 431.581052 -274.465542)
		(size 0.5588)
		(drill 0.3048)
		(layers "F.Cu" "B.Cu")
		(net "P12V_A")
	)
	(via
		(at 336.931 -159.490918)
		(size 0.5588)
		(drill 0.3048)
		(layers "F.Cu" "B.Cu")
		(net "P12V_A")
	)
	(via
		(at 431.581052 -159.490918)
		(size 0.5588)
		(drill 0.3048)
		(layers "F.Cu" "B.Cu")
		(net "P12V_A")
	)
	(via
		(at 284.332426 -226.976178)
		(size 0.5588)
		(drill 0.3048)
		(layers "F.Cu" "B.Cu")
		(net "P12V_A")
	)
	(via
		(at 205.46568 -166.74084)
		(size 0.5588)
		(drill 0.3048)
		(layers "F.Cu" "B.Cu")
		(net "P12V_A")
	)
	(via
		(at 427.834552 -162.134296)
		(size 0.5588)
		(drill 0.3048)
		(layers "F.Cu" "B.Cu")
		(net "P12V_A")
	)
	(via
		(at 141.169898 -170.793918)
		(size 0.5588)
		(drill 0.3048)
		(layers "F.Cu" "B.Cu")
		(net "P12V_A")
	)
	(via
		(at 461.275684 -279.027128)
		(size 0.5588)
		(drill 0.3048)
		(layers "F.Cu" "B.Cu")
		(net "P12V_A")
	)
	(via
		(at 337.312 -287.825942)
		(size 0.5588)
		(drill 0.3048)
		(layers "F.Cu" "B.Cu")
		(net "P12V_A")
	)
	(via
		(at 45.376846 -55.793894)
		(size 0.5588)
		(drill 0.3048)
		(layers "F.Cu" "B.Cu")
		(net "P12V_A")
	)
	(via
		(at 431.104294 -252.818138)
		(size 0.7112)
		(drill 0.4064)
		(layers "F.Cu" "B.Cu")
		(net "P12V_A")
	)
	(via
		(at 261.812532 -32.073596)
		(size 0.5588)
		(drill 0.3048)
		(layers "F.Cu" "B.Cu")
		(net "P12V_A")
	)
	(via
		(at 460.9719 -57.825894)
		(size 0.5588)
		(drill 0.3048)
		(layers "F.Cu" "B.Cu")
		(net "P12V_A")
	)
	(via
		(at 44.233846 -285.793942)
		(size 0.5588)
		(drill 0.3048)
		(layers "F.Cu" "B.Cu")
		(net "P12V_A")
	)
	(via
		(at 264.12063 -375.093484)
		(size 0.8636)
		(drill 0.508)
		(layers "F.Cu" "B.Cu")
		(net "P12V_A")
	)
	(via
		(at 333.1845 -277.729442)
		(size 0.5588)
		(drill 0.3048)
		(layers "F.Cu" "B.Cu")
		(net "P12V_A")
	)
	(via
		(at 338.024978 -46.094142)
		(size 0.5588)
		(drill 0.3048)
		(layers "F.Cu" "B.Cu")
		(net "P12V_A")
	)
	(via
		(at 108.159296 -160.608518)
		(size 0.5588)
		(drill 0.3048)
		(layers "F.Cu" "B.Cu")
		(net "P12V_A")
	)
	(via
		(at 431.962052 -57.825894)
		(size 0.5588)
		(drill 0.3048)
		(layers "F.Cu" "B.Cu")
		(net "P12V_A")
	)
	(via
		(at 172.0723 -47.159926)
		(size 0.5588)
		(drill 0.3048)
		(layers "F.Cu" "B.Cu")
		(net "P12V_A")
	)
	(via
		(at 365.6965 -278.554942)
		(size 0.5588)
		(drill 0.3048)
		(layers "F.Cu" "B.Cu")
		(net "P12V_A")
	)
	(via
		(at 267.6398 -371.6274)
		(size 0.8636)
		(drill 0.508)
		(layers "F.Cu" "B.Cu")
		(net "P12V_A")
	)
	(via
		(at 280.148538 -240.593118)
		(size 0.5588)
		(drill 0.3048)
		(layers "F.Cu" "B.Cu")
		(net "P12V_A")
	)
	(via
		(at 271.0688 -375.0564)
		(size 0.8636)
		(drill 0.508)
		(layers "F.Cu" "B.Cu")
		(net "P12V_A")
	)
	(via
		(at 463.5119 -287.825942)
		(size 0.5588)
		(drill 0.3048)
		(layers "F.Cu" "B.Cu")
		(net "P12V_A")
	)
	(via
		(at 468.926926 -170.793918)
		(size 0.5588)
		(drill 0.3048)
		(layers "F.Cu" "B.Cu")
		(net "P12V_A")
	)
	(via
		(at 264.12063 -372.807484)
		(size 0.8636)
		(drill 0.508)
		(layers "F.Cu" "B.Cu")
		(net "P12V_A")
	)
	(via
		(at 45.059346 -45.633894)
		(size 0.5588)
		(drill 0.3048)
		(layers "F.Cu" "B.Cu")
		(net "P12V_A")
	)
	(via
		(at 142.604998 -166.221918)
		(size 0.5588)
		(drill 0.3048)
		(layers "F.Cu" "B.Cu")
		(net "P12V_A")
	)
	(via
		(at 255.3716 -373.927878)
		(size 0.8636)
		(drill 0.508)
		(layers "F.Cu" "B.Cu")
		(net "P12V_A")
	)
	(via
		(at 204.3684 -314.0202)
		(size 0.5588)
		(drill 0.3048)
		(layers "F.Cu" "B.Cu")
		(net "P12V_A")
	)
	(via
		(at 469.97112 -282.288742)
		(size 0.5588)
		(drill 0.3048)
		(layers "F.Cu" "B.Cu")
		(net "P12V_A")
	)
	(via
		(at 430.438052 -171.555918)
		(size 0.5588)
		(drill 0.3048)
		(layers "F.Cu" "B.Cu")
		(net "P12V_A")
	)
	(via
		(at 463.5119 -57.825894)
		(size 0.5588)
		(drill 0.3048)
		(layers "F.Cu" "B.Cu")
		(net "P12V_A")
	)
	(via
		(at 271.0688 -372.7704)
		(size 0.8636)
		(drill 0.508)
		(layers "F.Cu" "B.Cu")
		(net "P12V_A")
	)
	(via
		(at 14.77645 -249.25655)
		(size 0.5588)
		(drill 0.3048)
		(layers "F.Cu" "B.Cu")
		(net "P12V_A")
	)
	(via
		(at 397.87195 -172.063918)
		(size 0.5588)
		(drill 0.3048)
		(layers "F.Cu" "B.Cu")
		(net "P12V_A")
	)
	(via
		(at 460.9719 -287.825942)
		(size 0.5588)
		(drill 0.3048)
		(layers "F.Cu" "B.Cu")
		(net "P12V_A")
	)
	(via
		(at 366.322102 -57.825894)
		(size 0.5588)
		(drill 0.3048)
		(layers "F.Cu" "B.Cu")
		(net "P12V_A")
	)
	(via
		(at 14.969998 -170.793918)
		(size 0.5588)
		(drill 0.3048)
		(layers "F.Cu" "B.Cu")
		(net "P12V_A")
	)
	(via
		(at 138.883898 -285.793942)
		(size 0.5588)
		(drill 0.3048)
		(layers "F.Cu" "B.Cu")
		(net "P12V_A")
	)
	(via
		(at 13.826998 -285.793942)
		(size 0.5588)
		(drill 0.3048)
		(layers "F.Cu" "B.Cu")
		(net "P12V_A")
	)
	(via
		(at 79.479648 -166.221918)
		(size 0.5588)
		(drill 0.3048)
		(layers "F.Cu" "B.Cu")
		(net "P12V_A")
	)
	(via
		(at 267.6398 -373.9134)
		(size 0.8636)
		(drill 0.508)
		(layers "F.Cu" "B.Cu")
		(net "P12V_A")
	)
	(via
		(at 177.701702 -152.59177)
		(size 0.7112)
		(drill 0.4064)
		(layers "F.Cu" "B.Cu")
		(net "P12V_A")
	)
	(via
		(at 459.3844 -47.729394)
		(size 0.5588)
		(drill 0.3048)
		(layers "F.Cu" "B.Cu")
		(net "P12V_A")
	)
	(via
		(at 16.379698 -51.247294)
		(size 0.5588)
		(drill 0.3048)
		(layers "F.Cu" "B.Cu")
		(net "P12V_A")
	)
	(via
		(at 78.069948 -170.793918)
		(size 0.5588)
		(drill 0.3048)
		(layers "F.Cu" "B.Cu")
		(net "P12V_A")
	)
	(via
		(at 467.783926 -55.793894)
		(size 0.5588)
		(drill 0.3048)
		(layers "F.Cu" "B.Cu")
		(net "P12V_A")
	)
	(via
		(at 468.823802 -242.83416)
		(size 0.7112)
		(drill 0.4064)
		(layers "F.Cu" "B.Cu")
		(net "P12V_A")
	)
	(via
		(at 468.823802 -244.99316)
		(size 0.7112)
		(drill 0.4064)
		(layers "F.Cu" "B.Cu")
		(net "P12V_A")
	)
	(via
		(at 108.476796 -170.793918)
		(size 0.5588)
		(drill 0.3048)
		(layers "F.Cu" "B.Cu")
		(net "P12V_A")
	)
	(via
		(at 253.0856 -373.927878)
		(size 0.8636)
		(drill 0.508)
		(layers "F.Cu" "B.Cu")
		(net "P12V_A")
	)
	(via
		(at 450.815202 -260.28015)
		(size 0.5588)
		(drill 0.3048)
		(layers "F.Cu" "B.Cu")
		(net "P12V_A")
	)
	(via
		(at 111.054896 -166.221918)
		(size 0.5588)
		(drill 0.3048)
		(layers "F.Cu" "B.Cu")
		(net "P12V_A")
	)
	(via
		(at 462.7626 -171.8056)
		(size 0.6604)
		(drill 0.3302)
		(layers "F.Cu" "B.Cu")
		(net "P12V_A")
	)
	(via
		(at 429.422052 -57.825894)
		(size 0.5588)
		(drill 0.3048)
		(layers "F.Cu" "B.Cu")
		(net "P12V_A")
	)
	(via
		(at 469.966802 -244.99316)
		(size 0.7112)
		(drill 0.4064)
		(layers "F.Cu" "B.Cu")
		(net "P12V_A")
	)
	(via
		(at 253.0856 -375.070878)
		(size 0.8636)
		(drill 0.508)
		(layers "F.Cu" "B.Cu")
		(net "P12V_A")
	)
	(via
		(at 76.609448 -45.633894)
		(size 0.5588)
		(drill 0.3048)
		(layers "F.Cu" "B.Cu")
		(net "P12V_A")
	)
	(via
		(at 45.150786 -170.829986)
		(size 0.5588)
		(drill 0.3048)
		(layers "F.Cu" "B.Cu")
		(net "P12V_A")
	)
	(via
		(at 47.027846 -156.959046)
		(size 0.5588)
		(drill 0.3048)
		(layers "F.Cu" "B.Cu")
		(net "P12V_A")
	)
	(via
		(at 113.771426 -284.91815)
		(size 0.5588)
		(drill 0.3048)
		(layers "F.Cu" "B.Cu")
		(net "P12V_A")
	)
	(via
		(at 206.451454 -19.216116)
		(size 0.5588)
		(drill 0.3048)
		(layers "F.Cu" "B.Cu")
		(net "P12V_A")
	)
	(via
		(at 260.69163 -372.807484)
		(size 0.8636)
		(drill 0.508)
		(layers "F.Cu" "B.Cu")
		(net "P12V_A")
	)
	(via
		(at 252.36551 -33.71342)
		(size 0.5588)
		(drill 0.3048)
		(layers "F.Cu" "B.Cu")
		(net "P12V_A")
	)
	(via
		(at 205.46568 -165.69436)
		(size 0.5588)
		(drill 0.3048)
		(layers "F.Cu" "B.Cu")
		(net "P12V_A")
	)
	(via
		(at 366.322102 -287.571942)
		(size 0.5588)
		(drill 0.3048)
		(layers "F.Cu" "B.Cu")
		(net "P12V_A")
	)
	(via
		(at 46.519846 -55.793894)
		(size 0.5588)
		(drill 0.3048)
		(layers "F.Cu" "B.Cu")
		(net "P12V_A")
	)
	(via
		(at 170.434 -285.793942)
		(size 0.5588)
		(drill 0.3048)
		(layers "F.Cu" "B.Cu")
		(net "P12V_A")
	)
	(via
		(at 271.0688 -371.6274)
		(size 0.8636)
		(drill 0.508)
		(layers "F.Cu" "B.Cu")
		(net "P12V_A")
	)
	(via
		(at 400.03095 -274.490942)
		(size 0.5588)
		(drill 0.3048)
		(layers "F.Cu" "B.Cu")
		(net "P12V_A")
	)
	(via
		(at 178.768502 -152.59177)
		(size 0.7112)
		(drill 0.4064)
		(layers "F.Cu" "B.Cu")
		(net "P12V_A")
	)
	(via
		(at 205.48981 -167.894)
		(size 0.5588)
		(drill 0.3048)
		(layers "F.Cu" "B.Cu")
		(net "P12V_A")
	)
	(via
		(at 193.663062 -221.592902)
		(size 0.5588)
		(drill 0.3048)
		(layers "F.Cu" "B.Cu")
		(net "P12V_A")
	)
	(via
		(at 334.772 -287.825942)
		(size 0.5588)
		(drill 0.3048)
		(layers "F.Cu" "B.Cu")
		(net "P12V_A")
	)
	(via
		(at 16.379698 -166.221918)
		(size 0.5588)
		(drill 0.3048)
		(layers "F.Cu" "B.Cu")
		(net "P12V_A")
	)
	(via
		(at 14.969998 -285.793942)
		(size 0.5588)
		(drill 0.3048)
		(layers "F.Cu" "B.Cu")
		(net "P12V_A")
	)
	(via
		(at 13.826998 -170.793918)
		(size 0.5588)
		(drill 0.3048)
		(layers "F.Cu" "B.Cu")
		(net "P12V_A")
	)
	(via
		(at 178.768502 -155.79217)
		(size 0.7112)
		(drill 0.4064)
		(layers "F.Cu" "B.Cu")
		(net "P12V_A")
	)
	(via
		(at 261.84606 -34.99612)
		(size 0.5588)
		(drill 0.3048)
		(layers "F.Cu" "B.Cu")
		(net "P12V_A")
	)
	(via
		(at 170.132502 -55.974996)
		(size 0.5588)
		(drill 0.3048)
		(layers "F.Cu" "B.Cu")
		(net "P12V_A")
	)
	(via
		(at 256.5146 -371.641878)
		(size 0.8636)
		(drill 0.508)
		(layers "F.Cu" "B.Cu")
		(net "P12V_A")
	)
	(via
		(at 175.568102 -154.72537)
		(size 0.7112)
		(drill 0.4064)
		(layers "F.Cu" "B.Cu")
		(net "P12V_A")
	)
	(via
		(at 395.01445 -163.237418)
		(size 0.5588)
		(drill 0.3048)
		(layers "F.Cu" "B.Cu")
		(net "P12V_A")
	)
	(via
		(at 133.903466 -144.457674)
		(size 0.5588)
		(drill 0.3048)
		(layers "F.Cu" "B.Cu")
		(net "P12V_A")
	)
	(via
		(at 268.7828 -375.0564)
		(size 0.8636)
		(drill 0.508)
		(layers "F.Cu" "B.Cu")
		(net "P12V_A")
	)
	(via
		(at 283.570426 -226.341178)
		(size 0.5588)
		(drill 0.3048)
		(layers "F.Cu" "B.Cu")
		(net "P12V_A")
	)
	(via
		(at 12.683998 -55.793894)
		(size 0.5588)
		(drill 0.3048)
		(layers "F.Cu" "B.Cu")
		(net "P12V_A")
	)
	(via
		(at 429.961294 -252.818138)
		(size 0.7112)
		(drill 0.4064)
		(layers "F.Cu" "B.Cu")
		(net "P12V_A")
	)
	(via
		(at 171.558966 -170.956732)
		(size 0.5588)
		(drill 0.3048)
		(layers "F.Cu" "B.Cu")
		(net "P12V_A")
	)
	(via
		(at 174.0535 -50.671222)
		(size 0.5588)
		(drill 0.3048)
		(layers "F.Cu" "B.Cu")
		(net "P12V_A")
	)
	(via
		(at 31.562802 -139.88415)
		(size 0.7112)
		(drill 0.4064)
		(layers "F.Cu" "B.Cu")
		(net "P12V_A")
	)
	(via
		(at 430.692052 -57.825894)
		(size 0.5588)
		(drill 0.3048)
		(layers "F.Cu" "B.Cu")
		(net "P12V_A")
	)
	(via
		(at 469.265 -167.4114)
		(size 0.6604)
		(drill 0.3302)
		(layers "F.Cu" "B.Cu")
		(net "P12V_A")
	)
	(via
		(at 241.3762 -380.873)
		(size 0.5588)
		(drill 0.3048)
		(layers "F.Cu" "B.Cu")
		(net "P12V_A")
	)
	(via
		(at 471.479626 -51.221894)
		(size 0.5588)
		(drill 0.3048)
		(layers "F.Cu" "B.Cu")
		(net "P12V_A")
	)
	(via
		(at 157.36824 -138.989054)
		(size 0.5588)
		(drill 0.3048)
		(layers "F.Cu" "B.Cu")
		(net "P12V_A")
	)
	(via
		(at 50.739802 -152.58415)
		(size 0.5588)
		(drill 0.3048)
		(layers "F.Cu" "B.Cu")
		(net "P12V_A")
	)
	(via
		(at 470.069926 -170.793918)
		(size 0.5588)
		(drill 0.3048)
		(layers "F.Cu" "B.Cu")
		(net "P12V_A")
	)
	(via
		(at 336.931 -274.490942)
		(size 0.5588)
		(drill 0.3048)
		(layers "F.Cu" "B.Cu")
		(net "P12V_A")
	)
	(via
		(at 175.568102 -155.79217)
		(size 0.7112)
		(drill 0.4064)
		(layers "F.Cu" "B.Cu")
		(net "P12V_A")
	)
	(via
		(at 142.604998 -50.101246)
		(size 0.5588)
		(drill 0.3048)
		(layers "F.Cu" "B.Cu")
		(net "P12V_A")
	)
	(via
		(at 282.053538 -239.831118)
		(size 0.5588)
		(drill 0.3048)
		(layers "F.Cu" "B.Cu")
		(net "P12V_A")
	)
	(via
		(at 467.783926 -170.793918)
		(size 0.5588)
		(drill 0.3048)
		(layers "F.Cu" "B.Cu")
		(net "P12V_A")
	)
	(via
		(at 261.816596 -33.99536)
		(size 0.5588)
		(drill 0.3048)
		(layers "F.Cu" "B.Cu")
		(net "P12V_A")
	)
	(via
		(at 368.862102 -287.571942)
		(size 0.5588)
		(drill 0.3048)
		(layers "F.Cu" "B.Cu")
		(net "P12V_A")
	)
	(via
		(at 471.943684 -277.565866)
		(size 0.5588)
		(drill 0.3048)
		(layers "F.Cu" "B.Cu")
		(net "P12V_A")
	)
	(via
		(at 222.634556 -384.796792)
		(size 0.5588)
		(drill 0.3048)
		(layers "F.Cu" "B.Cu")
		(net "P12V_A")
	)
	(via
		(at 336.042 -287.825942)
		(size 0.5588)
		(drill 0.3048)
		(layers "F.Cu" "B.Cu")
		(net "P12V_A")
	)
	(via
		(at 78.069948 -285.793942)
		(size 0.5588)
		(drill 0.3048)
		(layers "F.Cu" "B.Cu")
		(net "P12V_A")
	)
	(via
		(at 12.683998 -170.793918)
		(size 0.5588)
		(drill 0.3048)
		(layers "F.Cu" "B.Cu")
		(net "P12V_A")
	)
	(via
		(at 269.9258 -375.0564)
		(size 0.8636)
		(drill 0.508)
		(layers "F.Cu" "B.Cu")
		(net "P12V_A")
	)
	(via
		(at 261.83463 -372.807484)
		(size 0.8636)
		(drill 0.508)
		(layers "F.Cu" "B.Cu")
		(net "P12V_A")
	)
	(via
		(at 251.60351 -34.34842)
		(size 0.5588)
		(drill 0.3048)
		(layers "F.Cu" "B.Cu")
		(net "P12V_A")
	)
	(via
		(at 177.701702 -155.79217)
		(size 0.7112)
		(drill 0.4064)
		(layers "F.Cu" "B.Cu")
		(net "P12V_A")
	)
	(via
		(at 75.783948 -285.793942)
		(size 0.5588)
		(drill 0.3048)
		(layers "F.Cu" "B.Cu")
		(net "P12V_A")
	)
	(via
		(at 469.966802 -242.83416)
		(size 0.7112)
		(drill 0.4064)
		(layers "F.Cu" "B.Cu")
		(net "P12V_A")
	)
	(via
		(at 269.9258 -373.9134)
		(size 0.8636)
		(drill 0.508)
		(layers "F.Cu" "B.Cu")
		(net "P12V_A")
	)
	(via
		(at 252.36551 -32.44342)
		(size 0.5588)
		(drill 0.3048)
		(layers "F.Cu" "B.Cu")
		(net "P12V_A")
	)
	(via
		(at 13.484098 -160.608518)
		(size 0.5588)
		(drill 0.3048)
		(layers "F.Cu" "B.Cu")
		(net "P12V_A")
	)
	(via
		(at 284.332426 -228.246178)
		(size 0.5588)
		(drill 0.3048)
		(layers "F.Cu" "B.Cu")
		(net "P12V_A")
	)
	(via
		(at 264.12063 -373.950484)
		(size 0.8636)
		(drill 0.508)
		(layers "F.Cu" "B.Cu")
		(net "P12V_A")
	)
	(via
		(at 194.31635 -220.421708)
		(size 0.5588)
		(drill 0.3048)
		(layers "F.Cu" "B.Cu")
		(net "P12V_A")
	)
	(via
		(at 239.268 -380.873)
		(size 0.5588)
		(drill 0.3048)
		(layers "F.Cu" "B.Cu")
		(net "P12V_A")
	)
	(via
		(at 431.708052 -171.555918)
		(size 0.5588)
		(drill 0.3048)
		(layers "F.Cu" "B.Cu")
		(net "P12V_A")
	)
	(via
		(at 174.1297 -166.221918)
		(size 0.5588)
		(drill 0.3048)
		(layers "F.Cu" "B.Cu")
		(net "P12V_A")
	)
	(via
		(at 397.87195 -57.825894)
		(size 0.5588)
		(drill 0.3048)
		(layers "F.Cu" "B.Cu")
		(net "P12V_A")
	)
	(via
		(at 205.0034 -313.2582)
		(size 0.5588)
		(drill 0.3048)
		(layers "F.Cu" "B.Cu")
		(net "P12V_A")
	)
	(via
		(at 174.0535 -280.129742)
		(size 0.5588)
		(drill 0.3048)
		(layers "F.Cu" "B.Cu")
		(net "P12V_A")
	)
	(via
		(at 139.683998 -160.608518)
		(size 0.5588)
		(drill 0.3048)
		(layers "F.Cu" "B.Cu")
		(net "P12V_A")
	)
	(via
		(at 268.7828 -373.9134)
		(size 0.8636)
		(drill 0.508)
		(layers "F.Cu" "B.Cu")
		(net "P12V_A")
	)
	(via
		(at 176.634902 -155.79217)
		(size 0.7112)
		(drill 0.4064)
		(layers "F.Cu" "B.Cu")
		(net "P12V_A")
	)
	(via
		(at 364.734602 -162.729418)
		(size 0.5588)
		(drill 0.3048)
		(layers "F.Cu" "B.Cu")
		(net "P12V_A")
	)
	(via
		(at 333.1845 -47.729394)
		(size 0.5588)
		(drill 0.3048)
		(layers "F.Cu" "B.Cu")
		(net "P12V_A")
	)
	(via
		(at 468.926926 -55.793894)
		(size 0.5588)
		(drill 0.3048)
		(layers "F.Cu" "B.Cu")
		(net "P12V_A")
	)
	(via
		(at 30.419802 -138.74115)
		(size 0.7112)
		(drill 0.4064)
		(layers "F.Cu" "B.Cu")
		(net "P12V_A")
	)
	(via
		(at 261.83463 -371.664484)
		(size 0.8636)
		(drill 0.508)
		(layers "F.Cu" "B.Cu")
		(net "P12V_A")
	)
	(via
		(at 262.97763 -375.093484)
		(size 0.8636)
		(drill 0.508)
		(layers "F.Cu" "B.Cu")
		(net "P12V_A")
	)
	(via
		(at 262.97763 -372.807484)
		(size 0.8636)
		(drill 0.508)
		(layers "F.Cu" "B.Cu")
		(net "P12V_A")
	)
	(via
		(at 176.634902 -153.65857)
		(size 0.7112)
		(drill 0.4064)
		(layers "F.Cu" "B.Cu")
		(net "P12V_A")
	)
	(via
		(at 256.5146 -373.927878)
		(size 0.8636)
		(drill 0.508)
		(layers "F.Cu" "B.Cu")
		(net "P12V_A")
	)
	(via
		(at 367.592102 -287.571942)
		(size 0.5588)
		(drill 0.3048)
		(layers "F.Cu" "B.Cu")
		(net "P12V_A")
	)
	(via
		(at 255.3716 -375.070878)
		(size 0.8636)
		(drill 0.508)
		(layers "F.Cu" "B.Cu")
		(net "P12V_A")
	)
	(via
		(at 206.2734 -313.2582)
		(size 0.5588)
		(drill 0.3048)
		(layers "F.Cu" "B.Cu")
		(net "P12V_A")
	)
	(via
		(at 468.85098 -243.900706)
		(size 0.7112)
		(drill 0.4064)
		(layers "F.Cu" "B.Cu")
		(net "P12V_A")
	)
	(via
		(at 178.768502 -150.45817)
		(size 0.7112)
		(drill 0.4064)
		(layers "F.Cu" "B.Cu")
		(net "P12V_A")
	)
	(via
		(at 205.6384 -314.0202)
		(size 0.5588)
		(drill 0.3048)
		(layers "F.Cu" "B.Cu")
		(net "P12V_A")
	)
	(via
		(at 30.419802 -141.02715)
		(size 0.7112)
		(drill 0.4064)
		(layers "F.Cu" "B.Cu")
		(net "P12V_A")
	)
	(via
		(at 204.21981 -167.894)
		(size 0.5588)
		(drill 0.3048)
		(layers "F.Cu" "B.Cu")
		(net "P12V_A")
	)
	(via
		(at 396.28445 -47.729394)
		(size 0.5588)
		(drill 0.3048)
		(layers "F.Cu" "B.Cu")
		(net "P12V_A")
	)
	(via
		(at 205.181454 -19.216116)
		(size 0.5588)
		(drill 0.3048)
		(layers "F.Cu" "B.Cu")
		(net "P12V_A")
	)
	(via
		(at 139.642342 -275.633942)
		(size 0.5588)
		(drill 0.3048)
		(layers "F.Cu" "B.Cu")
		(net "P12V_A")
	)
	(via
		(at 138.883898 -170.793918)
		(size 0.5588)
		(drill 0.3048)
		(layers "F.Cu" "B.Cu")
		(net "P12V_A")
	)
	(via
		(at 279.513538 -239.831118)
		(size 0.5588)
		(drill 0.3048)
		(layers "F.Cu" "B.Cu")
		(net "P12V_A")
	)
	(via
		(at 463.1309 -274.490942)
		(size 0.5588)
		(drill 0.3048)
		(layers "F.Cu" "B.Cu")
		(net "P12V_A")
	)
	(via
		(at 203.911454 -19.216116)
		(size 0.5588)
		(drill 0.3048)
		(layers "F.Cu" "B.Cu")
		(net "P12V_A")
	)
	(via
		(at 262.97763 -371.664484)
		(size 0.8636)
		(drill 0.508)
		(layers "F.Cu" "B.Cu")
		(net "P12V_A")
	)
	(via
		(at 176.634902 -152.59177)
		(size 0.7112)
		(drill 0.4064)
		(layers "F.Cu" "B.Cu")
		(net "P12V_A")
	)
	(via
		(at 255.3716 -372.784878)
		(size 0.8636)
		(drill 0.508)
		(layers "F.Cu" "B.Cu")
		(net "P12V_A")
	)
	(via
		(at 138.686286 -47.706534)
		(size 0.5588)
		(drill 0.3048)
		(layers "F.Cu" "B.Cu")
		(net "P12V_A")
	)
	(via
		(at 462.2419 -57.825894)
		(size 0.5588)
		(drill 0.3048)
		(layers "F.Cu" "B.Cu")
		(net "P12V_A")
	)
	(via
		(at 481.823522 -227.1649)
		(size 0.5588)
		(drill 0.3048)
		(layers "F.Cu" "B.Cu")
		(net "P12V_A")
	)
	(via
		(at 470.069926 -55.793894)
		(size 0.5588)
		(drill 0.3048)
		(layers "F.Cu" "B.Cu")
		(net "P12V_A")
	)
	(via
		(at 76.609448 -160.633918)
		(size 0.5588)
		(drill 0.3048)
		(layers "F.Cu" "B.Cu")
		(net "P12V_A")
	)
	(via
		(at 367.592102 -172.825918)
		(size 0.5588)
		(drill 0.3048)
		(layers "F.Cu" "B.Cu")
		(net "P12V_A")
	)
	(via
		(at 75.783948 -55.793894)
		(size 0.5588)
		(drill 0.3048)
		(layers "F.Cu" "B.Cu")
		(net "P12V_A")
	)
	(via
		(at 266.1158 -376.301)
		(size 0.6096)
		(drill 0.3048)
		(layers "F.Cu" "B.Cu")
		(net "P12V_A")
	)
	(via
		(at 471.479626 -166.221918)
		(size 0.5588)
		(drill 0.3048)
		(layers "F.Cu" "B.Cu")
		(net "P12V_A")
	)
	(via
		(at 335.695798 -57.548272)
		(size 0.5588)
		(drill 0.3048)
		(layers "F.Cu" "B.Cu")
		(net "P12V_A")
	)
	(via
		(at 175.314102 -153.409142)
		(size 0.6604)
		(drill 0.3302)
		(layers "F.Cu" "B.Cu")
		(net "P12V_A")
	)
	(via
		(at 268.7828 -371.6274)
		(size 0.8636)
		(drill 0.508)
		(layers "F.Cu" "B.Cu")
		(net "P12V_A")
	)
	(via
		(at 261.81685 -33.024064)
		(size 0.5588)
		(drill 0.3048)
		(layers "F.Cu" "B.Cu")
		(net "P12V_A")
	)
	(via
		(at 13.468858 -275.608542)
		(size 0.5588)
		(drill 0.3048)
		(layers "F.Cu" "B.Cu")
		(net "P12V_A")
	)
	(via
		(at 234.315 -380.9238)
		(size 0.5588)
		(drill 0.3048)
		(layers "F.Cu" "B.Cu")
		(net "P12V_A")
	)
	(via
		(at 251.60351 -33.07842)
		(size 0.5588)
		(drill 0.3048)
		(layers "F.Cu" "B.Cu")
		(net "P12V_A")
	)
	(via
		(at 470.29751 -284.171136)
		(size 0.5588)
		(drill 0.3048)
		(layers "F.Cu" "B.Cu")
		(net "P12V_A")
	)
	(via
		(at 76.926948 -285.793942)
		(size 0.5588)
		(drill 0.3048)
		(layers "F.Cu" "B.Cu")
		(net "P12V_A")
	)
	(via
		(at 46.519846 -285.793942)
		(size 0.5588)
		(drill 0.3048)
		(layers "F.Cu" "B.Cu")
		(net "P12V_A")
	)
	(via
		(at 141.492478 -55.918608)
		(size 0.5588)
		(drill 0.3048)
		(layers "F.Cu" "B.Cu")
		(net "P12V_A")
	)
	(via
		(at 281.418538 -240.593118)
		(size 0.5588)
		(drill 0.3048)
		(layers "F.Cu" "B.Cu")
		(net "P12V_A")
	)
	(via
		(at 431.104294 -253.961138)
		(size 0.7112)
		(drill 0.4064)
		(layers "F.Cu" "B.Cu")
		(net "P12V_A")
	)
	(via
		(at 112.261904 -281.324304)
		(size 0.5588)
		(drill 0.3048)
		(layers "F.Cu" "B.Cu")
		(net "P12V_A")
	)
	(via
		(at 400.41195 -57.825894)
		(size 0.5588)
		(drill 0.3048)
		(layers "F.Cu" "B.Cu")
		(net "P12V_A")
	)
	(via
		(at 399.14195 -172.063918)
		(size 0.5588)
		(drill 0.3048)
		(layers "F.Cu" "B.Cu")
		(net "P12V_A")
	)
	(via
		(at 45.376846 -285.793942)
		(size 0.5588)
		(drill 0.3048)
		(layers "F.Cu" "B.Cu")
		(net "P12V_A")
	)
	(via
		(at 44.007786 -170.829986)
		(size 0.5588)
		(drill 0.3048)
		(layers "F.Cu" "B.Cu")
		(net "P12V_A")
	)
	(via
		(at 400.03095 -44.465494)
		(size 0.5588)
		(drill 0.3048)
		(layers "F.Cu" "B.Cu")
		(net "P12V_A")
	)
	(via
		(at 395.282674 -288.26968)
		(size 0.5588)
		(drill 0.3048)
		(layers "F.Cu" "B.Cu")
		(net "P12V_A")
	)
	(via
		(at 44.98467 -278.089106)
		(size 0.5588)
		(drill 0.3048)
		(layers "F.Cu" "B.Cu")
		(net "P12V_A")
	)
	(via
		(at 178.768502 -154.72537)
		(size 0.7112)
		(drill 0.4064)
		(layers "F.Cu" "B.Cu")
		(net "P12V_A")
	)
	(via
		(at 178.768502 -153.65857)
		(size 0.7112)
		(drill 0.4064)
		(layers "F.Cu" "B.Cu")
		(net "P12V_A")
	)
	(via
		(at 469.992202 -283.219398)
		(size 0.5588)
		(drill 0.3048)
		(layers "F.Cu" "B.Cu")
		(net "P12V_A")
	)
	(via
		(at 368.862102 -57.825894)
		(size 0.5588)
		(drill 0.3048)
		(layers "F.Cu" "B.Cu")
		(net "P12V_A")
	)
	(via
		(at 172.72 -285.793942)
		(size 0.5588)
		(drill 0.3048)
		(layers "F.Cu" "B.Cu")
		(net "P12V_A")
	)
	(via
		(at 269.9258 -371.6274)
		(size 0.8636)
		(drill 0.508)
		(layers "F.Cu" "B.Cu")
		(net "P12V_A")
	)
	(via
		(at 251.60351 -31.80842)
		(size 0.5588)
		(drill 0.3048)
		(layers "F.Cu" "B.Cu")
		(net "P12V_A")
	)
	(via
		(at 254.2286 -371.641878)
		(size 0.8636)
		(drill 0.508)
		(layers "F.Cu" "B.Cu")
		(net "P12V_A")
	)
	(via
		(at 195.26758 -220.635322)
		(size 0.6096)
		(drill 0.3048)
		(layers "F.Cu" "B.Cu")
		(net "P12V_A")
	)
	(via
		(at 78.069948 -55.793894)
		(size 0.5588)
		(drill 0.3048)
		(layers "F.Cu" "B.Cu")
		(net "P12V_A")
	)
	(via
		(at 194.743578 -221.55404)
		(size 0.5588)
		(drill 0.3048)
		(layers "F.Cu" "B.Cu")
		(net "P12V_A")
	)
	(via
		(at 429.422052 -287.444942)
		(size 0.5588)
		(drill 0.3048)
		(layers "F.Cu" "B.Cu")
		(net "P12V_A")
	)
	(via
		(at 260.69163 -371.664484)
		(size 0.8636)
		(drill 0.508)
		(layers "F.Cu" "B.Cu")
		(net "P12V_A")
	)
	(via
		(at 254.2286 -372.784878)
		(size 0.8636)
		(drill 0.508)
		(layers "F.Cu" "B.Cu")
		(net "P12V_A")
	)
	(via
		(at 254.2286 -375.070878)
		(size 0.8636)
		(drill 0.508)
		(layers "F.Cu" "B.Cu")
		(net "P12V_A")
	)
	(via
		(at 113.443258 -282.695142)
		(size 0.5588)
		(drill 0.3048)
		(layers "F.Cu" "B.Cu")
		(net "P12V_A")
	)
	(via
		(at 267.6398 -372.7704)
		(size 0.8636)
		(drill 0.508)
		(layers "F.Cu" "B.Cu")
		(net "P12V_A")
	)
	(via
		(at 76.926948 -55.793894)
		(size 0.5588)
		(drill 0.3048)
		(layers "F.Cu" "B.Cu")
		(net "P12V_A")
	)
	(via
		(at 334.772 -172.825918)
		(size 0.5588)
		(drill 0.3048)
		(layers "F.Cu" "B.Cu")
		(net "P12V_A")
	)
	(via
		(at 429.168052 -171.555918)
		(size 0.5588)
		(drill 0.3048)
		(layers "F.Cu" "B.Cu")
		(net "P12V_A")
	)
	(via
		(at 463.5119 -172.825918)
		(size 0.5588)
		(drill 0.3048)
		(layers "F.Cu" "B.Cu")
		(net "P12V_A")
	)
	(via
		(at 114.914426 -284.91815)
		(size 0.5588)
		(drill 0.3048)
		(layers "F.Cu" "B.Cu")
		(net "P12V_A")
	)
	(via
		(at 204.546454 -19.978116)
		(size 0.5588)
		(drill 0.3048)
		(layers "F.Cu" "B.Cu")
		(net "P12V_A")
	)
	(via
		(at 462.2419 -172.825918)
		(size 0.5588)
		(drill 0.3048)
		(layers "F.Cu" "B.Cu")
		(net "P12V_A")
	)
	(via
		(at 46.293786 -170.829986)
		(size 0.5588)
		(drill 0.3048)
		(layers "F.Cu" "B.Cu")
		(net "P12V_A")
	)
	(via
		(at 260.69163 -375.093484)
		(size 0.8636)
		(drill 0.508)
		(layers "F.Cu" "B.Cu")
		(net "P12V_A")
	)
	(via
		(at 261.83463 -373.950484)
		(size 0.8636)
		(drill 0.508)
		(layers "F.Cu" "B.Cu")
		(net "P12V_A")
	)
	(via
		(at 47.929546 -50.942494)
		(size 0.5588)
		(drill 0.3048)
		(layers "F.Cu" "B.Cu")
		(net "P12V_A")
	)
	(via
		(at 171.3738 -279.019)
		(size 0.5588)
		(drill 0.3048)
		(layers "F.Cu" "B.Cu")
		(net "P12V_A")
	)
	(via
		(at 140.026898 -170.793918)
		(size 0.5588)
		(drill 0.3048)
		(layers "F.Cu" "B.Cu")
		(net "P12V_A")
	)
	(via
		(at 429.961294 -255.104138)
		(size 0.7112)
		(drill 0.4064)
		(layers "F.Cu" "B.Cu")
		(net "P12V_A")
	)
	(via
		(at 400.41195 -172.063918)
		(size 0.5588)
		(drill 0.3048)
		(layers "F.Cu" "B.Cu")
		(net "P12V_A")
	)
	(via
		(at 109.022896 -44.7802)
		(size 0.5588)
		(drill 0.3048)
		(layers "F.Cu" "B.Cu")
		(net "P12V_A")
	)
	(via
		(at 368.481102 -274.490942)
		(size 0.5588)
		(drill 0.3048)
		(layers "F.Cu" "B.Cu")
		(net "P12V_A")
	)
	(via
		(at 140.633196 -55.910734)
		(size 0.5588)
		(drill 0.3048)
		(layers "F.Cu" "B.Cu")
		(net "P12V_A")
	)
	(via
		(at 141.169898 -285.793942)
		(size 0.5588)
		(drill 0.3048)
		(layers "F.Cu" "B.Cu")
		(net "P12V_A")
	)
	(via
		(at 79.560928 -281.050746)
		(size 0.5588)
		(drill 0.3048)
		(layers "F.Cu" "B.Cu")
		(net "P12V_A")
	)
	(via
		(at 12.683998 -285.793942)
		(size 0.5588)
		(drill 0.3048)
		(layers "F.Cu" "B.Cu")
		(net "P12V_A")
	)
	(via
		(at 256.5146 -372.784878)
		(size 0.8636)
		(drill 0.508)
		(layers "F.Cu" "B.Cu")
		(net "P12V_A")
	)
	(via
		(at 264.12063 -371.664484)
		(size 0.8636)
		(drill 0.508)
		(layers "F.Cu" "B.Cu")
		(net "P12V_A")
	)
	(via
		(at 76.537058 -275.633942)
		(size 0.5588)
		(drill 0.3048)
		(layers "F.Cu" "B.Cu")
		(net "P12V_A")
	)
	(via
		(at 429.961294 -253.961138)
		(size 0.7112)
		(drill 0.4064)
		(layers "F.Cu" "B.Cu")
		(net "P12V_A")
	)
	(via
		(at 173.228 -159.626046)
		(size 0.5588)
		(drill 0.3048)
		(layers "F.Cu" "B.Cu")
		(net "P12V_A")
	)
	(via
		(at 109.619796 -55.793894)
		(size 0.5588)
		(drill 0.3048)
		(layers "F.Cu" "B.Cu")
		(net "P12V_A")
	)
	(via
		(at 205.816454 -19.978116)
		(size 0.5588)
		(drill 0.3048)
		(layers "F.Cu" "B.Cu")
		(net "P12V_A")
	)
	(via
		(at 469.266524 -284.173676)
		(size 0.5588)
		(drill 0.3048)
		(layers "F.Cu" "B.Cu")
		(net "P12V_A")
	)
	(via
		(at 107.333796 -55.793894)
		(size 0.5588)
		(drill 0.3048)
		(layers "F.Cu" "B.Cu")
		(net "P12V_A")
	)
	(via
		(at 111.029496 -51.221894)
		(size 0.5588)
		(drill 0.3048)
		(layers "F.Cu" "B.Cu")
		(net "P12V_A")
	)
	(via
		(at 171.577 -285.793942)
		(size 0.5588)
		(drill 0.3048)
		(layers "F.Cu" "B.Cu")
		(net "P12V_A")
	)
	(via
		(at 364.734602 -46.693582)
		(size 0.5588)
		(drill 0.3048)
		(layers "F.Cu" "B.Cu")
		(net "P12V_A")
	)
	(via
		(at 140.026898 -285.793942)
		(size 0.5588)
		(drill 0.3048)
		(layers "F.Cu" "B.Cu")
		(net "P12V_A")
	)
	(via
		(at 178.768502 -151.52497)
		(size 0.7112)
		(drill 0.4064)
		(layers "F.Cu" "B.Cu")
		(net "P12V_A")
	)
	(via
		(at 427.834552 -47.729394)
		(size 0.5588)
		(drill 0.3048)
		(layers "F.Cu" "B.Cu")
		(net "P12V_A")
	)
	(via
		(at 172.701966 -170.956732)
		(size 0.5588)
		(drill 0.3048)
		(layers "F.Cu" "B.Cu")
		(net "P12V_A")
	)
	(via
		(at 367.592102 -57.825894)
		(size 0.5588)
		(drill 0.3048)
		(layers "F.Cu" "B.Cu")
		(net "P12V_A")
	)
	(via
		(at 128.199896 -281.196542)
		(size 0.5588)
		(drill 0.3048)
		(layers "F.Cu" "B.Cu")
		(net "P12V_A")
	)
	(via
		(at 283.570426 -227.611178)
		(size 0.5588)
		(drill 0.3048)
		(layers "F.Cu" "B.Cu")
		(net "P12V_A")
	)
	(via
		(at 261.83463 -375.093484)
		(size 0.8636)
		(drill 0.508)
		(layers "F.Cu" "B.Cu")
		(net "P12V_A")
	)
	(via
		(at 368.481102 -43.954446)
		(size 0.5588)
		(drill 0.3048)
		(layers "F.Cu" "B.Cu")
		(net "P12V_A")
	)
	(via
		(at 14.969998 -55.793894)
		(size 0.5588)
		(drill 0.3048)
		(layers "F.Cu" "B.Cu")
		(net "P12V_A")
	)
	(via
		(at 366.322102 -172.825918)
		(size 0.5588)
		(drill 0.3048)
		(layers "F.Cu" "B.Cu")
		(net "P12V_A")
	)
	(via
		(at 431.581052 -44.465494)
		(size 0.5588)
		(drill 0.3048)
		(layers "F.Cu" "B.Cu")
		(net "P12V_A")
	)
	(via
		(at 252.36551 -34.98342)
		(size 0.5588)
		(drill 0.3048)
		(layers "F.Cu" "B.Cu")
		(net "P12V_A")
	)
	(via
		(at 368.481102 -159.465518)
		(size 0.5588)
		(drill 0.3048)
		(layers "F.Cu" "B.Cu")
		(net "P12V_A")
	)
	(via
		(at 462.2419 -287.825942)
		(size 0.5588)
		(drill 0.3048)
		(layers "F.Cu" "B.Cu")
		(net "P12V_A")
	)
	(via
		(at 116.057426 -284.91815)
		(size 0.5588)
		(drill 0.3048)
		(layers "F.Cu" "B.Cu")
		(net "P12V_A")
	)
	(via
		(at 16.379698 -281.221942)
		(size 0.5588)
		(drill 0.3048)
		(layers "F.Cu" "B.Cu")
		(net "P12V_A")
	)
	(via
		(at 336.965798 -57.548272)
		(size 0.5588)
		(drill 0.3048)
		(layers "F.Cu" "B.Cu")
		(net "P12V_A")
	)
	(via
		(at 336.042 -172.825918)
		(size 0.5588)
		(drill 0.3048)
		(layers "F.Cu" "B.Cu")
		(net "P12V_A")
	)
	(via
		(at 267.6398 -375.0564)
		(size 0.8636)
		(drill 0.508)
		(layers "F.Cu" "B.Cu")
		(net "P12V_A")
	)
	(via
		(at 430.692052 -287.444942)
		(size 0.5588)
		(drill 0.3048)
		(layers "F.Cu" "B.Cu")
		(net "P12V_A")
	)
	(via
		(at 107.333796 -170.793918)
		(size 0.5588)
		(drill 0.3048)
		(layers "F.Cu" "B.Cu")
		(net "P12V_A")
	)
	(via
		(at 170.415966 -170.956732)
		(size 0.5588)
		(drill 0.3048)
		(layers "F.Cu" "B.Cu")
		(net "P12V_A")
	)
	(via
		(at 284.332426 -225.706178)
		(size 0.5588)
		(drill 0.3048)
		(layers "F.Cu" "B.Cu")
		(net "P12V_A")
	)
	(via
		(at 253.0856 -371.641878)
		(size 0.8636)
		(drill 0.508)
		(layers "F.Cu" "B.Cu")
		(net "P12V_A")
	)
	(via
		(at 204.85481 -168.656)
		(size 0.5588)
		(drill 0.3048)
		(layers "F.Cu" "B.Cu")
		(net "P12V_A")
	)
	(via
		(at 75.783948 -170.793918)
		(size 0.5588)
		(drill 0.3048)
		(layers "F.Cu" "B.Cu")
		(net "P12V_A")
	)
	(via
		(at 260.69163 -373.950484)
		(size 0.8636)
		(drill 0.508)
		(layers "F.Cu" "B.Cu")
		(net "P12V_A")
	)
	(via
		(at 139.755626 -55.908194)
		(size 0.5588)
		(drill 0.3048)
		(layers "F.Cu" "B.Cu")
		(net "P12V_A")
	)
	(via
		(at 171.275502 -55.974996)
		(size 0.5588)
		(drill 0.3048)
		(layers "F.Cu" "B.Cu")
		(net "P12V_A")
	)
	(via
		(at 44.233846 -55.793894)
		(size 0.5588)
		(drill 0.3048)
		(layers "F.Cu" "B.Cu")
		(net "P12V_A")
	)
	(via
		(at 431.104294 -255.104138)
		(size 0.7112)
		(drill 0.4064)
		(layers "F.Cu" "B.Cu")
		(net "P12V_A")
	)
	(via
		(at 399.14195 -57.825894)
		(size 0.5588)
		(drill 0.3048)
		(layers "F.Cu" "B.Cu")
		(net "P12V_A")
	)
	(via
		(at 463.1309 -44.490894)
		(size 0.5588)
		(drill 0.3048)
		(layers "F.Cu" "B.Cu")
		(net "P12V_A")
	)
	(via
		(at 177.701702 -153.65857)
		(size 0.7112)
		(drill 0.4064)
		(layers "F.Cu" "B.Cu")
		(net "P12V_A")
	)
	(via
		(at 31.562802 -141.02715)
		(size 0.7112)
		(drill 0.4064)
		(layers "F.Cu" "B.Cu")
		(net "P12V_A")
	)
	(via
		(at 427.834552 -277.297642)
		(size 0.5588)
		(drill 0.3048)
		(layers "F.Cu" "B.Cu")
		(net "P12V_A")
	)
	(via
		(at 47.853346 -280.129742)
		(size 0.5588)
		(drill 0.3048)
		(layers "F.Cu" "B.Cu")
		(net "P12V_A")
	)
	(via
		(at 108.476796 -55.793894)
		(size 0.5588)
		(drill 0.3048)
		(layers "F.Cu" "B.Cu")
		(net "P12V_A")
	)
	(via
		(at 13.826998 -55.793894)
		(size 0.5588)
		(drill 0.3048)
		(layers "F.Cu" "B.Cu")
		(net "P12V_A")
	)
	(via
		(at 268.7828 -372.7704)
		(size 0.8636)
		(drill 0.508)
		(layers "F.Cu" "B.Cu")
		(net "P12V_A")
	)
	(via
		(at 407.26995 -280.68016)
		(size 0.5588)
		(drill 0.3048)
		(layers "F.Cu" "B.Cu")
		(net "P12V_A")
	)
	(via
		(at 13.484098 -45.608494)
		(size 0.5588)
		(drill 0.3048)
		(layers "F.Cu" "B.Cu")
		(net "P12V_A")
	)
	(via
		(at 53.34 -165.1)
		(size 0.5588)
		(drill 0.3048)
		(layers "F.Cu" "B.Cu")
		(net "P12V_A")
	)
	(via
		(at 109.619796 -170.793918)
		(size 0.5588)
		(drill 0.3048)
		(layers "F.Cu" "B.Cu")
		(net "P12V_A")
	)
	(via
		(at 253.0856 -372.784878)
		(size 0.8636)
		(drill 0.508)
		(layers "F.Cu" "B.Cu")
		(net "P12V_A")
	)
	(via
		(at 262.97763 -373.950484)
		(size 0.8636)
		(drill 0.508)
		(layers "F.Cu" "B.Cu")
		(net "P12V_A")
	)
	(via
		(at 79.479648 -51.221894)
		(size 0.5588)
		(drill 0.3048)
		(layers "F.Cu" "B.Cu")
		(net "P12V_A")
	)
	(via
		(at 466.586062 -280.261314)
		(size 0.5588)
		(drill 0.3048)
		(layers "F.Cu" "B.Cu")
		(net "P12V_A")
	)
	(via
		(at 405.99995 -281.28976)
		(size 0.5588)
		(drill 0.3048)
		(layers "F.Cu" "B.Cu")
		(net "P12V_A")
	)
	(via
		(at 261.82955 -31.07309)
		(size 0.5588)
		(drill 0.3048)
		(layers "F.Cu" "B.Cu")
		(net "P12V_A")
	)
	(via
		(at 256.5146 -375.070878)
		(size 0.8636)
		(drill 0.508)
		(layers "F.Cu" "B.Cu")
		(net "P12V_A")
	)
	(via
		(at 463.1309 -159.490918)
		(size 0.5588)
		(drill 0.3048)
		(layers "F.Cu" "B.Cu")
		(net "P12V_A")
	)
	(via
		(at 33.798002 -257.23215)
		(size 0.5588)
		(drill 0.3048)
		(layers "F.Cu" "B.Cu")
		(net "P12V_A")
	)
	(segment
		(start 16.119602 -247.786398)
		(end 16.119602 -249.25655)
		(width 0.508)
		(layer "B.Cu")
		(net "P12V_A")
	)
	(segment
		(start 16.119602 -249.25655)
		(end 14.77645 -249.25655)
		(width 0.508)
		(layer "B.Cu")
		(net "P12V_A")
	)
	(segment
		(start 481.823522 -227.965)
		(end 481.823522 -227.1649)
		(width 0.508)
		(layer "B.Cu")
		(net "P12V_A")
	)
	(segment
		(start 16.129 -247.777)
		(end 16.119602 -247.786398)
		(width 0.508)
		(layer "B.Cu")
		(net "P12V_A")
	)
	(segment
		(start 331.359002 -24.449532)
		(end 331.359002 -25.595834)
		(width 0.17145)
		(layer "F.Cu")
		(net "IOM_B_SLOT_ID_0")
	)
	(segment
		(start 331.359002 -23.116032)
		(end 331.359002 -24.449532)
		(width 0.17145)
		(layer "F.Cu")
		(net "IOM_B_SLOT_ID_0")
	)
	(via
		(at 331.359002 -25.595834)
		(size 0.5588)
		(drill 0.3048)
		(layers "F.Cu" "B.Cu")
		(net "IOM_B_SLOT_ID_0")
	)
	(via
		(at 331.359002 -24.449532)
		(size 0.6604)
		(drill 0.3302)
		(layers "F.Cu" "B.Cu")
		(net "IOM_B_SLOT_ID_0")
	)
	(segment
		(start 352.586544 -34.982404)
		(end 346.64523 -29.04109)
		(width 0.13335)
		(layer "In2.Cu")
		(net "IOM_B_SLOT_ID_0")
	)
	(segment
		(start 346.64523 -29.04109)
		(end 340.823042 -29.04109)
		(width 0.13335)
		(layer "In2.Cu")
		(net "IOM_B_SLOT_ID_0")
	)
	(segment
		(start 364.884716 -29.215334)
		(end 364.884716 -30.879034)
		(width 0.13335)
		(layer "In2.Cu")
		(net "IOM_B_SLOT_ID_0")
	)
	(segment
		(start 331.359002 -25.898856)
		(end 331.359002 -25.595834)
		(width 0.13335)
		(layer "In2.Cu")
		(net "IOM_B_SLOT_ID_0")
	)
	(segment
		(start 364.884716 -30.879034)
		(end 360.781346 -34.982404)
		(width 0.13335)
		(layer "In2.Cu")
		(net "IOM_B_SLOT_ID_0")
	)
	(segment
		(start 365.949992 -28.150058)
		(end 364.884716 -29.215334)
		(width 0.13335)
		(layer "In2.Cu")
		(net "IOM_B_SLOT_ID_0")
	)
	(segment
		(start 340.823042 -29.04109)
		(end 340.109048 -28.327096)
		(width 0.13335)
		(layer "In2.Cu")
		(net "IOM_B_SLOT_ID_0")
	)
	(segment
		(start 333.787242 -28.327096)
		(end 331.359002 -25.898856)
		(width 0.13335)
		(layer "In2.Cu")
		(net "IOM_B_SLOT_ID_0")
	)
	(segment
		(start 360.781346 -34.982404)
		(end 352.586544 -34.982404)
		(width 0.13335)
		(layer "In2.Cu")
		(net "IOM_B_SLOT_ID_0")
	)
	(segment
		(start 340.109048 -28.327096)
		(end 333.787242 -28.327096)
		(width 0.13335)
		(layer "In2.Cu")
		(net "IOM_B_SLOT_ID_0")
	)
	(segment
		(start 256.645156 -257.044444)
		(end 256.645156 -257.79476)
		(width 0.17145)
		(layer "F.Cu")
		(net "IOM_B_INS_N")
	)
	(segment
		(start 87.711534 -22.22881)
		(end 87.711534 -26.0096)
		(width 0.17145)
		(layer "F.Cu")
		(net "IOM_B_INS_N")
	)
	(segment
		(start 342.73236 -33.995868)
		(end 342.882474 -34.145982)
		(width 0.17145)
		(layer "F.Cu")
		(net "IOM_B_INS_N")
	)
	(segment
		(start 257.4798 -256.2098)
		(end 256.645156 -257.044444)
		(width 0.17145)
		(layer "F.Cu")
		(net "IOM_B_INS_N")
	)
	(segment
		(start 341.821262 -33.995868)
		(end 342.73236 -33.995868)
		(width 0.17145)
		(layer "F.Cu")
		(net "IOM_B_INS_N")
	)
	(segment
		(start 342.882474 -34.145982)
		(end 342.882474 -35.143694)
		(width 0.17145)
		(layer "F.Cu")
		(net "IOM_B_INS_N")
	)
	(segment
		(start 257.4798 -255.94056)
		(end 257.4798 -256.2098)
		(width 0.17145)
		(layer "F.Cu")
		(net "IOM_B_INS_N")
	)
	(via
		(at 342.882474 -35.143694)
		(size 0.5588)
		(drill 0.3048)
		(layers "F.Cu" "B.Cu")
		(net "IOM_B_INS_N")
	)
	(via
		(at 342.882474 -34.145982)
		(size 0.6604)
		(drill 0.3302)
		(layers "F.Cu" "B.Cu")
		(net "IOM_B_INS_N")
	)
	(via
		(at 342.292178 -25.739598)
		(size 0.5588)
		(drill 0.3048)
		(layers "F.Cu" "B.Cu")
		(net "IOM_B_INS_N")
	)
	(via
		(at 71.3232 -257.0226)
		(size 0.5588)
		(drill 0.3048)
		(layers "F.Cu" "B.Cu")
		(net "IOM_B_INS_N")
	)
	(via
		(at 257.4798 -255.94056)
		(size 0.5588)
		(drill 0.3048)
		(layers "F.Cu" "B.Cu")
		(net "IOM_B_INS_N")
	)
	(via
		(at 87.711534 -26.0096)
		(size 0.5588)
		(drill 0.3048)
		(layers "F.Cu" "B.Cu")
		(net "IOM_B_INS_N")
	)
	(segment
		(start 88.31961 -26.617676)
		(end 88.42375 -26.617676)
		(width 0.13335)
		(layer "In2.Cu")
		(net "IOM_B_INS_N")
	)
	(segment
		(start 250.254008 -89.365836)
		(end 250.254008 -14.06017)
		(width 0.13335)
		(layer "In2.Cu")
		(net "IOM_B_INS_N")
	)
	(segment
		(start 88.42375 -26.617676)
		(end 112.60582 -50.799746)
		(width 0.13335)
		(layer "In2.Cu")
		(net "IOM_B_INS_N")
	)
	(segment
		(start 194.82435 -258.689602)
		(end 197.948804 -258.689602)
		(width 0.13335)
		(layer "In2.Cu")
		(net "IOM_B_INS_N")
	)
	(segment
		(start 347.827346 -40.088566)
		(end 342.882474 -35.143694)
		(width 0.13335)
		(layer "In2.Cu")
		(net "IOM_B_INS_N")
	)
	(segment
		(start 71.3232 -257.0226)
		(end 102.335838 -257.0226)
		(width 0.13335)
		(layer "In2.Cu")
		(net "IOM_B_INS_N")
	)
	(segment
		(start 121.289064 -56.565038)
		(end 164.630862 -56.565038)
		(width 0.13335)
		(layer "In2.Cu")
		(net "IOM_B_INS_N")
	)
	(segment
		(start 115.523772 -50.799746)
		(end 121.289064 -56.565038)
		(width 0.13335)
		(layer "In2.Cu")
		(net "IOM_B_INS_N")
	)
	(segment
		(start 232.530142 -258.562602)
		(end 234.070144 -257.0226)
		(width 0.13335)
		(layer "In2.Cu")
		(net "IOM_B_INS_N")
	)
	(segment
		(start 168.507664 -72.606408)
		(end 185.196226 -89.29497)
		(width 0.13335)
		(layer "In2.Cu")
		(net "IOM_B_INS_N")
	)
	(segment
		(start 381.51054 -31.209488)
		(end 373.190262 -39.529766)
		(width 0.13335)
		(layer "In2.Cu")
		(net "IOM_B_INS_N")
	)
	(segment
		(start 168.507664 -60.44184)
		(end 168.507664 -72.606408)
		(width 0.13335)
		(layer "In2.Cu")
		(net "IOM_B_INS_N")
	)
	(segment
		(start 373.190262 -39.529766)
		(end 363.676946 -39.529766)
		(width 0.13335)
		(layer "In2.Cu")
		(net "IOM_B_INS_N")
	)
	(segment
		(start 363.676946 -39.529766)
		(end 361.816142 -41.39057)
		(width 0.13335)
		(layer "In2.Cu")
		(net "IOM_B_INS_N")
	)
	(segment
		(start 102.52964 -257.216402)
		(end 110.0074 -257.216402)
		(width 0.13335)
		(layer "In2.Cu")
		(net "IOM_B_INS_N")
	)
	(segment
		(start 234.070144 -257.0226)
		(end 255.02616 -257.0226)
		(width 0.13335)
		(layer "In2.Cu")
		(net "IOM_B_INS_N")
	)
	(segment
		(start 306.429664 -10.052304)
		(end 308.8259 -12.44854)
		(width 0.13335)
		(layer "In2.Cu")
		(net "IOM_B_INS_N")
	)
	(segment
		(start 337.569556 -23.109682)
		(end 338.558124 -24.09825)
		(width 0.13335)
		(layer "In2.Cu")
		(net "IOM_B_INS_N")
	)
	(segment
		(start 164.630862 -56.565038)
		(end 168.507664 -60.44184)
		(width 0.13335)
		(layer "In2.Cu")
		(net "IOM_B_INS_N")
	)
	(segment
		(start 194.472052 -258.689348)
		(end 194.824096 -258.689348)
		(width 0.13335)
		(layer "In2.Cu")
		(net "IOM_B_INS_N")
	)
	(segment
		(start 193.779648 -259.381752)
		(end 194.472052 -258.689348)
		(width 0.13335)
		(layer "In2.Cu")
		(net "IOM_B_INS_N")
	)
	(segment
		(start 112.60582 -50.799746)
		(end 115.523772 -50.799746)
		(width 0.13335)
		(layer "In2.Cu")
		(net "IOM_B_INS_N")
	)
	(segment
		(start 198.075804 -258.562602)
		(end 232.530142 -258.562602)
		(width 0.13335)
		(layer "In2.Cu")
		(net "IOM_B_INS_N")
	)
	(segment
		(start 338.558124 -24.09825)
		(end 340.65083 -24.09825)
		(width 0.13335)
		(layer "In2.Cu")
		(net "IOM_B_INS_N")
	)
	(segment
		(start 285.663132 -1.297178)
		(end 294.418258 -10.052304)
		(width 0.13335)
		(layer "In2.Cu")
		(net "IOM_B_INS_N")
	)
	(segment
		(start 354.097082 -41.39057)
		(end 352.795078 -40.088566)
		(width 0.13335)
		(layer "In2.Cu")
		(net "IOM_B_INS_N")
	)
	(segment
		(start 197.948804 -258.689602)
		(end 198.075804 -258.562602)
		(width 0.13335)
		(layer "In2.Cu")
		(net "IOM_B_INS_N")
	)
	(segment
		(start 174.187612 -259.381752)
		(end 193.779648 -259.381752)
		(width 0.13335)
		(layer "In2.Cu")
		(net "IOM_B_INS_N")
	)
	(segment
		(start 87.711534 -26.0096)
		(end 88.31961 -26.617676)
		(width 0.13335)
		(layer "In2.Cu")
		(net "IOM_B_INS_N")
	)
	(segment
		(start 311.232042 -23.109682)
		(end 337.569556 -23.109682)
		(width 0.13335)
		(layer "In2.Cu")
		(net "IOM_B_INS_N")
	)
	(segment
		(start 255.02616 -257.0226)
		(end 256.1082 -255.94056)
		(width 0.13335)
		(layer "In2.Cu")
		(net "IOM_B_INS_N")
	)
	(segment
		(start 112.172496 -259.381498)
		(end 174.187358 -259.381498)
		(width 0.13335)
		(layer "In2.Cu")
		(net "IOM_B_INS_N")
	)
	(segment
		(start 382.150112 -26.950162)
		(end 381.51054 -27.589734)
		(width 0.13335)
		(layer "In2.Cu")
		(net "IOM_B_INS_N")
	)
	(segment
		(start 174.187358 -259.381498)
		(end 174.187612 -259.381752)
		(width 0.13335)
		(layer "In2.Cu")
		(net "IOM_B_INS_N")
	)
	(segment
		(start 185.196226 -89.29497)
		(end 228.249988 -89.29497)
		(width 0.13335)
		(layer "In2.Cu")
		(net "IOM_B_INS_N")
	)
	(segment
		(start 381.51054 -27.589734)
		(end 381.51054 -31.209488)
		(width 0.13335)
		(layer "In2.Cu")
		(net "IOM_B_INS_N")
	)
	(segment
		(start 352.795078 -40.088566)
		(end 347.827346 -40.088566)
		(width 0.13335)
		(layer "In2.Cu")
		(net "IOM_B_INS_N")
	)
	(segment
		(start 102.335838 -257.0226)
		(end 102.52964 -257.216402)
		(width 0.13335)
		(layer "In2.Cu")
		(net "IOM_B_INS_N")
	)
	(segment
		(start 340.65083 -24.09825)
		(end 342.292178 -25.739598)
		(width 0.13335)
		(layer "In2.Cu")
		(net "IOM_B_INS_N")
	)
	(segment
		(start 246.459248 -93.160596)
		(end 250.254008 -89.365836)
		(width 0.13335)
		(layer "In2.Cu")
		(net "IOM_B_INS_N")
	)
	(segment
		(start 228.249988 -89.29497)
		(end 232.115614 -93.160596)
		(width 0.13335)
		(layer "In2.Cu")
		(net "IOM_B_INS_N")
	)
	(segment
		(start 256.1082 -255.94056)
		(end 257.4798 -255.94056)
		(width 0.13335)
		(layer "In2.Cu")
		(net "IOM_B_INS_N")
	)
	(segment
		(start 232.115614 -93.160596)
		(end 246.459248 -93.160596)
		(width 0.13335)
		(layer "In2.Cu")
		(net "IOM_B_INS_N")
	)
	(segment
		(start 250.254008 -14.06017)
		(end 263.017 -1.297178)
		(width 0.13335)
		(layer "In2.Cu")
		(net "IOM_B_INS_N")
	)
	(segment
		(start 294.418258 -10.052304)
		(end 306.429664 -10.052304)
		(width 0.13335)
		(layer "In2.Cu")
		(net "IOM_B_INS_N")
	)
	(segment
		(start 110.0074 -257.216402)
		(end 112.172496 -259.381498)
		(width 0.13335)
		(layer "In2.Cu")
		(net "IOM_B_INS_N")
	)
	(segment
		(start 194.824096 -258.689348)
		(end 194.82435 -258.689602)
		(width 0.13335)
		(layer "In2.Cu")
		(net "IOM_B_INS_N")
	)
	(segment
		(start 308.8259 -12.44854)
		(end 308.8259 -20.70354)
		(width 0.13335)
		(layer "In2.Cu")
		(net "IOM_B_INS_N")
	)
	(segment
		(start 361.816142 -41.39057)
		(end 354.097082 -41.39057)
		(width 0.13335)
		(layer "In2.Cu")
		(net "IOM_B_INS_N")
	)
	(segment
		(start 308.8259 -20.70354)
		(end 311.232042 -23.109682)
		(width 0.13335)
		(layer "In2.Cu")
		(net "IOM_B_INS_N")
	)
	(segment
		(start 263.017 -1.297178)
		(end 285.663132 -1.297178)
		(width 0.13335)
		(layer "In2.Cu")
		(net "IOM_B_INS_N")
	)
	(segment
		(start 68.453 -54.718458)
		(end 68.453 -54.6354)
		(width 0.12065)
		(layer "In4.Cu")
		(net "IOM_B_INS_N")
	)
	(segment
		(start 71.3232 -256.8956)
		(end 70.957948 -256.530348)
		(width 0.12065)
		(layer "In4.Cu")
		(net "IOM_B_INS_N")
	)
	(segment
		(start 70.957948 -192.45707)
		(end 73.880218 -189.5348)
		(width 0.12065)
		(layer "In4.Cu")
		(net "IOM_B_INS_N")
	)
	(segment
		(start 85.1916 -37.8968)
		(end 85.1916 -28.529534)
		(width 0.12065)
		(layer "In4.Cu")
		(net "IOM_B_INS_N")
	)
	(segment
		(start 73.880218 -189.5348)
		(end 73.880218 -160.128712)
		(width 0.12065)
		(layer "In4.Cu")
		(net "IOM_B_INS_N")
	)
	(segment
		(start 342.4047 -29.21381)
		(end 341.649812 -28.458922)
		(width 0.12065)
		(layer "In4.Cu")
		(net "IOM_B_INS_N")
	)
	(segment
		(start 78.357222 -155.651708)
		(end 78.357222 -141.885162)
		(width 0.12065)
		(layer "In4.Cu")
		(net "IOM_B_INS_N")
	)
	(segment
		(start 85.1916 -28.529534)
		(end 87.711534 -26.0096)
		(width 0.12065)
		(layer "In4.Cu")
		(net "IOM_B_INS_N")
	)
	(segment
		(start 68.392548 -54.77891)
		(end 68.453 -54.718458)
		(width 0.12065)
		(layer "In4.Cu")
		(net "IOM_B_INS_N")
	)
	(segment
		(start 68.46189 -131.98983)
		(end 68.46189 -68.355464)
		(width 0.12065)
		(layer "In4.Cu")
		(net "IOM_B_INS_N")
	)
	(segment
		(start 68.46189 -68.355464)
		(end 68.983352 -67.834002)
		(width 0.12065)
		(layer "In4.Cu")
		(net "IOM_B_INS_N")
	)
	(segment
		(start 68.983352 -65.894204)
		(end 68.392548 -65.3034)
		(width 0.12065)
		(layer "In4.Cu")
		(net "IOM_B_INS_N")
	)
	(segment
		(start 341.649812 -26.381964)
		(end 342.292178 -25.739598)
		(width 0.12065)
		(layer "In4.Cu")
		(net "IOM_B_INS_N")
	)
	(segment
		(start 342.882474 -35.143694)
		(end 342.882474 -34.271712)
		(width 0.12065)
		(layer "In4.Cu")
		(net "IOM_B_INS_N")
	)
	(segment
		(start 68.453 -54.6354)
		(end 85.1916 -37.8968)
		(width 0.12065)
		(layer "In4.Cu")
		(net "IOM_B_INS_N")
	)
	(segment
		(start 342.882474 -34.271712)
		(end 342.4047 -33.793938)
		(width 0.12065)
		(layer "In4.Cu")
		(net "IOM_B_INS_N")
	)
	(segment
		(start 78.357222 -141.885162)
		(end 68.46189 -131.98983)
		(width 0.12065)
		(layer "In4.Cu")
		(net "IOM_B_INS_N")
	)
	(segment
		(start 68.983352 -67.834002)
		(end 68.983352 -65.894204)
		(width 0.12065)
		(layer "In4.Cu")
		(net "IOM_B_INS_N")
	)
	(segment
		(start 68.392548 -65.3034)
		(end 68.392548 -54.77891)
		(width 0.12065)
		(layer "In4.Cu")
		(net "IOM_B_INS_N")
	)
	(segment
		(start 341.649812 -28.458922)
		(end 341.649812 -26.381964)
		(width 0.12065)
		(layer "In4.Cu")
		(net "IOM_B_INS_N")
	)
	(segment
		(start 71.3232 -257.0226)
		(end 71.3232 -256.8956)
		(width 0.12065)
		(layer "In4.Cu")
		(net "IOM_B_INS_N")
	)
	(segment
		(start 70.957948 -256.530348)
		(end 70.957948 -192.45707)
		(width 0.12065)
		(layer "In4.Cu")
		(net "IOM_B_INS_N")
	)
	(segment
		(start 342.4047 -33.793938)
		(end 342.4047 -29.21381)
		(width 0.12065)
		(layer "In4.Cu")
		(net "IOM_B_INS_N")
	)
	(segment
		(start 73.880218 -160.128712)
		(end 78.357222 -155.651708)
		(width 0.12065)
		(layer "In4.Cu")
		(net "IOM_B_INS_N")
	)
	(segment
		(start 223.83242 -399.508726)
		(end 223.324674 -399.00098)
		(width 0.13335)
		(layer "In9.Cu")
		(net "IOM_B_INS_N")
	)
	(segment
		(start 223.151954 -382.325626)
		(end 223.5708 -381.90678)
		(width 0.13335)
		(layer "In9.Cu")
		(net "IOM_B_INS_N")
	)
	(segment
		(start 226.832668 -410.93263)
		(end 226.832668 -404.925276)
		(width 0.13335)
		(layer "In9.Cu")
		(net "IOM_B_INS_N")
	)
	(segment
		(start 223.534986 -380.79299)
		(end 223.534986 -370.307362)
		(width 0.13335)
		(layer "In9.Cu")
		(net "IOM_B_INS_N")
	)
	(segment
		(start 223.5708 -380.828804)
		(end 223.534986 -380.79299)
		(width 0.13335)
		(layer "In9.Cu")
		(net "IOM_B_INS_N")
	)
	(segment
		(start 254.561594 -257.650488)
		(end 256.271522 -255.94056)
		(width 0.13335)
		(layer "In9.Cu")
		(net "IOM_B_INS_N")
	)
	(segment
		(start 252.834394 -267.24229)
		(end 252.834394 -266.976352)
		(width 0.13335)
		(layer "In9.Cu")
		(net "IOM_B_INS_N")
	)
	(segment
		(start 229.149148 -364.6932)
		(end 229.149148 -335.315052)
		(width 0.13335)
		(layer "In9.Cu")
		(net "IOM_B_INS_N")
	)
	(segment
		(start 223.151954 -398.828006)
		(end 223.151954 -382.325626)
		(width 0.13335)
		(layer "In9.Cu")
		(net "IOM_B_INS_N")
	)
	(segment
		(start 223.32442 -399.000472)
		(end 223.151954 -398.828006)
		(width 0.13335)
		(layer "In9.Cu")
		(net "IOM_B_INS_N")
	)
	(segment
		(start 252.834394 -266.976352)
		(end 254.561594 -265.249152)
		(width 0.13335)
		(layer "In9.Cu")
		(net "IOM_B_INS_N")
	)
	(segment
		(start 239.474502 -295.850818)
		(end 252.716792 -282.608528)
		(width 0.13335)
		(layer "In9.Cu")
		(net "IOM_B_INS_N")
	)
	(segment
		(start 223.324674 -399.00098)
		(end 223.32442 -399.00098)
		(width 0.13335)
		(layer "In9.Cu")
		(net "IOM_B_INS_N")
	)
	(segment
		(start 252.716792 -282.608528)
		(end 252.716792 -267.359892)
		(width 0.13335)
		(layer "In9.Cu")
		(net "IOM_B_INS_N")
	)
	(segment
		(start 239.474502 -324.989698)
		(end 239.474502 -295.850818)
		(width 0.13335)
		(layer "In9.Cu")
		(net "IOM_B_INS_N")
	)
	(segment
		(start 223.534986 -370.307362)
		(end 229.149148 -364.6932)
		(width 0.13335)
		(layer "In9.Cu")
		(net "IOM_B_INS_N")
	)
	(segment
		(start 226.307142 -401.983194)
		(end 223.832674 -399.508726)
		(width 0.13335)
		(layer "In9.Cu")
		(net "IOM_B_INS_N")
	)
	(segment
		(start 226.307142 -404.39975)
		(end 226.307142 -401.983194)
		(width 0.13335)
		(layer "In9.Cu")
		(net "IOM_B_INS_N")
	)
	(segment
		(start 252.716792 -267.359892)
		(end 252.834394 -267.24229)
		(width 0.13335)
		(layer "In9.Cu")
		(net "IOM_B_INS_N")
	)
	(segment
		(start 226.832668 -404.925276)
		(end 226.307142 -404.39975)
		(width 0.13335)
		(layer "In9.Cu")
		(net "IOM_B_INS_N")
	)
	(segment
		(start 228.000052 -412.100014)
		(end 226.832668 -410.93263)
		(width 0.13335)
		(layer "In9.Cu")
		(net "IOM_B_INS_N")
	)
	(segment
		(start 223.32442 -399.00098)
		(end 223.32442 -399.000472)
		(width 0.13335)
		(layer "In9.Cu")
		(net "IOM_B_INS_N")
	)
	(segment
		(start 256.271522 -255.94056)
		(end 257.4798 -255.94056)
		(width 0.13335)
		(layer "In9.Cu")
		(net "IOM_B_INS_N")
	)
	(segment
		(start 229.149148 -335.315052)
		(end 239.474502 -324.989698)
		(width 0.13335)
		(layer "In9.Cu")
		(net "IOM_B_INS_N")
	)
	(segment
		(start 223.5708 -381.90678)
		(end 223.5708 -380.828804)
		(width 0.13335)
		(layer "In9.Cu")
		(net "IOM_B_INS_N")
	)
	(segment
		(start 223.832674 -399.508726)
		(end 223.83242 -399.508726)
		(width 0.13335)
		(layer "In9.Cu")
		(net "IOM_B_INS_N")
	)
	(segment
		(start 254.561594 -265.249152)
		(end 254.561594 -257.650488)
		(width 0.13335)
		(layer "In9.Cu")
		(net "IOM_B_INS_N")
	)
	(segment
		(start 94.391226 -21.51888)
		(end 92.751148 -21.51888)
		(width 0.17145)
		(layer "F.Cu")
		(net "IOM_A_SLOT_ID_0")
	)
	(segment
		(start 95.794576 -21.51888)
		(end 94.391226 -21.51888)
		(width 0.17145)
		(layer "F.Cu")
		(net "IOM_A_SLOT_ID_0")
	)
	(via
		(at 95.794576 -21.51888)
		(size 0.5588)
		(drill 0.3048)
		(layers "F.Cu" "B.Cu")
		(net "IOM_A_SLOT_ID_0")
	)
	(via
		(at 94.391226 -21.51888)
		(size 0.6604)
		(drill 0.3302)
		(layers "F.Cu" "B.Cu")
		(net "IOM_A_SLOT_ID_0")
	)
	(segment
		(start 117.49405 -33.22955)
		(end 107.505246 -33.22955)
		(width 0.13335)
		(layer "In2.Cu")
		(net "IOM_A_SLOT_ID_0")
	)
	(segment
		(start 119.183912 -28.916122)
		(end 119.183912 -31.539688)
		(width 0.13335)
		(layer "In2.Cu")
		(net "IOM_A_SLOT_ID_0")
	)
	(segment
		(start 119.949976 -28.150058)
		(end 119.183912 -28.916122)
		(width 0.13335)
		(layer "In2.Cu")
		(net "IOM_A_SLOT_ID_0")
	)
	(segment
		(start 119.183912 -31.539688)
		(end 117.49405 -33.22955)
		(width 0.13335)
		(layer "In2.Cu")
		(net "IOM_A_SLOT_ID_0")
	)
	(segment
		(start 107.505246 -33.22955)
		(end 95.794576 -21.51888)
		(width 0.13335)
		(layer "In2.Cu")
		(net "IOM_A_SLOT_ID_0")
	)
	(segment
		(start 257.295396 -257.79476)
		(end 257.295396 -259.39496)
		(width 0.17145)
		(layer "F.Cu")
		(net "IOM_A_INS_N")
	)
	(segment
		(start 341.254334 -24.41829)
		(end 341.254334 -22.708362)
		(width 0.17145)
		(layer "F.Cu")
		(net "IOM_A_INS_N")
	)
	(segment
		(start 155.359354 -28.531566)
		(end 154.413966 -28.531566)
		(width 0.17145)
		(layer "F.Cu")
		(net "IOM_A_INS_N")
	)
	(segment
		(start 341.254334 -22.708362)
		(end 341.254334 -21.709888)
		(width 0.17145)
		(layer "F.Cu")
		(net "IOM_A_INS_N")
	)
	(via
		(at 341.254334 -21.709888)
		(size 0.5588)
		(drill 0.3048)
		(layers "F.Cu" "B.Cu")
		(net "IOM_A_INS_N")
	)
	(via
		(at 323.700902 -250.091702)
		(size 0.5588)
		(drill 0.3048)
		(layers "F.Cu" "B.Cu")
		(net "IOM_A_INS_N")
	)
	(via
		(at 341.254334 -22.708362)
		(size 0.6604)
		(drill 0.3302)
		(layers "F.Cu" "B.Cu")
		(net "IOM_A_INS_N")
	)
	(via
		(at 154.413966 -28.531566)
		(size 0.5588)
		(drill 0.3048)
		(layers "F.Cu" "B.Cu")
		(net "IOM_A_INS_N")
	)
	(via
		(at 234.362498 -0.023622)
		(size 0.5588)
		(drill 0.3048)
		(layers "F.Cu" "B.Cu")
		(net "IOM_A_INS_N")
	)
	(via
		(at 257.295396 -259.39496)
		(size 0.5588)
		(drill 0.3048)
		(layers "F.Cu" "B.Cu")
		(net "IOM_A_INS_N")
	)
	(segment
		(start 288.61512 -248.432066)
		(end 276.775672 -248.432066)
		(width 0.13335)
		(layer "In2.Cu")
		(net "IOM_A_INS_N")
	)
	(segment
		(start 315.402976 -17.144746)
		(end 334.416908 -17.144746)
		(width 0.13335)
		(layer "In2.Cu")
		(net "IOM_A_INS_N")
	)
	(segment
		(start 308.436772 -5.1435)
		(end 313.715654 -10.422382)
		(width 0.13335)
		(layer "In2.Cu")
		(net "IOM_A_INS_N")
	)
	(segment
		(start 313.715654 -15.457424)
		(end 315.402976 -17.144746)
		(width 0.13335)
		(layer "In2.Cu")
		(net "IOM_A_INS_N")
	)
	(segment
		(start 334.416908 -17.144746)
		(end 334.839056 -16.722598)
		(width 0.13335)
		(layer "In2.Cu")
		(net "IOM_A_INS_N")
	)
	(segment
		(start 262.68553 -258.45135)
		(end 258.232656 -258.45135)
		(width 0.13335)
		(layer "In2.Cu")
		(net "IOM_A_INS_N")
	)
	(segment
		(start 343.906602 -17.133316)
		(end 343.906602 -17.133824)
		(width 0.13335)
		(layer "In2.Cu")
		(net "IOM_A_INS_N")
	)
	(segment
		(start 343.906602 -17.133824)
		(end 344.541602 -17.768824)
		(width 0.13335)
		(layer "In2.Cu")
		(net "IOM_A_INS_N")
	)
	(segment
		(start 313.715654 -10.422382)
		(end 313.715654 -15.457424)
		(width 0.13335)
		(layer "In2.Cu")
		(net "IOM_A_INS_N")
	)
	(segment
		(start 257.295396 -259.38861)
		(end 257.295396 -259.39496)
		(width 0.13335)
		(layer "In2.Cu")
		(net "IOM_A_INS_N")
	)
	(segment
		(start 258.232656 -258.45135)
		(end 257.295396 -259.38861)
		(width 0.13335)
		(layer "In2.Cu")
		(net "IOM_A_INS_N")
	)
	(segment
		(start 344.541602 -19.88312)
		(end 342.714834 -21.709888)
		(width 0.13335)
		(layer "In2.Cu")
		(net "IOM_A_INS_N")
	)
	(segment
		(start 234.362498 -0.023622)
		(end 234.38358 -0.044704)
		(width 0.13335)
		(layer "In2.Cu")
		(net "IOM_A_INS_N")
	)
	(segment
		(start 323.700902 -250.091702)
		(end 322.036186 -250.091702)
		(width 0.13335)
		(layer "In2.Cu")
		(net "IOM_A_INS_N")
	)
	(segment
		(start 312.162952 -250.264422)
		(end 304.776378 -257.650996)
		(width 0.13335)
		(layer "In2.Cu")
		(net "IOM_A_INS_N")
	)
	(segment
		(start 297.83405 -257.650996)
		(end 288.61512 -248.432066)
		(width 0.13335)
		(layer "In2.Cu")
		(net "IOM_A_INS_N")
	)
	(segment
		(start 344.541602 -17.768824)
		(end 344.541602 -19.88312)
		(width 0.13335)
		(layer "In2.Cu")
		(net "IOM_A_INS_N")
	)
	(segment
		(start 286.439864 4.842002)
		(end 296.425366 -5.1435)
		(width 0.13335)
		(layer "In2.Cu")
		(net "IOM_A_INS_N")
	)
	(segment
		(start 342.714834 -21.709888)
		(end 341.254334 -21.709888)
		(width 0.13335)
		(layer "In2.Cu")
		(net "IOM_A_INS_N")
	)
	(segment
		(start 296.425366 -5.1435)
		(end 308.436772 -5.1435)
		(width 0.13335)
		(layer "In2.Cu")
		(net "IOM_A_INS_N")
	)
	(segment
		(start 321.863466 -250.264422)
		(end 312.162952 -250.264422)
		(width 0.13335)
		(layer "In2.Cu")
		(net "IOM_A_INS_N")
	)
	(segment
		(start 253.324106 -0.044704)
		(end 258.210812 4.842002)
		(width 0.13335)
		(layer "In2.Cu")
		(net "IOM_A_INS_N")
	)
	(segment
		(start 322.036186 -250.091702)
		(end 321.863466 -250.264422)
		(width 0.13335)
		(layer "In2.Cu")
		(net "IOM_A_INS_N")
	)
	(segment
		(start 258.210812 4.842002)
		(end 286.439864 4.842002)
		(width 0.13335)
		(layer "In2.Cu")
		(net "IOM_A_INS_N")
	)
	(segment
		(start 271.563338 -253.6444)
		(end 267.49248 -253.6444)
		(width 0.13335)
		(layer "In2.Cu")
		(net "IOM_A_INS_N")
	)
	(segment
		(start 276.775672 -248.432066)
		(end 271.563338 -253.6444)
		(width 0.13335)
		(layer "In2.Cu")
		(net "IOM_A_INS_N")
	)
	(segment
		(start 334.839056 -16.722598)
		(end 343.495884 -16.722598)
		(width 0.13335)
		(layer "In2.Cu")
		(net "IOM_A_INS_N")
	)
	(segment
		(start 304.776378 -257.650996)
		(end 297.83405 -257.650996)
		(width 0.13335)
		(layer "In2.Cu")
		(net "IOM_A_INS_N")
	)
	(segment
		(start 267.49248 -253.6444)
		(end 262.68553 -258.45135)
		(width 0.13335)
		(layer "In2.Cu")
		(net "IOM_A_INS_N")
	)
	(segment
		(start 234.38358 -0.044704)
		(end 253.324106 -0.044704)
		(width 0.13335)
		(layer "In2.Cu")
		(net "IOM_A_INS_N")
	)
	(segment
		(start 343.495884 -16.722598)
		(end 343.906602 -17.133316)
		(width 0.13335)
		(layer "In2.Cu")
		(net "IOM_A_INS_N")
	)
	(segment
		(start 337.341972 -34.656776)
		(end 337.341972 -35.918394)
		(width 0.12065)
		(layer "In4.Cu")
		(net "IOM_A_INS_N")
	)
	(segment
		(start 337.341972 -35.918394)
		(end 336.844132 -36.416234)
		(width 0.12065)
		(layer "In4.Cu")
		(net "IOM_A_INS_N")
	)
	(segment
		(start 320.747898 -148.698966)
		(end 320.747898 -172.555916)
		(width 0.12065)
		(layer "In4.Cu")
		(net "IOM_A_INS_N")
	)
	(segment
		(start 332.1812 -55.448708)
		(end 332.1812 -64.9859)
		(width 0.12065)
		(layer "In4.Cu")
		(net "IOM_A_INS_N")
	)
	(segment
		(start 320.747898 -172.555916)
		(end 320.1924 -173.111414)
		(width 0.12065)
		(layer "In4.Cu")
		(net "IOM_A_INS_N")
	)
	(segment
		(start 321.437 -204.238352)
		(end 321.437 -222.024448)
		(width 0.12065)
		(layer "In4.Cu")
		(net "IOM_A_INS_N")
	)
	(segment
		(start 338.581238 -33.41751)
		(end 337.341972 -34.656776)
		(width 0.12065)
		(layer "In4.Cu")
		(net "IOM_A_INS_N")
	)
	(segment
		(start 320.1924 -173.111414)
		(end 320.1924 -202.993752)
		(width 0.12065)
		(layer "In4.Cu")
		(net "IOM_A_INS_N")
	)
	(segment
		(start 329.2602 -69.809868)
		(end 321.771264 -77.298804)
		(width 0.12065)
		(layer "In4.Cu")
		(net "IOM_A_INS_N")
	)
	(segment
		(start 329.2602 -67.9069)
		(end 329.2602 -69.809868)
		(width 0.12065)
		(layer "In4.Cu")
		(net "IOM_A_INS_N")
	)
	(segment
		(start 341.254334 -21.709888)
		(end 341.254334 -23.860252)
		(width 0.12065)
		(layer "In4.Cu")
		(net "IOM_A_INS_N")
	)
	(segment
		(start 321.771264 -77.298804)
		(end 321.771264 -147.6756)
		(width 0.12065)
		(layer "In4.Cu")
		(net "IOM_A_INS_N")
	)
	(segment
		(start 332.1812 -64.9859)
		(end 329.2602 -67.9069)
		(width 0.12065)
		(layer "In4.Cu")
		(net "IOM_A_INS_N")
	)
	(segment
		(start 338.581238 -32.04845)
		(end 338.581238 -33.41751)
		(width 0.12065)
		(layer "In4.Cu")
		(net "IOM_A_INS_N")
	)
	(segment
		(start 336.844132 -36.416234)
		(end 336.844132 -44.133008)
		(width 0.12065)
		(layer "In4.Cu")
		(net "IOM_A_INS_N")
	)
	(segment
		(start 338.580984 -32.048196)
		(end 338.581238 -32.04845)
		(width 0.12065)
		(layer "In4.Cu")
		(net "IOM_A_INS_N")
	)
	(segment
		(start 323.700902 -224.28835)
		(end 323.700902 -250.091702)
		(width 0.12065)
		(layer "In4.Cu")
		(net "IOM_A_INS_N")
	)
	(segment
		(start 341.254334 -23.860252)
		(end 338.580984 -26.533602)
		(width 0.12065)
		(layer "In4.Cu")
		(net "IOM_A_INS_N")
	)
	(segment
		(start 336.844132 -44.133008)
		(end 336.013298 -44.963842)
		(width 0.12065)
		(layer "In4.Cu")
		(net "IOM_A_INS_N")
	)
	(segment
		(start 320.1924 -202.993752)
		(end 321.437 -204.238352)
		(width 0.12065)
		(layer "In4.Cu")
		(net "IOM_A_INS_N")
	)
	(segment
		(start 336.013298 -51.61661)
		(end 332.1812 -55.448708)
		(width 0.12065)
		(layer "In4.Cu")
		(net "IOM_A_INS_N")
	)
	(segment
		(start 336.013298 -44.963842)
		(end 336.013298 -51.61661)
		(width 0.12065)
		(layer "In4.Cu")
		(net "IOM_A_INS_N")
	)
	(segment
		(start 338.580984 -26.533602)
		(end 338.580984 -32.048196)
		(width 0.12065)
		(layer "In4.Cu")
		(net "IOM_A_INS_N")
	)
	(segment
		(start 321.437 -222.024448)
		(end 323.700902 -224.28835)
		(width 0.12065)
		(layer "In4.Cu")
		(net "IOM_A_INS_N")
	)
	(segment
		(start 321.771264 -147.6756)
		(end 320.747898 -148.698966)
		(width 0.12065)
		(layer "In4.Cu")
		(net "IOM_A_INS_N")
	)
	(segment
		(start 167.448484 -18.73885)
		(end 179.904136 -6.283198)
		(width 0.12065)
		(layer "In7.Cu")
		(net "IOM_A_INS_N")
	)
	(segment
		(start 139.812268 -34.619692)
		(end 144.704562 -34.619692)
		(width 0.12065)
		(layer "In7.Cu")
		(net "IOM_A_INS_N")
	)
	(segment
		(start 233.923078 -0.044704)
		(end 234.341416 -0.044704)
		(width 0.12065)
		(layer "In7.Cu")
		(net "IOM_A_INS_N")
	)
	(segment
		(start 234.341416 -0.044704)
		(end 234.362498 -0.023622)
		(width 0.12065)
		(layer "In7.Cu")
		(net "IOM_A_INS_N")
	)
	(segment
		(start 179.904136 -6.283198)
		(end 227.684584 -6.283198)
		(width 0.12065)
		(layer "In7.Cu")
		(net "IOM_A_INS_N")
	)
	(segment
		(start 144.704562 -34.619692)
		(end 150.792688 -28.531566)
		(width 0.12065)
		(layer "In7.Cu")
		(net "IOM_A_INS_N")
	)
	(segment
		(start 150.792688 -28.531566)
		(end 154.413966 -28.531566)
		(width 0.12065)
		(layer "In7.Cu")
		(net "IOM_A_INS_N")
	)
	(segment
		(start 164.206682 -18.73885)
		(end 167.448484 -18.73885)
		(width 0.12065)
		(layer "In7.Cu")
		(net "IOM_A_INS_N")
	)
	(segment
		(start 137.919206 -32.72663)
		(end 139.812268 -34.619692)
		(width 0.12065)
		(layer "In7.Cu")
		(net "IOM_A_INS_N")
	)
	(segment
		(start 227.684584 -6.283198)
		(end 233.923078 -0.044704)
		(width 0.12065)
		(layer "In7.Cu")
		(net "IOM_A_INS_N")
	)
	(segment
		(start 135.51281 -31.904178)
		(end 136.335262 -32.72663)
		(width 0.12065)
		(layer "In7.Cu")
		(net "IOM_A_INS_N")
	)
	(segment
		(start 136.150096 -26.950162)
		(end 135.51281 -27.587448)
		(width 0.12065)
		(layer "In7.Cu")
		(net "IOM_A_INS_N")
	)
	(segment
		(start 154.413966 -28.531566)
		(end 164.206682 -18.73885)
		(width 0.12065)
		(layer "In7.Cu")
		(net "IOM_A_INS_N")
	)
	(segment
		(start 135.51281 -27.587448)
		(end 135.51281 -31.904178)
		(width 0.12065)
		(layer "In7.Cu")
		(net "IOM_A_INS_N")
	)
	(segment
		(start 136.335262 -32.72663)
		(end 137.919206 -32.72663)
		(width 0.12065)
		(layer "In7.Cu")
		(net "IOM_A_INS_N")
	)
	(segment
		(start 253.685294 -267.594842)
		(end 253.685294 -267.5636)
		(width 0.13335)
		(layer "In9.Cu")
		(net "IOM_A_INS_N")
	)
	(segment
		(start 228.000052 -413.200088)
		(end 228.661722 -412.538418)
		(width 0.13335)
		(layer "In9.Cu")
		(net "IOM_A_INS_N")
	)
	(segment
		(start 230.000048 -365.045752)
		(end 230.000048 -336.418174)
		(width 0.13335)
		(layer "In9.Cu")
		(net "IOM_A_INS_N")
	)
	(segment
		(start 224.002854 -382.678178)
		(end 224.4217 -382.259332)
		(width 0.13335)
		(layer "In9.Cu")
		(net "IOM_A_INS_N")
	)
	(segment
		(start 253.567692 -282.96108)
		(end 253.567692 -267.712444)
		(width 0.13335)
		(layer "In9.Cu")
		(net "IOM_A_INS_N")
	)
	(segment
		(start 230.000048 -336.418174)
		(end 240.725452 -325.69277)
		(width 0.13335)
		(layer "In9.Cu")
		(net "IOM_A_INS_N")
	)
	(segment
		(start 240.725452 -295.80332)
		(end 253.567692 -282.96108)
		(width 0.13335)
		(layer "In9.Cu")
		(net "IOM_A_INS_N")
	)
	(segment
		(start 224.4217 -380.476252)
		(end 224.385886 -380.440438)
		(width 0.13335)
		(layer "In9.Cu")
		(net "IOM_A_INS_N")
	)
	(segment
		(start 224.4217 -382.259332)
		(end 224.4217 -380.476252)
		(width 0.13335)
		(layer "In9.Cu")
		(net "IOM_A_INS_N")
	)
	(segment
		(start 255.45542 -265.793474)
		(end 255.45542 -262.012176)
		(width 0.13335)
		(layer "In9.Cu")
		(net "IOM_A_INS_N")
	)
	(segment
		(start 253.685294 -267.5636)
		(end 255.45542 -265.793474)
		(width 0.13335)
		(layer "In9.Cu")
		(net "IOM_A_INS_N")
	)
	(segment
		(start 224.002854 -398.475454)
		(end 224.002854 -382.678178)
		(width 0.13335)
		(layer "In9.Cu")
		(net "IOM_A_INS_N")
	)
	(segment
		(start 228.661722 -403.134322)
		(end 224.002854 -398.475454)
		(width 0.13335)
		(layer "In9.Cu")
		(net "IOM_A_INS_N")
	)
	(segment
		(start 228.661722 -412.538418)
		(end 228.661722 -403.134322)
		(width 0.13335)
		(layer "In9.Cu")
		(net "IOM_A_INS_N")
	)
	(segment
		(start 240.725452 -325.69277)
		(end 240.725452 -295.80332)
		(width 0.13335)
		(layer "In9.Cu")
		(net "IOM_A_INS_N")
	)
	(segment
		(start 255.45542 -262.012176)
		(end 257.295396 -260.1722)
		(width 0.13335)
		(layer "In9.Cu")
		(net "IOM_A_INS_N")
	)
	(segment
		(start 224.385886 -380.440438)
		(end 224.385886 -370.659914)
		(width 0.13335)
		(layer "In9.Cu")
		(net "IOM_A_INS_N")
	)
	(segment
		(start 253.567692 -267.712444)
		(end 253.685294 -267.594842)
		(width 0.13335)
		(layer "In9.Cu")
		(net "IOM_A_INS_N")
	)
	(segment
		(start 224.385886 -370.659914)
		(end 230.000048 -365.045752)
		(width 0.13335)
		(layer "In9.Cu")
		(net "IOM_A_INS_N")
	)
	(segment
		(start 257.295396 -260.1722)
		(end 257.295396 -259.39496)
		(width 0.13335)
		(layer "In9.Cu")
		(net "IOM_A_INS_N")
	)
	(via
		(at 243.1034 -188.6966)
		(size 0.5588)
		(drill 0.3048)
		(layers "F.Cu" "B.Cu")
		(net "I2C_SCC_B_SDA")
	)
	(via
		(at 380.492 -188.722)
		(size 0.5588)
		(drill 0.3048)
		(layers "F.Cu" "B.Cu")
		(net "I2C_SCC_B_SDA")
	)
	(segment
		(start 343.967562 -187.332366)
		(end 379.102366 -187.332366)
		(width 0.13335)
		(layer "In2.Cu")
		(net "I2C_SCC_B_SDA")
	)
	(segment
		(start 342.374728 -188.9252)
		(end 343.967562 -187.332366)
		(width 0.13335)
		(layer "In2.Cu")
		(net "I2C_SCC_B_SDA")
	)
	(segment
		(start 245.796816 -188.6966)
		(end 253.125224 -196.025008)
		(width 0.13335)
		(layer "In2.Cu")
		(net "I2C_SCC_B_SDA")
	)
	(segment
		(start 313.132724 -196.025008)
		(end 320.942208 -188.215524)
		(width 0.13335)
		(layer "In2.Cu")
		(net "I2C_SCC_B_SDA")
	)
	(segment
		(start 340.242652 -188.215524)
		(end 340.952328 -188.9252)
		(width 0.13335)
		(layer "In2.Cu")
		(net "I2C_SCC_B_SDA")
	)
	(segment
		(start 253.125224 -196.025008)
		(end 313.132724 -196.025008)
		(width 0.13335)
		(layer "In2.Cu")
		(net "I2C_SCC_B_SDA")
	)
	(segment
		(start 379.102366 -187.332366)
		(end 380.492 -188.722)
		(width 0.13335)
		(layer "In2.Cu")
		(net "I2C_SCC_B_SDA")
	)
	(segment
		(start 320.942208 -188.215524)
		(end 340.242652 -188.215524)
		(width 0.13335)
		(layer "In2.Cu")
		(net "I2C_SCC_B_SDA")
	)
	(segment
		(start 243.1034 -188.6966)
		(end 245.796816 -188.6966)
		(width 0.13335)
		(layer "In2.Cu")
		(net "I2C_SCC_B_SDA")
	)
	(segment
		(start 340.952328 -188.9252)
		(end 342.374728 -188.9252)
		(width 0.13335)
		(layer "In2.Cu")
		(net "I2C_SCC_B_SDA")
	)
	(segment
		(start 380.679198 -58.175398)
		(end 381.56515 -59.06135)
		(width 0.12065)
		(layer "In4.Cu")
		(net "I2C_SCC_B_SDA")
	)
	(segment
		(start 381.606298 -179.714906)
		(end 380.54915 -180.772054)
		(width 0.12065)
		(layer "In4.Cu")
		(net "I2C_SCC_B_SDA")
	)
	(segment
		(start 380.54915 -188.66485)
		(end 380.492 -188.722)
		(width 0.12065)
		(layer "In4.Cu")
		(net "I2C_SCC_B_SDA")
	)
	(segment
		(start 388.203948 -26.604214)
		(end 388.203948 -31.997396)
		(width 0.12065)
		(layer "In4.Cu")
		(net "I2C_SCC_B_SDA")
	)
	(segment
		(start 214.646002 -315.952632)
		(end 207.77581 -322.822824)
		(width 0.12065)
		(layer "In4.Cu")
		(net "I2C_SCC_B_SDA")
	)
	(segment
		(start 388.203948 -31.997396)
		(end 388.051548 -32.149796)
		(width 0.12065)
		(layer "In4.Cu")
		(net "I2C_SCC_B_SDA")
	)
	(segment
		(start 380.717044 -67.694302)
		(end 380.717044 -114.783108)
		(width 0.12065)
		(layer "In4.Cu")
		(net "I2C_SCC_B_SDA")
	)
	(segment
		(start 381.56515 -59.06135)
		(end 381.56515 -66.846196)
		(width 0.12065)
		(layer "In4.Cu")
		(net "I2C_SCC_B_SDA")
	)
	(segment
		(start 214.646002 -206.566516)
		(end 214.646002 -315.952632)
		(width 0.12065)
		(layer "In4.Cu")
		(net "I2C_SCC_B_SDA")
	)
	(segment
		(start 380.54915 -180.772054)
		(end 380.54915 -188.66485)
		(width 0.12065)
		(layer "In4.Cu")
		(net "I2C_SCC_B_SDA")
	)
	(segment
		(start 207.77581 -400.21383)
		(end 211.140548 -403.578568)
		(width 0.12065)
		(layer "In4.Cu")
		(net "I2C_SCC_B_SDA")
	)
	(segment
		(start 381.56515 -66.846196)
		(end 380.717044 -67.694302)
		(width 0.12065)
		(layer "In4.Cu")
		(net "I2C_SCC_B_SDA")
	)
	(segment
		(start 381.606298 -157.11551)
		(end 381.606298 -179.714906)
		(width 0.12065)
		(layer "In4.Cu")
		(net "I2C_SCC_B_SDA")
	)
	(segment
		(start 207.77581 -322.822824)
		(end 207.77581 -400.21383)
		(width 0.12065)
		(layer "In4.Cu")
		(net "I2C_SCC_B_SDA")
	)
	(segment
		(start 393.91209 -127.978154)
		(end 393.91209 -144.809718)
		(width 0.12065)
		(layer "In4.Cu")
		(net "I2C_SCC_B_SDA")
	)
	(segment
		(start 387.549898 -25.950164)
		(end 388.203948 -26.604214)
		(width 0.12065)
		(layer "In4.Cu")
		(net "I2C_SCC_B_SDA")
	)
	(segment
		(start 231.874568 -189.33795)
		(end 214.646002 -206.566516)
		(width 0.12065)
		(layer "In4.Cu")
		(net "I2C_SCC_B_SDA")
	)
	(segment
		(start 242.46205 -189.33795)
		(end 231.874568 -189.33795)
		(width 0.12065)
		(layer "In4.Cu")
		(net "I2C_SCC_B_SDA")
	)
	(segment
		(start 380.717044 -114.783108)
		(end 393.91209 -127.978154)
		(width 0.12065)
		(layer "In4.Cu")
		(net "I2C_SCC_B_SDA")
	)
	(segment
		(start 211.140548 -412.54045)
		(end 211.800186 -413.200088)
		(width 0.12065)
		(layer "In4.Cu")
		(net "I2C_SCC_B_SDA")
	)
	(segment
		(start 243.1034 -188.6966)
		(end 242.46205 -189.33795)
		(width 0.12065)
		(layer "In4.Cu")
		(net "I2C_SCC_B_SDA")
	)
	(segment
		(start 393.91209 -144.809718)
		(end 381.606298 -157.11551)
		(width 0.12065)
		(layer "In4.Cu")
		(net "I2C_SCC_B_SDA")
	)
	(segment
		(start 380.679198 -40.529002)
		(end 380.679198 -58.175398)
		(width 0.12065)
		(layer "In4.Cu")
		(net "I2C_SCC_B_SDA")
	)
	(segment
		(start 211.140548 -403.578568)
		(end 211.140548 -412.54045)
		(width 0.12065)
		(layer "In4.Cu")
		(net "I2C_SCC_B_SDA")
	)
	(segment
		(start 388.051548 -32.149796)
		(end 388.051548 -33.156652)
		(width 0.12065)
		(layer "In4.Cu")
		(net "I2C_SCC_B_SDA")
	)
	(segment
		(start 388.051548 -33.156652)
		(end 380.679198 -40.529002)
		(width 0.12065)
		(layer "In4.Cu")
		(net "I2C_SCC_B_SDA")
	)
	(via
		(at 381.136906 -187.868306)
		(size 0.5588)
		(drill 0.3048)
		(layers "F.Cu" "B.Cu")
		(net "I2C_SCC_B_SCL")
	)
	(via
		(at 241.8588 -188.6204)
		(size 0.5588)
		(drill 0.3048)
		(layers "F.Cu" "B.Cu")
		(net "I2C_SCC_B_SCL")
	)
	(segment
		(start 242.42395 -188.05525)
		(end 241.8588 -188.6204)
		(width 0.13335)
		(layer "In2.Cu")
		(net "I2C_SCC_B_SCL")
	)
	(segment
		(start 342.013032 -188.1378)
		(end 341.071962 -188.1378)
		(width 0.13335)
		(layer "In2.Cu")
		(net "I2C_SCC_B_SCL")
	)
	(segment
		(start 320.676524 -187.574174)
		(end 312.86704 -195.383658)
		(width 0.13335)
		(layer "In2.Cu")
		(net "I2C_SCC_B_SCL")
	)
	(segment
		(start 340.508336 -187.574174)
		(end 320.676524 -187.574174)
		(width 0.13335)
		(layer "In2.Cu")
		(net "I2C_SCC_B_SCL")
	)
	(segment
		(start 381.136906 -187.868306)
		(end 379.948186 -186.679586)
		(width 0.13335)
		(layer "In2.Cu")
		(net "I2C_SCC_B_SCL")
	)
	(segment
		(start 341.071962 -188.1378)
		(end 340.508336 -187.574174)
		(width 0.13335)
		(layer "In2.Cu")
		(net "I2C_SCC_B_SCL")
	)
	(segment
		(start 246.0625 -188.05525)
		(end 242.42395 -188.05525)
		(width 0.13335)
		(layer "In2.Cu")
		(net "I2C_SCC_B_SCL")
	)
	(segment
		(start 312.86704 -195.383658)
		(end 253.390908 -195.383658)
		(width 0.13335)
		(layer "In2.Cu")
		(net "I2C_SCC_B_SCL")
	)
	(segment
		(start 343.471246 -186.679586)
		(end 342.013032 -188.1378)
		(width 0.13335)
		(layer "In2.Cu")
		(net "I2C_SCC_B_SCL")
	)
	(segment
		(start 253.390908 -195.383658)
		(end 246.0625 -188.05525)
		(width 0.13335)
		(layer "In2.Cu")
		(net "I2C_SCC_B_SCL")
	)
	(segment
		(start 379.948186 -186.679586)
		(end 343.471246 -186.679586)
		(width 0.13335)
		(layer "In2.Cu")
		(net "I2C_SCC_B_SCL")
	)
	(segment
		(start 381.307848 -40.92575)
		(end 381.307848 -57.889648)
		(width 0.12065)
		(layer "In4.Cu")
		(net "I2C_SCC_B_SCL")
	)
	(segment
		(start 382.234948 -179.97551)
		(end 381.1778 -181.032658)
		(width 0.12065)
		(layer "In4.Cu")
		(net "I2C_SCC_B_SCL")
	)
	(segment
		(start 388.680198 -33.5534)
		(end 381.307848 -40.92575)
		(width 0.12065)
		(layer "In4.Cu")
		(net "I2C_SCC_B_SCL")
	)
	(segment
		(start 210.664298 -413.464248)
		(end 211.800186 -414.600136)
		(width 0.12065)
		(layer "In4.Cu")
		(net "I2C_SCC_B_SCL")
	)
	(segment
		(start 207.137 -322.57238)
		(end 207.137 -400.464274)
		(width 0.12065)
		(layer "In4.Cu")
		(net "I2C_SCC_B_SCL")
	)
	(segment
		(start 381.1778 -187.827412)
		(end 381.136906 -187.868306)
		(width 0.12065)
		(layer "In4.Cu")
		(net "I2C_SCC_B_SCL")
	)
	(segment
		(start 210.664298 -403.991572)
		(end 210.664298 -413.464248)
		(width 0.12065)
		(layer "In4.Cu")
		(net "I2C_SCC_B_SCL")
	)
	(segment
		(start 381.345694 -114.522504)
		(end 394.54074 -127.71755)
		(width 0.12065)
		(layer "In4.Cu")
		(net "I2C_SCC_B_SCL")
	)
	(segment
		(start 382.1938 -67.1068)
		(end 381.345694 -67.954906)
		(width 0.12065)
		(layer "In4.Cu")
		(net "I2C_SCC_B_SCL")
	)
	(segment
		(start 382.1938 -58.7756)
		(end 382.1938 -67.1068)
		(width 0.12065)
		(layer "In4.Cu")
		(net "I2C_SCC_B_SCL")
	)
	(segment
		(start 388.680198 -25.680416)
		(end 388.680198 -33.5534)
		(width 0.12065)
		(layer "In4.Cu")
		(net "I2C_SCC_B_SCL")
	)
	(segment
		(start 381.345694 -67.954906)
		(end 381.345694 -114.522504)
		(width 0.12065)
		(layer "In4.Cu")
		(net "I2C_SCC_B_SCL")
	)
	(segment
		(start 381.307848 -57.889648)
		(end 382.1938 -58.7756)
		(width 0.12065)
		(layer "In4.Cu")
		(net "I2C_SCC_B_SCL")
	)
	(segment
		(start 214.017352 -206.305912)
		(end 214.017352 -315.692028)
		(width 0.12065)
		(layer "In4.Cu")
		(net "I2C_SCC_B_SCL")
	)
	(segment
		(start 214.017352 -315.692028)
		(end 207.137 -322.57238)
		(width 0.12065)
		(layer "In4.Cu")
		(net "I2C_SCC_B_SCL")
	)
	(segment
		(start 381.1778 -181.032658)
		(end 381.1778 -187.827412)
		(width 0.12065)
		(layer "In4.Cu")
		(net "I2C_SCC_B_SCL")
	)
	(segment
		(start 382.234948 -157.376114)
		(end 382.234948 -179.97551)
		(width 0.12065)
		(layer "In4.Cu")
		(net "I2C_SCC_B_SCL")
	)
	(segment
		(start 207.137 -400.464274)
		(end 210.664298 -403.991572)
		(width 0.12065)
		(layer "In4.Cu")
		(net "I2C_SCC_B_SCL")
	)
	(segment
		(start 241.8588 -188.6204)
		(end 231.702864 -188.6204)
		(width 0.12065)
		(layer "In4.Cu")
		(net "I2C_SCC_B_SCL")
	)
	(segment
		(start 394.54074 -127.71755)
		(end 394.54074 -145.070322)
		(width 0.12065)
		(layer "In4.Cu")
		(net "I2C_SCC_B_SCL")
	)
	(segment
		(start 387.549898 -24.550116)
		(end 388.680198 -25.680416)
		(width 0.12065)
		(layer "In4.Cu")
		(net "I2C_SCC_B_SCL")
	)
	(segment
		(start 394.54074 -145.070322)
		(end 382.234948 -157.376114)
		(width 0.12065)
		(layer "In4.Cu")
		(net "I2C_SCC_B_SCL")
	)
	(segment
		(start 231.702864 -188.6204)
		(end 214.017352 -206.305912)
		(width 0.12065)
		(layer "In4.Cu")
		(net "I2C_SCC_B_SCL")
	)
	(segment
		(start 225.014028 -218.850972)
		(end 224.1296 -218.850972)
		(width 0.17145)
		(layer "F.Cu")
		(net "I2C_SCC_A_SDA")
	)
	(segment
		(start 223.825562 -214.770462)
		(end 223.825562 -216.6366)
		(width 0.17145)
		(layer "F.Cu")
		(net "I2C_SCC_A_SDA")
	)
	(segment
		(start 223.805242 -218.526614)
		(end 223.805242 -217.653362)
		(width 0.17145)
		(layer "F.Cu")
		(net "I2C_SCC_A_SDA")
	)
	(segment
		(start 224.1296 -218.850972)
		(end 223.805242 -218.526614)
		(width 0.17145)
		(layer "F.Cu")
		(net "I2C_SCC_A_SDA")
	)
	(segment
		(start 223.805242 -217.653362)
		(end 223.825562 -217.633042)
		(width 0.17145)
		(layer "F.Cu")
		(net "I2C_SCC_A_SDA")
	)
	(segment
		(start 223.825562 -217.633042)
		(end 223.825562 -216.6366)
		(width 0.17145)
		(layer "F.Cu")
		(net "I2C_SCC_A_SDA")
	)
	(via
		(at 150.523956 -224.1042)
		(size 0.5588)
		(drill 0.3048)
		(layers "F.Cu" "B.Cu")
		(net "I2C_SCC_A_SDA")
	)
	(via
		(at 223.825562 -216.6366)
		(size 0.6604)
		(drill 0.3302)
		(layers "F.Cu" "B.Cu")
		(net "I2C_SCC_A_SDA")
	)
	(via
		(at 225.014028 -218.850972)
		(size 0.5588)
		(drill 0.3048)
		(layers "F.Cu" "B.Cu")
		(net "I2C_SCC_A_SDA")
	)
	(segment
		(start 179.287424 -213.44001)
		(end 215.34501 -213.44001)
		(width 0.13335)
		(layer "In2.Cu")
		(net "I2C_SCC_A_SDA")
	)
	(segment
		(start 150.523956 -224.1042)
		(end 168.623234 -224.1042)
		(width 0.13335)
		(layer "In2.Cu")
		(net "I2C_SCC_A_SDA")
	)
	(segment
		(start 215.34501 -213.44001)
		(end 219.456 -217.551)
		(width 0.13335)
		(layer "In2.Cu")
		(net "I2C_SCC_A_SDA")
	)
	(segment
		(start 168.623234 -224.1042)
		(end 179.287424 -213.44001)
		(width 0.13335)
		(layer "In2.Cu")
		(net "I2C_SCC_A_SDA")
	)
	(segment
		(start 223.714056 -217.551)
		(end 225.014028 -218.850972)
		(width 0.13335)
		(layer "In2.Cu")
		(net "I2C_SCC_A_SDA")
	)
	(segment
		(start 219.456 -217.551)
		(end 223.714056 -217.551)
		(width 0.13335)
		(layer "In2.Cu")
		(net "I2C_SCC_A_SDA")
	)
	(segment
		(start 136.315196 -172.321982)
		(end 136.314942 -172.322236)
		(width 0.12065)
		(layer "In4.Cu")
		(net "I2C_SCC_A_SDA")
	)
	(segment
		(start 142.218918 -26.6192)
		(end 142.218918 -31.375604)
		(width 0.12065)
		(layer "In4.Cu")
		(net "I2C_SCC_A_SDA")
	)
	(segment
		(start 138.008868 -85.338158)
		(end 132.641848 -90.705178)
		(width 0.12065)
		(layer "In4.Cu")
		(net "I2C_SCC_A_SDA")
	)
	(segment
		(start 138.008868 -49.50714)
		(end 138.008868 -85.338158)
		(width 0.12065)
		(layer "In4.Cu")
		(net "I2C_SCC_A_SDA")
	)
	(segment
		(start 132.641848 -90.705178)
		(end 132.641848 -126.539244)
		(width 0.12065)
		(layer "In4.Cu")
		(net "I2C_SCC_A_SDA")
	)
	(segment
		(start 136.315196 -165.87089)
		(end 136.315196 -172.321982)
		(width 0.12065)
		(layer "In4.Cu")
		(net "I2C_SCC_A_SDA")
	)
	(segment
		(start 129.6924 -130.582924)
		(end 129.610104 -130.66522)
		(width 0.12065)
		(layer "In4.Cu")
		(net "I2C_SCC_A_SDA")
	)
	(segment
		(start 132.641848 -126.539244)
		(end 129.6924 -129.488692)
		(width 0.12065)
		(layer "In4.Cu")
		(net "I2C_SCC_A_SDA")
	)
	(segment
		(start 150.08606 -193.486278)
		(end 150.08606 -223.666304)
		(width 0.12065)
		(layer "In4.Cu")
		(net "I2C_SCC_A_SDA")
	)
	(segment
		(start 128.082294 -149.006052)
		(end 128.082294 -157.637988)
		(width 0.12065)
		(layer "In4.Cu")
		(net "I2C_SCC_A_SDA")
	)
	(segment
		(start 129.6924 -129.488692)
		(end 129.6924 -130.582924)
		(width 0.12065)
		(layer "In4.Cu")
		(net "I2C_SCC_A_SDA")
	)
	(segment
		(start 147.685506 -184.2135)
		(end 147.685506 -191.085724)
		(width 0.12065)
		(layer "In4.Cu")
		(net "I2C_SCC_A_SDA")
	)
	(segment
		(start 127.94488 -148.868638)
		(end 128.082294 -149.006052)
		(width 0.12065)
		(layer "In4.Cu")
		(net "I2C_SCC_A_SDA")
	)
	(segment
		(start 142.218918 -31.375604)
		(end 141.687042 -31.90748)
		(width 0.12065)
		(layer "In4.Cu")
		(net "I2C_SCC_A_SDA")
	)
	(segment
		(start 129.610104 -130.66522)
		(end 129.591054 -130.66522)
		(width 0.12065)
		(layer "In4.Cu")
		(net "I2C_SCC_A_SDA")
	)
	(segment
		(start 141.687042 -31.90748)
		(end 141.687042 -45.828966)
		(width 0.12065)
		(layer "In4.Cu")
		(net "I2C_SCC_A_SDA")
	)
	(segment
		(start 141.549882 -25.950164)
		(end 142.218918 -26.6192)
		(width 0.12065)
		(layer "In4.Cu")
		(net "I2C_SCC_A_SDA")
	)
	(segment
		(start 129.591054 -130.66522)
		(end 127.94488 -132.311394)
		(width 0.12065)
		(layer "In4.Cu")
		(net "I2C_SCC_A_SDA")
	)
	(segment
		(start 150.08606 -223.666304)
		(end 150.523956 -224.1042)
		(width 0.12065)
		(layer "In4.Cu")
		(net "I2C_SCC_A_SDA")
	)
	(segment
		(start 136.314942 -172.322236)
		(end 136.314942 -172.842936)
		(width 0.12065)
		(layer "In4.Cu")
		(net "I2C_SCC_A_SDA")
	)
	(segment
		(start 141.687042 -45.828966)
		(end 138.008868 -49.50714)
		(width 0.12065)
		(layer "In4.Cu")
		(net "I2C_SCC_A_SDA")
	)
	(segment
		(start 127.94488 -132.311394)
		(end 127.94488 -148.868638)
		(width 0.12065)
		(layer "In4.Cu")
		(net "I2C_SCC_A_SDA")
	)
	(segment
		(start 136.314942 -172.842936)
		(end 147.685506 -184.2135)
		(width 0.12065)
		(layer "In4.Cu")
		(net "I2C_SCC_A_SDA")
	)
	(segment
		(start 147.685506 -191.085724)
		(end 150.08606 -193.486278)
		(width 0.12065)
		(layer "In4.Cu")
		(net "I2C_SCC_A_SDA")
	)
	(segment
		(start 128.082294 -157.637988)
		(end 136.315196 -165.87089)
		(width 0.12065)
		(layer "In4.Cu")
		(net "I2C_SCC_A_SDA")
	)
	(segment
		(start 224.287842 -207.290162)
		(end 224.287842 -208.049368)
		(width 0.17145)
		(layer "F.Cu")
		(net "I2C_SCC_A_SCL")
	)
	(segment
		(start 224.582228 -208.792572)
		(end 223.825562 -209.549238)
		(width 0.17145)
		(layer "F.Cu")
		(net "I2C_SCC_A_SCL")
	)
	(segment
		(start 225.4504 -206.2226)
		(end 225.318828 -206.091028)
		(width 0.17145)
		(layer "F.Cu")
		(net "I2C_SCC_A_SCL")
	)
	(segment
		(start 224.3836 -206.091028)
		(end 224.287842 -206.186786)
		(width 0.17145)
		(layer "F.Cu")
		(net "I2C_SCC_A_SCL")
	)
	(segment
		(start 225.318828 -206.091028)
		(end 224.3836 -206.091028)
		(width 0.17145)
		(layer "F.Cu")
		(net "I2C_SCC_A_SCL")
	)
	(segment
		(start 223.825562 -209.549238)
		(end 223.825562 -210.630262)
		(width 0.17145)
		(layer "F.Cu")
		(net "I2C_SCC_A_SCL")
	)
	(segment
		(start 224.287842 -208.049368)
		(end 224.582228 -208.343754)
		(width 0.17145)
		(layer "F.Cu")
		(net "I2C_SCC_A_SCL")
	)
	(segment
		(start 224.287842 -206.186786)
		(end 224.287842 -207.290162)
		(width 0.17145)
		(layer "F.Cu")
		(net "I2C_SCC_A_SCL")
	)
	(segment
		(start 224.582228 -208.343754)
		(end 224.582228 -208.792572)
		(width 0.17145)
		(layer "F.Cu")
		(net "I2C_SCC_A_SCL")
	)
	(via
		(at 150.71471 -222.848932)
		(size 0.5588)
		(drill 0.3048)
		(layers "F.Cu" "B.Cu")
		(net "I2C_SCC_A_SCL")
	)
	(via
		(at 225.4504 -206.2226)
		(size 0.5588)
		(drill 0.3048)
		(layers "F.Cu" "B.Cu")
		(net "I2C_SCC_A_SCL")
	)
	(via
		(at 224.582228 -208.343754)
		(size 0.6604)
		(drill 0.3302)
		(layers "F.Cu" "B.Cu")
		(net "I2C_SCC_A_SCL")
	)
	(segment
		(start 221.152974 -205.4606)
		(end 221.830138 -205.4606)
		(width 0.13335)
		(layer "In2.Cu")
		(net "I2C_SCC_A_SCL")
	)
	(segment
		(start 213.814914 -212.79866)
		(end 221.152974 -205.4606)
		(width 0.13335)
		(layer "In2.Cu")
		(net "I2C_SCC_A_SCL")
	)
	(segment
		(start 179.02174 -212.79866)
		(end 213.814914 -212.79866)
		(width 0.13335)
		(layer "In2.Cu")
		(net "I2C_SCC_A_SCL")
	)
	(segment
		(start 168.971468 -222.848932)
		(end 179.02174 -212.79866)
		(width 0.13335)
		(layer "In2.Cu")
		(net "I2C_SCC_A_SCL")
	)
	(segment
		(start 221.830138 -205.4606)
		(end 221.990158 -205.30058)
		(width 0.13335)
		(layer "In2.Cu")
		(net "I2C_SCC_A_SCL")
	)
	(segment
		(start 224.6884 -205.4606)
		(end 225.4504 -206.2226)
		(width 0.13335)
		(layer "In2.Cu")
		(net "I2C_SCC_A_SCL")
	)
	(segment
		(start 222.453962 -205.30058)
		(end 222.613982 -205.4606)
		(width 0.13335)
		(layer "In2.Cu")
		(net "I2C_SCC_A_SCL")
	)
	(segment
		(start 150.71471 -222.848932)
		(end 168.971468 -222.848932)
		(width 0.13335)
		(layer "In2.Cu")
		(net "I2C_SCC_A_SCL")
	)
	(segment
		(start 222.613982 -205.4606)
		(end 224.6884 -205.4606)
		(width 0.13335)
		(layer "In2.Cu")
		(net "I2C_SCC_A_SCL")
	)
	(segment
		(start 221.990158 -205.30058)
		(end 222.453962 -205.30058)
		(width 0.13335)
		(layer "In2.Cu")
		(net "I2C_SCC_A_SCL")
	)
	(segment
		(start 148.314156 -183.952896)
		(end 148.314156 -190.699644)
		(width 0.12065)
		(layer "In4.Cu")
		(net "I2C_SCC_A_SCL")
	)
	(segment
		(start 130.824478 -129.565908)
		(end 130.824478 -131.110736)
		(width 0.12065)
		(layer "In4.Cu")
		(net "I2C_SCC_A_SCL")
	)
	(segment
		(start 128.57353 -133.361684)
		(end 128.57353 -148.608034)
		(width 0.12065)
		(layer "In4.Cu")
		(net "I2C_SCC_A_SCL")
	)
	(segment
		(start 142.695168 -45.710094)
		(end 138.637518 -49.767744)
		(width 0.12065)
		(layer "In4.Cu")
		(net "I2C_SCC_A_SCL")
	)
	(segment
		(start 133.805676 -90.430604)
		(end 133.805676 -126.58471)
		(width 0.12065)
		(layer "In4.Cu")
		(net "I2C_SCC_A_SCL")
	)
	(segment
		(start 150.641304 -193.026792)
		(end 150.641304 -193.152268)
		(width 0.12065)
		(layer "In4.Cu")
		(net "I2C_SCC_A_SCL")
	)
	(segment
		(start 138.637518 -49.767744)
		(end 138.637518 -85.598762)
		(width 0.12065)
		(layer "In4.Cu")
		(net "I2C_SCC_A_SCL")
	)
	(segment
		(start 150.71471 -193.225674)
		(end 150.71471 -222.848932)
		(width 0.12065)
		(layer "In4.Cu")
		(net "I2C_SCC_A_SCL")
	)
	(segment
		(start 141.549882 -24.550116)
		(end 142.695168 -25.695402)
		(width 0.12065)
		(layer "In4.Cu")
		(net "I2C_SCC_A_SCL")
	)
	(segment
		(start 142.695168 -25.695402)
		(end 142.695168 -45.710094)
		(width 0.12065)
		(layer "In4.Cu")
		(net "I2C_SCC_A_SCL")
	)
	(segment
		(start 128.57353 -148.608034)
		(end 128.710944 -148.745448)
		(width 0.12065)
		(layer "In4.Cu")
		(net "I2C_SCC_A_SCL")
	)
	(segment
		(start 133.805676 -126.58471)
		(end 130.824478 -129.565908)
		(width 0.12065)
		(layer "In4.Cu")
		(net "I2C_SCC_A_SCL")
	)
	(segment
		(start 136.943846 -172.582586)
		(end 148.314156 -183.952896)
		(width 0.12065)
		(layer "In4.Cu")
		(net "I2C_SCC_A_SCL")
	)
	(segment
		(start 150.641304 -193.152268)
		(end 150.71471 -193.225674)
		(width 0.12065)
		(layer "In4.Cu")
		(net "I2C_SCC_A_SCL")
	)
	(segment
		(start 136.943846 -165.610286)
		(end 136.943846 -172.582586)
		(width 0.12065)
		(layer "In4.Cu")
		(net "I2C_SCC_A_SCL")
	)
	(segment
		(start 128.710944 -157.377384)
		(end 136.943846 -165.610286)
		(width 0.12065)
		(layer "In4.Cu")
		(net "I2C_SCC_A_SCL")
	)
	(segment
		(start 138.637518 -85.598762)
		(end 133.805676 -90.430604)
		(width 0.12065)
		(layer "In4.Cu")
		(net "I2C_SCC_A_SCL")
	)
	(segment
		(start 148.314156 -190.699644)
		(end 150.641304 -193.026792)
		(width 0.12065)
		(layer "In4.Cu")
		(net "I2C_SCC_A_SCL")
	)
	(segment
		(start 130.824478 -131.110736)
		(end 128.57353 -133.361684)
		(width 0.12065)
		(layer "In4.Cu")
		(net "I2C_SCC_A_SCL")
	)
	(segment
		(start 128.710944 -148.745448)
		(end 128.710944 -157.377384)
		(width 0.12065)
		(layer "In4.Cu")
		(net "I2C_SCC_A_SCL")
	)
	(segment
		(start 260.3881 -229.6668)
		(end 260.3881 -228.0539)
		(width 0.17145)
		(layer "F.Cu")
		(net "I2C_DRIVE_A_PWR_SDA")
	)
	(segment
		(start 260.3881 -228.0539)
		(end 260.35 -228.0158)
		(width 0.17145)
		(layer "F.Cu")
		(net "I2C_DRIVE_A_PWR_SDA")
	)
	(segment
		(start 260.39699 -230.785162)
		(end 260.39699 -229.67569)
		(width 0.17145)
		(layer "F.Cu")
		(net "I2C_DRIVE_A_PWR_SDA")
	)
	(segment
		(start 260.39699 -229.67569)
		(end 260.3881 -229.6668)
		(width 0.17145)
		(layer "F.Cu")
		(net "I2C_DRIVE_A_PWR_SDA")
	)
	(segment
		(start 241.4016 -243.1161)
		(end 240.582196 -243.1161)
		(width 0.17145)
		(layer "F.Cu")
		(net "I2C_DRIVE_A_PWR_SDA")
	)
	(segment
		(start 235.7374 -229.9462)
		(end 235.7374 -228.7651)
		(width 0.17145)
		(layer "F.Cu")
		(net "I2C_DRIVE_A_PWR_SDA")
	)
	(segment
		(start 235.7374 -230.8733)
		(end 235.7374 -229.9462)
		(width 0.17145)
		(layer "F.Cu")
		(net "I2C_DRIVE_A_PWR_SDA")
	)
	(via
		(at 260.35 -228.0158)
		(size 0.5588)
		(drill 0.3048)
		(layers "F.Cu" "B.Cu")
		(net "I2C_DRIVE_A_PWR_SDA")
	)
	(via
		(at 235.7374 -228.7651)
		(size 0.5588)
		(drill 0.3048)
		(layers "F.Cu" "B.Cu")
		(net "I2C_DRIVE_A_PWR_SDA")
	)
	(via
		(at 240.582196 -243.1161)
		(size 0.5588)
		(drill 0.3048)
		(layers "F.Cu" "B.Cu")
		(net "I2C_DRIVE_A_PWR_SDA")
	)
	(via
		(at 235.7374 -229.9462)
		(size 0.6604)
		(drill 0.3302)
		(layers "F.Cu" "B.Cu")
		(net "I2C_DRIVE_A_PWR_SDA")
	)
	(segment
		(start 236.544104 -230.91267)
		(end 235.7374 -230.105966)
		(width 0.13335)
		(layer "In2.Cu")
		(net "I2C_DRIVE_A_PWR_SDA")
	)
	(segment
		(start 260.000496 -229.259638)
		(end 247.186704 -229.259638)
		(width 0.13335)
		(layer "In2.Cu")
		(net "I2C_DRIVE_A_PWR_SDA")
	)
	(segment
		(start 260.403086 -228.857048)
		(end 260.000496 -229.259638)
		(width 0.13335)
		(layer "In2.Cu")
		(net "I2C_DRIVE_A_PWR_SDA")
	)
	(segment
		(start 235.7374 -230.105966)
		(end 235.7374 -228.7651)
		(width 0.13335)
		(layer "In2.Cu")
		(net "I2C_DRIVE_A_PWR_SDA")
	)
	(segment
		(start 245.533672 -230.91267)
		(end 236.544104 -230.91267)
		(width 0.13335)
		(layer "In2.Cu")
		(net "I2C_DRIVE_A_PWR_SDA")
	)
	(segment
		(start 260.35 -228.0158)
		(end 260.403086 -228.068886)
		(width 0.13335)
		(layer "In2.Cu")
		(net "I2C_DRIVE_A_PWR_SDA")
	)
	(segment
		(start 260.403086 -228.068886)
		(end 260.403086 -228.857048)
		(width 0.13335)
		(layer "In2.Cu")
		(net "I2C_DRIVE_A_PWR_SDA")
	)
	(segment
		(start 247.186704 -229.259638)
		(end 245.533672 -230.91267)
		(width 0.13335)
		(layer "In2.Cu")
		(net "I2C_DRIVE_A_PWR_SDA")
	)
	(segment
		(start 253.0856 -254.3556)
		(end 256.935478 -250.505722)
		(width 0.12065)
		(layer "In4.Cu")
		(net "I2C_DRIVE_A_PWR_SDA")
	)
	(segment
		(start 256.173732 -285.066994)
		(end 256.173732 -266.519152)
		(width 0.12065)
		(layer "In4.Cu")
		(net "I2C_DRIVE_A_PWR_SDA")
	)
	(segment
		(start 274.885404 -333.114142)
		(end 270.93926 -333.114142)
		(width 0.12065)
		(layer "In4.Cu")
		(net "I2C_DRIVE_A_PWR_SDA")
	)
	(segment
		(start 253.0856 -260.2738)
		(end 253.0856 -254.3556)
		(width 0.12065)
		(layer "In4.Cu")
		(net "I2C_DRIVE_A_PWR_SDA")
	)
	(segment
		(start 274.924012 -333.15275)
		(end 274.885404 -333.114142)
		(width 0.12065)
		(layer "In4.Cu")
		(net "I2C_DRIVE_A_PWR_SDA")
	)
	(segment
		(start 255.717548 -291.023548)
		(end 255.717548 -285.523178)
		(width 0.12065)
		(layer "In4.Cu")
		(net "I2C_DRIVE_A_PWR_SDA")
	)
	(segment
		(start 270.93926 -333.114142)
		(end 256.282698 -318.45758)
		(width 0.12065)
		(layer "In4.Cu")
		(net "I2C_DRIVE_A_PWR_SDA")
	)
	(segment
		(start 282.83662 -332.50505)
		(end 282.18892 -333.15275)
		(width 0.12065)
		(layer "In4.Cu")
		(net "I2C_DRIVE_A_PWR_SDA")
	)
	(segment
		(start 252.3998 -260.9596)
		(end 253.0856 -260.2738)
		(width 0.12065)
		(layer "In4.Cu")
		(net "I2C_DRIVE_A_PWR_SDA")
	)
	(segment
		(start 282.18892 -333.15275)
		(end 274.924012 -333.15275)
		(width 0.12065)
		(layer "In4.Cu")
		(net "I2C_DRIVE_A_PWR_SDA")
	)
	(segment
		(start 256.173732 -266.519152)
		(end 252.3998 -262.74522)
		(width 0.12065)
		(layer "In4.Cu")
		(net "I2C_DRIVE_A_PWR_SDA")
	)
	(segment
		(start 256.282698 -291.588698)
		(end 255.717548 -291.023548)
		(width 0.12065)
		(layer "In4.Cu")
		(net "I2C_DRIVE_A_PWR_SDA")
	)
	(segment
		(start 256.935478 -244.892322)
		(end 260.35 -241.4778)
		(width 0.12065)
		(layer "In4.Cu")
		(net "I2C_DRIVE_A_PWR_SDA")
	)
	(segment
		(start 256.282698 -318.45758)
		(end 256.282698 -291.588698)
		(width 0.12065)
		(layer "In4.Cu")
		(net "I2C_DRIVE_A_PWR_SDA")
	)
	(segment
		(start 256.935478 -250.505722)
		(end 256.935478 -244.892322)
		(width 0.12065)
		(layer "In4.Cu")
		(net "I2C_DRIVE_A_PWR_SDA")
	)
	(segment
		(start 255.717548 -285.523178)
		(end 256.173732 -285.066994)
		(width 0.12065)
		(layer "In4.Cu")
		(net "I2C_DRIVE_A_PWR_SDA")
	)
	(segment
		(start 252.3998 -262.74522)
		(end 252.3998 -260.9596)
		(width 0.12065)
		(layer "In4.Cu")
		(net "I2C_DRIVE_A_PWR_SDA")
	)
	(segment
		(start 260.35 -241.4778)
		(end 260.35 -228.0158)
		(width 0.12065)
		(layer "In4.Cu")
		(net "I2C_DRIVE_A_PWR_SDA")
	)
	(segment
		(start 234.221528 -231.739694)
		(end 234.221528 -240.190528)
		(width 0.12065)
		(layer "In7.Cu")
		(net "I2C_DRIVE_A_PWR_SDA")
	)
	(segment
		(start 235.7374 -230.223822)
		(end 234.221528 -231.739694)
		(width 0.12065)
		(layer "In7.Cu")
		(net "I2C_DRIVE_A_PWR_SDA")
	)
	(segment
		(start 234.221528 -240.190528)
		(end 237.9472 -243.9162)
		(width 0.12065)
		(layer "In7.Cu")
		(net "I2C_DRIVE_A_PWR_SDA")
	)
	(segment
		(start 235.7374 -228.7651)
		(end 235.7374 -230.223822)
		(width 0.12065)
		(layer "In7.Cu")
		(net "I2C_DRIVE_A_PWR_SDA")
	)
	(segment
		(start 239.782096 -243.9162)
		(end 240.582196 -243.1161)
		(width 0.12065)
		(layer "In7.Cu")
		(net "I2C_DRIVE_A_PWR_SDA")
	)
	(segment
		(start 237.9472 -243.9162)
		(end 239.782096 -243.9162)
		(width 0.12065)
		(layer "In7.Cu")
		(net "I2C_DRIVE_A_PWR_SDA")
	)
	(segment
		(start 259.20192 -229.8065)
		(end 257.994912 -229.8065)
		(width 0.17145)
		(layer "F.Cu")
		(net "I2C_DRIVE_A_PWR_SCL")
	)
	(segment
		(start 234.5944 -230.8733)
		(end 234.5944 -229.87)
		(width 0.17145)
		(layer "F.Cu")
		(net "I2C_DRIVE_A_PWR_SCL")
	)
	(segment
		(start 242.5446 -243.1161)
		(end 242.5446 -243.39804)
		(width 0.17145)
		(layer "F.Cu")
		(net "I2C_DRIVE_A_PWR_SCL")
	)
	(segment
		(start 257.994912 -229.8065)
		(end 256.8575 -229.8065)
		(width 0.17145)
		(layer "F.Cu")
		(net "I2C_DRIVE_A_PWR_SCL")
	)
	(segment
		(start 242.5446 -243.39804)
		(end 242.065302 -243.877338)
		(width 0.17145)
		(layer "F.Cu")
		(net "I2C_DRIVE_A_PWR_SCL")
	)
	(segment
		(start 234.5944 -229.87)
		(end 233.88574 -229.16134)
		(width 0.17145)
		(layer "F.Cu")
		(net "I2C_DRIVE_A_PWR_SCL")
	)
	(segment
		(start 256.8575 -229.8065)
		(end 256.8194 -229.7684)
		(width 0.17145)
		(layer "F.Cu")
		(net "I2C_DRIVE_A_PWR_SCL")
	)
	(via
		(at 233.88574 -229.16134)
		(size 0.5588)
		(drill 0.3048)
		(layers "F.Cu" "B.Cu")
		(net "I2C_DRIVE_A_PWR_SCL")
	)
	(via
		(at 256.8194 -229.7684)
		(size 0.5588)
		(drill 0.3048)
		(layers "F.Cu" "B.Cu")
		(net "I2C_DRIVE_A_PWR_SCL")
	)
	(via
		(at 242.065302 -243.877338)
		(size 0.5588)
		(drill 0.3048)
		(layers "F.Cu" "B.Cu")
		(net "I2C_DRIVE_A_PWR_SCL")
	)
	(via
		(at 234.5944 -229.87)
		(size 0.6604)
		(drill 0.3302)
		(layers "F.Cu" "B.Cu")
		(net "I2C_DRIVE_A_PWR_SCL")
	)
	(segment
		(start 247.471184 -230.0224)
		(end 256.5654 -230.0224)
		(width 0.13335)
		(layer "In2.Cu")
		(net "I2C_DRIVE_A_PWR_SCL")
	)
	(segment
		(start 236.27842 -231.55402)
		(end 245.939564 -231.55402)
		(width 0.13335)
		(layer "In2.Cu")
		(net "I2C_DRIVE_A_PWR_SCL")
	)
	(segment
		(start 233.88574 -229.16134)
		(end 236.27842 -231.55402)
		(width 0.13335)
		(layer "In2.Cu")
		(net "I2C_DRIVE_A_PWR_SCL")
	)
	(segment
		(start 256.5654 -230.0224)
		(end 256.8194 -229.7684)
		(width 0.13335)
		(layer "In2.Cu")
		(net "I2C_DRIVE_A_PWR_SCL")
	)
	(segment
		(start 245.939564 -231.55402)
		(end 247.471184 -230.0224)
		(width 0.13335)
		(layer "In2.Cu")
		(net "I2C_DRIVE_A_PWR_SCL")
	)
	(segment
		(start 254.507492 -290.953444)
		(end 255.234948 -291.6809)
		(width 0.12065)
		(layer "In4.Cu")
		(net "I2C_DRIVE_A_PWR_SCL")
	)
	(segment
		(start 255.545082 -266.779756)
		(end 255.545082 -284.6324)
		(width 0.12065)
		(layer "In4.Cu")
		(net "I2C_DRIVE_A_PWR_SCL")
	)
	(segment
		(start 255.654048 -303.558448)
		(end 255.654048 -318.718184)
		(width 0.12065)
		(layer "In4.Cu")
		(net "I2C_DRIVE_A_PWR_SCL")
	)
	(segment
		(start 270.678656 -333.742792)
		(end 274.885404 -333.742792)
		(width 0.12065)
		(layer "In4.Cu")
		(net "I2C_DRIVE_A_PWR_SCL")
	)
	(segment
		(start 283.112718 -333.629)
		(end 284.236668 -332.50505)
		(width 0.12065)
		(layer "In4.Cu")
		(net "I2C_DRIVE_A_PWR_SCL")
	)
	(segment
		(start 256.8194 -229.7684)
		(end 258.7244 -229.7684)
		(width 0.12065)
		(layer "In4.Cu")
		(net "I2C_DRIVE_A_PWR_SCL")
	)
	(segment
		(start 259.219446 -241.718846)
		(end 256.306828 -244.631464)
		(width 0.12065)
		(layer "In4.Cu")
		(net "I2C_DRIVE_A_PWR_SCL")
	)
	(segment
		(start 254.507492 -285.66999)
		(end 254.507492 -290.953444)
		(width 0.12065)
		(layer "In4.Cu")
		(net "I2C_DRIVE_A_PWR_SCL")
	)
	(segment
		(start 251.620528 -262.855202)
		(end 255.545082 -266.779756)
		(width 0.12065)
		(layer "In4.Cu")
		(net "I2C_DRIVE_A_PWR_SCL")
	)
	(segment
		(start 255.654048 -318.718184)
		(end 270.678656 -333.742792)
		(width 0.12065)
		(layer "In4.Cu")
		(net "I2C_DRIVE_A_PWR_SCL")
	)
	(segment
		(start 256.306828 -249.610118)
		(end 251.620528 -254.296418)
		(width 0.12065)
		(layer "In4.Cu")
		(net "I2C_DRIVE_A_PWR_SCL")
	)
	(segment
		(start 255.234948 -291.6809)
		(end 255.234948 -303.139348)
		(width 0.12065)
		(layer "In4.Cu")
		(net "I2C_DRIVE_A_PWR_SCL")
	)
	(segment
		(start 255.545082 -284.6324)
		(end 254.507492 -285.66999)
		(width 0.12065)
		(layer "In4.Cu")
		(net "I2C_DRIVE_A_PWR_SCL")
	)
	(segment
		(start 255.234948 -303.139348)
		(end 255.654048 -303.558448)
		(width 0.12065)
		(layer "In4.Cu")
		(net "I2C_DRIVE_A_PWR_SCL")
	)
	(segment
		(start 259.219446 -230.263446)
		(end 259.219446 -241.718846)
		(width 0.12065)
		(layer "In4.Cu")
		(net "I2C_DRIVE_A_PWR_SCL")
	)
	(segment
		(start 274.885404 -333.742792)
		(end 274.999196 -333.629)
		(width 0.12065)
		(layer "In4.Cu")
		(net "I2C_DRIVE_A_PWR_SCL")
	)
	(segment
		(start 274.999196 -333.629)
		(end 283.112718 -333.629)
		(width 0.12065)
		(layer "In4.Cu")
		(net "I2C_DRIVE_A_PWR_SCL")
	)
	(segment
		(start 256.306828 -244.631464)
		(end 256.306828 -249.610118)
		(width 0.12065)
		(layer "In4.Cu")
		(net "I2C_DRIVE_A_PWR_SCL")
	)
	(segment
		(start 258.7244 -229.7684)
		(end 259.219446 -230.263446)
		(width 0.12065)
		(layer "In4.Cu")
		(net "I2C_DRIVE_A_PWR_SCL")
	)
	(segment
		(start 251.620528 -254.296418)
		(end 251.620528 -262.855202)
		(width 0.12065)
		(layer "In4.Cu")
		(net "I2C_DRIVE_A_PWR_SCL")
	)
	(segment
		(start 237.744 -244.6274)
		(end 241.31524 -244.6274)
		(width 0.12065)
		(layer "In7.Cu")
		(net "I2C_DRIVE_A_PWR_SCL")
	)
	(segment
		(start 233.56951 -240.45291)
		(end 237.744 -244.6274)
		(width 0.12065)
		(layer "In7.Cu")
		(net "I2C_DRIVE_A_PWR_SCL")
	)
	(segment
		(start 233.88574 -229.16134)
		(end 233.56951 -229.47757)
		(width 0.12065)
		(layer "In7.Cu")
		(net "I2C_DRIVE_A_PWR_SCL")
	)
	(segment
		(start 233.56951 -229.47757)
		(end 233.56951 -240.45291)
		(width 0.12065)
		(layer "In7.Cu")
		(net "I2C_DRIVE_A_PWR_SCL")
	)
	(segment
		(start 241.31524 -244.6274)
		(end 242.065302 -243.877338)
		(width 0.12065)
		(layer "In7.Cu")
		(net "I2C_DRIVE_A_PWR_SCL")
	)
	(segment
		(start 253.603506 -261.769098)
		(end 252.38837 -261.769098)
		(width 0.17145)
		(layer "F.Cu")
		(net "I2C_DRIVE_A_INS_SDA")
	)
	(segment
		(start 238.176054 -248.5263)
		(end 237.323122 -248.5263)
		(width 0.17145)
		(layer "F.Cu")
		(net "I2C_DRIVE_A_INS_SDA")
	)
	(segment
		(start 240.4618 -260.9977)
		(end 240.4618 -261.7978)
		(width 0.17145)
		(layer "F.Cu")
		(net "I2C_DRIVE_A_INS_SDA")
	)
	(segment
		(start 236.3724 -248.5263)
		(end 237.323122 -248.5263)
		(width 0.17145)
		(layer "F.Cu")
		(net "I2C_DRIVE_A_INS_SDA")
	)
	(segment
		(start 252.386846 -261.770622)
		(end 252.386846 -262.318246)
		(width 0.17145)
		(layer "F.Cu")
		(net "I2C_DRIVE_A_INS_SDA")
	)
	(segment
		(start 252.38837 -261.769098)
		(end 252.386846 -261.770622)
		(width 0.17145)
		(layer "F.Cu")
		(net "I2C_DRIVE_A_INS_SDA")
	)
	(segment
		(start 238.628174 -248.97842)
		(end 238.176054 -248.5263)
		(width 0.17145)
		(layer "F.Cu")
		(net "I2C_DRIVE_A_INS_SDA")
	)
	(segment
		(start 252.639322 -262.570722)
		(end 253.1364 -262.570722)
		(width 0.17145)
		(layer "F.Cu")
		(net "I2C_DRIVE_A_INS_SDA")
	)
	(segment
		(start 252.386846 -262.318246)
		(end 252.639322 -262.570722)
		(width 0.17145)
		(layer "F.Cu")
		(net "I2C_DRIVE_A_INS_SDA")
	)
	(via
		(at 237.323122 -248.5263)
		(size 0.6604)
		(drill 0.3302)
		(layers "F.Cu" "B.Cu")
		(net "I2C_DRIVE_A_INS_SDA")
	)
	(via
		(at 240.4618 -261.7978)
		(size 0.5588)
		(drill 0.3048)
		(layers "F.Cu" "B.Cu")
		(net "I2C_DRIVE_A_INS_SDA")
	)
	(via
		(at 238.628174 -248.97842)
		(size 0.5588)
		(drill 0.3048)
		(layers "F.Cu" "B.Cu")
		(net "I2C_DRIVE_A_INS_SDA")
	)
	(via
		(at 253.1364 -262.570722)
		(size 0.5588)
		(drill 0.3048)
		(layers "F.Cu" "B.Cu")
		(net "I2C_DRIVE_A_INS_SDA")
	)
	(segment
		(start 281.836622 -330.705206)
		(end 281.17927 -330.047854)
		(width 0.12065)
		(layer "In4.Cu")
		(net "I2C_DRIVE_A_INS_SDA")
	)
	(segment
		(start 274.885404 -330.14285)
		(end 270.082264 -330.14285)
		(width 0.12065)
		(layer "In4.Cu")
		(net "I2C_DRIVE_A_INS_SDA")
	)
	(segment
		(start 256.911348 -317.493142)
		(end 256.911348 -266.367514)
		(width 0.12065)
		(layer "In4.Cu")
		(net "I2C_DRIVE_A_INS_SDA")
	)
	(segment
		(start 269.56131 -330.143104)
		(end 256.911348 -317.493142)
		(width 0.12065)
		(layer "In4.Cu")
		(net "I2C_DRIVE_A_INS_SDA")
	)
	(segment
		(start 270.08201 -330.143104)
		(end 269.56131 -330.143104)
		(width 0.12065)
		(layer "In4.Cu")
		(net "I2C_DRIVE_A_INS_SDA")
	)
	(segment
		(start 256.911348 -266.367514)
		(end 254.297434 -263.7536)
		(width 0.12065)
		(layer "In4.Cu")
		(net "I2C_DRIVE_A_INS_SDA")
	)
	(segment
		(start 274.9804 -330.047854)
		(end 274.885404 -330.14285)
		(width 0.12065)
		(layer "In4.Cu")
		(net "I2C_DRIVE_A_INS_SDA")
	)
	(segment
		(start 254.297434 -263.7536)
		(end 254.297434 -263.731756)
		(width 0.12065)
		(layer "In4.Cu")
		(net "I2C_DRIVE_A_INS_SDA")
	)
	(segment
		(start 270.082264 -330.14285)
		(end 270.08201 -330.143104)
		(width 0.12065)
		(layer "In4.Cu")
		(net "I2C_DRIVE_A_INS_SDA")
	)
	(segment
		(start 254.297434 -263.731756)
		(end 253.1364 -262.570722)
		(width 0.12065)
		(layer "In4.Cu")
		(net "I2C_DRIVE_A_INS_SDA")
	)
	(segment
		(start 281.17927 -330.047854)
		(end 274.9804 -330.047854)
		(width 0.12065)
		(layer "In4.Cu")
		(net "I2C_DRIVE_A_INS_SDA")
	)
	(segment
		(start 252.334522 -263.3726)
		(end 253.1364 -262.570722)
		(width 0.12065)
		(layer "In7.Cu")
		(net "I2C_DRIVE_A_INS_SDA")
	)
	(segment
		(start 241.28095 -260.97865)
		(end 240.4618 -261.7978)
		(width 0.12065)
		(layer "In7.Cu")
		(net "I2C_DRIVE_A_INS_SDA")
	)
	(segment
		(start 239.437164 -248.97842)
		(end 241.28095 -250.822206)
		(width 0.12065)
		(layer "In7.Cu")
		(net "I2C_DRIVE_A_INS_SDA")
	)
	(segment
		(start 242.0366 -263.3726)
		(end 252.334522 -263.3726)
		(width 0.12065)
		(layer "In7.Cu")
		(net "I2C_DRIVE_A_INS_SDA")
	)
	(segment
		(start 238.628174 -248.97842)
		(end 239.437164 -248.97842)
		(width 0.12065)
		(layer "In7.Cu")
		(net "I2C_DRIVE_A_INS_SDA")
	)
	(segment
		(start 240.4618 -261.7978)
		(end 242.0366 -263.3726)
		(width 0.12065)
		(layer "In7.Cu")
		(net "I2C_DRIVE_A_INS_SDA")
	)
	(segment
		(start 241.28095 -250.822206)
		(end 241.28095 -260.97865)
		(width 0.12065)
		(layer "In7.Cu")
		(net "I2C_DRIVE_A_INS_SDA")
	)
	(segment
		(start 254.812038 -261.770622)
		(end 254.811276 -261.76986)
		(width 0.17145)
		(layer "F.Cu")
		(net "I2C_DRIVE_A_INS_SCL")
	)
	(segment
		(start 237.272068 -247.483376)
		(end 235.690918 -247.483376)
		(width 0.17145)
		(layer "F.Cu")
		(net "I2C_DRIVE_A_INS_SCL")
	)
	(segment
		(start 235.2294 -248.5263)
		(end 235.2294 -247.944894)
		(width 0.17145)
		(layer "F.Cu")
		(net "I2C_DRIVE_A_INS_SCL")
	)
	(segment
		(start 255.993646 -262.570722)
		(end 255.993646 -261.770622)
		(width 0.17145)
		(layer "F.Cu")
		(net "I2C_DRIVE_A_INS_SCL")
	)
	(segment
		(start 241.6048 -260.9977)
		(end 241.6048 -261.7978)
		(width 0.17145)
		(layer "F.Cu")
		(net "I2C_DRIVE_A_INS_SCL")
	)
	(segment
		(start 255.993646 -261.770622)
		(end 254.812038 -261.770622)
		(width 0.17145)
		(layer "F.Cu")
		(net "I2C_DRIVE_A_INS_SCL")
	)
	(segment
		(start 235.2294 -247.944894)
		(end 235.690918 -247.483376)
		(width 0.17145)
		(layer "F.Cu")
		(net "I2C_DRIVE_A_INS_SCL")
	)
	(via
		(at 235.690918 -247.483376)
		(size 0.6604)
		(drill 0.3302)
		(layers "F.Cu" "B.Cu")
		(net "I2C_DRIVE_A_INS_SCL")
	)
	(via
		(at 255.993646 -262.570722)
		(size 0.5588)
		(drill 0.3048)
		(layers "F.Cu" "B.Cu")
		(net "I2C_DRIVE_A_INS_SCL")
	)
	(via
		(at 237.272068 -247.483376)
		(size 0.5588)
		(drill 0.3048)
		(layers "F.Cu" "B.Cu")
		(net "I2C_DRIVE_A_INS_SCL")
	)
	(via
		(at 241.6048 -261.7978)
		(size 0.5588)
		(drill 0.3048)
		(layers "F.Cu" "B.Cu")
		(net "I2C_DRIVE_A_INS_SCL")
	)
	(segment
		(start 283.23667 -330.705206)
		(end 282.103068 -329.571604)
		(width 0.12065)
		(layer "In4.Cu")
		(net "I2C_DRIVE_A_INS_SCL")
	)
	(segment
		(start 257.604768 -266.17168)
		(end 255.993646 -264.560558)
		(width 0.12065)
		(layer "In4.Cu")
		(net "I2C_DRIVE_A_INS_SCL")
	)
	(segment
		(start 257.607562 -288.432748)
		(end 257.604768 -288.432748)
		(width 0.12065)
		(layer "In4.Cu")
		(net "I2C_DRIVE_A_INS_SCL")
	)
	(segment
		(start 269.82166 -329.5142)
		(end 257.539998 -317.232538)
		(width 0.12065)
		(layer "In4.Cu")
		(net "I2C_DRIVE_A_INS_SCL")
	)
	(segment
		(start 282.103068 -329.571604)
		(end 274.942808 -329.571604)
		(width 0.12065)
		(layer "In4.Cu")
		(net "I2C_DRIVE_A_INS_SCL")
	)
	(segment
		(start 274.885404 -329.5142)
		(end 269.82166 -329.5142)
		(width 0.12065)
		(layer "In4.Cu")
		(net "I2C_DRIVE_A_INS_SCL")
	)
	(segment
		(start 257.539998 -289.417252)
		(end 257.607562 -289.417252)
		(width 0.12065)
		(layer "In4.Cu")
		(net "I2C_DRIVE_A_INS_SCL")
	)
	(segment
		(start 257.604768 -288.432748)
		(end 257.604768 -266.17168)
		(width 0.12065)
		(layer "In4.Cu")
		(net "I2C_DRIVE_A_INS_SCL")
	)
	(segment
		(start 255.993646 -264.560558)
		(end 255.993646 -262.570722)
		(width 0.12065)
		(layer "In4.Cu")
		(net "I2C_DRIVE_A_INS_SCL")
	)
	(segment
		(start 257.539998 -317.232538)
		(end 257.539998 -289.417252)
		(width 0.12065)
		(layer "In4.Cu")
		(net "I2C_DRIVE_A_INS_SCL")
	)
	(segment
		(start 274.942808 -329.571604)
		(end 274.885404 -329.5142)
		(width 0.12065)
		(layer "In4.Cu")
		(net "I2C_DRIVE_A_INS_SCL")
	)
	(segment
		(start 257.607562 -289.417252)
		(end 257.895852 -289.128962)
		(width 0.12065)
		(layer "In4.Cu")
		(net "I2C_DRIVE_A_INS_SCL")
	)
	(segment
		(start 257.895852 -288.721038)
		(end 257.607562 -288.432748)
		(width 0.12065)
		(layer "In4.Cu")
		(net "I2C_DRIVE_A_INS_SCL")
	)
	(segment
		(start 257.895852 -289.128962)
		(end 257.895852 -288.721038)
		(width 0.12065)
		(layer "In4.Cu")
		(net "I2C_DRIVE_A_INS_SCL")
	)
	(segment
		(start 241.6048 -261.7978)
		(end 241.9096 -261.493)
		(width 0.12065)
		(layer "In7.Cu")
		(net "I2C_DRIVE_A_INS_SCL")
	)
	(segment
		(start 255.144524 -261.7216)
		(end 252.857 -261.7216)
		(width 0.12065)
		(layer "In7.Cu")
		(net "I2C_DRIVE_A_INS_SCL")
	)
	(segment
		(start 255.993646 -262.570722)
		(end 255.144524 -261.7216)
		(width 0.12065)
		(layer "In7.Cu")
		(net "I2C_DRIVE_A_INS_SCL")
	)
	(segment
		(start 241.9096 -261.493)
		(end 241.9096 -250.561602)
		(width 0.12065)
		(layer "In7.Cu")
		(net "I2C_DRIVE_A_INS_SCL")
	)
	(segment
		(start 241.9096 -250.561602)
		(end 238.831374 -247.483376)
		(width 0.12065)
		(layer "In7.Cu")
		(net "I2C_DRIVE_A_INS_SCL")
	)
	(segment
		(start 251.83465 -262.74395)
		(end 242.37315 -262.74395)
		(width 0.12065)
		(layer "In7.Cu")
		(net "I2C_DRIVE_A_INS_SCL")
	)
	(segment
		(start 252.857 -261.7216)
		(end 251.83465 -262.74395)
		(width 0.12065)
		(layer "In7.Cu")
		(net "I2C_DRIVE_A_INS_SCL")
	)
	(segment
		(start 238.831374 -247.483376)
		(end 237.272068 -247.483376)
		(width 0.12065)
		(layer "In7.Cu")
		(net "I2C_DRIVE_A_INS_SCL")
	)
	(segment
		(start 242.37315 -262.74395)
		(end 241.6048 -261.9756)
		(width 0.12065)
		(layer "In7.Cu")
		(net "I2C_DRIVE_A_INS_SCL")
	)
	(segment
		(start 241.6048 -261.9756)
		(end 241.6048 -261.7978)
		(width 0.12065)
		(layer "In7.Cu")
		(net "I2C_DRIVE_A_INS_SCL")
	)
	(segment
		(start 259.6896 -285.828994)
		(end 259.6896 -286.812482)
		(width 0.17145)
		(layer "F.Cu")
		(net "I2C_DRIVE_A_FLT_LED_SDA")
	)
	(segment
		(start 272.923 -285.1785)
		(end 271.820132 -285.1785)
		(width 0.17145)
		(layer "F.Cu")
		(net "I2C_DRIVE_A_FLT_LED_SDA")
	)
	(segment
		(start 271.81937 -285.179262)
		(end 271.81937 -285.979362)
		(width 0.17145)
		(layer "F.Cu")
		(net "I2C_DRIVE_A_FLT_LED_SDA")
	)
	(segment
		(start 283.21 -284.9753)
		(end 283.21 -285.7754)
		(width 0.17145)
		(layer "F.Cu")
		(net "I2C_DRIVE_A_FLT_LED_SDA")
	)
	(segment
		(start 271.820132 -285.1785)
		(end 271.81937 -285.179262)
		(width 0.17145)
		(layer "F.Cu")
		(net "I2C_DRIVE_A_FLT_LED_SDA")
	)
	(segment
		(start 259.6896 -284.8737)
		(end 259.6896 -285.828994)
		(width 0.17145)
		(layer "F.Cu")
		(net "I2C_DRIVE_A_FLT_LED_SDA")
	)
	(via
		(at 259.6896 -286.812482)
		(size 0.5588)
		(drill 0.3048)
		(layers "F.Cu" "B.Cu")
		(net "I2C_DRIVE_A_FLT_LED_SDA")
	)
	(via
		(at 283.21 -285.7754)
		(size 0.5588)
		(drill 0.3048)
		(layers "F.Cu" "B.Cu")
		(net "I2C_DRIVE_A_FLT_LED_SDA")
	)
	(via
		(at 271.81937 -285.979362)
		(size 0.5588)
		(drill 0.3048)
		(layers "F.Cu" "B.Cu")
		(net "I2C_DRIVE_A_FLT_LED_SDA")
	)
	(via
		(at 259.6896 -285.828994)
		(size 0.6604)
		(drill 0.3302)
		(layers "F.Cu" "B.Cu")
		(net "I2C_DRIVE_A_FLT_LED_SDA")
	)
	(segment
		(start 289.51555 -293.071804)
		(end 288.80435 -292.360604)
		(width 0.12065)
		(layer "In4.Cu")
		(net "I2C_DRIVE_A_FLT_LED_SDA")
	)
	(segment
		(start 289.51555 -326.33031)
		(end 289.51555 -293.071804)
		(width 0.12065)
		(layer "In4.Cu")
		(net "I2C_DRIVE_A_FLT_LED_SDA")
	)
	(segment
		(start 283.929328 -327.8124)
		(end 288.03346 -327.8124)
		(width 0.12065)
		(layer "In4.Cu")
		(net "I2C_DRIVE_A_FLT_LED_SDA")
	)
	(segment
		(start 282.83662 -328.905108)
		(end 283.929328 -327.8124)
		(width 0.12065)
		(layer "In4.Cu")
		(net "I2C_DRIVE_A_FLT_LED_SDA")
	)
	(segment
		(start 288.03346 -327.8124)
		(end 289.51555 -326.33031)
		(width 0.12065)
		(layer "In4.Cu")
		(net "I2C_DRIVE_A_FLT_LED_SDA")
	)
	(segment
		(start 288.80435 -291.36975)
		(end 283.21 -285.7754)
		(width 0.12065)
		(layer "In4.Cu")
		(net "I2C_DRIVE_A_FLT_LED_SDA")
	)
	(segment
		(start 288.80435 -292.360604)
		(end 288.80435 -291.36975)
		(width 0.12065)
		(layer "In4.Cu")
		(net "I2C_DRIVE_A_FLT_LED_SDA")
	)
	(segment
		(start 272.91411 -287.074102)
		(end 281.911298 -287.074102)
		(width 0.12065)
		(layer "In7.Cu")
		(net "I2C_DRIVE_A_FLT_LED_SDA")
	)
	(segment
		(start 281.911298 -287.074102)
		(end 283.21 -285.7754)
		(width 0.12065)
		(layer "In7.Cu")
		(net "I2C_DRIVE_A_FLT_LED_SDA")
	)
	(segment
		(start 259.6896 -286.812482)
		(end 259.6896 -287.107122)
		(width 0.12065)
		(layer "In7.Cu")
		(net "I2C_DRIVE_A_FLT_LED_SDA")
	)
	(segment
		(start 269.898368 -287.900364)
		(end 271.81937 -285.979362)
		(width 0.12065)
		(layer "In7.Cu")
		(net "I2C_DRIVE_A_FLT_LED_SDA")
	)
	(segment
		(start 260.482842 -287.900364)
		(end 269.898368 -287.900364)
		(width 0.12065)
		(layer "In7.Cu")
		(net "I2C_DRIVE_A_FLT_LED_SDA")
	)
	(segment
		(start 259.6896 -287.107122)
		(end 260.482842 -287.900364)
		(width 0.12065)
		(layer "In7.Cu")
		(net "I2C_DRIVE_A_FLT_LED_SDA")
	)
	(segment
		(start 271.81937 -285.979362)
		(end 272.91411 -287.074102)
		(width 0.12065)
		(layer "In7.Cu")
		(net "I2C_DRIVE_A_FLT_LED_SDA")
	)
	(segment
		(start 260.8326 -286.884364)
		(end 260.8326 -285.91256)
		(width 0.17145)
		(layer "F.Cu")
		(net "I2C_DRIVE_A_FLT_LED_SCL")
	)
	(segment
		(start 274.066 -285.1785)
		(end 275.171408 -285.1785)
		(width 0.17145)
		(layer "F.Cu")
		(net "I2C_DRIVE_A_FLT_LED_SCL")
	)
	(segment
		(start 284.353 -284.9753)
		(end 284.353 -285.7754)
		(width 0.17145)
		(layer "F.Cu")
		(net "I2C_DRIVE_A_FLT_LED_SCL")
	)
	(segment
		(start 260.8326 -285.91256)
		(end 260.8326 -284.8737)
		(width 0.17145)
		(layer "F.Cu")
		(net "I2C_DRIVE_A_FLT_LED_SCL")
	)
	(segment
		(start 275.171408 -285.1785)
		(end 275.17217 -285.179262)
		(width 0.17145)
		(layer "F.Cu")
		(net "I2C_DRIVE_A_FLT_LED_SCL")
	)
	(segment
		(start 275.17217 -285.179262)
		(end 275.17217 -285.979362)
		(width 0.17145)
		(layer "F.Cu")
		(net "I2C_DRIVE_A_FLT_LED_SCL")
	)
	(via
		(at 260.8326 -285.91256)
		(size 0.6604)
		(drill 0.3302)
		(layers "F.Cu" "B.Cu")
		(net "I2C_DRIVE_A_FLT_LED_SCL")
	)
	(via
		(at 275.17217 -285.979362)
		(size 0.5588)
		(drill 0.3048)
		(layers "F.Cu" "B.Cu")
		(net "I2C_DRIVE_A_FLT_LED_SCL")
	)
	(via
		(at 260.8326 -286.884364)
		(size 0.5588)
		(drill 0.3048)
		(layers "F.Cu" "B.Cu")
		(net "I2C_DRIVE_A_FLT_LED_SCL")
	)
	(via
		(at 284.353 -285.7754)
		(size 0.5588)
		(drill 0.3048)
		(layers "F.Cu" "B.Cu")
		(net "I2C_DRIVE_A_FLT_LED_SCL")
	)
	(segment
		(start 284.853126 -328.28865)
		(end 288.230818 -328.28865)
		(width 0.12065)
		(layer "In4.Cu")
		(net "I2C_DRIVE_A_FLT_LED_SCL")
	)
	(segment
		(start 288.230818 -328.28865)
		(end 289.9918 -326.527668)
		(width 0.12065)
		(layer "In4.Cu")
		(net "I2C_DRIVE_A_FLT_LED_SCL")
	)
	(segment
		(start 284.236668 -328.905108)
		(end 284.853126 -328.28865)
		(width 0.12065)
		(layer "In4.Cu")
		(net "I2C_DRIVE_A_FLT_LED_SCL")
	)
	(segment
		(start 289.9918 -291.4142)
		(end 284.353 -285.7754)
		(width 0.12065)
		(layer "In4.Cu")
		(net "I2C_DRIVE_A_FLT_LED_SCL")
	)
	(segment
		(start 289.9918 -326.527668)
		(end 289.9918 -291.4142)
		(width 0.12065)
		(layer "In4.Cu")
		(net "I2C_DRIVE_A_FLT_LED_SCL")
	)
	(segment
		(start 269.756636 -286.884364)
		(end 260.8326 -286.884364)
		(width 0.12065)
		(layer "In7.Cu")
		(net "I2C_DRIVE_A_FLT_LED_SCL")
	)
	(segment
		(start 280.482548 -286.445452)
		(end 275.63826 -286.445452)
		(width 0.12065)
		(layer "In7.Cu")
		(net "I2C_DRIVE_A_FLT_LED_SCL")
	)
	(segment
		(start 284.353 -285.7754)
		(end 283.4386 -284.861)
		(width 0.12065)
		(layer "In7.Cu")
		(net "I2C_DRIVE_A_FLT_LED_SCL")
	)
	(segment
		(start 283.4386 -284.861)
		(end 282.067 -284.861)
		(width 0.12065)
		(layer "In7.Cu")
		(net "I2C_DRIVE_A_FLT_LED_SCL")
	)
	(segment
		(start 274.561808 -285.369)
		(end 271.272 -285.369)
		(width 0.12065)
		(layer "In7.Cu")
		(net "I2C_DRIVE_A_FLT_LED_SCL")
	)
	(segment
		(start 275.17217 -285.979362)
		(end 274.561808 -285.369)
		(width 0.12065)
		(layer "In7.Cu")
		(net "I2C_DRIVE_A_FLT_LED_SCL")
	)
	(segment
		(start 271.272 -285.369)
		(end 269.756636 -286.884364)
		(width 0.12065)
		(layer "In7.Cu")
		(net "I2C_DRIVE_A_FLT_LED_SCL")
	)
	(segment
		(start 275.63826 -286.445452)
		(end 275.17217 -285.979362)
		(width 0.12065)
		(layer "In7.Cu")
		(net "I2C_DRIVE_A_FLT_LED_SCL")
	)
	(segment
		(start 282.067 -284.861)
		(end 280.482548 -286.445452)
		(width 0.12065)
		(layer "In7.Cu")
		(net "I2C_DRIVE_A_FLT_LED_SCL")
	)
	(segment
		(start 268.405102 31.074868)
		(end 268.405102 29.314902)
		(width 0.17145)
		(layer "F.Cu")
		(net "I2C_DPB_B_SDA")
	)
	(via
		(at 268.405102 29.314902)
		(size 0.5588)
		(drill 0.3048)
		(layers "F.Cu" "B.Cu")
		(net "I2C_DPB_B_SDA")
	)
	(via
		(at 242.8748 -190.0428)
		(size 0.5588)
		(drill 0.3048)
		(layers "F.Cu" "B.Cu")
		(net "I2C_DPB_B_SDA")
	)
	(via
		(at 345.67368 -190.456566)
		(size 0.5588)
		(drill 0.3048)
		(layers "F.Cu" "B.Cu")
		(net "I2C_DPB_B_SDA")
	)
	(via
		(at 265.651742 6.26364)
		(size 0.5588)
		(drill 0.3048)
		(layers "F.Cu" "B.Cu")
		(net "I2C_DPB_B_SDA")
	)
	(segment
		(start 344.984832 -15.655798)
		(end 334.396842 -15.655798)
		(width 0.13335)
		(layer "In2.Cu")
		(net "I2C_DPB_B_SDA")
	)
	(segment
		(start 314.782454 -9.980422)
		(end 308.878732 -4.0767)
		(width 0.13335)
		(layer "In2.Cu")
		(net "I2C_DPB_B_SDA")
	)
	(segment
		(start 357.021384 -32.202882)
		(end 354.50653 -32.202882)
		(width 0.13335)
		(layer "In2.Cu")
		(net "I2C_DPB_B_SDA")
	)
	(segment
		(start 354.088446 -32.126936)
		(end 346.7735 -24.81199)
		(width 0.13335)
		(layer "In2.Cu")
		(net "I2C_DPB_B_SDA")
	)
	(segment
		(start 346.7735 -24.81199)
		(end 346.7735 -17.444466)
		(width 0.13335)
		(layer "In2.Cu")
		(net "I2C_DPB_B_SDA")
	)
	(segment
		(start 296.867326 -4.0767)
		(end 286.526986 6.26364)
		(width 0.13335)
		(layer "In2.Cu")
		(net "I2C_DPB_B_SDA")
	)
	(segment
		(start 314.782454 -15.015464)
		(end 314.782454 -9.980422)
		(width 0.13335)
		(layer "In2.Cu")
		(net "I2C_DPB_B_SDA")
	)
	(segment
		(start 339.711284 -189.498224)
		(end 321.473576 -189.498224)
		(width 0.13335)
		(layer "In2.Cu")
		(net "I2C_DPB_B_SDA")
	)
	(segment
		(start 340.669626 -190.456566)
		(end 339.711284 -189.498224)
		(width 0.13335)
		(layer "In2.Cu")
		(net "I2C_DPB_B_SDA")
	)
	(segment
		(start 334.396842 -15.655798)
		(end 333.974694 -16.077946)
		(width 0.13335)
		(layer "In2.Cu")
		(net "I2C_DPB_B_SDA")
	)
	(segment
		(start 244.97411 -190.0428)
		(end 242.8748 -190.0428)
		(width 0.13335)
		(layer "In2.Cu")
		(net "I2C_DPB_B_SDA")
	)
	(segment
		(start 315.844936 -16.077946)
		(end 314.782454 -15.015464)
		(width 0.13335)
		(layer "In2.Cu")
		(net "I2C_DPB_B_SDA")
	)
	(segment
		(start 333.974694 -16.077946)
		(end 315.844936 -16.077946)
		(width 0.13335)
		(layer "In2.Cu")
		(net "I2C_DPB_B_SDA")
	)
	(segment
		(start 321.473576 -189.498224)
		(end 313.664092 -197.307708)
		(width 0.13335)
		(layer "In2.Cu")
		(net "I2C_DPB_B_SDA")
	)
	(segment
		(start 313.664092 -197.307708)
		(end 252.239018 -197.307708)
		(width 0.13335)
		(layer "In2.Cu")
		(net "I2C_DPB_B_SDA")
	)
	(segment
		(start 345.67368 -190.456566)
		(end 340.669626 -190.456566)
		(width 0.13335)
		(layer "In2.Cu")
		(net "I2C_DPB_B_SDA")
	)
	(segment
		(start 358.750108 -29.550106)
		(end 358.175306 -30.124908)
		(width 0.13335)
		(layer "In2.Cu")
		(net "I2C_DPB_B_SDA")
	)
	(segment
		(start 252.239018 -197.307708)
		(end 244.97411 -190.0428)
		(width 0.13335)
		(layer "In2.Cu")
		(net "I2C_DPB_B_SDA")
	)
	(segment
		(start 354.50653 -32.202882)
		(end 354.430584 -32.126936)
		(width 0.13335)
		(layer "In2.Cu")
		(net "I2C_DPB_B_SDA")
	)
	(segment
		(start 354.430584 -32.126936)
		(end 354.088446 -32.126936)
		(width 0.13335)
		(layer "In2.Cu")
		(net "I2C_DPB_B_SDA")
	)
	(segment
		(start 346.7735 -17.444466)
		(end 344.984832 -15.655798)
		(width 0.13335)
		(layer "In2.Cu")
		(net "I2C_DPB_B_SDA")
	)
	(segment
		(start 358.175306 -30.124908)
		(end 358.175306 -31.04896)
		(width 0.13335)
		(layer "In2.Cu")
		(net "I2C_DPB_B_SDA")
	)
	(segment
		(start 358.175306 -31.04896)
		(end 357.021384 -32.202882)
		(width 0.13335)
		(layer "In2.Cu")
		(net "I2C_DPB_B_SDA")
	)
	(segment
		(start 308.878732 -4.0767)
		(end 296.867326 -4.0767)
		(width 0.13335)
		(layer "In2.Cu")
		(net "I2C_DPB_B_SDA")
	)
	(segment
		(start 286.526986 6.26364)
		(end 265.651742 6.26364)
		(width 0.13335)
		(layer "In2.Cu")
		(net "I2C_DPB_B_SDA")
	)
	(segment
		(start 347.4212 -108.74248)
		(end 334.381602 -121.782078)
		(width 0.12065)
		(layer "In4.Cu")
		(net "I2C_DPB_B_SDA")
	)
	(segment
		(start 339.902546 -175.34001)
		(end 345.67368 -181.111144)
		(width 0.12065)
		(layer "In4.Cu")
		(net "I2C_DPB_B_SDA")
	)
	(segment
		(start 336.350102 -168.469056)
		(end 339.902546 -172.0215)
		(width 0.12065)
		(layer "In4.Cu")
		(net "I2C_DPB_B_SDA")
	)
	(segment
		(start 215.903302 -316.47384)
		(end 209.03311 -323.344032)
		(width 0.12065)
		(layer "In4.Cu")
		(net "I2C_DPB_B_SDA")
	)
	(segment
		(start 268.405102 28.171902)
		(end 268.405102 29.314902)
		(width 0.12065)
		(layer "In4.Cu")
		(net "I2C_DPB_B_SDA")
	)
	(segment
		(start 266.754102 18.535396)
		(end 266.754102 26.520902)
		(width 0.12065)
		(layer "In4.Cu")
		(net "I2C_DPB_B_SDA")
	)
	(segment
		(start 334.381602 -160.260284)
		(end 336.350102 -162.228784)
		(width 0.12065)
		(layer "In4.Cu")
		(net "I2C_DPB_B_SDA")
	)
	(segment
		(start 358.0892 -32.178752)
		(end 347.4212 -42.846752)
		(width 0.12065)
		(layer "In4.Cu")
		(net "I2C_DPB_B_SDA")
	)
	(segment
		(start 358.0892 -30.211014)
		(end 358.0892 -32.178752)
		(width 0.12065)
		(layer "In4.Cu")
		(net "I2C_DPB_B_SDA")
	)
	(segment
		(start 232.395776 -190.59525)
		(end 215.903302 -207.087724)
		(width 0.12065)
		(layer "In4.Cu")
		(net "I2C_DPB_B_SDA")
	)
	(segment
		(start 266.28725 6.899148)
		(end 266.28725 18.068544)
		(width 0.12065)
		(layer "In4.Cu")
		(net "I2C_DPB_B_SDA")
	)
	(segment
		(start 266.754102 26.520902)
		(end 268.405102 28.171902)
		(width 0.12065)
		(layer "In4.Cu")
		(net "I2C_DPB_B_SDA")
	)
	(segment
		(start 212.930486 -402.237702)
		(end 212.930486 -417.130484)
		(width 0.12065)
		(layer "In4.Cu")
		(net "I2C_DPB_B_SDA")
	)
	(segment
		(start 209.03311 -323.344032)
		(end 209.03311 -398.340326)
		(width 0.12065)
		(layer "In4.Cu")
		(net "I2C_DPB_B_SDA")
	)
	(segment
		(start 358.750108 -29.550106)
		(end 358.0892 -30.211014)
		(width 0.12065)
		(layer "In4.Cu")
		(net "I2C_DPB_B_SDA")
	)
	(segment
		(start 347.4212 -42.846752)
		(end 347.4212 -108.74248)
		(width 0.12065)
		(layer "In4.Cu")
		(net "I2C_DPB_B_SDA")
	)
	(segment
		(start 212.930486 -417.130484)
		(end 213.60003 -417.800028)
		(width 0.12065)
		(layer "In4.Cu")
		(net "I2C_DPB_B_SDA")
	)
	(segment
		(start 334.381602 -121.782078)
		(end 334.381602 -160.260284)
		(width 0.12065)
		(layer "In4.Cu")
		(net "I2C_DPB_B_SDA")
	)
	(segment
		(start 242.32235 -190.59525)
		(end 232.395776 -190.59525)
		(width 0.12065)
		(layer "In4.Cu")
		(net "I2C_DPB_B_SDA")
	)
	(segment
		(start 345.67368 -181.111144)
		(end 345.67368 -190.456566)
		(width 0.12065)
		(layer "In4.Cu")
		(net "I2C_DPB_B_SDA")
	)
	(segment
		(start 336.350102 -162.228784)
		(end 336.350102 -168.469056)
		(width 0.12065)
		(layer "In4.Cu")
		(net "I2C_DPB_B_SDA")
	)
	(segment
		(start 339.902546 -172.0215)
		(end 339.902546 -175.34001)
		(width 0.12065)
		(layer "In4.Cu")
		(net "I2C_DPB_B_SDA")
	)
	(segment
		(start 209.03311 -398.340326)
		(end 212.930486 -402.237702)
		(width 0.12065)
		(layer "In4.Cu")
		(net "I2C_DPB_B_SDA")
	)
	(segment
		(start 215.903302 -207.087724)
		(end 215.903302 -316.47384)
		(width 0.12065)
		(layer "In4.Cu")
		(net "I2C_DPB_B_SDA")
	)
	(segment
		(start 242.8748 -190.0428)
		(end 242.32235 -190.59525)
		(width 0.12065)
		(layer "In4.Cu")
		(net "I2C_DPB_B_SDA")
	)
	(segment
		(start 265.651742 6.26364)
		(end 266.28725 6.899148)
		(width 0.12065)
		(layer "In4.Cu")
		(net "I2C_DPB_B_SDA")
	)
	(segment
		(start 266.28725 18.068544)
		(end 266.754102 18.535396)
		(width 0.12065)
		(layer "In4.Cu")
		(net "I2C_DPB_B_SDA")
	)
	(segment
		(start 267.135102 31.074868)
		(end 267.135102 29.181298)
		(width 0.17145)
		(layer "F.Cu")
		(net "I2C_DPB_B_SCL")
	)
	(via
		(at 241.6302 -189.9666)
		(size 0.5588)
		(drill 0.3048)
		(layers "F.Cu" "B.Cu")
		(net "I2C_DPB_B_SCL")
	)
	(via
		(at 267.135102 29.181298)
		(size 0.5588)
		(drill 0.3048)
		(layers "F.Cu" "B.Cu")
		(net "I2C_DPB_B_SCL")
	)
	(via
		(at 264.998962 7.03199)
		(size 0.5588)
		(drill 0.3048)
		(layers "F.Cu" "B.Cu")
		(net "I2C_DPB_B_SCL")
	)
	(via
		(at 344.043 -189.815216)
		(size 0.5588)
		(drill 0.3048)
		(layers "F.Cu" "B.Cu")
		(net "I2C_DPB_B_SCL")
	)
	(segment
		(start 347.41485 -24.546306)
		(end 347.41485 -17.178782)
		(width 0.13335)
		(layer "In2.Cu")
		(net "I2C_DPB_B_SCL")
	)
	(segment
		(start 354.35413 -31.485586)
		(end 347.41485 -24.546306)
		(width 0.13335)
		(layer "In2.Cu")
		(net "I2C_DPB_B_SCL")
	)
	(segment
		(start 357.679244 -29.220922)
		(end 357.679244 -30.85338)
		(width 0.13335)
		(layer "In2.Cu")
		(net "I2C_DPB_B_SCL")
	)
	(segment
		(start 354.709222 -31.713932)
		(end 354.480876 -31.485586)
		(width 0.13335)
		(layer "In2.Cu")
		(net "I2C_DPB_B_SCL")
	)
	(segment
		(start 357.679244 -30.85338)
		(end 356.818692 -31.713932)
		(width 0.13335)
		(layer "In2.Cu")
		(net "I2C_DPB_B_SCL")
	)
	(segment
		(start 315.423804 -14.74978)
		(end 315.423804 -9.714738)
		(width 0.13335)
		(layer "In2.Cu")
		(net "I2C_DPB_B_SCL")
	)
	(segment
		(start 316.11062 -15.436596)
		(end 315.423804 -14.74978)
		(width 0.13335)
		(layer "In2.Cu")
		(net "I2C_DPB_B_SCL")
	)
	(segment
		(start 309.144416 -3.43535)
		(end 297.13301 -3.43535)
		(width 0.13335)
		(layer "In2.Cu")
		(net "I2C_DPB_B_SCL")
	)
	(segment
		(start 344.043 -189.815216)
		(end 340.93531 -189.815216)
		(width 0.13335)
		(layer "In2.Cu")
		(net "I2C_DPB_B_SCL")
	)
	(segment
		(start 345.250516 -15.014448)
		(end 334.131158 -15.014448)
		(width 0.13335)
		(layer "In2.Cu")
		(net "I2C_DPB_B_SCL")
	)
	(segment
		(start 340.93531 -189.815216)
		(end 339.976968 -188.856874)
		(width 0.13335)
		(layer "In2.Cu")
		(net "I2C_DPB_B_SCL")
	)
	(segment
		(start 252.85954 -196.666358)
		(end 245.594632 -189.40145)
		(width 0.13335)
		(layer "In2.Cu")
		(net "I2C_DPB_B_SCL")
	)
	(segment
		(start 334.131158 -15.014448)
		(end 333.70901 -15.436596)
		(width 0.13335)
		(layer "In2.Cu")
		(net "I2C_DPB_B_SCL")
	)
	(segment
		(start 265.104372 7.1374)
		(end 264.998962 7.03199)
		(width 0.13335)
		(layer "In2.Cu")
		(net "I2C_DPB_B_SCL")
	)
	(segment
		(start 242.19535 -189.40145)
		(end 241.6302 -189.9666)
		(width 0.13335)
		(layer "In2.Cu")
		(net "I2C_DPB_B_SCL")
	)
	(segment
		(start 339.976968 -188.856874)
		(end 321.207892 -188.856874)
		(width 0.13335)
		(layer "In2.Cu")
		(net "I2C_DPB_B_SCL")
	)
	(segment
		(start 333.70901 -15.436596)
		(end 316.11062 -15.436596)
		(width 0.13335)
		(layer "In2.Cu")
		(net "I2C_DPB_B_SCL")
	)
	(segment
		(start 286.56026 7.1374)
		(end 265.104372 7.1374)
		(width 0.13335)
		(layer "In2.Cu")
		(net "I2C_DPB_B_SCL")
	)
	(segment
		(start 313.398408 -196.666358)
		(end 252.85954 -196.666358)
		(width 0.13335)
		(layer "In2.Cu")
		(net "I2C_DPB_B_SCL")
	)
	(segment
		(start 354.480876 -31.485586)
		(end 354.35413 -31.485586)
		(width 0.13335)
		(layer "In2.Cu")
		(net "I2C_DPB_B_SCL")
	)
	(segment
		(start 321.207892 -188.856874)
		(end 313.398408 -196.666358)
		(width 0.13335)
		(layer "In2.Cu")
		(net "I2C_DPB_B_SCL")
	)
	(segment
		(start 245.594632 -189.40145)
		(end 242.19535 -189.40145)
		(width 0.13335)
		(layer "In2.Cu")
		(net "I2C_DPB_B_SCL")
	)
	(segment
		(start 297.13301 -3.43535)
		(end 286.56026 7.1374)
		(width 0.13335)
		(layer "In2.Cu")
		(net "I2C_DPB_B_SCL")
	)
	(segment
		(start 358.750108 -28.150058)
		(end 357.679244 -29.220922)
		(width 0.13335)
		(layer "In2.Cu")
		(net "I2C_DPB_B_SCL")
	)
	(segment
		(start 315.423804 -9.714738)
		(end 309.144416 -3.43535)
		(width 0.13335)
		(layer "In2.Cu")
		(net "I2C_DPB_B_SCL")
	)
	(segment
		(start 356.818692 -31.713932)
		(end 354.709222 -31.713932)
		(width 0.13335)
		(layer "In2.Cu")
		(net "I2C_DPB_B_SCL")
	)
	(segment
		(start 347.41485 -17.178782)
		(end 345.250516 -15.014448)
		(width 0.13335)
		(layer "In2.Cu")
		(net "I2C_DPB_B_SCL")
	)
	(segment
		(start 212.454236 -403.233636)
		(end 212.454236 -418.054282)
		(width 0.12065)
		(layer "In4.Cu")
		(net "I2C_DPB_B_SCL")
	)
	(segment
		(start 267.135102 27.791156)
		(end 267.135102 29.181298)
		(width 0.12065)
		(layer "In4.Cu")
		(net "I2C_DPB_B_SCL")
	)
	(segment
		(start 333.752952 -160.520888)
		(end 335.721452 -162.489388)
		(width 0.12065)
		(layer "In4.Cu")
		(net "I2C_DPB_B_SCL")
	)
	(segment
		(start 215.274652 -206.82712)
		(end 215.274652 -316.213236)
		(width 0.12065)
		(layer "In4.Cu")
		(net "I2C_DPB_B_SCL")
	)
	(segment
		(start 346.79255 -108.481876)
		(end 333.752952 -121.521474)
		(width 0.12065)
		(layer "In4.Cu")
		(net "I2C_DPB_B_SCL")
	)
	(segment
		(start 357.612442 -29.287724)
		(end 357.612442 -31.766256)
		(width 0.12065)
		(layer "In4.Cu")
		(net "I2C_DPB_B_SCL")
	)
	(segment
		(start 232.135172 -189.9666)
		(end 215.274652 -206.82712)
		(width 0.12065)
		(layer "In4.Cu")
		(net "I2C_DPB_B_SCL")
	)
	(segment
		(start 344.043 -180.369718)
		(end 344.043 -189.815216)
		(width 0.12065)
		(layer "In4.Cu")
		(net "I2C_DPB_B_SCL")
	)
	(segment
		(start 212.454236 -418.054282)
		(end 213.60003 -419.200076)
		(width 0.12065)
		(layer "In4.Cu")
		(net "I2C_DPB_B_SCL")
	)
	(segment
		(start 333.752952 -121.521474)
		(end 333.752952 -160.520888)
		(width 0.12065)
		(layer "In4.Cu")
		(net "I2C_DPB_B_SCL")
	)
	(segment
		(start 358.750108 -28.150058)
		(end 357.612442 -29.287724)
		(width 0.12065)
		(layer "In4.Cu")
		(net "I2C_DPB_B_SCL")
	)
	(segment
		(start 241.6302 -189.9666)
		(end 232.135172 -189.9666)
		(width 0.12065)
		(layer "In4.Cu")
		(net "I2C_DPB_B_SCL")
	)
	(segment
		(start 339.273896 -175.600614)
		(end 344.043 -180.369718)
		(width 0.12065)
		(layer "In4.Cu")
		(net "I2C_DPB_B_SCL")
	)
	(segment
		(start 208.40446 -399.18386)
		(end 212.454236 -403.233636)
		(width 0.12065)
		(layer "In4.Cu")
		(net "I2C_DPB_B_SCL")
	)
	(segment
		(start 335.721452 -168.72966)
		(end 339.273896 -172.282104)
		(width 0.12065)
		(layer "In4.Cu")
		(net "I2C_DPB_B_SCL")
	)
	(segment
		(start 266.125452 18.796)
		(end 266.125452 26.781506)
		(width 0.12065)
		(layer "In4.Cu")
		(net "I2C_DPB_B_SCL")
	)
	(segment
		(start 215.274652 -316.213236)
		(end 208.40446 -323.083428)
		(width 0.12065)
		(layer "In4.Cu")
		(net "I2C_DPB_B_SCL")
	)
	(segment
		(start 265.6586 7.691628)
		(end 265.6586 18.329148)
		(width 0.12065)
		(layer "In4.Cu")
		(net "I2C_DPB_B_SCL")
	)
	(segment
		(start 346.79255 -42.480992)
		(end 346.79255 -108.481876)
		(width 0.12065)
		(layer "In4.Cu")
		(net "I2C_DPB_B_SCL")
	)
	(segment
		(start 265.6586 18.329148)
		(end 266.125452 18.796)
		(width 0.12065)
		(layer "In4.Cu")
		(net "I2C_DPB_B_SCL")
	)
	(segment
		(start 339.273896 -172.282104)
		(end 339.273896 -175.600614)
		(width 0.12065)
		(layer "In4.Cu")
		(net "I2C_DPB_B_SCL")
	)
	(segment
		(start 357.612442 -31.766256)
		(end 354.932234 -34.446464)
		(width 0.12065)
		(layer "In4.Cu")
		(net "I2C_DPB_B_SCL")
	)
	(segment
		(start 354.932234 -34.446464)
		(end 354.827078 -34.446464)
		(width 0.12065)
		(layer "In4.Cu")
		(net "I2C_DPB_B_SCL")
	)
	(segment
		(start 264.998962 7.03199)
		(end 265.6586 7.691628)
		(width 0.12065)
		(layer "In4.Cu")
		(net "I2C_DPB_B_SCL")
	)
	(segment
		(start 354.827078 -34.446464)
		(end 346.79255 -42.480992)
		(width 0.12065)
		(layer "In4.Cu")
		(net "I2C_DPB_B_SCL")
	)
	(segment
		(start 266.125452 26.781506)
		(end 267.135102 27.791156)
		(width 0.12065)
		(layer "In4.Cu")
		(net "I2C_DPB_B_SCL")
	)
	(segment
		(start 208.40446 -323.083428)
		(end 208.40446 -399.18386)
		(width 0.12065)
		(layer "In4.Cu")
		(net "I2C_DPB_B_SCL")
	)
	(segment
		(start 335.721452 -162.489388)
		(end 335.721452 -168.72966)
		(width 0.12065)
		(layer "In4.Cu")
		(net "I2C_DPB_B_SCL")
	)
	(segment
		(start 264.821162 -220.45168)
		(end 264.699242 -220.5736)
		(width 0.17145)
		(layer "F.Cu")
		(net "I2C_DPB_A_SDA")
	)
	(segment
		(start 264.693654 -222.806514)
		(end 263.70661 -222.806514)
		(width 0.17145)
		(layer "F.Cu")
		(net "I2C_DPB_A_SDA")
	)
	(segment
		(start 264.699242 -220.5736)
		(end 264.699242 -221.666562)
		(width 0.17145)
		(layer "F.Cu")
		(net "I2C_DPB_A_SDA")
	)
	(segment
		(start 264.699242 -222.800926)
		(end 264.693654 -222.806514)
		(width 0.17145)
		(layer "F.Cu")
		(net "I2C_DPB_A_SDA")
	)
	(segment
		(start 264.821162 -218.936062)
		(end 264.821162 -220.45168)
		(width 0.17145)
		(layer "F.Cu")
		(net "I2C_DPB_A_SDA")
	)
	(segment
		(start 264.699242 -221.666562)
		(end 264.699242 -222.800926)
		(width 0.17145)
		(layer "F.Cu")
		(net "I2C_DPB_A_SDA")
	)
	(via
		(at 111.1504 -233.1212)
		(size 0.5588)
		(drill 0.3048)
		(layers "F.Cu" "B.Cu")
		(net "I2C_DPB_A_SDA")
	)
	(via
		(at 263.70661 -222.806514)
		(size 0.5588)
		(drill 0.3048)
		(layers "F.Cu" "B.Cu")
		(net "I2C_DPB_A_SDA")
	)
	(via
		(at 264.699242 -220.5736)
		(size 0.6604)
		(drill 0.3302)
		(layers "F.Cu" "B.Cu")
		(net "I2C_DPB_A_SDA")
	)
	(segment
		(start 179.935124 -214.72271)
		(end 212.760814 -214.72271)
		(width 0.13335)
		(layer "In2.Cu")
		(net "I2C_DPB_A_SDA")
	)
	(segment
		(start 111.159798 -233.130598)
		(end 161.527236 -233.130598)
		(width 0.13335)
		(layer "In2.Cu")
		(net "I2C_DPB_A_SDA")
	)
	(segment
		(start 229.077266 -218.234768)
		(end 262.814562 -218.234768)
		(width 0.13335)
		(layer "In2.Cu")
		(net "I2C_DPB_A_SDA")
	)
	(segment
		(start 263.563862 -218.984068)
		(end 263.563862 -222.663766)
		(width 0.13335)
		(layer "In2.Cu")
		(net "I2C_DPB_A_SDA")
	)
	(segment
		(start 225.42754 -221.884494)
		(end 229.077266 -218.234768)
		(width 0.13335)
		(layer "In2.Cu")
		(net "I2C_DPB_A_SDA")
	)
	(segment
		(start 161.527236 -233.130598)
		(end 179.935124 -214.72271)
		(width 0.13335)
		(layer "In2.Cu")
		(net "I2C_DPB_A_SDA")
	)
	(segment
		(start 262.814562 -218.234768)
		(end 263.563862 -218.984068)
		(width 0.13335)
		(layer "In2.Cu")
		(net "I2C_DPB_A_SDA")
	)
	(segment
		(start 263.563862 -222.663766)
		(end 263.70661 -222.806514)
		(width 0.13335)
		(layer "In2.Cu")
		(net "I2C_DPB_A_SDA")
	)
	(segment
		(start 212.760814 -214.72271)
		(end 219.922598 -221.884494)
		(width 0.13335)
		(layer "In2.Cu")
		(net "I2C_DPB_A_SDA")
	)
	(segment
		(start 111.1504 -233.1212)
		(end 111.159798 -233.130598)
		(width 0.13335)
		(layer "In2.Cu")
		(net "I2C_DPB_A_SDA")
	)
	(segment
		(start 219.922598 -221.884494)
		(end 225.42754 -221.884494)
		(width 0.13335)
		(layer "In2.Cu")
		(net "I2C_DPB_A_SDA")
	)
	(segment
		(start 110.0582 -124.1298)
		(end 105.248964 -128.939036)
		(width 0.12065)
		(layer "In4.Cu")
		(net "I2C_DPB_A_SDA")
	)
	(segment
		(start 111.139732 -232.20045)
		(end 111.139732 -233.110532)
		(width 0.12065)
		(layer "In4.Cu")
		(net "I2C_DPB_A_SDA")
	)
	(segment
		(start 104.72166 -82.743294)
		(end 110.0582 -88.079834)
		(width 0.12065)
		(layer "In4.Cu")
		(net "I2C_DPB_A_SDA")
	)
	(segment
		(start 112.230154 -32.446722)
		(end 112.230154 -37.156644)
		(width 0.12065)
		(layer "In4.Cu")
		(net "I2C_DPB_A_SDA")
	)
	(segment
		(start 105.248964 -130.326638)
		(end 104.960674 -130.614928)
		(width 0.12065)
		(layer "In4.Cu")
		(net "I2C_DPB_A_SDA")
	)
	(segment
		(start 105.248964 -128.939036)
		(end 105.248964 -130.326638)
		(width 0.12065)
		(layer "In4.Cu")
		(net "I2C_DPB_A_SDA")
	)
	(segment
		(start 107.771184 -228.831902)
		(end 111.139732 -232.20045)
		(width 0.12065)
		(layer "In4.Cu")
		(net "I2C_DPB_A_SDA")
	)
	(segment
		(start 110.0582 -88.079834)
		(end 110.0582 -124.1298)
		(width 0.12065)
		(layer "In4.Cu")
		(net "I2C_DPB_A_SDA")
	)
	(segment
		(start 112.085628 -30.21457)
		(end 112.085628 -32.302196)
		(width 0.12065)
		(layer "In4.Cu")
		(net "I2C_DPB_A_SDA")
	)
	(segment
		(start 112.750092 -29.550106)
		(end 112.085628 -30.21457)
		(width 0.12065)
		(layer "In4.Cu")
		(net "I2C_DPB_A_SDA")
	)
	(segment
		(start 111.139732 -233.110532)
		(end 111.1504 -233.1212)
		(width 0.12065)
		(layer "In4.Cu")
		(net "I2C_DPB_A_SDA")
	)
	(segment
		(start 112.230154 -37.156644)
		(end 104.72166 -44.665138)
		(width 0.12065)
		(layer "In4.Cu")
		(net "I2C_DPB_A_SDA")
	)
	(segment
		(start 107.771184 -180.704998)
		(end 107.771184 -228.831902)
		(width 0.12065)
		(layer "In4.Cu")
		(net "I2C_DPB_A_SDA")
	)
	(segment
		(start 104.72166 -44.665138)
		(end 104.72166 -82.743294)
		(width 0.12065)
		(layer "In4.Cu")
		(net "I2C_DPB_A_SDA")
	)
	(segment
		(start 108.327698 -173.434248)
		(end 108.327698 -180.148484)
		(width 0.12065)
		(layer "In4.Cu")
		(net "I2C_DPB_A_SDA")
	)
	(segment
		(start 104.960674 -170.067224)
		(end 108.327698 -173.434248)
		(width 0.12065)
		(layer "In4.Cu")
		(net "I2C_DPB_A_SDA")
	)
	(segment
		(start 112.085628 -32.302196)
		(end 112.230154 -32.446722)
		(width 0.12065)
		(layer "In4.Cu")
		(net "I2C_DPB_A_SDA")
	)
	(segment
		(start 108.327698 -180.148484)
		(end 107.771184 -180.704998)
		(width 0.12065)
		(layer "In4.Cu")
		(net "I2C_DPB_A_SDA")
	)
	(segment
		(start 104.960674 -130.614928)
		(end 104.960674 -170.067224)
		(width 0.12065)
		(layer "In4.Cu")
		(net "I2C_DPB_A_SDA")
	)
	(segment
		(start 265.232642 -212.268562)
		(end 265.232642 -212.871558)
		(width 0.17145)
		(layer "F.Cu")
		(net "I2C_DPB_A_SCL")
	)
	(segment
		(start 267.822426 -212.268562)
		(end 266.522454 -212.268562)
		(width 0.17145)
		(layer "F.Cu")
		(net "I2C_DPB_A_SCL")
	)
	(segment
		(start 264.821162 -213.283038)
		(end 264.821162 -214.795862)
		(width 0.17145)
		(layer "F.Cu")
		(net "I2C_DPB_A_SCL")
	)
	(segment
		(start 265.232642 -212.871558)
		(end 264.821162 -213.283038)
		(width 0.17145)
		(layer "F.Cu")
		(net "I2C_DPB_A_SCL")
	)
	(segment
		(start 267.822426 -213.231222)
		(end 267.822426 -212.268562)
		(width 0.17145)
		(layer "F.Cu")
		(net "I2C_DPB_A_SCL")
	)
	(segment
		(start 266.522454 -212.268562)
		(end 265.232642 -212.268562)
		(width 0.17145)
		(layer "F.Cu")
		(net "I2C_DPB_A_SCL")
	)
	(via
		(at 266.522454 -212.268562)
		(size 0.6604)
		(drill 0.3302)
		(layers "F.Cu" "B.Cu")
		(net "I2C_DPB_A_SCL")
	)
	(via
		(at 267.822426 -213.231222)
		(size 0.5588)
		(drill 0.3048)
		(layers "F.Cu" "B.Cu")
		(net "I2C_DPB_A_SCL")
	)
	(via
		(at 110.510828 -232.4608)
		(size 0.5588)
		(drill 0.3048)
		(layers "F.Cu" "B.Cu")
		(net "I2C_DPB_A_SCL")
	)
	(segment
		(start 179.66944 -214.08136)
		(end 213.026498 -214.08136)
		(width 0.13335)
		(layer "In2.Cu")
		(net "I2C_DPB_A_SCL")
	)
	(segment
		(start 110.513876 -232.463848)
		(end 161.286952 -232.463848)
		(width 0.13335)
		(layer "In2.Cu")
		(net "I2C_DPB_A_SCL")
	)
	(segment
		(start 220.188282 -221.243144)
		(end 225.161856 -221.243144)
		(width 0.13335)
		(layer "In2.Cu")
		(net "I2C_DPB_A_SCL")
	)
	(segment
		(start 266.878308 -214.17534)
		(end 267.822426 -213.231222)
		(width 0.13335)
		(layer "In2.Cu")
		(net "I2C_DPB_A_SCL")
	)
	(segment
		(start 213.026498 -214.08136)
		(end 220.188282 -221.243144)
		(width 0.13335)
		(layer "In2.Cu")
		(net "I2C_DPB_A_SCL")
	)
	(segment
		(start 225.161856 -221.243144)
		(end 228.854 -217.551)
		(width 0.13335)
		(layer "In2.Cu")
		(net "I2C_DPB_A_SCL")
	)
	(segment
		(start 228.854 -217.551)
		(end 257.718306 -217.551)
		(width 0.13335)
		(layer "In2.Cu")
		(net "I2C_DPB_A_SCL")
	)
	(segment
		(start 261.093966 -214.17534)
		(end 266.878308 -214.17534)
		(width 0.13335)
		(layer "In2.Cu")
		(net "I2C_DPB_A_SCL")
	)
	(segment
		(start 110.510828 -232.4608)
		(end 110.513876 -232.463848)
		(width 0.13335)
		(layer "In2.Cu")
		(net "I2C_DPB_A_SCL")
	)
	(segment
		(start 161.286952 -232.463848)
		(end 179.66944 -214.08136)
		(width 0.13335)
		(layer "In2.Cu")
		(net "I2C_DPB_A_SCL")
	)
	(segment
		(start 257.718306 -217.551)
		(end 261.093966 -214.17534)
		(width 0.13335)
		(layer "In2.Cu")
		(net "I2C_DPB_A_SCL")
	)
	(segment
		(start 104.297734 -130.359912)
		(end 104.297734 -170.450002)
		(width 0.12065)
		(layer "In4.Cu")
		(net "I2C_DPB_A_SCL")
	)
	(segment
		(start 104.26446 -130.326638)
		(end 104.297734 -130.359912)
		(width 0.12065)
		(layer "In4.Cu")
		(net "I2C_DPB_A_SCL")
	)
	(segment
		(start 108.839 -87.749888)
		(end 108.839 -124.302774)
		(width 0.12065)
		(layer "In4.Cu")
		(net "I2C_DPB_A_SCL")
	)
	(segment
		(start 108.839 -124.302774)
		(end 104.297734 -128.84404)
		(width 0.12065)
		(layer "In4.Cu")
		(net "I2C_DPB_A_SCL")
	)
	(segment
		(start 104.09301 -44.404534)
		(end 104.09301 -83.003898)
		(width 0.12065)
		(layer "In4.Cu")
		(net "I2C_DPB_A_SCL")
	)
	(segment
		(start 104.09301 -83.003898)
		(end 108.839 -87.749888)
		(width 0.12065)
		(layer "In4.Cu")
		(net "I2C_DPB_A_SCL")
	)
	(segment
		(start 104.297734 -129.88544)
		(end 104.26446 -129.918714)
		(width 0.12065)
		(layer "In4.Cu")
		(net "I2C_DPB_A_SCL")
	)
	(segment
		(start 107.142534 -229.092506)
		(end 110.510828 -232.4608)
		(width 0.12065)
		(layer "In4.Cu")
		(net "I2C_DPB_A_SCL")
	)
	(segment
		(start 107.699048 -173.851316)
		(end 107.699048 -179.88788)
		(width 0.12065)
		(layer "In4.Cu")
		(net "I2C_DPB_A_SCL")
	)
	(segment
		(start 104.26446 -129.918714)
		(end 104.26446 -130.326638)
		(width 0.12065)
		(layer "In4.Cu")
		(net "I2C_DPB_A_SCL")
	)
	(segment
		(start 111.601504 -36.89604)
		(end 104.09301 -44.404534)
		(width 0.12065)
		(layer "In4.Cu")
		(net "I2C_DPB_A_SCL")
	)
	(segment
		(start 107.142534 -180.444394)
		(end 107.142534 -229.092506)
		(width 0.12065)
		(layer "In4.Cu")
		(net "I2C_DPB_A_SCL")
	)
	(segment
		(start 104.297734 -128.84404)
		(end 104.297734 -129.88544)
		(width 0.12065)
		(layer "In4.Cu")
		(net "I2C_DPB_A_SCL")
	)
	(segment
		(start 104.297734 -170.450002)
		(end 107.699048 -173.851316)
		(width 0.12065)
		(layer "In4.Cu")
		(net "I2C_DPB_A_SCL")
	)
	(segment
		(start 107.699048 -179.88788)
		(end 107.142534 -180.444394)
		(width 0.12065)
		(layer "In4.Cu")
		(net "I2C_DPB_A_SCL")
	)
	(segment
		(start 112.750092 -28.150058)
		(end 111.601504 -29.298646)
		(width 0.12065)
		(layer "In4.Cu")
		(net "I2C_DPB_A_SCL")
	)
	(segment
		(start 111.601504 -29.298646)
		(end 111.601504 -36.89604)
		(width 0.12065)
		(layer "In4.Cu")
		(net "I2C_DPB_A_SCL")
	)
	(via
		(at 241.928904 -191.427608)
		(size 0.5588)
		(drill 0.3048)
		(layers "F.Cu" "B.Cu")
		(net "I2C_BMC_B_EXP_B_SDA")
	)
	(via
		(at 375.674382 -193.613786)
		(size 0.5588)
		(drill 0.3048)
		(layers "F.Cu" "B.Cu")
		(net "I2C_BMC_B_EXP_B_SDA")
	)
	(segment
		(start 374.142762 -193.613786)
		(end 374.03151 -193.725038)
		(width 0.13335)
		(layer "In2.Cu")
		(net "I2C_BMC_B_EXP_B_SDA")
	)
	(segment
		(start 251.258832 -198.590408)
		(end 244.096032 -191.427608)
		(width 0.13335)
		(layer "In2.Cu")
		(net "I2C_BMC_B_EXP_B_SDA")
	)
	(segment
		(start 244.096032 -191.427608)
		(end 241.928904 -191.427608)
		(width 0.13335)
		(layer "In2.Cu")
		(net "I2C_BMC_B_EXP_B_SDA")
	)
	(segment
		(start 375.674382 -193.613786)
		(end 374.142762 -193.613786)
		(width 0.13335)
		(layer "In2.Cu")
		(net "I2C_BMC_B_EXP_B_SDA")
	)
	(segment
		(start 331.803248 -192.88125)
		(end 331.03947 -193.645028)
		(width 0.13335)
		(layer "In2.Cu")
		(net "I2C_BMC_B_EXP_B_SDA")
	)
	(segment
		(start 356.277672 -193.725038)
		(end 355.433884 -192.88125)
		(width 0.13335)
		(layer "In2.Cu")
		(net "I2C_BMC_B_EXP_B_SDA")
	)
	(segment
		(start 314.19546 -198.590408)
		(end 251.258832 -198.590408)
		(width 0.13335)
		(layer "In2.Cu")
		(net "I2C_BMC_B_EXP_B_SDA")
	)
	(segment
		(start 319.14084 -193.645028)
		(end 314.19546 -198.590408)
		(width 0.13335)
		(layer "In2.Cu")
		(net "I2C_BMC_B_EXP_B_SDA")
	)
	(segment
		(start 355.433884 -192.88125)
		(end 331.803248 -192.88125)
		(width 0.13335)
		(layer "In2.Cu")
		(net "I2C_BMC_B_EXP_B_SDA")
	)
	(segment
		(start 374.03151 -193.725038)
		(end 356.277672 -193.725038)
		(width 0.13335)
		(layer "In2.Cu")
		(net "I2C_BMC_B_EXP_B_SDA")
	)
	(segment
		(start 331.03947 -193.645028)
		(end 319.14084 -193.645028)
		(width 0.13335)
		(layer "In2.Cu")
		(net "I2C_BMC_B_EXP_B_SDA")
	)
	(segment
		(start 375.3866 -116.108988)
		(end 388.970266 -129.692654)
		(width 0.12065)
		(layer "In4.Cu")
		(net "I2C_BMC_B_EXP_B_SDA")
	)
	(segment
		(start 375.674382 -156.391102)
		(end 375.674382 -193.613786)
		(width 0.12065)
		(layer "In4.Cu")
		(net "I2C_BMC_B_EXP_B_SDA")
	)
	(segment
		(start 233.253534 -192.5066)
		(end 217.789252 -207.970882)
		(width 0.12065)
		(layer "In4.Cu")
		(net "I2C_BMC_B_EXP_B_SDA")
	)
	(segment
		(start 380.350014 -29.550106)
		(end 379.733556 -30.166564)
		(width 0.12065)
		(layer "In4.Cu")
		(net "I2C_BMC_B_EXP_B_SDA")
	)
	(segment
		(start 379.733556 -30.166564)
		(end 379.733556 -33.505394)
		(width 0.12065)
		(layer "In4.Cu")
		(net "I2C_BMC_B_EXP_B_SDA")
	)
	(segment
		(start 388.970266 -143.095218)
		(end 375.674382 -156.391102)
		(width 0.12065)
		(layer "In4.Cu")
		(net "I2C_BMC_B_EXP_B_SDA")
	)
	(segment
		(start 379.733556 -33.505394)
		(end 375.3866 -37.85235)
		(width 0.12065)
		(layer "In4.Cu")
		(net "I2C_BMC_B_EXP_B_SDA")
	)
	(segment
		(start 375.3866 -37.85235)
		(end 375.3866 -116.108988)
		(width 0.12065)
		(layer "In4.Cu")
		(net "I2C_BMC_B_EXP_B_SDA")
	)
	(segment
		(start 241.58067 -192.5066)
		(end 233.253534 -192.5066)
		(width 0.12065)
		(layer "In4.Cu")
		(net "I2C_BMC_B_EXP_B_SDA")
	)
	(segment
		(start 241.928904 -192.158366)
		(end 241.58067 -192.5066)
		(width 0.12065)
		(layer "In4.Cu")
		(net "I2C_BMC_B_EXP_B_SDA")
	)
	(segment
		(start 210.91906 -396.69466)
		(end 216.58326 -402.35886)
		(width 0.12065)
		(layer "In4.Cu")
		(net "I2C_BMC_B_EXP_B_SDA")
	)
	(segment
		(start 216.58326 -402.35886)
		(end 216.58326 -409.983432)
		(width 0.12065)
		(layer "In4.Cu")
		(net "I2C_BMC_B_EXP_B_SDA")
	)
	(segment
		(start 388.970266 -129.692654)
		(end 388.970266 -143.095218)
		(width 0.12065)
		(layer "In4.Cu")
		(net "I2C_BMC_B_EXP_B_SDA")
	)
	(segment
		(start 210.91906 -324.125844)
		(end 210.91906 -396.69466)
		(width 0.12065)
		(layer "In4.Cu")
		(net "I2C_BMC_B_EXP_B_SDA")
	)
	(segment
		(start 241.928904 -191.427608)
		(end 241.928904 -192.158366)
		(width 0.12065)
		(layer "In4.Cu")
		(net "I2C_BMC_B_EXP_B_SDA")
	)
	(segment
		(start 216.58326 -409.983432)
		(end 217.199972 -410.600144)
		(width 0.12065)
		(layer "In4.Cu")
		(net "I2C_BMC_B_EXP_B_SDA")
	)
	(segment
		(start 217.789252 -207.970882)
		(end 217.789252 -317.255652)
		(width 0.12065)
		(layer "In4.Cu")
		(net "I2C_BMC_B_EXP_B_SDA")
	)
	(segment
		(start 217.789252 -317.255652)
		(end 210.91906 -324.125844)
		(width 0.12065)
		(layer "In4.Cu")
		(net "I2C_BMC_B_EXP_B_SDA")
	)
	(via
		(at 375.045732 -192.808352)
		(size 0.5588)
		(drill 0.3048)
		(layers "F.Cu" "B.Cu")
		(net "I2C_BMC_B_EXP_B_SCL")
	)
	(via
		(at 241.058192 -191.82715)
		(size 0.5588)
		(drill 0.3048)
		(layers "F.Cu" "B.Cu")
		(net "I2C_BMC_B_EXP_B_SCL")
	)
	(segment
		(start 313.929776 -197.949058)
		(end 321.39255 -190.486284)
		(width 0.13335)
		(layer "In2.Cu")
		(net "I2C_BMC_B_EXP_B_SCL")
	)
	(segment
		(start 373.885968 -192.963546)
		(end 374.890538 -192.963546)
		(width 0.13335)
		(layer "In2.Cu")
		(net "I2C_BMC_B_EXP_B_SCL")
	)
	(segment
		(start 321.39255 -190.486284)
		(end 339.79231 -190.486284)
		(width 0.13335)
		(layer "In2.Cu")
		(net "I2C_BMC_B_EXP_B_SCL")
	)
	(segment
		(start 355.559868 -192.1002)
		(end 356.543356 -193.083688)
		(width 0.13335)
		(layer "In2.Cu")
		(net "I2C_BMC_B_EXP_B_SCL")
	)
	(segment
		(start 251.838968 -197.949058)
		(end 313.929776 -197.949058)
		(width 0.13335)
		(layer "In2.Cu")
		(net "I2C_BMC_B_EXP_B_SCL")
	)
	(segment
		(start 341.406226 -192.1002)
		(end 355.559868 -192.1002)
		(width 0.13335)
		(layer "In2.Cu")
		(net "I2C_BMC_B_EXP_B_SCL")
	)
	(segment
		(start 339.79231 -190.486284)
		(end 341.406226 -192.1002)
		(width 0.13335)
		(layer "In2.Cu")
		(net "I2C_BMC_B_EXP_B_SCL")
	)
	(segment
		(start 241.622072 -190.754)
		(end 244.64391 -190.754)
		(width 0.13335)
		(layer "In2.Cu")
		(net "I2C_BMC_B_EXP_B_SCL")
	)
	(segment
		(start 241.058192 -191.82715)
		(end 241.058192 -191.31788)
		(width 0.13335)
		(layer "In2.Cu")
		(net "I2C_BMC_B_EXP_B_SCL")
	)
	(segment
		(start 373.765826 -193.083688)
		(end 373.885968 -192.963546)
		(width 0.13335)
		(layer "In2.Cu")
		(net "I2C_BMC_B_EXP_B_SCL")
	)
	(segment
		(start 374.890538 -192.963546)
		(end 375.045732 -192.808352)
		(width 0.13335)
		(layer "In2.Cu")
		(net "I2C_BMC_B_EXP_B_SCL")
	)
	(segment
		(start 356.543356 -193.083688)
		(end 373.765826 -193.083688)
		(width 0.13335)
		(layer "In2.Cu")
		(net "I2C_BMC_B_EXP_B_SCL")
	)
	(segment
		(start 244.64391 -190.754)
		(end 251.838968 -197.949058)
		(width 0.13335)
		(layer "In2.Cu")
		(net "I2C_BMC_B_EXP_B_SCL")
	)
	(segment
		(start 241.058192 -191.31788)
		(end 241.622072 -190.754)
		(width 0.13335)
		(layer "In2.Cu")
		(net "I2C_BMC_B_EXP_B_SCL")
	)
	(segment
		(start 374.75795 -36.497006)
		(end 374.75795 -116.369592)
		(width 0.12065)
		(layer "In4.Cu")
		(net "I2C_BMC_B_EXP_B_SCL")
	)
	(segment
		(start 379.104906 -32.15005)
		(end 374.75795 -36.497006)
		(width 0.12065)
		(layer "In4.Cu")
		(net "I2C_BMC_B_EXP_B_SCL")
	)
	(segment
		(start 241.032792 -191.85255)
		(end 233.01833 -191.85255)
		(width 0.12065)
		(layer "In4.Cu")
		(net "I2C_BMC_B_EXP_B_SCL")
	)
	(segment
		(start 241.058192 -191.82715)
		(end 241.032792 -191.85255)
		(width 0.12065)
		(layer "In4.Cu")
		(net "I2C_BMC_B_EXP_B_SCL")
	)
	(segment
		(start 379.104906 -32.149796)
		(end 379.104906 -32.15005)
		(width 0.12065)
		(layer "In4.Cu")
		(net "I2C_BMC_B_EXP_B_SCL")
	)
	(segment
		(start 233.01833 -191.85255)
		(end 217.160602 -207.710278)
		(width 0.12065)
		(layer "In4.Cu")
		(net "I2C_BMC_B_EXP_B_SCL")
	)
	(segment
		(start 217.160602 -316.995048)
		(end 210.29041 -323.86524)
		(width 0.12065)
		(layer "In4.Cu")
		(net "I2C_BMC_B_EXP_B_SCL")
	)
	(segment
		(start 380.350014 -28.150058)
		(end 379.205236 -29.294836)
		(width 0.12065)
		(layer "In4.Cu")
		(net "I2C_BMC_B_EXP_B_SCL")
	)
	(segment
		(start 210.29041 -323.86524)
		(end 210.29041 -397.819118)
		(width 0.12065)
		(layer "In4.Cu")
		(net "I2C_BMC_B_EXP_B_SCL")
	)
	(segment
		(start 375.045732 -156.130498)
		(end 375.045732 -192.808352)
		(width 0.12065)
		(layer "In4.Cu")
		(net "I2C_BMC_B_EXP_B_SCL")
	)
	(segment
		(start 216.10701 -410.90723)
		(end 217.199972 -412.000192)
		(width 0.12065)
		(layer "In4.Cu")
		(net "I2C_BMC_B_EXP_B_SCL")
	)
	(segment
		(start 379.205236 -32.049466)
		(end 379.104906 -32.149796)
		(width 0.12065)
		(layer "In4.Cu")
		(net "I2C_BMC_B_EXP_B_SCL")
	)
	(segment
		(start 216.10701 -403.635718)
		(end 216.10701 -410.90723)
		(width 0.12065)
		(layer "In4.Cu")
		(net "I2C_BMC_B_EXP_B_SCL")
	)
	(segment
		(start 210.29041 -397.819118)
		(end 216.10701 -403.635718)
		(width 0.12065)
		(layer "In4.Cu")
		(net "I2C_BMC_B_EXP_B_SCL")
	)
	(segment
		(start 379.205236 -29.294836)
		(end 379.205236 -32.049466)
		(width 0.12065)
		(layer "In4.Cu")
		(net "I2C_BMC_B_EXP_B_SCL")
	)
	(segment
		(start 374.75795 -116.369592)
		(end 388.341616 -129.953258)
		(width 0.12065)
		(layer "In4.Cu")
		(net "I2C_BMC_B_EXP_B_SCL")
	)
	(segment
		(start 217.160602 -207.710278)
		(end 217.160602 -316.995048)
		(width 0.12065)
		(layer "In4.Cu")
		(net "I2C_BMC_B_EXP_B_SCL")
	)
	(segment
		(start 388.341616 -142.834614)
		(end 375.045732 -156.130498)
		(width 0.12065)
		(layer "In4.Cu")
		(net "I2C_BMC_B_EXP_B_SCL")
	)
	(segment
		(start 388.341616 -129.953258)
		(end 388.341616 -142.834614)
		(width 0.12065)
		(layer "In4.Cu")
		(net "I2C_BMC_B_EXP_B_SCL")
	)
	(segment
		(start 302.2346 -262.567674)
		(end 303.372266 -262.567674)
		(width 0.17145)
		(layer "F.Cu")
		(net "I2C_BMC_B_EXP_A_SDA")
	)
	(segment
		(start 299.384974 -262.567674)
		(end 302.2346 -262.567674)
		(width 0.17145)
		(layer "F.Cu")
		(net "I2C_BMC_B_EXP_A_SDA")
	)
	(segment
		(start 298.967144 -262.149844)
		(end 299.384974 -262.567674)
		(width 0.17145)
		(layer "F.Cu")
		(net "I2C_BMC_B_EXP_A_SDA")
	)
	(via
		(at 376.301 -252.922532)
		(size 0.5588)
		(drill 0.3048)
		(layers "F.Cu" "B.Cu")
		(net "I2C_BMC_B_EXP_A_SDA")
	)
	(via
		(at 302.2346 -262.567674)
		(size 0.6604)
		(drill 0.3302)
		(layers "F.Cu" "B.Cu")
		(net "I2C_BMC_B_EXP_A_SDA")
	)
	(via
		(at 298.967144 -262.149844)
		(size 0.5588)
		(drill 0.3048)
		(layers "F.Cu" "B.Cu")
		(net "I2C_BMC_B_EXP_A_SDA")
	)
	(segment
		(start 304.140108 -262.163306)
		(end 313.380882 -252.922532)
		(width 0.13335)
		(layer "In2.Cu")
		(net "I2C_BMC_B_EXP_A_SDA")
	)
	(segment
		(start 298.967144 -262.149844)
		(end 298.980606 -262.163306)
		(width 0.13335)
		(layer "In2.Cu")
		(net "I2C_BMC_B_EXP_A_SDA")
	)
	(segment
		(start 298.355766 -262.761222)
		(end 298.967144 -262.149844)
		(width 0.13335)
		(layer "In2.Cu")
		(net "I2C_BMC_B_EXP_A_SDA")
	)
	(segment
		(start 282.69565 -262.761222)
		(end 298.355766 -262.761222)
		(width 0.13335)
		(layer "In2.Cu")
		(net "I2C_BMC_B_EXP_A_SDA")
	)
	(segment
		(start 313.380882 -252.922532)
		(end 376.301 -252.922532)
		(width 0.13335)
		(layer "In2.Cu")
		(net "I2C_BMC_B_EXP_A_SDA")
	)
	(segment
		(start 281.836622 -261.902194)
		(end 282.69565 -262.761222)
		(width 0.13335)
		(layer "In2.Cu")
		(net "I2C_BMC_B_EXP_A_SDA")
	)
	(segment
		(start 298.980606 -262.163306)
		(end 304.140108 -262.163306)
		(width 0.13335)
		(layer "In2.Cu")
		(net "I2C_BMC_B_EXP_A_SDA")
	)
	(segment
		(start 380.48692 -33.641284)
		(end 376.01525 -38.112954)
		(width 0.12065)
		(layer "In4.Cu")
		(net "I2C_BMC_B_EXP_A_SDA")
	)
	(segment
		(start 376.303032 -156.651706)
		(end 376.303032 -199.206358)
		(width 0.12065)
		(layer "In4.Cu")
		(net "I2C_BMC_B_EXP_A_SDA")
	)
	(segment
		(start 389.795766 -143.158972)
		(end 376.303032 -156.651706)
		(width 0.12065)
		(layer "In4.Cu")
		(net "I2C_BMC_B_EXP_A_SDA")
	)
	(segment
		(start 376.272044 -199.237346)
		(end 376.272044 -252.893576)
		(width 0.12065)
		(layer "In4.Cu")
		(net "I2C_BMC_B_EXP_A_SDA")
	)
	(segment
		(start 381.00635 -26.6065)
		(end 381.00635 -31.300166)
		(width 0.12065)
		(layer "In4.Cu")
		(net "I2C_BMC_B_EXP_A_SDA")
	)
	(segment
		(start 376.01525 -115.848384)
		(end 389.795766 -129.6289)
		(width 0.12065)
		(layer "In4.Cu")
		(net "I2C_BMC_B_EXP_A_SDA")
	)
	(segment
		(start 380.48692 -31.819596)
		(end 380.48692 -33.641284)
		(width 0.12065)
		(layer "In4.Cu")
		(net "I2C_BMC_B_EXP_A_SDA")
	)
	(segment
		(start 376.272044 -252.893576)
		(end 376.301 -252.922532)
		(width 0.12065)
		(layer "In4.Cu")
		(net "I2C_BMC_B_EXP_A_SDA")
	)
	(segment
		(start 376.01525 -38.112954)
		(end 376.01525 -115.848384)
		(width 0.12065)
		(layer "In4.Cu")
		(net "I2C_BMC_B_EXP_A_SDA")
	)
	(segment
		(start 389.795766 -129.6289)
		(end 389.795766 -143.158972)
		(width 0.12065)
		(layer "In4.Cu")
		(net "I2C_BMC_B_EXP_A_SDA")
	)
	(segment
		(start 376.303032 -199.206358)
		(end 376.272044 -199.237346)
		(width 0.12065)
		(layer "In4.Cu")
		(net "I2C_BMC_B_EXP_A_SDA")
	)
	(segment
		(start 380.350014 -25.950164)
		(end 381.00635 -26.6065)
		(width 0.12065)
		(layer "In4.Cu")
		(net "I2C_BMC_B_EXP_A_SDA")
	)
	(segment
		(start 381.00635 -31.300166)
		(end 380.48692 -31.819596)
		(width 0.12065)
		(layer "In4.Cu")
		(net "I2C_BMC_B_EXP_A_SDA")
	)
	(segment
		(start 298.574714 -261.373874)
		(end 301.8536 -261.373874)
		(width 0.17145)
		(layer "F.Cu")
		(net "I2C_BMC_B_EXP_A_SCL")
	)
	(segment
		(start 303.372266 -261.373874)
		(end 301.8536 -261.373874)
		(width 0.17145)
		(layer "F.Cu")
		(net "I2C_BMC_B_EXP_A_SCL")
	)
	(segment
		(start 297.874944 -262.073644)
		(end 298.574714 -261.373874)
		(width 0.17145)
		(layer "F.Cu")
		(net "I2C_BMC_B_EXP_A_SCL")
	)
	(via
		(at 301.8536 -261.373874)
		(size 0.6604)
		(drill 0.3302)
		(layers "F.Cu" "B.Cu")
		(net "I2C_BMC_B_EXP_A_SCL")
	)
	(via
		(at 376.936 -252.04801)
		(size 0.5588)
		(drill 0.3048)
		(layers "F.Cu" "B.Cu")
		(net "I2C_BMC_B_EXP_A_SCL")
	)
	(via
		(at 297.874944 -262.073644)
		(size 0.5588)
		(drill 0.3048)
		(layers "F.Cu" "B.Cu")
		(net "I2C_BMC_B_EXP_A_SCL")
	)
	(segment
		(start 303.98593 -261.41045)
		(end 313.115198 -252.281182)
		(width 0.13335)
		(layer "In2.Cu")
		(net "I2C_BMC_B_EXP_A_SCL")
	)
	(segment
		(start 283.999686 -261.139178)
		(end 296.940478 -261.139178)
		(width 0.13335)
		(layer "In2.Cu")
		(net "I2C_BMC_B_EXP_A_SCL")
	)
	(segment
		(start 325.157084 -252.281182)
		(end 325.390256 -252.04801)
		(width 0.13335)
		(layer "In2.Cu")
		(net "I2C_BMC_B_EXP_A_SCL")
	)
	(segment
		(start 298.538138 -261.41045)
		(end 303.98593 -261.41045)
		(width 0.13335)
		(layer "In2.Cu")
		(net "I2C_BMC_B_EXP_A_SCL")
	)
	(segment
		(start 297.874944 -262.073644)
		(end 298.538138 -261.41045)
		(width 0.13335)
		(layer "In2.Cu")
		(net "I2C_BMC_B_EXP_A_SCL")
	)
	(segment
		(start 296.940478 -261.139178)
		(end 297.874944 -262.073644)
		(width 0.13335)
		(layer "In2.Cu")
		(net "I2C_BMC_B_EXP_A_SCL")
	)
	(segment
		(start 325.390256 -252.04801)
		(end 376.936 -252.04801)
		(width 0.13335)
		(layer "In2.Cu")
		(net "I2C_BMC_B_EXP_A_SCL")
	)
	(segment
		(start 283.23667 -261.902194)
		(end 283.999686 -261.139178)
		(width 0.13335)
		(layer "In2.Cu")
		(net "I2C_BMC_B_EXP_A_SCL")
	)
	(segment
		(start 313.115198 -252.281182)
		(end 325.157084 -252.281182)
		(width 0.13335)
		(layer "In2.Cu")
		(net "I2C_BMC_B_EXP_A_SCL")
	)
	(segment
		(start 376.900694 -252.012704)
		(end 376.936 -252.04801)
		(width 0.12065)
		(layer "In4.Cu")
		(net "I2C_BMC_B_EXP_A_SCL")
	)
	(segment
		(start 376.6439 -115.58778)
		(end 390.463786 -129.407666)
		(width 0.12065)
		(layer "In4.Cu")
		(net "I2C_BMC_B_EXP_A_SCL")
	)
	(segment
		(start 381.4826 -25.682702)
		(end 381.4826 -31.755588)
		(width 0.12065)
		(layer "In4.Cu")
		(net "I2C_BMC_B_EXP_A_SCL")
	)
	(segment
		(start 376.900694 -199.49795)
		(end 376.900694 -252.012704)
		(width 0.12065)
		(layer "In4.Cu")
		(net "I2C_BMC_B_EXP_A_SCL")
	)
	(segment
		(start 380.350014 -24.550116)
		(end 381.4826 -25.682702)
		(width 0.12065)
		(layer "In4.Cu")
		(net "I2C_BMC_B_EXP_A_SCL")
	)
	(segment
		(start 381.192024 -33.825434)
		(end 376.6439 -38.373558)
		(width 0.12065)
		(layer "In4.Cu")
		(net "I2C_BMC_B_EXP_A_SCL")
	)
	(segment
		(start 381.4826 -31.755588)
		(end 381.192024 -32.046164)
		(width 0.12065)
		(layer "In4.Cu")
		(net "I2C_BMC_B_EXP_A_SCL")
	)
	(segment
		(start 381.192024 -32.046164)
		(end 381.192024 -33.825434)
		(width 0.12065)
		(layer "In4.Cu")
		(net "I2C_BMC_B_EXP_A_SCL")
	)
	(segment
		(start 376.931682 -156.91231)
		(end 376.931682 -199.466962)
		(width 0.12065)
		(layer "In4.Cu")
		(net "I2C_BMC_B_EXP_A_SCL")
	)
	(segment
		(start 390.463786 -129.407666)
		(end 390.463786 -143.380206)
		(width 0.12065)
		(layer "In4.Cu")
		(net "I2C_BMC_B_EXP_A_SCL")
	)
	(segment
		(start 376.6439 -38.373558)
		(end 376.6439 -115.58778)
		(width 0.12065)
		(layer "In4.Cu")
		(net "I2C_BMC_B_EXP_A_SCL")
	)
	(segment
		(start 376.931682 -199.466962)
		(end 376.900694 -199.49795)
		(width 0.12065)
		(layer "In4.Cu")
		(net "I2C_BMC_B_EXP_A_SCL")
	)
	(segment
		(start 390.463786 -143.380206)
		(end 376.931682 -156.91231)
		(width 0.12065)
		(layer "In4.Cu")
		(net "I2C_BMC_B_EXP_A_SCL")
	)
	(via
		(at 137.505948 -345.395804)
		(size 0.5588)
		(drill 0.3048)
		(layers "F.Cu" "B.Cu")
		(net "I2C_BMC_A_EXP_B_SDA")
	)
	(segment
		(start 139.0904 -267.1826)
		(end 138.8618 -267.4112)
		(width 0.12065)
		(layer "In4.Cu")
		(net "I2C_BMC_A_EXP_B_SDA")
	)
	(segment
		(start 134.349998 -25.950164)
		(end 133.679184 -26.620978)
		(width 0.12065)
		(layer "In4.Cu")
		(net "I2C_BMC_A_EXP_B_SDA")
	)
	(segment
		(start 133.679184 -26.620978)
		(end 133.679184 -31.11627)
		(width 0.12065)
		(layer "In4.Cu")
		(net "I2C_BMC_A_EXP_B_SDA")
	)
	(segment
		(start 125.43409 -158.735776)
		(end 133.666738 -166.968424)
		(width 0.12065)
		(layer "In4.Cu")
		(net "I2C_BMC_A_EXP_B_SDA")
	)
	(segment
		(start 139.37615 -282.60675)
		(end 139.37615 -285.997904)
		(width 0.12065)
		(layer "In4.Cu")
		(net "I2C_BMC_A_EXP_B_SDA")
	)
	(segment
		(start 123.23699 -150.744428)
		(end 125.43409 -152.941528)
		(width 0.12065)
		(layer "In4.Cu")
		(net "I2C_BMC_A_EXP_B_SDA")
	)
	(segment
		(start 123.23699 -128.441958)
		(end 123.23699 -150.744428)
		(width 0.12065)
		(layer "In4.Cu")
		(net "I2C_BMC_A_EXP_B_SDA")
	)
	(segment
		(start 134.034022 -83.772756)
		(end 127.358902 -90.447876)
		(width 0.12065)
		(layer "In4.Cu")
		(net "I2C_BMC_A_EXP_B_SDA")
	)
	(segment
		(start 134.99084 -339.866732)
		(end 135.115554 -339.991446)
		(width 0.12065)
		(layer "In4.Cu")
		(net "I2C_BMC_A_EXP_B_SDA")
	)
	(segment
		(start 135.115554 -343.00541)
		(end 137.505948 -345.395804)
		(width 0.12065)
		(layer "In4.Cu")
		(net "I2C_BMC_A_EXP_B_SDA")
	)
	(segment
		(start 144.933924 -192.272158)
		(end 147.437856 -194.77609)
		(width 0.12065)
		(layer "In4.Cu")
		(net "I2C_BMC_A_EXP_B_SDA")
	)
	(segment
		(start 139.120626 -237.5281)
		(end 139.120626 -248.180352)
		(width 0.12065)
		(layer "In4.Cu")
		(net "I2C_BMC_A_EXP_B_SDA")
	)
	(segment
		(start 127.359156 -124.319792)
		(end 123.23699 -128.441958)
		(width 0.12065)
		(layer "In4.Cu")
		(net "I2C_BMC_A_EXP_B_SDA")
	)
	(segment
		(start 127.358902 -90.447876)
		(end 127.358902 -122.179842)
		(width 0.12065)
		(layer "In4.Cu")
		(net "I2C_BMC_A_EXP_B_SDA")
	)
	(segment
		(start 133.666738 -175.426624)
		(end 144.933924 -186.69381)
		(width 0.12065)
		(layer "In4.Cu")
		(net "I2C_BMC_A_EXP_B_SDA")
	)
	(segment
		(start 139.2682 -286.105854)
		(end 139.2682 -313.087258)
		(width 0.12065)
		(layer "In4.Cu")
		(net "I2C_BMC_A_EXP_B_SDA")
	)
	(segment
		(start 139.120626 -248.180352)
		(end 139.0904 -248.210578)
		(width 0.12065)
		(layer "In4.Cu")
		(net "I2C_BMC_A_EXP_B_SDA")
	)
	(segment
		(start 139.2682 -313.087258)
		(end 134.99084 -317.364618)
		(width 0.12065)
		(layer "In4.Cu")
		(net "I2C_BMC_A_EXP_B_SDA")
	)
	(segment
		(start 134.034022 -31.471108)
		(end 134.034022 -83.772756)
		(width 0.12065)
		(layer "In4.Cu")
		(net "I2C_BMC_A_EXP_B_SDA")
	)
	(segment
		(start 138.8618 -282.0924)
		(end 139.37615 -282.60675)
		(width 0.12065)
		(layer "In4.Cu")
		(net "I2C_BMC_A_EXP_B_SDA")
	)
	(segment
		(start 147.437856 -194.77609)
		(end 147.437856 -229.21087)
		(width 0.12065)
		(layer "In4.Cu")
		(net "I2C_BMC_A_EXP_B_SDA")
	)
	(segment
		(start 138.8618 -267.4112)
		(end 138.8618 -282.0924)
		(width 0.12065)
		(layer "In4.Cu")
		(net "I2C_BMC_A_EXP_B_SDA")
	)
	(segment
		(start 134.99084 -317.364618)
		(end 134.99084 -339.866732)
		(width 0.12065)
		(layer "In4.Cu")
		(net "I2C_BMC_A_EXP_B_SDA")
	)
	(segment
		(start 147.437856 -229.21087)
		(end 139.120626 -237.5281)
		(width 0.12065)
		(layer "In4.Cu")
		(net "I2C_BMC_A_EXP_B_SDA")
	)
	(segment
		(start 133.679184 -31.11627)
		(end 134.034022 -31.471108)
		(width 0.12065)
		(layer "In4.Cu")
		(net "I2C_BMC_A_EXP_B_SDA")
	)
	(segment
		(start 127.358902 -122.179842)
		(end 127.359156 -122.180096)
		(width 0.12065)
		(layer "In4.Cu")
		(net "I2C_BMC_A_EXP_B_SDA")
	)
	(segment
		(start 135.115554 -339.991446)
		(end 135.115554 -343.00541)
		(width 0.12065)
		(layer "In4.Cu")
		(net "I2C_BMC_A_EXP_B_SDA")
	)
	(segment
		(start 139.37615 -285.997904)
		(end 139.2682 -286.105854)
		(width 0.12065)
		(layer "In4.Cu")
		(net "I2C_BMC_A_EXP_B_SDA")
	)
	(segment
		(start 127.359156 -122.180096)
		(end 127.359156 -124.319792)
		(width 0.12065)
		(layer "In4.Cu")
		(net "I2C_BMC_A_EXP_B_SDA")
	)
	(segment
		(start 125.43409 -152.941528)
		(end 125.43409 -158.735776)
		(width 0.12065)
		(layer "In4.Cu")
		(net "I2C_BMC_A_EXP_B_SDA")
	)
	(segment
		(start 144.933924 -186.69381)
		(end 144.933924 -192.272158)
		(width 0.12065)
		(layer "In4.Cu")
		(net "I2C_BMC_A_EXP_B_SDA")
	)
	(segment
		(start 133.666738 -166.968424)
		(end 133.666738 -175.426624)
		(width 0.12065)
		(layer "In4.Cu")
		(net "I2C_BMC_A_EXP_B_SDA")
	)
	(segment
		(start 139.0904 -248.210578)
		(end 139.0904 -267.1826)
		(width 0.12065)
		(layer "In4.Cu")
		(net "I2C_BMC_A_EXP_B_SDA")
	)
	(segment
		(start 217.8812 -417.1188)
		(end 217.8812 -403.892258)
		(width 0.12065)
		(layer "In7.Cu")
		(net "I2C_BMC_A_EXP_B_SDA")
	)
	(segment
		(start 217.8812 -403.892258)
		(end 207.65135 -393.662408)
		(width 0.12065)
		(layer "In7.Cu")
		(net "I2C_BMC_A_EXP_B_SDA")
	)
	(segment
		(start 217.199972 -417.800028)
		(end 217.8812 -417.1188)
		(width 0.12065)
		(layer "In7.Cu")
		(net "I2C_BMC_A_EXP_B_SDA")
	)
	(segment
		(start 207.65135 -351.711768)
		(end 201.335386 -345.395804)
		(width 0.12065)
		(layer "In7.Cu")
		(net "I2C_BMC_A_EXP_B_SDA")
	)
	(segment
		(start 201.335386 -345.395804)
		(end 137.505948 -345.395804)
		(width 0.12065)
		(layer "In7.Cu")
		(net "I2C_BMC_A_EXP_B_SDA")
	)
	(segment
		(start 207.65135 -393.662408)
		(end 207.65135 -351.711768)
		(width 0.12065)
		(layer "In7.Cu")
		(net "I2C_BMC_A_EXP_B_SDA")
	)
	(via
		(at 136.144 -345.395804)
		(size 0.5588)
		(drill 0.3048)
		(layers "F.Cu" "B.Cu")
		(net "I2C_BMC_A_EXP_B_SCL")
	)
	(segment
		(start 134.36219 -340.127336)
		(end 134.486904 -340.25205)
		(width 0.12065)
		(layer "In4.Cu")
		(net "I2C_BMC_A_EXP_B_SCL")
	)
	(segment
		(start 126.096522 -161.111692)
		(end 126.096522 -164.192204)
		(width 0.12065)
		(layer "In4.Cu")
		(net "I2C_BMC_A_EXP_B_SCL")
	)
	(segment
		(start 134.36219 -317.104014)
		(end 134.36219 -340.127336)
		(width 0.12065)
		(layer "In4.Cu")
		(net "I2C_BMC_A_EXP_B_SCL")
	)
	(segment
		(start 137.63625 -313.829954)
		(end 134.36219 -317.104014)
		(width 0.12065)
		(layer "In4.Cu")
		(net "I2C_BMC_A_EXP_B_SCL")
	)
	(segment
		(start 134.349998 -24.550116)
		(end 133.202934 -25.69718)
		(width 0.12065)
		(layer "In4.Cu")
		(net "I2C_BMC_A_EXP_B_SCL")
	)
	(segment
		(start 133.202934 -25.69718)
		(end 133.202934 -43.525694)
		(width 0.12065)
		(layer "In4.Cu")
		(net "I2C_BMC_A_EXP_B_SCL")
	)
	(segment
		(start 146.809206 -195.603876)
		(end 146.809206 -228.909626)
		(width 0.12065)
		(layer "In4.Cu")
		(net "I2C_BMC_A_EXP_B_SCL")
	)
	(segment
		(start 122.60834 -151.005032)
		(end 124.80544 -153.202132)
		(width 0.12065)
		(layer "In4.Cu")
		(net "I2C_BMC_A_EXP_B_SCL")
	)
	(segment
		(start 137.8331 -237.885732)
		(end 137.8331 -285.259272)
		(width 0.12065)
		(layer "In4.Cu")
		(net "I2C_BMC_A_EXP_B_SCL")
	)
	(segment
		(start 137.8331 -285.259272)
		(end 137.635996 -285.456376)
		(width 0.12065)
		(layer "In4.Cu")
		(net "I2C_BMC_A_EXP_B_SCL")
	)
	(segment
		(start 126.730252 -90.064844)
		(end 126.730252 -122.440446)
		(width 0.12065)
		(layer "In4.Cu")
		(net "I2C_BMC_A_EXP_B_SCL")
	)
	(segment
		(start 122.60834 -128.181354)
		(end 122.60834 -151.005032)
		(width 0.12065)
		(layer "In4.Cu")
		(net "I2C_BMC_A_EXP_B_SCL")
	)
	(segment
		(start 137.63625 -313.309254)
		(end 137.63625 -313.829954)
		(width 0.12065)
		(layer "In4.Cu")
		(net "I2C_BMC_A_EXP_B_SCL")
	)
	(segment
		(start 126.730506 -124.059188)
		(end 122.60834 -128.181354)
		(width 0.12065)
		(layer "In4.Cu")
		(net "I2C_BMC_A_EXP_B_SCL")
	)
	(segment
		(start 133.202934 -43.525694)
		(end 133.405372 -43.728132)
		(width 0.12065)
		(layer "In4.Cu")
		(net "I2C_BMC_A_EXP_B_SCL")
	)
	(segment
		(start 124.80544 -159.82061)
		(end 126.096522 -161.111692)
		(width 0.12065)
		(layer "In4.Cu")
		(net "I2C_BMC_A_EXP_B_SCL")
	)
	(segment
		(start 137.635996 -285.456376)
		(end 137.635996 -313.309)
		(width 0.12065)
		(layer "In4.Cu")
		(net "I2C_BMC_A_EXP_B_SCL")
	)
	(segment
		(start 126.096522 -164.192204)
		(end 133.038088 -171.13377)
		(width 0.12065)
		(layer "In4.Cu")
		(net "I2C_BMC_A_EXP_B_SCL")
	)
	(segment
		(start 134.486904 -343.266014)
		(end 136.144 -344.92311)
		(width 0.12065)
		(layer "In4.Cu")
		(net "I2C_BMC_A_EXP_B_SCL")
	)
	(segment
		(start 124.80544 -153.202132)
		(end 124.80544 -159.82061)
		(width 0.12065)
		(layer "In4.Cu")
		(net "I2C_BMC_A_EXP_B_SCL")
	)
	(segment
		(start 134.486904 -340.25205)
		(end 134.486904 -343.266014)
		(width 0.12065)
		(layer "In4.Cu")
		(net "I2C_BMC_A_EXP_B_SCL")
	)
	(segment
		(start 137.635996 -313.309)
		(end 137.63625 -313.309254)
		(width 0.12065)
		(layer "In4.Cu")
		(net "I2C_BMC_A_EXP_B_SCL")
	)
	(segment
		(start 133.405372 -83.389724)
		(end 126.730252 -90.064844)
		(width 0.12065)
		(layer "In4.Cu")
		(net "I2C_BMC_A_EXP_B_SCL")
	)
	(segment
		(start 133.038088 -171.13377)
		(end 133.038088 -175.687228)
		(width 0.12065)
		(layer "In4.Cu")
		(net "I2C_BMC_A_EXP_B_SCL")
	)
	(segment
		(start 144.122902 -186.772042)
		(end 144.122902 -192.917572)
		(width 0.12065)
		(layer "In4.Cu")
		(net "I2C_BMC_A_EXP_B_SCL")
	)
	(segment
		(start 126.730252 -122.440446)
		(end 126.730506 -122.4407)
		(width 0.12065)
		(layer "In4.Cu")
		(net "I2C_BMC_A_EXP_B_SCL")
	)
	(segment
		(start 133.038088 -175.687228)
		(end 144.122902 -186.772042)
		(width 0.12065)
		(layer "In4.Cu")
		(net "I2C_BMC_A_EXP_B_SCL")
	)
	(segment
		(start 133.405372 -43.728132)
		(end 133.405372 -83.389724)
		(width 0.12065)
		(layer "In4.Cu")
		(net "I2C_BMC_A_EXP_B_SCL")
	)
	(segment
		(start 136.144 -344.92311)
		(end 136.144 -345.395804)
		(width 0.12065)
		(layer "In4.Cu")
		(net "I2C_BMC_A_EXP_B_SCL")
	)
	(segment
		(start 126.730506 -122.4407)
		(end 126.730506 -124.059188)
		(width 0.12065)
		(layer "In4.Cu")
		(net "I2C_BMC_A_EXP_B_SCL")
	)
	(segment
		(start 146.809206 -228.909626)
		(end 137.8331 -237.885732)
		(width 0.12065)
		(layer "In4.Cu")
		(net "I2C_BMC_A_EXP_B_SCL")
	)
	(segment
		(start 144.122902 -192.917572)
		(end 146.809206 -195.603876)
		(width 0.12065)
		(layer "In4.Cu")
		(net "I2C_BMC_A_EXP_B_SCL")
	)
	(segment
		(start 208.28 -393.401804)
		(end 208.28 -351.451164)
		(width 0.12065)
		(layer "In7.Cu")
		(net "I2C_BMC_A_EXP_B_SCL")
	)
	(segment
		(start 201.506836 -344.678)
		(end 136.861804 -344.678)
		(width 0.12065)
		(layer "In7.Cu")
		(net "I2C_BMC_A_EXP_B_SCL")
	)
	(segment
		(start 217.199972 -419.200076)
		(end 218.35745 -418.042598)
		(width 0.12065)
		(layer "In7.Cu")
		(net "I2C_BMC_A_EXP_B_SCL")
	)
	(segment
		(start 218.35745 -403.479254)
		(end 208.28 -393.401804)
		(width 0.12065)
		(layer "In7.Cu")
		(net "I2C_BMC_A_EXP_B_SCL")
	)
	(segment
		(start 218.35745 -418.042598)
		(end 218.35745 -403.929342)
		(width 0.12065)
		(layer "In7.Cu")
		(net "I2C_BMC_A_EXP_B_SCL")
	)
	(segment
		(start 218.357704 -403.929088)
		(end 218.357704 -403.53488)
		(width 0.12065)
		(layer "In7.Cu")
		(net "I2C_BMC_A_EXP_B_SCL")
	)
	(segment
		(start 218.357704 -403.53488)
		(end 218.35745 -403.534626)
		(width 0.12065)
		(layer "In7.Cu")
		(net "I2C_BMC_A_EXP_B_SCL")
	)
	(segment
		(start 218.35745 -403.929342)
		(end 218.357704 -403.929088)
		(width 0.12065)
		(layer "In7.Cu")
		(net "I2C_BMC_A_EXP_B_SCL")
	)
	(segment
		(start 218.35745 -403.534626)
		(end 218.35745 -403.479254)
		(width 0.12065)
		(layer "In7.Cu")
		(net "I2C_BMC_A_EXP_B_SCL")
	)
	(segment
		(start 208.28 -351.451164)
		(end 201.506836 -344.678)
		(width 0.12065)
		(layer "In7.Cu")
		(net "I2C_BMC_A_EXP_B_SCL")
	)
	(segment
		(start 136.861804 -344.678)
		(end 136.144 -345.395804)
		(width 0.12065)
		(layer "In7.Cu")
		(net "I2C_BMC_A_EXP_B_SCL")
	)
	(segment
		(start 270.489172 -241.955066)
		(end 270.489172 -239.369346)
		(width 0.17145)
		(layer "F.Cu")
		(net "I2C_BMC_A_EXP_A_SDA")
	)
	(segment
		(start 272.932906 -244.3988)
		(end 270.489172 -241.955066)
		(width 0.17145)
		(layer "F.Cu")
		(net "I2C_BMC_A_EXP_A_SDA")
	)
	(segment
		(start 279.436068 -244.3988)
		(end 272.932906 -244.3988)
		(width 0.17145)
		(layer "F.Cu")
		(net "I2C_BMC_A_EXP_A_SDA")
	)
	(segment
		(start 282.213812 -247.176544)
		(end 279.436068 -244.3988)
		(width 0.17145)
		(layer "F.Cu")
		(net "I2C_BMC_A_EXP_A_SDA")
	)
	(segment
		(start 269.246096 -239.369346)
		(end 268.877034 -239.738408)
		(width 0.17145)
		(layer "F.Cu")
		(net "I2C_BMC_A_EXP_A_SDA")
	)
	(segment
		(start 282.213812 -250.725178)
		(end 282.213812 -247.176544)
		(width 0.17145)
		(layer "F.Cu")
		(net "I2C_BMC_A_EXP_A_SDA")
	)
	(segment
		(start 270.489172 -239.369346)
		(end 269.246096 -239.369346)
		(width 0.17145)
		(layer "F.Cu")
		(net "I2C_BMC_A_EXP_A_SDA")
	)
	(segment
		(start 281.836622 -251.102368)
		(end 282.213812 -250.725178)
		(width 0.17145)
		(layer "F.Cu")
		(net "I2C_BMC_A_EXP_A_SDA")
	)
	(via
		(at 140.318744 -264.793476)
		(size 0.5588)
		(drill 0.3048)
		(layers "F.Cu" "B.Cu")
		(net "I2C_BMC_A_EXP_A_SDA")
	)
	(via
		(at 268.877034 -239.738408)
		(size 0.5588)
		(drill 0.3048)
		(layers "F.Cu" "B.Cu")
		(net "I2C_BMC_A_EXP_A_SDA")
	)
	(via
		(at 266.322048 -259.430012)
		(size 0.5588)
		(drill 0.3048)
		(layers "F.Cu" "B.Cu")
		(net "I2C_BMC_A_EXP_A_SDA")
	)
	(segment
		(start 231.159812 -264.964926)
		(end 230.356156 -264.16127)
		(width 0.13335)
		(layer "In2.Cu")
		(net "I2C_BMC_A_EXP_A_SDA")
	)
	(segment
		(start 140.335 -264.77722)
		(end 140.318744 -264.793476)
		(width 0.13335)
		(layer "In2.Cu")
		(net "I2C_BMC_A_EXP_A_SDA")
	)
	(segment
		(start 140.335 -264.5664)
		(end 140.335 -264.77722)
		(width 0.13335)
		(layer "In2.Cu")
		(net "I2C_BMC_A_EXP_A_SDA")
	)
	(segment
		(start 193.106294 -264.16127)
		(end 192.905634 -263.96061)
		(width 0.13335)
		(layer "In2.Cu")
		(net "I2C_BMC_A_EXP_A_SDA")
	)
	(segment
		(start 230.356156 -264.16127)
		(end 193.106294 -264.16127)
		(width 0.13335)
		(layer "In2.Cu")
		(net "I2C_BMC_A_EXP_A_SDA")
	)
	(segment
		(start 192.905634 -263.96061)
		(end 140.94079 -263.96061)
		(width 0.13335)
		(layer "In2.Cu")
		(net "I2C_BMC_A_EXP_A_SDA")
	)
	(segment
		(start 260.787134 -264.964926)
		(end 231.159812 -264.964926)
		(width 0.13335)
		(layer "In2.Cu")
		(net "I2C_BMC_A_EXP_A_SDA")
	)
	(segment
		(start 140.94079 -263.96061)
		(end 140.335 -264.5664)
		(width 0.13335)
		(layer "In2.Cu")
		(net "I2C_BMC_A_EXP_A_SDA")
	)
	(segment
		(start 266.322048 -259.430012)
		(end 260.787134 -264.964926)
		(width 0.13335)
		(layer "In2.Cu")
		(net "I2C_BMC_A_EXP_A_SDA")
	)
	(segment
		(start 127.987552 -121.919238)
		(end 127.987806 -121.919492)
		(width 0.12065)
		(layer "In4.Cu")
		(net "I2C_BMC_A_EXP_A_SDA")
	)
	(segment
		(start 145.562574 -192.011554)
		(end 148.066506 -194.515486)
		(width 0.12065)
		(layer "In4.Cu")
		(net "I2C_BMC_A_EXP_A_SDA")
	)
	(segment
		(start 139.749276 -237.788704)
		(end 139.749276 -264.209276)
		(width 0.12065)
		(layer "In4.Cu")
		(net "I2C_BMC_A_EXP_A_SDA")
	)
	(segment
		(start 134.295388 -166.70782)
		(end 134.295388 -173.990508)
		(width 0.12065)
		(layer "In4.Cu")
		(net "I2C_BMC_A_EXP_A_SDA")
	)
	(segment
		(start 148.066506 -194.515486)
		(end 148.066506 -229.471474)
		(width 0.12065)
		(layer "In4.Cu")
		(net "I2C_BMC_A_EXP_A_SDA")
	)
	(segment
		(start 139.749276 -264.209276)
		(end 140.318744 -264.778744)
		(width 0.12065)
		(layer "In4.Cu")
		(net "I2C_BMC_A_EXP_A_SDA")
	)
	(segment
		(start 134.295388 -173.990508)
		(end 145.562574 -185.257694)
		(width 0.12065)
		(layer "In4.Cu")
		(net "I2C_BMC_A_EXP_A_SDA")
	)
	(segment
		(start 127.987552 -90.70848)
		(end 127.987552 -121.919238)
		(width 0.12065)
		(layer "In4.Cu")
		(net "I2C_BMC_A_EXP_A_SDA")
	)
	(segment
		(start 134.662672 -31.141416)
		(end 134.662672 -84.03336)
		(width 0.12065)
		(layer "In4.Cu")
		(net "I2C_BMC_A_EXP_A_SDA")
	)
	(segment
		(start 134.91845 -30.885638)
		(end 134.662672 -31.141416)
		(width 0.12065)
		(layer "In4.Cu")
		(net "I2C_BMC_A_EXP_A_SDA")
	)
	(segment
		(start 127.987806 -124.580396)
		(end 123.86564 -128.702562)
		(width 0.12065)
		(layer "In4.Cu")
		(net "I2C_BMC_A_EXP_A_SDA")
	)
	(segment
		(start 123.86564 -147.646136)
		(end 126.06274 -149.843236)
		(width 0.12065)
		(layer "In4.Cu")
		(net "I2C_BMC_A_EXP_A_SDA")
	)
	(segment
		(start 126.06274 -149.843236)
		(end 126.06274 -158.475172)
		(width 0.12065)
		(layer "In4.Cu")
		(net "I2C_BMC_A_EXP_A_SDA")
	)
	(segment
		(start 134.91845 -30.118558)
		(end 134.91845 -30.885638)
		(width 0.12065)
		(layer "In4.Cu")
		(net "I2C_BMC_A_EXP_A_SDA")
	)
	(segment
		(start 134.662672 -84.03336)
		(end 127.987552 -90.70848)
		(width 0.12065)
		(layer "In4.Cu")
		(net "I2C_BMC_A_EXP_A_SDA")
	)
	(segment
		(start 140.318744 -264.778744)
		(end 140.318744 -264.793476)
		(width 0.12065)
		(layer "In4.Cu")
		(net "I2C_BMC_A_EXP_A_SDA")
	)
	(segment
		(start 126.06274 -158.475172)
		(end 134.295388 -166.70782)
		(width 0.12065)
		(layer "In4.Cu")
		(net "I2C_BMC_A_EXP_A_SDA")
	)
	(segment
		(start 127.987806 -121.919492)
		(end 127.987806 -124.580396)
		(width 0.12065)
		(layer "In4.Cu")
		(net "I2C_BMC_A_EXP_A_SDA")
	)
	(segment
		(start 148.066506 -229.471474)
		(end 139.749276 -237.788704)
		(width 0.12065)
		(layer "In4.Cu")
		(net "I2C_BMC_A_EXP_A_SDA")
	)
	(segment
		(start 145.562574 -185.257694)
		(end 145.562574 -192.011554)
		(width 0.12065)
		(layer "In4.Cu")
		(net "I2C_BMC_A_EXP_A_SDA")
	)
	(segment
		(start 134.349998 -29.550106)
		(end 134.91845 -30.118558)
		(width 0.12065)
		(layer "In4.Cu")
		(net "I2C_BMC_A_EXP_A_SDA")
	)
	(segment
		(start 123.86564 -128.702562)
		(end 123.86564 -147.646136)
		(width 0.12065)
		(layer "In4.Cu")
		(net "I2C_BMC_A_EXP_A_SDA")
	)
	(segment
		(start 269.367 -250.570746)
		(end 269.367 -240.228374)
		(width 0.13335)
		(layer "In9.Cu")
		(net "I2C_BMC_A_EXP_A_SDA")
	)
	(segment
		(start 266.322048 -253.615698)
		(end 269.367 -250.570746)
		(width 0.13335)
		(layer "In9.Cu")
		(net "I2C_BMC_A_EXP_A_SDA")
	)
	(segment
		(start 266.322048 -259.430012)
		(end 266.322048 -253.615698)
		(width 0.13335)
		(layer "In9.Cu")
		(net "I2C_BMC_A_EXP_A_SDA")
	)
	(segment
		(start 269.367 -240.228374)
		(end 268.877034 -239.738408)
		(width 0.13335)
		(layer "In9.Cu")
		(net "I2C_BMC_A_EXP_A_SDA")
	)
	(segment
		(start 282.893262 -246.894858)
		(end 279.717754 -243.71935)
		(width 0.17145)
		(layer "F.Cu")
		(net "I2C_BMC_A_EXP_A_SCL")
	)
	(segment
		(start 279.717754 -243.71935)
		(end 273.214592 -243.71935)
		(width 0.17145)
		(layer "F.Cu")
		(net "I2C_BMC_A_EXP_A_SCL")
	)
	(segment
		(start 282.893262 -250.75896)
		(end 282.893262 -246.894858)
		(width 0.17145)
		(layer "F.Cu")
		(net "I2C_BMC_A_EXP_A_SCL")
	)
	(segment
		(start 273.214592 -243.71935)
		(end 271.759172 -242.26393)
		(width 0.17145)
		(layer "F.Cu")
		(net "I2C_BMC_A_EXP_A_SCL")
	)
	(segment
		(start 272.645632 -239.369346)
		(end 271.759172 -239.369346)
		(width 0.17145)
		(layer "F.Cu")
		(net "I2C_BMC_A_EXP_A_SCL")
	)
	(segment
		(start 271.759172 -242.26393)
		(end 271.759172 -239.369346)
		(width 0.17145)
		(layer "F.Cu")
		(net "I2C_BMC_A_EXP_A_SCL")
	)
	(segment
		(start 283.23667 -251.102368)
		(end 282.893262 -250.75896)
		(width 0.17145)
		(layer "F.Cu")
		(net "I2C_BMC_A_EXP_A_SCL")
	)
	(via
		(at 141.229588 -264.875518)
		(size 0.5588)
		(drill 0.3048)
		(layers "F.Cu" "B.Cu")
		(net "I2C_BMC_A_EXP_A_SCL")
	)
	(via
		(at 267.487146 -259.500878)
		(size 0.5588)
		(drill 0.3048)
		(layers "F.Cu" "B.Cu")
		(net "I2C_BMC_A_EXP_A_SCL")
	)
	(via
		(at 272.645632 -239.369346)
		(size 0.5588)
		(drill 0.3048)
		(layers "F.Cu" "B.Cu")
		(net "I2C_BMC_A_EXP_A_SCL")
	)
	(segment
		(start 230.038656 -264.80262)
		(end 192.84061 -264.80262)
		(width 0.13335)
		(layer "In2.Cu")
		(net "I2C_BMC_A_EXP_A_SCL")
	)
	(segment
		(start 192.63995 -264.60196)
		(end 141.503146 -264.60196)
		(width 0.13335)
		(layer "In2.Cu")
		(net "I2C_BMC_A_EXP_A_SCL")
	)
	(segment
		(start 192.84061 -264.80262)
		(end 192.63995 -264.60196)
		(width 0.13335)
		(layer "In2.Cu")
		(net "I2C_BMC_A_EXP_A_SCL")
	)
	(segment
		(start 141.503146 -264.60196)
		(end 141.229588 -264.875518)
		(width 0.13335)
		(layer "In2.Cu")
		(net "I2C_BMC_A_EXP_A_SCL")
	)
	(segment
		(start 267.487146 -259.500878)
		(end 261.381748 -265.606276)
		(width 0.13335)
		(layer "In2.Cu")
		(net "I2C_BMC_A_EXP_A_SCL")
	)
	(segment
		(start 261.381748 -265.606276)
		(end 230.842312 -265.606276)
		(width 0.13335)
		(layer "In2.Cu")
		(net "I2C_BMC_A_EXP_A_SCL")
	)
	(segment
		(start 230.842312 -265.606276)
		(end 230.038656 -264.80262)
		(width 0.13335)
		(layer "In2.Cu")
		(net "I2C_BMC_A_EXP_A_SCL")
	)
	(segment
		(start 128.616456 -124.841)
		(end 124.52731 -128.930146)
		(width 0.12065)
		(layer "In4.Cu")
		(net "I2C_BMC_A_EXP_A_SCL")
	)
	(segment
		(start 126.69139 -149.582632)
		(end 126.69139 -158.214568)
		(width 0.12065)
		(layer "In4.Cu")
		(net "I2C_BMC_A_EXP_A_SCL")
	)
	(segment
		(start 141.075156 -264.721086)
		(end 141.229588 -264.875518)
		(width 0.12065)
		(layer "In4.Cu")
		(net "I2C_BMC_A_EXP_A_SCL")
	)
	(segment
		(start 140.435076 -238.297974)
		(end 140.435076 -264.005822)
		(width 0.12065)
		(layer "In4.Cu")
		(net "I2C_BMC_A_EXP_A_SCL")
	)
	(segment
		(start 148.695156 -230.037894)
		(end 140.435076 -238.297974)
		(width 0.12065)
		(layer "In4.Cu")
		(net "I2C_BMC_A_EXP_A_SCL")
	)
	(segment
		(start 124.52731 -128.930146)
		(end 124.52731 -147.418552)
		(width 0.12065)
		(layer "In4.Cu")
		(net "I2C_BMC_A_EXP_A_SCL")
	)
	(segment
		(start 134.924038 -173.586648)
		(end 146.191224 -184.853834)
		(width 0.12065)
		(layer "In4.Cu")
		(net "I2C_BMC_A_EXP_A_SCL")
	)
	(segment
		(start 141.075156 -264.645902)
		(end 141.075156 -264.721086)
		(width 0.12065)
		(layer "In4.Cu")
		(net "I2C_BMC_A_EXP_A_SCL")
	)
	(segment
		(start 135.4582 -32.365696)
		(end 135.636254 -32.54375)
		(width 0.12065)
		(layer "In4.Cu")
		(net "I2C_BMC_A_EXP_A_SCL")
	)
	(segment
		(start 128.616202 -90.969084)
		(end 128.616202 -121.658634)
		(width 0.12065)
		(layer "In4.Cu")
		(net "I2C_BMC_A_EXP_A_SCL")
	)
	(segment
		(start 124.52731 -147.418552)
		(end 126.69139 -149.582632)
		(width 0.12065)
		(layer "In4.Cu")
		(net "I2C_BMC_A_EXP_A_SCL")
	)
	(segment
		(start 135.4582 -29.25826)
		(end 135.4582 -32.365696)
		(width 0.12065)
		(layer "In4.Cu")
		(net "I2C_BMC_A_EXP_A_SCL")
	)
	(segment
		(start 126.69139 -158.214568)
		(end 134.924038 -166.447216)
		(width 0.12065)
		(layer "In4.Cu")
		(net "I2C_BMC_A_EXP_A_SCL")
	)
	(segment
		(start 135.636254 -32.54375)
		(end 135.636254 -43.466004)
		(width 0.12065)
		(layer "In4.Cu")
		(net "I2C_BMC_A_EXP_A_SCL")
	)
	(segment
		(start 128.616202 -121.658634)
		(end 128.616456 -121.658888)
		(width 0.12065)
		(layer "In4.Cu")
		(net "I2C_BMC_A_EXP_A_SCL")
	)
	(segment
		(start 146.191224 -191.75095)
		(end 148.695156 -194.254882)
		(width 0.12065)
		(layer "In4.Cu")
		(net "I2C_BMC_A_EXP_A_SCL")
	)
	(segment
		(start 135.360664 -84.224622)
		(end 128.616202 -90.969084)
		(width 0.12065)
		(layer "In4.Cu")
		(net "I2C_BMC_A_EXP_A_SCL")
	)
	(segment
		(start 128.616456 -121.658888)
		(end 128.616456 -124.841)
		(width 0.12065)
		(layer "In4.Cu")
		(net "I2C_BMC_A_EXP_A_SCL")
	)
	(segment
		(start 134.349998 -28.150058)
		(end 135.4582 -29.25826)
		(width 0.12065)
		(layer "In4.Cu")
		(net "I2C_BMC_A_EXP_A_SCL")
	)
	(segment
		(start 135.360664 -43.741594)
		(end 135.360664 -84.224622)
		(width 0.12065)
		(layer "In4.Cu")
		(net "I2C_BMC_A_EXP_A_SCL")
	)
	(segment
		(start 134.924038 -166.447216)
		(end 134.924038 -173.586648)
		(width 0.12065)
		(layer "In4.Cu")
		(net "I2C_BMC_A_EXP_A_SCL")
	)
	(segment
		(start 140.435076 -264.005822)
		(end 141.075156 -264.645902)
		(width 0.12065)
		(layer "In4.Cu")
		(net "I2C_BMC_A_EXP_A_SCL")
	)
	(segment
		(start 135.636254 -43.466004)
		(end 135.360664 -43.741594)
		(width 0.12065)
		(layer "In4.Cu")
		(net "I2C_BMC_A_EXP_A_SCL")
	)
	(segment
		(start 148.695156 -194.254882)
		(end 148.695156 -230.037894)
		(width 0.12065)
		(layer "In4.Cu")
		(net "I2C_BMC_A_EXP_A_SCL")
	)
	(segment
		(start 146.191224 -184.853834)
		(end 146.191224 -191.75095)
		(width 0.12065)
		(layer "In4.Cu")
		(net "I2C_BMC_A_EXP_A_SCL")
	)
	(segment
		(start 270.590264 -241.424714)
		(end 270.590264 -250.868942)
		(width 0.13335)
		(layer "In9.Cu")
		(net "I2C_BMC_A_EXP_A_SCL")
	)
	(segment
		(start 267.487146 -253.97206)
		(end 267.487146 -259.500878)
		(width 0.13335)
		(layer "In9.Cu")
		(net "I2C_BMC_A_EXP_A_SCL")
	)
	(segment
		(start 272.645632 -239.369346)
		(end 270.590264 -241.424714)
		(width 0.13335)
		(layer "In9.Cu")
		(net "I2C_BMC_A_EXP_A_SCL")
	)
	(segment
		(start 270.590264 -250.868942)
		(end 267.487146 -253.97206)
		(width 0.13335)
		(layer "In9.Cu")
		(net "I2C_BMC_A_EXP_A_SCL")
	)
	(segment
		(start 87.061294 -21.331428)
		(end 87.453216 -20.939506)
		(width 0.17145)
		(layer "F.Cu")
		(net "FAN_3_INS_N")
	)
	(segment
		(start 257.945636 -257.79476)
		(end 257.945636 -260.05536)
		(width 0.17145)
		(layer "F.Cu")
		(net "FAN_3_INS_N")
	)
	(segment
		(start 340.604094 -24.41829)
		(end 340.604094 -20.994624)
		(width 0.17145)
		(layer "F.Cu")
		(net "FAN_3_INS_N")
	)
	(segment
		(start 87.061294 -22.22881)
		(end 87.061294 -21.331428)
		(width 0.17145)
		(layer "F.Cu")
		(net "FAN_3_INS_N")
	)
	(segment
		(start 340.604094 -20.994624)
		(end 340.604094 -20.017994)
		(width 0.17145)
		(layer "F.Cu")
		(net "FAN_3_INS_N")
	)
	(via
		(at 257.945636 -260.05536)
		(size 0.5588)
		(drill 0.3048)
		(layers "F.Cu" "B.Cu")
		(net "FAN_3_INS_N")
	)
	(via
		(at 340.604094 -20.994624)
		(size 0.6604)
		(drill 0.3302)
		(layers "F.Cu" "B.Cu")
		(net "FAN_3_INS_N")
	)
	(via
		(at 87.453216 -20.939506)
		(size 0.5588)
		(drill 0.3048)
		(layers "F.Cu" "B.Cu")
		(net "FAN_3_INS_N")
	)
	(via
		(at 340.604094 -20.017994)
		(size 0.5588)
		(drill 0.3048)
		(layers "F.Cu" "B.Cu")
		(net "FAN_3_INS_N")
	)
	(via
		(at 322.909184 -250.664218)
		(size 0.5588)
		(drill 0.3048)
		(layers "F.Cu" "B.Cu")
		(net "FAN_3_INS_N")
	)
	(segment
		(start 246.505222 -87.828374)
		(end 246.505222 -10.936478)
		(width 0.13335)
		(layer "In2.Cu")
		(net "FAN_3_INS_N")
	)
	(segment
		(start 127.418338 -38.156896)
		(end 146.870166 -38.156896)
		(width 0.13335)
		(layer "In2.Cu")
		(net "FAN_3_INS_N")
	)
	(segment
		(start 103.113586 -35.646106)
		(end 124.907548 -35.646106)
		(width 0.13335)
		(layer "In2.Cu")
		(net "FAN_3_INS_N")
	)
	(segment
		(start 259.140452 1.698752)
		(end 286.17418 1.698752)
		(width 0.13335)
		(layer "In2.Cu")
		(net "FAN_3_INS_N")
	)
	(segment
		(start 338.72678 -18.777966)
		(end 339.364066 -18.777966)
		(width 0.13335)
		(layer "In2.Cu")
		(net "FAN_3_INS_N")
	)
	(segment
		(start 169.78122 -36.784026)
		(end 182.202074 -49.20488)
		(width 0.13335)
		(layer "In2.Cu")
		(net "FAN_3_INS_N")
	)
	(segment
		(start 267.754354 -254.06985)
		(end 262.947404 -258.8768)
		(width 0.13335)
		(layer "In2.Cu")
		(net "FAN_3_INS_N")
	)
	(segment
		(start 147.744688 -37.282374)
		(end 147.744688 -37.28212)
		(width 0.13335)
		(layer "In2.Cu")
		(net "FAN_3_INS_N")
	)
	(segment
		(start 87.453216 -20.939506)
		(end 89.189814 -22.676104)
		(width 0.13335)
		(layer "In2.Cu")
		(net "FAN_3_INS_N")
	)
	(segment
		(start 90.143584 -22.676104)
		(end 103.113586 -35.646106)
		(width 0.13335)
		(layer "In2.Cu")
		(net "FAN_3_INS_N")
	)
	(segment
		(start 182.202074 -49.20488)
		(end 182.202074 -54.697884)
		(width 0.13335)
		(layer "In2.Cu")
		(net "FAN_3_INS_N")
	)
	(segment
		(start 147.744688 -37.28212)
		(end 148.242782 -36.784026)
		(width 0.13335)
		(layer "In2.Cu")
		(net "FAN_3_INS_N")
	)
	(segment
		(start 312.424826 -250.689872)
		(end 305.038252 -258.076446)
		(width 0.13335)
		(layer "In2.Cu")
		(net "FAN_3_INS_N")
	)
	(segment
		(start 235.659168 -89.615772)
		(end 244.717824 -89.615772)
		(width 0.13335)
		(layer "In2.Cu")
		(net "FAN_3_INS_N")
	)
	(segment
		(start 322.88353 -250.689872)
		(end 312.424826 -250.689872)
		(width 0.13335)
		(layer "In2.Cu")
		(net "FAN_3_INS_N")
	)
	(segment
		(start 286.17418 1.698752)
		(end 286.174434 1.699006)
		(width 0.13335)
		(layer "In2.Cu")
		(net "FAN_3_INS_N")
	)
	(segment
		(start 286.87903 1.699006)
		(end 295.63314 -7.055104)
		(width 0.13335)
		(layer "In2.Cu")
		(net "FAN_3_INS_N")
	)
	(segment
		(start 305.038252 -258.076446)
		(end 297.657774 -258.076446)
		(width 0.13335)
		(layer "In2.Cu")
		(net "FAN_3_INS_N")
	)
	(segment
		(start 257.945636 -259.340096)
		(end 257.945636 -260.05536)
		(width 0.13335)
		(layer "In2.Cu")
		(net "FAN_3_INS_N")
	)
	(segment
		(start 307.644546 -7.055104)
		(end 311.80405 -11.214608)
		(width 0.13335)
		(layer "In2.Cu")
		(net "FAN_3_INS_N")
	)
	(segment
		(start 338.448396 -19.05635)
		(end 338.72678 -18.777966)
		(width 0.13335)
		(layer "In2.Cu")
		(net "FAN_3_INS_N")
	)
	(segment
		(start 187.41898 -59.91479)
		(end 187.41898 -76.044552)
		(width 0.13335)
		(layer "In2.Cu")
		(net "FAN_3_INS_N")
	)
	(segment
		(start 196.7103 -85.335872)
		(end 200.650602 -85.335872)
		(width 0.13335)
		(layer "In2.Cu")
		(net "FAN_3_INS_N")
	)
	(segment
		(start 271.739614 -254.06985)
		(end 267.754354 -254.06985)
		(width 0.13335)
		(layer "In2.Cu")
		(net "FAN_3_INS_N")
	)
	(segment
		(start 286.174434 1.699006)
		(end 286.87903 1.699006)
		(width 0.13335)
		(layer "In2.Cu")
		(net "FAN_3_INS_N")
	)
	(segment
		(start 200.650602 -85.335872)
		(end 200.683622 -85.368892)
		(width 0.13335)
		(layer "In2.Cu")
		(net "FAN_3_INS_N")
	)
	(segment
		(start 295.63314 -7.055104)
		(end 307.644546 -7.055104)
		(width 0.13335)
		(layer "In2.Cu")
		(net "FAN_3_INS_N")
	)
	(segment
		(start 339.364066 -18.777966)
		(end 340.604094 -20.017994)
		(width 0.13335)
		(layer "In2.Cu")
		(net "FAN_3_INS_N")
	)
	(segment
		(start 288.438844 -248.857516)
		(end 276.951948 -248.857516)
		(width 0.13335)
		(layer "In2.Cu")
		(net "FAN_3_INS_N")
	)
	(segment
		(start 148.242782 -36.784026)
		(end 169.78122 -36.784026)
		(width 0.13335)
		(layer "In2.Cu")
		(net "FAN_3_INS_N")
	)
	(segment
		(start 258.408932 -258.8768)
		(end 257.945636 -259.340096)
		(width 0.13335)
		(layer "In2.Cu")
		(net "FAN_3_INS_N")
	)
	(segment
		(start 89.189814 -22.676104)
		(end 90.143584 -22.676104)
		(width 0.13335)
		(layer "In2.Cu")
		(net "FAN_3_INS_N")
	)
	(segment
		(start 187.41898 -76.044552)
		(end 196.7103 -85.335872)
		(width 0.13335)
		(layer "In2.Cu")
		(net "FAN_3_INS_N")
	)
	(segment
		(start 297.657774 -258.076446)
		(end 288.438844 -248.857516)
		(width 0.13335)
		(layer "In2.Cu")
		(net "FAN_3_INS_N")
	)
	(segment
		(start 231.412288 -85.368892)
		(end 235.659168 -89.615772)
		(width 0.13335)
		(layer "In2.Cu")
		(net "FAN_3_INS_N")
	)
	(segment
		(start 276.951948 -248.857516)
		(end 271.739614 -254.06985)
		(width 0.13335)
		(layer "In2.Cu")
		(net "FAN_3_INS_N")
	)
	(segment
		(start 244.717824 -89.615772)
		(end 246.505222 -87.828374)
		(width 0.13335)
		(layer "In2.Cu")
		(net "FAN_3_INS_N")
	)
	(segment
		(start 311.80405 -11.214608)
		(end 311.80405 -16.24965)
		(width 0.13335)
		(layer "In2.Cu")
		(net "FAN_3_INS_N")
	)
	(segment
		(start 124.907548 -35.646106)
		(end 127.418338 -38.156896)
		(width 0.13335)
		(layer "In2.Cu")
		(net "FAN_3_INS_N")
	)
	(segment
		(start 146.870166 -38.156896)
		(end 147.744688 -37.282374)
		(width 0.13335)
		(layer "In2.Cu")
		(net "FAN_3_INS_N")
	)
	(segment
		(start 182.202074 -54.697884)
		(end 187.41898 -59.91479)
		(width 0.13335)
		(layer "In2.Cu")
		(net "FAN_3_INS_N")
	)
	(segment
		(start 246.505222 -10.936478)
		(end 259.140452 1.698752)
		(width 0.13335)
		(layer "In2.Cu")
		(net "FAN_3_INS_N")
	)
	(segment
		(start 322.909184 -250.664218)
		(end 322.88353 -250.689872)
		(width 0.13335)
		(layer "In2.Cu")
		(net "FAN_3_INS_N")
	)
	(segment
		(start 200.683622 -85.368892)
		(end 231.412288 -85.368892)
		(width 0.13335)
		(layer "In2.Cu")
		(net "FAN_3_INS_N")
	)
	(segment
		(start 262.947404 -258.8768)
		(end 258.408932 -258.8768)
		(width 0.13335)
		(layer "In2.Cu")
		(net "FAN_3_INS_N")
	)
	(segment
		(start 311.80405 -16.24965)
		(end 314.61075 -19.05635)
		(width 0.13335)
		(layer "In2.Cu")
		(net "FAN_3_INS_N")
	)
	(segment
		(start 314.61075 -19.05635)
		(end 338.448396 -19.05635)
		(width 0.13335)
		(layer "In2.Cu")
		(net "FAN_3_INS_N")
	)
	(segment
		(start 336.431382 -36.149534)
		(end 336.929222 -35.651694)
		(width 0.12065)
		(layer "In4.Cu")
		(net "FAN_3_INS_N")
	)
	(segment
		(start 328.769218 -67.813936)
		(end 331.76845 -64.814704)
		(width 0.12065)
		(layer "In4.Cu")
		(net "FAN_3_INS_N")
	)
	(segment
		(start 338.168234 -32.219392)
		(end 338.168234 -26.345388)
		(width 0.12065)
		(layer "In4.Cu")
		(net "FAN_3_INS_N")
	)
	(segment
		(start 320.2178 -221.389194)
		(end 320.2178 -203.603098)
		(width 0.12065)
		(layer "In4.Cu")
		(net "FAN_3_INS_N")
	)
	(segment
		(start 320.760598 -77.725524)
		(end 328.769218 -69.716904)
		(width 0.12065)
		(layer "In4.Cu")
		(net "FAN_3_INS_N")
	)
	(segment
		(start 336.928968 -34.827718)
		(end 336.928968 -34.485834)
		(width 0.12065)
		(layer "In4.Cu")
		(net "FAN_3_INS_N")
	)
	(segment
		(start 331.76845 -48.27905)
		(end 336.431382 -43.616118)
		(width 0.12065)
		(layer "In4.Cu")
		(net "FAN_3_INS_N")
	)
	(segment
		(start 336.928968 -34.485834)
		(end 338.168488 -33.246314)
		(width 0.12065)
		(layer "In4.Cu")
		(net "FAN_3_INS_N")
	)
	(segment
		(start 336.929222 -35.651694)
		(end 336.929222 -34.827972)
		(width 0.12065)
		(layer "In4.Cu")
		(net "FAN_3_INS_N")
	)
	(segment
		(start 320.760598 -147.48891)
		(end 320.760598 -77.725524)
		(width 0.12065)
		(layer "In4.Cu")
		(net "FAN_3_INS_N")
	)
	(segment
		(start 331.76845 -64.814704)
		(end 331.76845 -48.27905)
		(width 0.12065)
		(layer "In4.Cu")
		(net "FAN_3_INS_N")
	)
	(segment
		(start 340.604094 -23.909528)
		(end 340.604094 -20.017994)
		(width 0.12065)
		(layer "In4.Cu")
		(net "FAN_3_INS_N")
	)
	(segment
		(start 338.168234 -26.345388)
		(end 340.604094 -23.909528)
		(width 0.12065)
		(layer "In4.Cu")
		(net "FAN_3_INS_N")
	)
	(segment
		(start 336.431382 -43.616118)
		(end 336.431382 -36.149534)
		(width 0.12065)
		(layer "In4.Cu")
		(net "FAN_3_INS_N")
	)
	(segment
		(start 319.77965 -172.962824)
		(end 319.547748 -172.730922)
		(width 0.12065)
		(layer "In4.Cu")
		(net "FAN_3_INS_N")
	)
	(segment
		(start 319.547748 -154.075892)
		(end 320.2178 -153.40584)
		(width 0.12065)
		(layer "In4.Cu")
		(net "FAN_3_INS_N")
	)
	(segment
		(start 319.547748 -172.730922)
		(end 319.547748 -154.075892)
		(width 0.12065)
		(layer "In4.Cu")
		(net "FAN_3_INS_N")
	)
	(segment
		(start 322.909184 -224.080578)
		(end 320.2178 -221.389194)
		(width 0.12065)
		(layer "In4.Cu")
		(net "FAN_3_INS_N")
	)
	(segment
		(start 328.769218 -69.716904)
		(end 328.769218 -67.813936)
		(width 0.12065)
		(layer "In4.Cu")
		(net "FAN_3_INS_N")
	)
	(segment
		(start 320.2178 -203.603098)
		(end 319.77965 -203.164948)
		(width 0.12065)
		(layer "In4.Cu")
		(net "FAN_3_INS_N")
	)
	(segment
		(start 336.929222 -34.827972)
		(end 336.928968 -34.827718)
		(width 0.12065)
		(layer "In4.Cu")
		(net "FAN_3_INS_N")
	)
	(segment
		(start 319.77965 -203.164948)
		(end 319.77965 -172.962824)
		(width 0.12065)
		(layer "In4.Cu")
		(net "FAN_3_INS_N")
	)
	(segment
		(start 320.2178 -148.031708)
		(end 320.760598 -147.48891)
		(width 0.12065)
		(layer "In4.Cu")
		(net "FAN_3_INS_N")
	)
	(segment
		(start 320.2178 -153.40584)
		(end 320.2178 -148.031708)
		(width 0.12065)
		(layer "In4.Cu")
		(net "FAN_3_INS_N")
	)
	(segment
		(start 338.168488 -33.246314)
		(end 338.168488 -32.219646)
		(width 0.12065)
		(layer "In4.Cu")
		(net "FAN_3_INS_N")
	)
	(segment
		(start 322.909184 -250.664218)
		(end 322.909184 -224.080578)
		(width 0.12065)
		(layer "In4.Cu")
		(net "FAN_3_INS_N")
	)
	(segment
		(start 338.168488 -32.219646)
		(end 338.168234 -32.219392)
		(width 0.12065)
		(layer "In4.Cu")
		(net "FAN_3_INS_N")
	)
	(segment
		(start 256.544572 -262.030464)
		(end 257.945636 -260.6294)
		(width 0.13335)
		(layer "In9.Cu")
		(net "FAN_3_INS_N")
	)
	(segment
		(start 224.84715 -382.51511)
		(end 224.84715 -380.299976)
		(width 0.13335)
		(layer "In9.Cu")
		(net "FAN_3_INS_N")
	)
	(segment
		(start 228.40442 -402.275294)
		(end 224.428304 -398.299178)
		(width 0.13335)
		(layer "In9.Cu")
		(net "FAN_3_INS_N")
	)
	(segment
		(start 224.811336 -371.47119)
		(end 230.425498 -365.857028)
		(width 0.13335)
		(layer "In9.Cu")
		(net "FAN_3_INS_N")
	)
	(segment
		(start 253.993142 -283.137356)
		(end 253.993142 -267.88872)
		(width 0.13335)
		(layer "In9.Cu")
		(net "FAN_3_INS_N")
	)
	(segment
		(start 229.150672 -413.449516)
		(end 229.150672 -402.93163)
		(width 0.13335)
		(layer "In9.Cu")
		(net "FAN_3_INS_N")
	)
	(segment
		(start 228.494336 -402.275294)
		(end 228.40442 -402.275294)
		(width 0.13335)
		(layer "In9.Cu")
		(net "FAN_3_INS_N")
	)
	(segment
		(start 230.425498 -365.857028)
		(end 230.425498 -336.59445)
		(width 0.13335)
		(layer "In9.Cu")
		(net "FAN_3_INS_N")
	)
	(segment
		(start 228.000052 -414.600136)
		(end 229.150672 -413.449516)
		(width 0.13335)
		(layer "In9.Cu")
		(net "FAN_3_INS_N")
	)
	(segment
		(start 224.811336 -380.264162)
		(end 224.811336 -371.47119)
		(width 0.13335)
		(layer "In9.Cu")
		(net "FAN_3_INS_N")
	)
	(segment
		(start 224.428304 -382.933956)
		(end 224.84715 -382.51511)
		(width 0.13335)
		(layer "In9.Cu")
		(net "FAN_3_INS_N")
	)
	(segment
		(start 253.993142 -267.88872)
		(end 256.544572 -265.33729)
		(width 0.13335)
		(layer "In9.Cu")
		(net "FAN_3_INS_N")
	)
	(segment
		(start 241.150902 -295.979596)
		(end 253.993142 -283.137356)
		(width 0.13335)
		(layer "In9.Cu")
		(net "FAN_3_INS_N")
	)
	(segment
		(start 241.150902 -325.869046)
		(end 241.150902 -295.979596)
		(width 0.13335)
		(layer "In9.Cu")
		(net "FAN_3_INS_N")
	)
	(segment
		(start 256.544572 -265.33729)
		(end 256.544572 -262.030464)
		(width 0.13335)
		(layer "In9.Cu")
		(net "FAN_3_INS_N")
	)
	(segment
		(start 257.945636 -260.6294)
		(end 257.945636 -260.05536)
		(width 0.13335)
		(layer "In9.Cu")
		(net "FAN_3_INS_N")
	)
	(segment
		(start 230.425498 -336.59445)
		(end 241.150902 -325.869046)
		(width 0.13335)
		(layer "In9.Cu")
		(net "FAN_3_INS_N")
	)
	(segment
		(start 224.84715 -380.299976)
		(end 224.811336 -380.264162)
		(width 0.13335)
		(layer "In9.Cu")
		(net "FAN_3_INS_N")
	)
	(segment
		(start 229.150672 -402.93163)
		(end 228.494336 -402.275294)
		(width 0.13335)
		(layer "In9.Cu")
		(net "FAN_3_INS_N")
	)
	(segment
		(start 224.428304 -398.299178)
		(end 224.428304 -382.933956)
		(width 0.13335)
		(layer "In9.Cu")
		(net "FAN_3_INS_N")
	)
	(segment
		(start 340.089744 -23.279608)
		(end 340.089744 -21.573744)
		(width 0.17145)
		(layer "F.Cu")
		(net "FAN_2_INS_N")
	)
	(segment
		(start 338.987892 -19.276568)
		(end 339.642704 -19.93138)
		(width 0.17145)
		(layer "F.Cu")
		(net "FAN_2_INS_N")
	)
	(segment
		(start 86.411054 -22.22881)
		(end 86.411054 -21.006308)
		(width 0.17145)
		(layer "F.Cu")
		(net "FAN_2_INS_N")
	)
	(segment
		(start 340.089744 -21.573744)
		(end 339.979 -21.463)
		(width 0.17145)
		(layer "F.Cu")
		(net "FAN_2_INS_N")
	)
	(segment
		(start 86.411054 -21.006308)
		(end 86.338156 -20.93341)
		(width 0.17145)
		(layer "F.Cu")
		(net "FAN_2_INS_N")
	)
	(segment
		(start 339.979 -20.717256)
		(end 339.642704 -20.38096)
		(width 0.17145)
		(layer "F.Cu")
		(net "FAN_2_INS_N")
	)
	(segment
		(start 339.953854 -23.415498)
		(end 340.089744 -23.279608)
		(width 0.17145)
		(layer "F.Cu")
		(net "FAN_2_INS_N")
	)
	(segment
		(start 258.595876 -257.79476)
		(end 258.595876 -259.39496)
		(width 0.17145)
		(layer "F.Cu")
		(net "FAN_2_INS_N")
	)
	(segment
		(start 338.933282 -19.276568)
		(end 338.987892 -19.276568)
		(width 0.17145)
		(layer "F.Cu")
		(net "FAN_2_INS_N")
	)
	(segment
		(start 339.953854 -24.41829)
		(end 339.953854 -23.415498)
		(width 0.17145)
		(layer "F.Cu")
		(net "FAN_2_INS_N")
	)
	(segment
		(start 339.642704 -20.38096)
		(end 339.642704 -19.93138)
		(width 0.17145)
		(layer "F.Cu")
		(net "FAN_2_INS_N")
	)
	(segment
		(start 339.979 -21.463)
		(end 339.979 -20.717256)
		(width 0.17145)
		(layer "F.Cu")
		(net "FAN_2_INS_N")
	)
	(via
		(at 86.338156 -20.93341)
		(size 0.5588)
		(drill 0.3048)
		(layers "F.Cu" "B.Cu")
		(net "FAN_2_INS_N")
	)
	(via
		(at 339.642704 -19.93138)
		(size 0.6604)
		(drill 0.3302)
		(layers "F.Cu" "B.Cu")
		(net "FAN_2_INS_N")
	)
	(via
		(at 338.933282 -19.276568)
		(size 0.5588)
		(drill 0.3048)
		(layers "F.Cu" "B.Cu")
		(net "FAN_2_INS_N")
	)
	(via
		(at 226.82708 -397.89862)
		(size 0.5588)
		(drill 0.3048)
		(layers "F.Cu" "B.Cu")
		(net "FAN_2_INS_N")
	)
	(via
		(at 258.595876 -259.39496)
		(size 0.5588)
		(drill 0.3048)
		(layers "F.Cu" "B.Cu")
		(net "FAN_2_INS_N")
	)
	(via
		(at 322.168012 -251.614432)
		(size 0.5588)
		(drill 0.3048)
		(layers "F.Cu" "B.Cu")
		(net "FAN_2_INS_N")
	)
	(segment
		(start 286.702754 1.273556)
		(end 295.456864 -7.480554)
		(width 0.13335)
		(layer "In2.Cu")
		(net "FAN_2_INS_N")
	)
	(segment
		(start 286.350456 1.273302)
		(end 286.35071 1.273556)
		(width 0.13335)
		(layer "In2.Cu")
		(net "FAN_2_INS_N")
	)
	(segment
		(start 297.481498 -258.501896)
		(end 288.262568 -249.282966)
		(width 0.13335)
		(layer "In2.Cu")
		(net "FAN_2_INS_N")
	)
	(segment
		(start 311.3786 -11.390884)
		(end 311.3786 -18.20418)
		(width 0.13335)
		(layer "In2.Cu")
		(net "FAN_2_INS_N")
	)
	(segment
		(start 183.931814 -74.385932)
		(end 183.931814 -76.944474)
		(width 0.13335)
		(layer "In2.Cu")
		(net "FAN_2_INS_N")
	)
	(segment
		(start 321.668902 -251.115322)
		(end 312.6867 -251.115322)
		(width 0.13335)
		(layer "In2.Cu")
		(net "FAN_2_INS_N")
	)
	(segment
		(start 338.72805 -19.4818)
		(end 338.933282 -19.276568)
		(width 0.13335)
		(layer "In2.Cu")
		(net "FAN_2_INS_N")
	)
	(segment
		(start 164.513006 -37.209476)
		(end 176.759362 -49.455832)
		(width 0.13335)
		(layer "In2.Cu")
		(net "FAN_2_INS_N")
	)
	(segment
		(start 177.586894 -49.455832)
		(end 178.31435 -50.183288)
		(width 0.13335)
		(layer "In2.Cu")
		(net "FAN_2_INS_N")
	)
	(segment
		(start 271.91589 -254.4953)
		(end 268.016228 -254.4953)
		(width 0.13335)
		(layer "In2.Cu")
		(net "FAN_2_INS_N")
	)
	(segment
		(start 295.456864 -7.480554)
		(end 307.46827 -7.480554)
		(width 0.13335)
		(layer "In2.Cu")
		(net "FAN_2_INS_N")
	)
	(segment
		(start 179.342796 -53.845206)
		(end 183.907684 -58.410094)
		(width 0.13335)
		(layer "In2.Cu")
		(net "FAN_2_INS_N")
	)
	(segment
		(start 307.46827 -7.480554)
		(end 311.3786 -11.390884)
		(width 0.13335)
		(layer "In2.Cu")
		(net "FAN_2_INS_N")
	)
	(segment
		(start 183.907684 -58.410094)
		(end 183.907684 -74.361802)
		(width 0.13335)
		(layer "In2.Cu")
		(net "FAN_2_INS_N")
	)
	(segment
		(start 192.951862 -85.964522)
		(end 231.1019 -85.964522)
		(width 0.13335)
		(layer "In2.Cu")
		(net "FAN_2_INS_N")
	)
	(segment
		(start 277.128224 -249.282966)
		(end 271.91589 -254.4953)
		(width 0.13335)
		(layer "In2.Cu")
		(net "FAN_2_INS_N")
	)
	(segment
		(start 312.6867 -251.115322)
		(end 305.300126 -258.501896)
		(width 0.13335)
		(layer "In2.Cu")
		(net "FAN_2_INS_N")
	)
	(segment
		(start 148.170138 -37.458396)
		(end 148.419058 -37.209476)
		(width 0.13335)
		(layer "In2.Cu")
		(net "FAN_2_INS_N")
	)
	(segment
		(start 183.907684 -74.361802)
		(end 183.931814 -74.385932)
		(width 0.13335)
		(layer "In2.Cu")
		(net "FAN_2_INS_N")
	)
	(segment
		(start 246.987822 -87.979504)
		(end 246.987822 -11.636756)
		(width 0.13335)
		(layer "In2.Cu")
		(net "FAN_2_INS_N")
	)
	(segment
		(start 147.046442 -38.582346)
		(end 148.170138 -37.45865)
		(width 0.13335)
		(layer "In2.Cu")
		(net "FAN_2_INS_N")
	)
	(segment
		(start 178.31435 -50.183288)
		(end 178.31435 -51.136296)
		(width 0.13335)
		(layer "In2.Cu")
		(net "FAN_2_INS_N")
	)
	(segment
		(start 125.732794 -37.209476)
		(end 127.105664 -38.582346)
		(width 0.13335)
		(layer "In2.Cu")
		(net "FAN_2_INS_N")
	)
	(segment
		(start 286.35071 1.273556)
		(end 286.702754 1.273556)
		(width 0.13335)
		(layer "In2.Cu")
		(net "FAN_2_INS_N")
	)
	(segment
		(start 178.31435 -51.136296)
		(end 179.342796 -52.164742)
		(width 0.13335)
		(layer "In2.Cu")
		(net "FAN_2_INS_N")
	)
	(segment
		(start 90.091768 -23.25243)
		(end 90.102944 -23.25243)
		(width 0.13335)
		(layer "In2.Cu")
		(net "FAN_2_INS_N")
	)
	(segment
		(start 183.931814 -76.944474)
		(end 192.951862 -85.964522)
		(width 0.13335)
		(layer "In2.Cu")
		(net "FAN_2_INS_N")
	)
	(segment
		(start 88.5063 -23.101554)
		(end 89.940892 -23.101554)
		(width 0.13335)
		(layer "In2.Cu")
		(net "FAN_2_INS_N")
	)
	(segment
		(start 322.168012 -251.614432)
		(end 321.668902 -251.115322)
		(width 0.13335)
		(layer "In2.Cu")
		(net "FAN_2_INS_N")
	)
	(segment
		(start 311.3786 -18.20418)
		(end 312.65622 -19.4818)
		(width 0.13335)
		(layer "In2.Cu")
		(net "FAN_2_INS_N")
	)
	(segment
		(start 86.338156 -20.93341)
		(end 88.5063 -23.101554)
		(width 0.13335)
		(layer "In2.Cu")
		(net "FAN_2_INS_N")
	)
	(segment
		(start 127.105664 -38.582346)
		(end 147.046442 -38.582346)
		(width 0.13335)
		(layer "In2.Cu")
		(net "FAN_2_INS_N")
	)
	(segment
		(start 268.016228 -254.4953)
		(end 263.116568 -259.39496)
		(width 0.13335)
		(layer "In2.Cu")
		(net "FAN_2_INS_N")
	)
	(segment
		(start 104.05999 -37.209476)
		(end 125.732794 -37.209476)
		(width 0.13335)
		(layer "In2.Cu")
		(net "FAN_2_INS_N")
	)
	(segment
		(start 148.170138 -37.45865)
		(end 148.170138 -37.458396)
		(width 0.13335)
		(layer "In2.Cu")
		(net "FAN_2_INS_N")
	)
	(segment
		(start 305.300126 -258.501896)
		(end 297.481498 -258.501896)
		(width 0.13335)
		(layer "In2.Cu")
		(net "FAN_2_INS_N")
	)
	(segment
		(start 148.419058 -37.209476)
		(end 164.513006 -37.209476)
		(width 0.13335)
		(layer "In2.Cu")
		(net "FAN_2_INS_N")
	)
	(segment
		(start 259.89788 1.273302)
		(end 286.350456 1.273302)
		(width 0.13335)
		(layer "In2.Cu")
		(net "FAN_2_INS_N")
	)
	(segment
		(start 235.1786 -90.041222)
		(end 244.926104 -90.041222)
		(width 0.13335)
		(layer "In2.Cu")
		(net "FAN_2_INS_N")
	)
	(segment
		(start 90.102944 -23.25243)
		(end 104.05999 -37.209476)
		(width 0.13335)
		(layer "In2.Cu")
		(net "FAN_2_INS_N")
	)
	(segment
		(start 231.1019 -85.964522)
		(end 235.1786 -90.041222)
		(width 0.13335)
		(layer "In2.Cu")
		(net "FAN_2_INS_N")
	)
	(segment
		(start 288.262568 -249.282966)
		(end 277.128224 -249.282966)
		(width 0.13335)
		(layer "In2.Cu")
		(net "FAN_2_INS_N")
	)
	(segment
		(start 263.116568 -259.39496)
		(end 258.595876 -259.39496)
		(width 0.13335)
		(layer "In2.Cu")
		(net "FAN_2_INS_N")
	)
	(segment
		(start 179.342796 -52.164742)
		(end 179.342796 -53.845206)
		(width 0.13335)
		(layer "In2.Cu")
		(net "FAN_2_INS_N")
	)
	(segment
		(start 312.65622 -19.4818)
		(end 338.72805 -19.4818)
		(width 0.13335)
		(layer "In2.Cu")
		(net "FAN_2_INS_N")
	)
	(segment
		(start 176.759362 -49.455832)
		(end 177.586894 -49.455832)
		(width 0.13335)
		(layer "In2.Cu")
		(net "FAN_2_INS_N")
	)
	(segment
		(start 244.926104 -90.041222)
		(end 246.987822 -87.979504)
		(width 0.13335)
		(layer "In2.Cu")
		(net "FAN_2_INS_N")
	)
	(segment
		(start 246.987822 -11.636756)
		(end 259.89788 1.273302)
		(width 0.13335)
		(layer "In2.Cu")
		(net "FAN_2_INS_N")
	)
	(segment
		(start 89.940892 -23.101554)
		(end 90.091768 -23.25243)
		(width 0.13335)
		(layer "In2.Cu")
		(net "FAN_2_INS_N")
	)
	(segment
		(start 320.347848 -77.554328)
		(end 328.3204 -69.581776)
		(width 0.12065)
		(layer "In4.Cu")
		(net "FAN_2_INS_N")
	)
	(segment
		(start 319.48374 -221.23908)
		(end 319.48374 -203.452984)
		(width 0.12065)
		(layer "In4.Cu")
		(net "FAN_2_INS_N")
	)
	(segment
		(start 331.3557 -48.107854)
		(end 335.856326 -43.607228)
		(width 0.12065)
		(layer "In4.Cu")
		(net "FAN_2_INS_N")
	)
	(segment
		(start 328.3204 -67.678808)
		(end 331.3557 -64.643508)
		(width 0.12065)
		(layer "In4.Cu")
		(net "FAN_2_INS_N")
	)
	(segment
		(start 319.134998 -153.904696)
		(end 319.48374 -153.555954)
		(width 0.12065)
		(layer "In4.Cu")
		(net "FAN_2_INS_N")
	)
	(segment
		(start 337.755738 -33.075118)
		(end 337.755738 -32.390842)
		(width 0.12065)
		(layer "In4.Cu")
		(net "FAN_2_INS_N")
	)
	(segment
		(start 337.755738 -32.390842)
		(end 337.755484 -32.390588)
		(width 0.12065)
		(layer "In4.Cu")
		(net "FAN_2_INS_N")
	)
	(segment
		(start 337.755484 -26.094944)
		(end 339.844888 -24.00554)
		(width 0.12065)
		(layer "In4.Cu")
		(net "FAN_2_INS_N")
	)
	(segment
		(start 335.856326 -43.607228)
		(end 335.856326 -34.97453)
		(width 0.12065)
		(layer "In4.Cu")
		(net "FAN_2_INS_N")
	)
	(segment
		(start 339.844888 -24.00554)
		(end 339.844888 -20.188174)
		(width 0.12065)
		(layer "In4.Cu")
		(net "FAN_2_INS_N")
	)
	(segment
		(start 331.3557 -64.643508)
		(end 331.3557 -48.107854)
		(width 0.12065)
		(layer "In4.Cu")
		(net "FAN_2_INS_N")
	)
	(segment
		(start 337.755484 -32.390588)
		(end 337.755484 -26.094944)
		(width 0.12065)
		(layer "In4.Cu")
		(net "FAN_2_INS_N")
	)
	(segment
		(start 320.347848 -147.317714)
		(end 320.347848 -77.554328)
		(width 0.12065)
		(layer "In4.Cu")
		(net "FAN_2_INS_N")
	)
	(segment
		(start 339.844888 -20.188174)
		(end 338.933282 -19.276568)
		(width 0.12065)
		(layer "In4.Cu")
		(net "FAN_2_INS_N")
	)
	(segment
		(start 319.3669 -203.336144)
		(end 319.3669 -173.289468)
		(width 0.12065)
		(layer "In4.Cu")
		(net "FAN_2_INS_N")
	)
	(segment
		(start 328.3204 -69.581776)
		(end 328.3204 -67.678808)
		(width 0.12065)
		(layer "In4.Cu")
		(net "FAN_2_INS_N")
	)
	(segment
		(start 319.48374 -153.555954)
		(end 319.48374 -148.181822)
		(width 0.12065)
		(layer "In4.Cu")
		(net "FAN_2_INS_N")
	)
	(segment
		(start 322.168012 -251.614432)
		(end 322.168012 -223.923352)
		(width 0.12065)
		(layer "In4.Cu")
		(net "FAN_2_INS_N")
	)
	(segment
		(start 319.48374 -203.452984)
		(end 319.3669 -203.336144)
		(width 0.12065)
		(layer "In4.Cu")
		(net "FAN_2_INS_N")
	)
	(segment
		(start 322.168012 -223.923352)
		(end 319.48374 -221.23908)
		(width 0.12065)
		(layer "In4.Cu")
		(net "FAN_2_INS_N")
	)
	(segment
		(start 319.134998 -173.057566)
		(end 319.134998 -153.904696)
		(width 0.12065)
		(layer "In4.Cu")
		(net "FAN_2_INS_N")
	)
	(segment
		(start 335.856326 -34.97453)
		(end 337.755738 -33.075118)
		(width 0.12065)
		(layer "In4.Cu")
		(net "FAN_2_INS_N")
	)
	(segment
		(start 319.48374 -148.181822)
		(end 320.347848 -147.317714)
		(width 0.12065)
		(layer "In4.Cu")
		(net "FAN_2_INS_N")
	)
	(segment
		(start 319.3669 -173.289468)
		(end 319.134998 -173.057566)
		(width 0.12065)
		(layer "In4.Cu")
		(net "FAN_2_INS_N")
	)
	(segment
		(start 227.31476 -415.25698)
		(end 227.31476 -398.3863)
		(width 0.12065)
		(layer "In7.Cu")
		(net "FAN_2_INS_N")
	)
	(segment
		(start 227.31476 -398.3863)
		(end 226.82708 -397.89862)
		(width 0.12065)
		(layer "In7.Cu")
		(net "FAN_2_INS_N")
	)
	(segment
		(start 227.757736 -415.699956)
		(end 227.31476 -415.25698)
		(width 0.12065)
		(layer "In7.Cu")
		(net "FAN_2_INS_N")
	)
	(segment
		(start 228.000052 -415.699956)
		(end 227.757736 -415.699956)
		(width 0.12065)
		(layer "In7.Cu")
		(net "FAN_2_INS_N")
	)
	(segment
		(start 258.595876 -261.102602)
		(end 258.595876 -259.39496)
		(width 0.13335)
		(layer "In9.Cu")
		(net "FAN_2_INS_N")
	)
	(segment
		(start 257.81 -264.673588)
		(end 257.81 -261.888478)
		(width 0.13335)
		(layer "In9.Cu")
		(net "FAN_2_INS_N")
	)
	(segment
		(start 225.42627 -380.27737)
		(end 225.23704 -380.08814)
		(width 0.13335)
		(layer "In9.Cu")
		(net "FAN_2_INS_N")
	)
	(segment
		(start 224.958148 -396.029688)
		(end 224.958148 -383.334006)
		(width 0.13335)
		(layer "In9.Cu")
		(net "FAN_2_INS_N")
	)
	(segment
		(start 241.576352 -326.045576)
		(end 241.576352 -296.155872)
		(width 0.13335)
		(layer "In9.Cu")
		(net "FAN_2_INS_N")
	)
	(segment
		(start 254.418592 -283.313632)
		(end 254.418592 -268.064996)
		(width 0.13335)
		(layer "In9.Cu")
		(net "FAN_2_INS_N")
	)
	(segment
		(start 225.23704 -380.08814)
		(end 225.23704 -371.647212)
		(width 0.13335)
		(layer "In9.Cu")
		(net "FAN_2_INS_N")
	)
	(segment
		(start 241.576352 -296.155872)
		(end 254.418592 -283.313632)
		(width 0.13335)
		(layer "In9.Cu")
		(net "FAN_2_INS_N")
	)
	(segment
		(start 230.850948 -366.033304)
		(end 230.850948 -336.77098)
		(width 0.13335)
		(layer "In9.Cu")
		(net "FAN_2_INS_N")
	)
	(segment
		(start 230.850948 -336.77098)
		(end 241.576352 -326.045576)
		(width 0.13335)
		(layer "In9.Cu")
		(net "FAN_2_INS_N")
	)
	(segment
		(start 226.82708 -397.89862)
		(end 224.958148 -396.029688)
		(width 0.13335)
		(layer "In9.Cu")
		(net "FAN_2_INS_N")
	)
	(segment
		(start 224.958148 -383.334006)
		(end 225.42627 -382.865884)
		(width 0.13335)
		(layer "In9.Cu")
		(net "FAN_2_INS_N")
	)
	(segment
		(start 225.42627 -382.865884)
		(end 225.42627 -380.27737)
		(width 0.13335)
		(layer "In9.Cu")
		(net "FAN_2_INS_N")
	)
	(segment
		(start 225.23704 -371.647212)
		(end 230.850948 -366.033304)
		(width 0.13335)
		(layer "In9.Cu")
		(net "FAN_2_INS_N")
	)
	(segment
		(start 254.418592 -268.064996)
		(end 257.81 -264.673588)
		(width 0.13335)
		(layer "In9.Cu")
		(net "FAN_2_INS_N")
	)
	(segment
		(start 257.81 -261.888478)
		(end 258.595876 -261.102602)
		(width 0.13335)
		(layer "In9.Cu")
		(net "FAN_2_INS_N")
	)
	(segment
		(start 339.352636 -20.965668)
		(end 339.352636 -21.664676)
		(width 0.17145)
		(layer "F.Cu")
		(net "FAN_1_INS_N")
	)
	(segment
		(start 85.760814 -22.22881)
		(end 85.760814 -23.77694)
		(width 0.17145)
		(layer "F.Cu")
		(net "FAN_1_INS_N")
	)
	(segment
		(start 339.475064 -22.699472)
		(end 339.475064 -22.20214)
		(width 0.17145)
		(layer "F.Cu")
		(net "FAN_1_INS_N")
	)
	(segment
		(start 339.352636 -21.664676)
		(end 339.475064 -21.787104)
		(width 0.17145)
		(layer "F.Cu")
		(net "FAN_1_INS_N")
	)
	(segment
		(start 339.303614 -22.870922)
		(end 339.475064 -22.699472)
		(width 0.17145)
		(layer "F.Cu")
		(net "FAN_1_INS_N")
	)
	(segment
		(start 339.303614 -24.41829)
		(end 339.303614 -22.870922)
		(width 0.17145)
		(layer "F.Cu")
		(net "FAN_1_INS_N")
	)
	(segment
		(start 259.246116 -257.79476)
		(end 259.246116 -260.08076)
		(width 0.17145)
		(layer "F.Cu")
		(net "FAN_1_INS_N")
	)
	(segment
		(start 339.475064 -21.787104)
		(end 339.475064 -22.20214)
		(width 0.17145)
		(layer "F.Cu")
		(net "FAN_1_INS_N")
	)
	(segment
		(start 85.760814 -23.77694)
		(end 86.161626 -24.177752)
		(width 0.17145)
		(layer "F.Cu")
		(net "FAN_1_INS_N")
	)
	(via
		(at 259.246116 -260.08076)
		(size 0.5588)
		(drill 0.3048)
		(layers "F.Cu" "B.Cu")
		(net "FAN_1_INS_N")
	)
	(via
		(at 339.352636 -20.965668)
		(size 0.5588)
		(drill 0.3048)
		(layers "F.Cu" "B.Cu")
		(net "FAN_1_INS_N")
	)
	(via
		(at 86.161626 -24.177752)
		(size 0.5588)
		(drill 0.3048)
		(layers "F.Cu" "B.Cu")
		(net "FAN_1_INS_N")
	)
	(via
		(at 339.475064 -22.20214)
		(size 0.6604)
		(drill 0.3302)
		(layers "F.Cu" "B.Cu")
		(net "FAN_1_INS_N")
	)
	(via
		(at 320.958972 -251.613924)
		(size 0.5588)
		(drill 0.3048)
		(layers "F.Cu" "B.Cu")
		(net "FAN_1_INS_N")
	)
	(via
		(at 225.7552 -379.349)
		(size 0.5588)
		(drill 0.3048)
		(layers "F.Cu" "B.Cu")
		(net "FAN_1_INS_N")
	)
	(segment
		(start 226.77247 -400.63547)
		(end 224.83445 -398.69745)
		(width 0.13335)
		(layer "In2.Cu")
		(net "FAN_1_INS_N")
	)
	(segment
		(start 228.000052 -416.80003)
		(end 227.78085 -416.80003)
		(width 0.13335)
		(layer "In2.Cu")
		(net "FAN_1_INS_N")
	)
	(segment
		(start 86.161626 -24.177752)
		(end 87.44331 -25.459436)
		(width 0.13335)
		(layer "In2.Cu")
		(net "FAN_1_INS_N")
	)
	(segment
		(start 287.928304 -249.708416)
		(end 277.584154 -249.708416)
		(width 0.13335)
		(layer "In2.Cu")
		(net "FAN_1_INS_N")
	)
	(segment
		(start 226.8474 -410.45892)
		(end 226.8474 -405.73452)
		(width 0.13335)
		(layer "In2.Cu")
		(net "FAN_1_INS_N")
	)
	(segment
		(start 189.40907 -87.849456)
		(end 229.42423 -87.849456)
		(width 0.13335)
		(layer "In2.Cu")
		(net "FAN_1_INS_N")
	)
	(segment
		(start 105.361486 -41.184576)
		(end 159.15767 -41.184576)
		(width 0.13335)
		(layer "In2.Cu")
		(net "FAN_1_INS_N")
	)
	(segment
		(start 320.958972 -251.614178)
		(end 312.875168 -251.614178)
		(width 0.13335)
		(layer "In2.Cu")
		(net "FAN_1_INS_N")
	)
	(segment
		(start 305.562 -258.927346)
		(end 297.147234 -258.927346)
		(width 0.13335)
		(layer "In2.Cu")
		(net "FAN_1_INS_N")
	)
	(segment
		(start 320.958972 -251.613924)
		(end 320.958972 -251.614178)
		(width 0.13335)
		(layer "In2.Cu")
		(net "FAN_1_INS_N")
	)
	(segment
		(start 227.20808 -416.22726)
		(end 227.20808 -410.8196)
		(width 0.13335)
		(layer "In2.Cu")
		(net "FAN_1_INS_N")
	)
	(segment
		(start 249.403108 -12.95019)
		(end 261.90702 -0.446278)
		(width 0.13335)
		(layer "In2.Cu")
		(net "FAN_1_INS_N")
	)
	(segment
		(start 312.981594 -22.258782)
		(end 338.723478 -22.258782)
		(width 0.13335)
		(layer "In2.Cu")
		(net "FAN_1_INS_N")
	)
	(segment
		(start 174.225966 -74.612754)
		(end 187.708286 -88.095074)
		(width 0.13335)
		(layer "In2.Cu")
		(net "FAN_1_INS_N")
	)
	(segment
		(start 226.8474 -405.73452)
		(end 226.77247 -405.65959)
		(width 0.13335)
		(layer "In2.Cu")
		(net "FAN_1_INS_N")
	)
	(segment
		(start 174.225966 -56.252872)
		(end 174.225966 -74.612754)
		(width 0.13335)
		(layer "In2.Cu")
		(net "FAN_1_INS_N")
	)
	(segment
		(start 224.83445 -398.69745)
		(end 224.83445 -382.638808)
		(width 0.13335)
		(layer "In2.Cu")
		(net "FAN_1_INS_N")
	)
	(segment
		(start 227.20808 -410.8196)
		(end 226.8474 -410.45892)
		(width 0.13335)
		(layer "In2.Cu")
		(net "FAN_1_INS_N")
	)
	(segment
		(start 312.875168 -251.614178)
		(end 305.562 -258.927346)
		(width 0.13335)
		(layer "In2.Cu")
		(net "FAN_1_INS_N")
	)
	(segment
		(start 309.6768 -18.953988)
		(end 312.981594 -22.258782)
		(width 0.13335)
		(layer "In2.Cu")
		(net "FAN_1_INS_N")
	)
	(segment
		(start 226.77247 -405.65959)
		(end 226.77247 -400.63547)
		(width 0.13335)
		(layer "In2.Cu")
		(net "FAN_1_INS_N")
	)
	(segment
		(start 249.403108 -88.726264)
		(end 249.403108 -12.95019)
		(width 0.13335)
		(layer "In2.Cu")
		(net "FAN_1_INS_N")
	)
	(segment
		(start 261.90702 -0.446278)
		(end 286.015684 -0.446278)
		(width 0.13335)
		(layer "In2.Cu")
		(net "FAN_1_INS_N")
	)
	(segment
		(start 159.15767 -41.184576)
		(end 174.225966 -56.252872)
		(width 0.13335)
		(layer "In2.Cu")
		(net "FAN_1_INS_N")
	)
	(segment
		(start 338.723478 -22.258782)
		(end 339.352636 -21.629624)
		(width 0.13335)
		(layer "In2.Cu")
		(net "FAN_1_INS_N")
	)
	(segment
		(start 339.352636 -21.629624)
		(end 339.352636 -20.965668)
		(width 0.13335)
		(layer "In2.Cu")
		(net "FAN_1_INS_N")
	)
	(segment
		(start 306.763166 -9.182354)
		(end 309.6768 -12.095988)
		(width 0.13335)
		(layer "In2.Cu")
		(net "FAN_1_INS_N")
	)
	(segment
		(start 187.708286 -88.095074)
		(end 189.163452 -88.095074)
		(width 0.13335)
		(layer "In2.Cu")
		(net "FAN_1_INS_N")
	)
	(segment
		(start 294.75176 -9.182354)
		(end 306.763166 -9.182354)
		(width 0.13335)
		(layer "In2.Cu")
		(net "FAN_1_INS_N")
	)
	(segment
		(start 233.73207 -92.157296)
		(end 245.972076 -92.157296)
		(width 0.13335)
		(layer "In2.Cu")
		(net "FAN_1_INS_N")
	)
	(segment
		(start 224.83445 -382.638808)
		(end 225.7552 -381.718058)
		(width 0.13335)
		(layer "In2.Cu")
		(net "FAN_1_INS_N")
	)
	(segment
		(start 89.636346 -25.459436)
		(end 105.361486 -41.184576)
		(width 0.13335)
		(layer "In2.Cu")
		(net "FAN_1_INS_N")
	)
	(segment
		(start 309.6768 -12.095988)
		(end 309.6768 -18.953988)
		(width 0.13335)
		(layer "In2.Cu")
		(net "FAN_1_INS_N")
	)
	(segment
		(start 272.37182 -254.92075)
		(end 268.278102 -254.92075)
		(width 0.13335)
		(layer "In2.Cu")
		(net "FAN_1_INS_N")
	)
	(segment
		(start 245.972076 -92.157296)
		(end 249.403108 -88.726264)
		(width 0.13335)
		(layer "In2.Cu")
		(net "FAN_1_INS_N")
	)
	(segment
		(start 227.78085 -416.80003)
		(end 227.20808 -416.22726)
		(width 0.13335)
		(layer "In2.Cu")
		(net "FAN_1_INS_N")
	)
	(segment
		(start 263.118092 -260.08076)
		(end 259.246116 -260.08076)
		(width 0.13335)
		(layer "In2.Cu")
		(net "FAN_1_INS_N")
	)
	(segment
		(start 189.163452 -88.095074)
		(end 189.40907 -87.849456)
		(width 0.13335)
		(layer "In2.Cu")
		(net "FAN_1_INS_N")
	)
	(segment
		(start 268.278102 -254.92075)
		(end 263.118092 -260.08076)
		(width 0.13335)
		(layer "In2.Cu")
		(net "FAN_1_INS_N")
	)
	(segment
		(start 229.42423 -87.849456)
		(end 233.73207 -92.157296)
		(width 0.13335)
		(layer "In2.Cu")
		(net "FAN_1_INS_N")
	)
	(segment
		(start 277.584154 -249.708416)
		(end 272.37182 -254.92075)
		(width 0.13335)
		(layer "In2.Cu")
		(net "FAN_1_INS_N")
	)
	(segment
		(start 225.7552 -381.718058)
		(end 225.7552 -379.349)
		(width 0.13335)
		(layer "In2.Cu")
		(net "FAN_1_INS_N")
	)
	(segment
		(start 297.147234 -258.927346)
		(end 287.928304 -249.708416)
		(width 0.13335)
		(layer "In2.Cu")
		(net "FAN_1_INS_N")
	)
	(segment
		(start 286.015684 -0.446278)
		(end 294.75176 -9.182354)
		(width 0.13335)
		(layer "In2.Cu")
		(net "FAN_1_INS_N")
	)
	(segment
		(start 87.44331 -25.459436)
		(end 89.636346 -25.459436)
		(width 0.13335)
		(layer "In2.Cu")
		(net "FAN_1_INS_N")
	)
	(segment
		(start 327.78065 -69.53758)
		(end 319.935098 -77.383132)
		(width 0.12065)
		(layer "In4.Cu")
		(net "FAN_1_INS_N")
	)
	(segment
		(start 317.972948 -175.626522)
		(end 318.655446 -176.30902)
		(width 0.12065)
		(layer "In4.Cu")
		(net "FAN_1_INS_N")
	)
	(segment
		(start 337.342988 -32.562038)
		(end 337.342988 -32.903922)
		(width 0.12065)
		(layer "In4.Cu")
		(net "FAN_1_INS_N")
	)
	(segment
		(start 319.935098 -77.383132)
		(end 319.935098 -146.816318)
		(width 0.12065)
		(layer "In4.Cu")
		(net "FAN_1_INS_N")
	)
	(segment
		(start 327.78065 -67.634612)
		(end 327.78065 -69.53758)
		(width 0.12065)
		(layer "In4.Cu")
		(net "FAN_1_INS_N")
	)
	(segment
		(start 320.958972 -251.607574)
		(end 320.958972 -251.613924)
		(width 0.12065)
		(layer "In4.Cu")
		(net "FAN_1_INS_N")
	)
	(segment
		(start 335.443576 -43.436032)
		(end 330.94295 -47.936658)
		(width 0.12065)
		(layer "In4.Cu")
		(net "FAN_1_INS_N")
	)
	(segment
		(start 335.443576 -34.803334)
		(end 335.443576 -43.436032)
		(width 0.12065)
		(layer "In4.Cu")
		(net "FAN_1_INS_N")
	)
	(segment
		(start 339.352636 -20.965668)
		(end 339.352636 -23.890732)
		(width 0.12065)
		(layer "In4.Cu")
		(net "FAN_1_INS_N")
	)
	(segment
		(start 330.94295 -47.936658)
		(end 330.94295 -64.472312)
		(width 0.12065)
		(layer "In4.Cu")
		(net "FAN_1_INS_N")
	)
	(segment
		(start 337.342734 -25.900634)
		(end 337.342734 -32.561784)
		(width 0.12065)
		(layer "In4.Cu")
		(net "FAN_1_INS_N")
	)
	(segment
		(start 317.972948 -148.778468)
		(end 317.972948 -175.626522)
		(width 0.12065)
		(layer "In4.Cu")
		(net "FAN_1_INS_N")
	)
	(segment
		(start 337.342734 -32.561784)
		(end 337.342988 -32.562038)
		(width 0.12065)
		(layer "In4.Cu")
		(net "FAN_1_INS_N")
	)
	(segment
		(start 318.655446 -220.994732)
		(end 321.616578 -223.955864)
		(width 0.12065)
		(layer "In4.Cu")
		(net "FAN_1_INS_N")
	)
	(segment
		(start 321.616578 -250.949968)
		(end 320.958972 -251.607574)
		(width 0.12065)
		(layer "In4.Cu")
		(net "FAN_1_INS_N")
	)
	(segment
		(start 339.352636 -23.890732)
		(end 337.342734 -25.900634)
		(width 0.12065)
		(layer "In4.Cu")
		(net "FAN_1_INS_N")
	)
	(segment
		(start 319.935098 -146.816318)
		(end 317.972948 -148.778468)
		(width 0.12065)
		(layer "In4.Cu")
		(net "FAN_1_INS_N")
	)
	(segment
		(start 337.342988 -32.903922)
		(end 335.443576 -34.803334)
		(width 0.12065)
		(layer "In4.Cu")
		(net "FAN_1_INS_N")
	)
	(segment
		(start 321.616578 -223.955864)
		(end 321.616578 -250.949968)
		(width 0.12065)
		(layer "In4.Cu")
		(net "FAN_1_INS_N")
	)
	(segment
		(start 330.94295 -64.472312)
		(end 327.78065 -67.634612)
		(width 0.12065)
		(layer "In4.Cu")
		(net "FAN_1_INS_N")
	)
	(segment
		(start 318.655446 -176.30902)
		(end 318.655446 -220.994732)
		(width 0.12065)
		(layer "In4.Cu")
		(net "FAN_1_INS_N")
	)
	(segment
		(start 225.7552 -379.349)
		(end 225.79584 -379.38964)
		(width 0.13335)
		(layer "In9.Cu")
		(net "FAN_1_INS_N")
	)
	(segment
		(start 259.246116 -263.839198)
		(end 259.246116 -260.08076)
		(width 0.13335)
		(layer "In9.Cu")
		(net "FAN_1_INS_N")
	)
	(segment
		(start 231.276398 -336.947256)
		(end 242.001802 -326.221852)
		(width 0.13335)
		(layer "In9.Cu")
		(net "FAN_1_INS_N")
	)
	(segment
		(start 242.001802 -326.221852)
		(end 242.001802 -296.332148)
		(width 0.13335)
		(layer "In9.Cu")
		(net "FAN_1_INS_N")
	)
	(segment
		(start 254.844042 -268.241272)
		(end 259.246116 -263.839198)
		(width 0.13335)
		(layer "In9.Cu")
		(net "FAN_1_INS_N")
	)
	(segment
		(start 254.844042 -283.489908)
		(end 254.844042 -268.241272)
		(width 0.13335)
		(layer "In9.Cu")
		(net "FAN_1_INS_N")
	)
	(segment
		(start 227.926646 -378.234194)
		(end 227.926646 -369.559332)
		(width 0.13335)
		(layer "In9.Cu")
		(net "FAN_1_INS_N")
	)
	(segment
		(start 225.79584 -379.38964)
		(end 226.7712 -379.38964)
		(width 0.13335)
		(layer "In9.Cu")
		(net "FAN_1_INS_N")
	)
	(segment
		(start 227.926646 -369.559332)
		(end 231.276398 -366.20958)
		(width 0.13335)
		(layer "In9.Cu")
		(net "FAN_1_INS_N")
	)
	(segment
		(start 242.001802 -296.332148)
		(end 254.844042 -283.489908)
		(width 0.13335)
		(layer "In9.Cu")
		(net "FAN_1_INS_N")
	)
	(segment
		(start 226.7712 -379.38964)
		(end 227.926646 -378.234194)
		(width 0.13335)
		(layer "In9.Cu")
		(net "FAN_1_INS_N")
	)
	(segment
		(start 231.276398 -366.20958)
		(end 231.276398 -336.947256)
		(width 0.13335)
		(layer "In9.Cu")
		(net "FAN_1_INS_N")
	)
	(segment
		(start 85.110574 -27.86761)
		(end 85.110574 -26.436574)
		(width 0.17145)
		(layer "F.Cu")
		(net "DRAWER_CLOSED_N")
	)
	(segment
		(start 260.546596 -257.044444)
		(end 260.546596 -257.79476)
		(width 0.17145)
		(layer "F.Cu")
		(net "DRAWER_CLOSED_N")
	)
	(segment
		(start 339.90661 -27.326844)
		(end 338.653374 -28.58008)
		(width 0.17145)
		(layer "F.Cu")
		(net "DRAWER_CLOSED_N")
	)
	(segment
		(start 261.278878 -256.312162)
		(end 260.546596 -257.044444)
		(width 0.17145)
		(layer "F.Cu")
		(net "DRAWER_CLOSED_N")
	)
	(segment
		(start 338.653374 -28.58008)
		(end 338.653374 -30.05709)
		(width 0.17145)
		(layer "F.Cu")
		(net "DRAWER_CLOSED_N")
	)
	(via
		(at 261.278878 -256.312162)
		(size 0.5588)
		(drill 0.3048)
		(layers "F.Cu" "B.Cu")
		(net "DRAWER_CLOSED_N")
	)
	(via
		(at 326.644 -249.4788)
		(size 0.5588)
		(drill 0.3048)
		(layers "F.Cu" "B.Cu")
		(net "DRAWER_CLOSED_N")
	)
	(via
		(at 85.110574 -26.436574)
		(size 0.5588)
		(drill 0.3048)
		(layers "F.Cu" "B.Cu")
		(net "DRAWER_CLOSED_N")
	)
	(via
		(at 339.90661 -27.326844)
		(size 0.5588)
		(drill 0.3048)
		(layers "F.Cu" "B.Cu")
		(net "DRAWER_CLOSED_N")
	)
	(segment
		(start 267.299186 -253.21895)
		(end 264.205974 -256.312162)
		(width 0.13335)
		(layer "In2.Cu")
		(net "DRAWER_CLOSED_N")
	)
	(segment
		(start 264.205974 -256.312162)
		(end 261.278878 -256.312162)
		(width 0.13335)
		(layer "In2.Cu")
		(net "DRAWER_CLOSED_N")
	)
	(segment
		(start 303.23282 -235.49102)
		(end 297.141138 -235.49102)
		(width 0.13335)
		(layer "In2.Cu")
		(net "DRAWER_CLOSED_N")
	)
	(segment
		(start 88.805512 -30.354016)
		(end 88.513412 -30.061916)
		(width 0.13335)
		(layer "In2.Cu")
		(net "DRAWER_CLOSED_N")
	)
	(segment
		(start 293.884604 -10.903204)
		(end 285.3182 -2.3368)
		(width 0.13335)
		(layer "In2.Cu")
		(net "DRAWER_CLOSED_N")
	)
	(segment
		(start 307.975 -12.801092)
		(end 306.077112 -10.903204)
		(width 0.13335)
		(layer "In2.Cu")
		(net "DRAWER_CLOSED_N")
	)
	(segment
		(start 307.975 -21.082)
		(end 307.975 -12.801092)
		(width 0.13335)
		(layer "In2.Cu")
		(net "DRAWER_CLOSED_N")
	)
	(segment
		(start 285.3182 -2.3368)
		(end 264.761472 -2.3368)
		(width 0.13335)
		(layer "In2.Cu")
		(net "DRAWER_CLOSED_N")
	)
	(segment
		(start 336.287872 -25.438608)
		(end 332.231492 -25.438608)
		(width 0.13335)
		(layer "In2.Cu")
		(net "DRAWER_CLOSED_N")
	)
	(segment
		(start 88.513412 -30.061916)
		(end 88.513412 -30.043374)
		(width 0.13335)
		(layer "In2.Cu")
		(net "DRAWER_CLOSED_N")
	)
	(segment
		(start 251.104908 -89.836244)
		(end 246.91594 -94.025212)
		(width 0.13335)
		(layer "In2.Cu")
		(net "DRAWER_CLOSED_N")
	)
	(segment
		(start 264.761472 -2.3368)
		(end 251.104908 -15.993364)
		(width 0.13335)
		(layer "In2.Cu")
		(net "DRAWER_CLOSED_N")
	)
	(segment
		(start 224.985834 -90.657934)
		(end 224.740724 -90.903044)
		(width 0.13335)
		(layer "In2.Cu")
		(net "DRAWER_CLOSED_N")
	)
	(segment
		(start 339.567266 -26.9875)
		(end 337.836764 -26.9875)
		(width 0.13335)
		(layer "In2.Cu")
		(net "DRAWER_CLOSED_N")
	)
	(segment
		(start 339.90661 -27.326844)
		(end 339.567266 -26.9875)
		(width 0.13335)
		(layer "In2.Cu")
		(net "DRAWER_CLOSED_N")
	)
	(segment
		(start 330.753466 -23.960582)
		(end 310.853582 -23.960582)
		(width 0.13335)
		(layer "In2.Cu")
		(net "DRAWER_CLOSED_N")
	)
	(segment
		(start 167.10279 -74.111358)
		(end 167.10279 -61.269372)
		(width 0.13335)
		(layer "In2.Cu")
		(net "DRAWER_CLOSED_N")
	)
	(segment
		(start 317.5762 -249.8344)
		(end 303.23282 -235.49102)
		(width 0.13335)
		(layer "In2.Cu")
		(net "DRAWER_CLOSED_N")
	)
	(segment
		(start 167.10279 -61.269372)
		(end 163.249356 -57.415938)
		(width 0.13335)
		(layer "In2.Cu")
		(net "DRAWER_CLOSED_N")
	)
	(segment
		(start 87.663782 -28.989782)
		(end 85.110574 -26.436574)
		(width 0.13335)
		(layer "In2.Cu")
		(net "DRAWER_CLOSED_N")
	)
	(segment
		(start 88.513412 -30.043374)
		(end 87.663782 -29.193744)
		(width 0.13335)
		(layer "In2.Cu")
		(net "DRAWER_CLOSED_N")
	)
	(segment
		(start 251.104908 -15.993364)
		(end 251.104908 -89.836244)
		(width 0.13335)
		(layer "In2.Cu")
		(net "DRAWER_CLOSED_N")
	)
	(segment
		(start 332.231492 -25.438608)
		(end 330.753466 -23.960582)
		(width 0.13335)
		(layer "In2.Cu")
		(net "DRAWER_CLOSED_N")
	)
	(segment
		(start 88.824054 -30.354016)
		(end 88.805512 -30.354016)
		(width 0.13335)
		(layer "In2.Cu")
		(net "DRAWER_CLOSED_N")
	)
	(segment
		(start 230.633778 -94.025212)
		(end 227.2665 -90.657934)
		(width 0.13335)
		(layer "In2.Cu")
		(net "DRAWER_CLOSED_N")
	)
	(segment
		(start 306.077112 -10.903204)
		(end 293.884604 -10.903204)
		(width 0.13335)
		(layer "In2.Cu")
		(net "DRAWER_CLOSED_N")
	)
	(segment
		(start 163.249356 -57.415938)
		(end 115.885976 -57.415938)
		(width 0.13335)
		(layer "In2.Cu")
		(net "DRAWER_CLOSED_N")
	)
	(segment
		(start 115.885976 -57.415938)
		(end 88.824054 -30.354016)
		(width 0.13335)
		(layer "In2.Cu")
		(net "DRAWER_CLOSED_N")
	)
	(segment
		(start 183.894476 -90.903044)
		(end 167.10279 -74.111358)
		(width 0.13335)
		(layer "In2.Cu")
		(net "DRAWER_CLOSED_N")
	)
	(segment
		(start 271.387062 -253.21895)
		(end 267.299186 -253.21895)
		(width 0.13335)
		(layer "In2.Cu")
		(net "DRAWER_CLOSED_N")
	)
	(segment
		(start 326.644 -249.4788)
		(end 321.945 -249.4788)
		(width 0.13335)
		(layer "In2.Cu")
		(net "DRAWER_CLOSED_N")
	)
	(segment
		(start 224.740724 -90.903044)
		(end 183.894476 -90.903044)
		(width 0.13335)
		(layer "In2.Cu")
		(net "DRAWER_CLOSED_N")
	)
	(segment
		(start 246.91594 -94.025212)
		(end 230.633778 -94.025212)
		(width 0.13335)
		(layer "In2.Cu")
		(net "DRAWER_CLOSED_N")
	)
	(segment
		(start 87.663782 -29.193744)
		(end 87.663782 -28.989782)
		(width 0.13335)
		(layer "In2.Cu")
		(net "DRAWER_CLOSED_N")
	)
	(segment
		(start 276.599396 -248.006616)
		(end 271.387062 -253.21895)
		(width 0.13335)
		(layer "In2.Cu")
		(net "DRAWER_CLOSED_N")
	)
	(segment
		(start 321.5894 -249.8344)
		(end 317.5762 -249.8344)
		(width 0.13335)
		(layer "In2.Cu")
		(net "DRAWER_CLOSED_N")
	)
	(segment
		(start 310.853582 -23.960582)
		(end 307.975 -21.082)
		(width 0.13335)
		(layer "In2.Cu")
		(net "DRAWER_CLOSED_N")
	)
	(segment
		(start 227.2665 -90.657934)
		(end 224.985834 -90.657934)
		(width 0.13335)
		(layer "In2.Cu")
		(net "DRAWER_CLOSED_N")
	)
	(segment
		(start 337.836764 -26.9875)
		(end 336.287872 -25.438608)
		(width 0.13335)
		(layer "In2.Cu")
		(net "DRAWER_CLOSED_N")
	)
	(segment
		(start 284.625542 -248.006616)
		(end 276.599396 -248.006616)
		(width 0.13335)
		(layer "In2.Cu")
		(net "DRAWER_CLOSED_N")
	)
	(segment
		(start 297.141138 -235.49102)
		(end 284.625542 -248.006616)
		(width 0.13335)
		(layer "In2.Cu")
		(net "DRAWER_CLOSED_N")
	)
	(segment
		(start 321.945 -249.4788)
		(end 321.5894 -249.8344)
		(width 0.13335)
		(layer "In2.Cu")
		(net "DRAWER_CLOSED_N")
	)
	(segment
		(start 321.681348 -186.77001)
		(end 322.801742 -187.890404)
		(width 0.12065)
		(layer "In4.Cu")
		(net "DRAWER_CLOSED_N")
	)
	(segment
		(start 338.243418 -106.510074)
		(end 324.744842 -120.00865)
		(width 0.12065)
		(layer "In4.Cu")
		(net "DRAWER_CLOSED_N")
	)
	(segment
		(start 322.028566 -177.49012)
		(end 322.028566 -177.898044)
		(width 0.12065)
		(layer "In4.Cu")
		(net "DRAWER_CLOSED_N")
	)
	(segment
		(start 321.986148 -177.447702)
		(end 322.028566 -177.49012)
		(width 0.12065)
		(layer "In4.Cu")
		(net "DRAWER_CLOSED_N")
	)
	(segment
		(start 322.801742 -221.227396)
		(end 326.804782 -225.230436)
		(width 0.12065)
		(layer "In4.Cu")
		(net "DRAWER_CLOSED_N")
	)
	(segment
		(start 338.293964 -37.640514)
		(end 338.293964 -44.772834)
		(width 0.12065)
		(layer "In4.Cu")
		(net "DRAWER_CLOSED_N")
	)
	(segment
		(start 338.243418 -76.2889)
		(end 338.243418 -106.510074)
		(width 0.12065)
		(layer "In4.Cu")
		(net "DRAWER_CLOSED_N")
	)
	(segment
		(start 326.644 -245.96852)
		(end 326.644 -249.4788)
		(width 0.12065)
		(layer "In4.Cu")
		(net "DRAWER_CLOSED_N")
	)
	(segment
		(start 321.681348 -181.685438)
		(end 321.681348 -186.77001)
		(width 0.12065)
		(layer "In4.Cu")
		(net "DRAWER_CLOSED_N")
	)
	(segment
		(start 322.801742 -187.890404)
		(end 322.801742 -221.227396)
		(width 0.12065)
		(layer "In4.Cu")
		(net "DRAWER_CLOSED_N")
	)
	(segment
		(start 339.90661 -28.683204)
		(end 340.445852 -29.222446)
		(width 0.12065)
		(layer "In4.Cu")
		(net "DRAWER_CLOSED_N")
	)
	(segment
		(start 336.41538 -74.460862)
		(end 338.243418 -76.2889)
		(width 0.12065)
		(layer "In4.Cu")
		(net "DRAWER_CLOSED_N")
	)
	(segment
		(start 326.804782 -225.230436)
		(end 326.804782 -245.807738)
		(width 0.12065)
		(layer "In4.Cu")
		(net "DRAWER_CLOSED_N")
	)
	(segment
		(start 326.804782 -245.807738)
		(end 326.644 -245.96852)
		(width 0.12065)
		(layer "In4.Cu")
		(net "DRAWER_CLOSED_N")
	)
	(segment
		(start 321.986148 -149.488652)
		(end 321.986148 -177.447702)
		(width 0.12065)
		(layer "In4.Cu")
		(net "DRAWER_CLOSED_N")
	)
	(segment
		(start 321.986148 -177.940462)
		(end 321.986148 -181.380638)
		(width 0.12065)
		(layer "In4.Cu")
		(net "DRAWER_CLOSED_N")
	)
	(segment
		(start 322.028566 -177.898044)
		(end 321.986148 -177.940462)
		(width 0.12065)
		(layer "In4.Cu")
		(net "DRAWER_CLOSED_N")
	)
	(segment
		(start 337.251548 -52.663852)
		(end 336.41538 -53.50002)
		(width 0.12065)
		(layer "In4.Cu")
		(net "DRAWER_CLOSED_N")
	)
	(segment
		(start 338.293964 -44.772834)
		(end 337.251548 -45.81525)
		(width 0.12065)
		(layer "In4.Cu")
		(net "DRAWER_CLOSED_N")
	)
	(segment
		(start 321.986148 -181.380638)
		(end 321.681348 -181.685438)
		(width 0.12065)
		(layer "In4.Cu")
		(net "DRAWER_CLOSED_N")
	)
	(segment
		(start 337.251548 -45.81525)
		(end 337.251548 -52.663852)
		(width 0.12065)
		(layer "In4.Cu")
		(net "DRAWER_CLOSED_N")
	)
	(segment
		(start 340.445852 -29.222446)
		(end 340.445852 -35.488626)
		(width 0.12065)
		(layer "In4.Cu")
		(net "DRAWER_CLOSED_N")
	)
	(segment
		(start 340.445852 -35.488626)
		(end 338.293964 -37.640514)
		(width 0.12065)
		(layer "In4.Cu")
		(net "DRAWER_CLOSED_N")
	)
	(segment
		(start 336.41538 -53.50002)
		(end 336.41538 -74.460862)
		(width 0.12065)
		(layer "In4.Cu")
		(net "DRAWER_CLOSED_N")
	)
	(segment
		(start 324.744842 -146.729958)
		(end 321.986148 -149.488652)
		(width 0.12065)
		(layer "In4.Cu")
		(net "DRAWER_CLOSED_N")
	)
	(segment
		(start 339.90661 -27.326844)
		(end 339.90661 -28.683204)
		(width 0.12065)
		(layer "In4.Cu")
		(net "DRAWER_CLOSED_N")
	)
	(segment
		(start 324.744842 -120.00865)
		(end 324.744842 -146.729958)
		(width 0.12065)
		(layer "In4.Cu")
		(net "DRAWER_CLOSED_N")
	)
	(segment
		(start 223.109536 -377.32716)
		(end 223.109536 -370.131086)
		(width 0.13335)
		(layer "In9.Cu")
		(net "DRAWER_CLOSED_N")
	)
	(segment
		(start 225.22942 -413.229298)
		(end 225.22942 -401.53082)
		(width 0.13335)
		(layer "In9.Cu")
		(net "DRAWER_CLOSED_N")
	)
	(segment
		(start 252.291342 -267.183616)
		(end 252.408944 -267.066014)
		(width 0.13335)
		(layer "In9.Cu")
		(net "DRAWER_CLOSED_N")
	)
	(segment
		(start 223.109536 -370.131086)
		(end 228.723698 -364.516924)
		(width 0.13335)
		(layer "In9.Cu")
		(net "DRAWER_CLOSED_N")
	)
	(segment
		(start 228.723698 -364.516924)
		(end 228.723698 -334.597502)
		(width 0.13335)
		(layer "In9.Cu")
		(net "DRAWER_CLOSED_N")
	)
	(segment
		(start 228.723698 -334.597502)
		(end 239.049052 -324.272148)
		(width 0.13335)
		(layer "In9.Cu")
		(net "DRAWER_CLOSED_N")
	)
	(segment
		(start 221.9833 -398.2847)
		(end 221.9833 -378.453396)
		(width 0.13335)
		(layer "In9.Cu")
		(net "DRAWER_CLOSED_N")
	)
	(segment
		(start 252.291342 -282.432252)
		(end 252.291342 -267.183616)
		(width 0.13335)
		(layer "In9.Cu")
		(net "DRAWER_CLOSED_N")
	)
	(segment
		(start 256.168398 -255.441958)
		(end 257.964432 -255.441958)
		(width 0.13335)
		(layer "In9.Cu")
		(net "DRAWER_CLOSED_N")
	)
	(segment
		(start 254.136144 -257.474212)
		(end 256.168398 -255.441958)
		(width 0.13335)
		(layer "In9.Cu")
		(net "DRAWER_CLOSED_N")
	)
	(segment
		(start 252.408944 -266.799822)
		(end 252.657864 -266.550902)
		(width 0.13335)
		(layer "In9.Cu")
		(net "DRAWER_CLOSED_N")
	)
	(segment
		(start 252.408944 -267.066014)
		(end 252.408944 -266.799822)
		(width 0.13335)
		(layer "In9.Cu")
		(net "DRAWER_CLOSED_N")
	)
	(segment
		(start 221.9833 -378.453396)
		(end 223.109536 -377.32716)
		(width 0.13335)
		(layer "In9.Cu")
		(net "DRAWER_CLOSED_N")
	)
	(segment
		(start 254.136144 -265.072876)
		(end 254.136144 -257.474212)
		(width 0.13335)
		(layer "In9.Cu")
		(net "DRAWER_CLOSED_N")
	)
	(segment
		(start 252.658118 -266.550902)
		(end 254.136144 -265.072876)
		(width 0.13335)
		(layer "In9.Cu")
		(net "DRAWER_CLOSED_N")
	)
	(segment
		(start 259.689854 -256.312162)
		(end 261.278878 -256.312162)
		(width 0.13335)
		(layer "In9.Cu")
		(net "DRAWER_CLOSED_N")
	)
	(segment
		(start 259.686298 -256.308606)
		(end 259.689854 -256.312162)
		(width 0.13335)
		(layer "In9.Cu")
		(net "DRAWER_CLOSED_N")
	)
	(segment
		(start 226.200208 -414.200086)
		(end 225.22942 -413.229298)
		(width 0.13335)
		(layer "In9.Cu")
		(net "DRAWER_CLOSED_N")
	)
	(segment
		(start 252.657864 -266.550902)
		(end 252.658118 -266.550902)
		(width 0.13335)
		(layer "In9.Cu")
		(net "DRAWER_CLOSED_N")
	)
	(segment
		(start 257.964432 -255.441958)
		(end 258.83108 -256.308606)
		(width 0.13335)
		(layer "In9.Cu")
		(net "DRAWER_CLOSED_N")
	)
	(segment
		(start 258.83108 -256.308606)
		(end 259.686298 -256.308606)
		(width 0.13335)
		(layer "In9.Cu")
		(net "DRAWER_CLOSED_N")
	)
	(segment
		(start 239.049052 -324.272148)
		(end 239.049052 -295.674542)
		(width 0.13335)
		(layer "In9.Cu")
		(net "DRAWER_CLOSED_N")
	)
	(segment
		(start 239.049052 -295.674542)
		(end 252.291342 -282.432252)
		(width 0.13335)
		(layer "In9.Cu")
		(net "DRAWER_CLOSED_N")
	)
	(segment
		(start 225.22942 -401.53082)
		(end 221.9833 -398.2847)
		(width 0.13335)
		(layer "In9.Cu")
		(net "DRAWER_CLOSED_N")
	)
	(segment
		(start 273.68627 -5.69087)
		(end 272.6436 -5.69087)
		(width 0.17145)
		(layer "F.Cu")
		(net "COMP_B_SEC_INS_N")
	)
	(segment
		(start 337.38693 -16.542766)
		(end 337.38693 -14.1732)
		(width 0.17145)
		(layer "F.Cu")
		(net "COMP_B_SEC_INS_N")
	)
	(segment
		(start 272.6436 -5.69087)
		(end 271.695672 -5.69087)
		(width 0.17145)
		(layer "F.Cu")
		(net "COMP_B_SEC_INS_N")
	)
	(via
		(at 272.6436 -5.69087)
		(size 0.6604)
		(drill 0.3302)
		(layers "F.Cu" "B.Cu")
		(net "COMP_B_SEC_INS_N")
	)
	(via
		(at 337.38693 -14.1732)
		(size 0.5588)
		(drill 0.3048)
		(layers "F.Cu" "B.Cu")
		(net "COMP_B_SEC_INS_N")
	)
	(via
		(at 273.68627 -5.69087)
		(size 0.5588)
		(drill 0.3048)
		(layers "F.Cu" "B.Cu")
		(net "COMP_B_SEC_INS_N")
	)
	(segment
		(start 280.75001 -3.200146)
		(end 276.176994 -3.200146)
		(width 0.13335)
		(layer "In2.Cu")
		(net "COMP_B_SEC_INS_N")
	)
	(segment
		(start 276.176994 -3.200146)
		(end 273.68627 -5.69087)
		(width 0.13335)
		(layer "In2.Cu")
		(net "COMP_B_SEC_INS_N")
	)
	(segment
		(start 280.75001 -3.200146)
		(end 281.690064 -4.1402)
		(width 0.12065)
		(layer "In7.Cu")
		(net "COMP_B_SEC_INS_N")
	)
	(segment
		(start 281.690064 -4.1402)
		(end 283.9974 -4.1402)
		(width 0.12065)
		(layer "In7.Cu")
		(net "COMP_B_SEC_INS_N")
	)
	(segment
		(start 283.9974 -4.1402)
		(end 285.4198 -2.7178)
		(width 0.12065)
		(layer "In7.Cu")
		(net "COMP_B_SEC_INS_N")
	)
	(segment
		(start 285.4198 -2.7178)
		(end 299.213778 -2.7178)
		(width 0.12065)
		(layer "In7.Cu")
		(net "COMP_B_SEC_INS_N")
	)
	(segment
		(start 299.213778 -2.7178)
		(end 314.936378 -18.4404)
		(width 0.12065)
		(layer "In7.Cu")
		(net "COMP_B_SEC_INS_N")
	)
	(segment
		(start 314.936378 -18.4404)
		(end 335.0768 -18.4404)
		(width 0.12065)
		(layer "In7.Cu")
		(net "COMP_B_SEC_INS_N")
	)
	(segment
		(start 337.38693 -16.13027)
		(end 337.38693 -14.1732)
		(width 0.12065)
		(layer "In7.Cu")
		(net "COMP_B_SEC_INS_N")
	)
	(segment
		(start 335.0768 -18.4404)
		(end 337.38693 -16.13027)
		(width 0.12065)
		(layer "In7.Cu")
		(net "COMP_B_SEC_INS_N")
	)
	(segment
		(start 381.51435 -139.13485)
		(end 378.741432 -139.13485)
		(width 0.17145)
		(layer "F.Cu")
		(net "COMP_B_PWR_EN")
	)
	(segment
		(start 381.6096 -138.2014)
		(end 381.6096 -139.0396)
		(width 0.17145)
		(layer "F.Cu")
		(net "COMP_B_PWR_EN")
	)
	(segment
		(start 381.6096 -139.0396)
		(end 381.51435 -139.13485)
		(width 0.17145)
		(layer "F.Cu")
		(net "COMP_B_PWR_EN")
	)
	(via
		(at 393.197334 -138.2014)
		(size 0.6096)
		(drill 0.3048)
		(layers "F.Cu" "B.Cu")
		(net "COMP_B_PWR_EN")
	)
	(via
		(at 398.399 -138.2014)
		(size 0.5588)
		(drill 0.3048)
		(layers "F.Cu" "B.Cu")
		(net "COMP_B_PWR_EN")
	)
	(via
		(at 398.399 -111.379)
		(size 0.5588)
		(drill 0.3048)
		(layers "F.Cu" "B.Cu")
		(net "COMP_B_PWR_EN")
	)
	(via
		(at 354.4062 -111.379)
		(size 0.5588)
		(drill 0.3048)
		(layers "F.Cu" "B.Cu")
		(net "COMP_B_PWR_EN")
	)
	(via
		(at 381.6096 -138.2014)
		(size 0.5588)
		(drill 0.3048)
		(layers "F.Cu" "B.Cu")
		(net "COMP_B_PWR_EN")
	)
	(segment
		(start 354.4062 -111.379)
		(end 398.399 -111.379)
		(width 0.17145)
		(layer "B.Cu")
		(net "COMP_B_PWR_EN")
	)
	(segment
		(start 393.197334 -138.2014)
		(end 398.399 -138.2014)
		(width 0.17145)
		(layer "B.Cu")
		(net "COMP_B_PWR_EN")
	)
	(segment
		(start 381.6096 -138.2014)
		(end 393.197334 -138.2014)
		(width 0.17145)
		(layer "B.Cu")
		(net "COMP_B_PWR_EN")
	)
	(segment
		(start 361.714796 -39.383716)
		(end 352.552 -48.546512)
		(width 0.12065)
		(layer "In4.Cu")
		(net "COMP_B_PWR_EN")
	)
	(segment
		(start 352.552 -109.5248)
		(end 354.4062 -111.379)
		(width 0.12065)
		(layer "In4.Cu")
		(net "COMP_B_PWR_EN")
	)
	(segment
		(start 362.35005 -25.950164)
		(end 361.714796 -26.585418)
		(width 0.12065)
		(layer "In4.Cu")
		(net "COMP_B_PWR_EN")
	)
	(segment
		(start 398.399 -111.379)
		(end 398.399 -138.2014)
		(width 0.12065)
		(layer "In4.Cu")
		(net "COMP_B_PWR_EN")
	)
	(segment
		(start 361.714796 -26.585418)
		(end 361.714796 -39.383716)
		(width 0.12065)
		(layer "In4.Cu")
		(net "COMP_B_PWR_EN")
	)
	(segment
		(start 352.552 -48.546512)
		(end 352.552 -109.5248)
		(width 0.12065)
		(layer "In4.Cu")
		(net "COMP_B_PWR_EN")
	)
	(via
		(at 349.4278 -105.0036)
		(size 0.5588)
		(drill 0.3048)
		(layers "F.Cu" "B.Cu")
		(net "COMP_B_PWR_BTN_N")
	)
	(segment
		(start 286.72155 -106.499914)
		(end 285.249874 -106.499914)
		(width 0.13335)
		(layer "In2.Cu")
		(net "COMP_B_PWR_BTN_N")
	)
	(segment
		(start 287.238186 -107.01655)
		(end 286.72155 -106.499914)
		(width 0.13335)
		(layer "In2.Cu")
		(net "COMP_B_PWR_BTN_N")
	)
	(segment
		(start 347.41485 -107.01655)
		(end 287.238186 -107.01655)
		(width 0.13335)
		(layer "In2.Cu")
		(net "COMP_B_PWR_BTN_N")
	)
	(segment
		(start 349.4278 -105.0036)
		(end 347.41485 -107.01655)
		(width 0.13335)
		(layer "In2.Cu")
		(net "COMP_B_PWR_BTN_N")
	)
	(segment
		(start 349.4278 -76.835)
		(end 349.4278 -105.0036)
		(width 0.12065)
		(layer "In4.Cu")
		(net "COMP_B_PWR_BTN_N")
	)
	(segment
		(start 348.04985 -43.107356)
		(end 348.04985 -75.45705)
		(width 0.12065)
		(layer "In4.Cu")
		(net "COMP_B_PWR_BTN_N")
	)
	(segment
		(start 348.04985 -75.45705)
		(end 349.4278 -76.835)
		(width 0.12065)
		(layer "In4.Cu")
		(net "COMP_B_PWR_BTN_N")
	)
	(segment
		(start 359.414318 -25.353518)
		(end 359.414318 -31.742888)
		(width 0.12065)
		(layer "In4.Cu")
		(net "COMP_B_PWR_BTN_N")
	)
	(segment
		(start 358.750108 -24.550116)
		(end 358.750108 -24.689308)
		(width 0.12065)
		(layer "In4.Cu")
		(net "COMP_B_PWR_BTN_N")
	)
	(segment
		(start 359.414318 -31.742888)
		(end 348.04985 -43.107356)
		(width 0.12065)
		(layer "In4.Cu")
		(net "COMP_B_PWR_BTN_N")
	)
	(segment
		(start 358.750108 -24.689308)
		(end 359.414318 -25.353518)
		(width 0.12065)
		(layer "In4.Cu")
		(net "COMP_B_PWR_BTN_N")
	)
	(segment
		(start 300.332394 -80.712056)
		(end 302.1838 -78.86065)
		(width 0.17145)
		(layer "F.Cu")
		(net "COMP_B_PRI_INS_N")
	)
	(segment
		(start 336.252566 -14.205966)
		(end 336.73669 -14.69009)
		(width 0.17145)
		(layer "F.Cu")
		(net "COMP_B_PRI_INS_N")
	)
	(segment
		(start 303.4284 -77.121258)
		(end 302.1838 -78.365858)
		(width 0.17145)
		(layer "F.Cu")
		(net "COMP_B_PRI_INS_N")
	)
	(segment
		(start 303.4284 -75.2221)
		(end 303.4284 -77.121258)
		(width 0.17145)
		(layer "F.Cu")
		(net "COMP_B_PRI_INS_N")
	)
	(segment
		(start 336.73669 -14.69009)
		(end 336.73669 -16.542766)
		(width 0.17145)
		(layer "F.Cu")
		(net "COMP_B_PRI_INS_N")
	)
	(segment
		(start 280.75001 -99.499928)
		(end 281.544522 -99.499928)
		(width 0.17145)
		(layer "F.Cu")
		(net "COMP_B_PRI_INS_N")
	)
	(segment
		(start 281.544522 -99.499928)
		(end 300.332394 -80.712056)
		(width 0.17145)
		(layer "F.Cu")
		(net "COMP_B_PRI_INS_N")
	)
	(segment
		(start 302.1838 -78.86065)
		(end 302.1838 -78.365858)
		(width 0.17145)
		(layer "F.Cu")
		(net "COMP_B_PRI_INS_N")
	)
	(via
		(at 336.252566 -14.205966)
		(size 0.5588)
		(drill 0.3048)
		(layers "F.Cu" "B.Cu")
		(net "COMP_B_PRI_INS_N")
	)
	(via
		(at 300.332394 -80.712056)
		(size 0.6604)
		(drill 0.3302)
		(layers "F.Cu" "B.Cu")
		(net "COMP_B_PRI_INS_N")
	)
	(via
		(at 320.56705 -75.4634)
		(size 0.5588)
		(drill 0.3048)
		(layers "F.Cu" "B.Cu")
		(net "COMP_B_PRI_INS_N")
	)
	(via
		(at 302.1838 -78.365858)
		(size 0.5588)
		(drill 0.3048)
		(layers "F.Cu" "B.Cu")
		(net "COMP_B_PRI_INS_N")
	)
	(segment
		(start 302.1838 -78.365858)
		(end 302.1838 -77.545438)
		(width 0.13335)
		(layer "In2.Cu")
		(net "COMP_B_PRI_INS_N")
	)
	(segment
		(start 302.1838 -77.545438)
		(end 304.265838 -75.4634)
		(width 0.13335)
		(layer "In2.Cu")
		(net "COMP_B_PRI_INS_N")
	)
	(segment
		(start 304.265838 -75.4634)
		(end 320.56705 -75.4634)
		(width 0.13335)
		(layer "In2.Cu")
		(net "COMP_B_PRI_INS_N")
	)
	(segment
		(start 334.618076 -33.006284)
		(end 334.618076 -41.436544)
		(width 0.12065)
		(layer "In4.Cu")
		(net "COMP_B_PRI_INS_N")
	)
	(segment
		(start 330.11745 -64.079882)
		(end 326.897238 -67.300094)
		(width 0.12065)
		(layer "In4.Cu")
		(net "COMP_B_PRI_INS_N")
	)
	(segment
		(start 338.114386 -23.870412)
		(end 336.235548 -25.74925)
		(width 0.12065)
		(layer "In4.Cu")
		(net "COMP_B_PRI_INS_N")
	)
	(segment
		(start 326.897238 -67.300094)
		(end 326.897238 -69.133212)
		(width 0.12065)
		(layer "In4.Cu")
		(net "COMP_B_PRI_INS_N")
	)
	(segment
		(start 336.252566 -14.205966)
		(end 338.114386 -16.067786)
		(width 0.12065)
		(layer "In4.Cu")
		(net "COMP_B_PRI_INS_N")
	)
	(segment
		(start 338.114386 -16.067786)
		(end 338.114386 -23.870412)
		(width 0.12065)
		(layer "In4.Cu")
		(net "COMP_B_PRI_INS_N")
	)
	(segment
		(start 334.618076 -41.436544)
		(end 330.11745 -45.93717)
		(width 0.12065)
		(layer "In4.Cu")
		(net "COMP_B_PRI_INS_N")
	)
	(segment
		(start 326.897238 -69.133212)
		(end 320.56705 -75.4634)
		(width 0.12065)
		(layer "In4.Cu")
		(net "COMP_B_PRI_INS_N")
	)
	(segment
		(start 336.235548 -31.388812)
		(end 334.618076 -33.006284)
		(width 0.12065)
		(layer "In4.Cu")
		(net "COMP_B_PRI_INS_N")
	)
	(segment
		(start 336.235548 -25.74925)
		(end 336.235548 -31.388812)
		(width 0.12065)
		(layer "In4.Cu")
		(net "COMP_B_PRI_INS_N")
	)
	(segment
		(start 330.11745 -45.93717)
		(end 330.11745 -64.079882)
		(width 0.12065)
		(layer "In4.Cu")
		(net "COMP_B_PRI_INS_N")
	)
	(segment
		(start 297.9166 -74.9046)
		(end 297.9166 -73.1266)
		(width 0.17145)
		(layer "F.Cu")
		(net "COMP_B_POWER_FAIL_N")
	)
	(segment
		(start 297.9166 -73.1266)
		(end 298.7802 -72.263)
		(width 0.17145)
		(layer "F.Cu")
		(net "COMP_B_POWER_FAIL_N")
	)
	(segment
		(start 298.7802 -75.2221)
		(end 298.7802 -76.61656)
		(width 0.17145)
		(layer "F.Cu")
		(net "COMP_B_POWER_FAIL_N")
	)
	(segment
		(start 298.7802 -75.2221)
		(end 298.2341 -75.2221)
		(width 0.17145)
		(layer "F.Cu")
		(net "COMP_B_POWER_FAIL_N")
	)
	(segment
		(start 285.249874 -86.200234)
		(end 289.196526 -86.200234)
		(width 0.17145)
		(layer "F.Cu")
		(net "COMP_B_POWER_FAIL_N")
	)
	(segment
		(start 289.196526 -86.200234)
		(end 298.773088 -76.623672)
		(width 0.17145)
		(layer "F.Cu")
		(net "COMP_B_POWER_FAIL_N")
	)
	(segment
		(start 298.7802 -76.61656)
		(end 298.773088 -76.623672)
		(width 0.17145)
		(layer "F.Cu")
		(net "COMP_B_POWER_FAIL_N")
	)
	(segment
		(start 298.2341 -75.2221)
		(end 297.9166 -74.9046)
		(width 0.17145)
		(layer "F.Cu")
		(net "COMP_B_POWER_FAIL_N")
	)
	(via
		(at 348.557596 -69.309996)
		(size 0.5588)
		(drill 0.3048)
		(layers "F.Cu" "B.Cu")
		(net "COMP_B_POWER_FAIL_N")
	)
	(via
		(at 298.7802 -72.263)
		(size 0.5588)
		(drill 0.3048)
		(layers "F.Cu" "B.Cu")
		(net "COMP_B_POWER_FAIL_N")
	)
	(via
		(at 298.773088 -76.623672)
		(size 0.6604)
		(drill 0.3302)
		(layers "F.Cu" "B.Cu")
		(net "COMP_B_POWER_FAIL_N")
	)
	(segment
		(start 340.779862 -71.839582)
		(end 343.385394 -69.23405)
		(width 0.13335)
		(layer "In2.Cu")
		(net "COMP_B_POWER_FAIL_N")
	)
	(segment
		(start 302.258984 -70.919848)
		(end 303.178718 -71.839582)
		(width 0.13335)
		(layer "In2.Cu")
		(net "COMP_B_POWER_FAIL_N")
	)
	(segment
		(start 343.385394 -69.23405)
		(end 348.48165 -69.23405)
		(width 0.13335)
		(layer "In2.Cu")
		(net "COMP_B_POWER_FAIL_N")
	)
	(segment
		(start 300.123352 -70.919848)
		(end 302.258984 -70.919848)
		(width 0.13335)
		(layer "In2.Cu")
		(net "COMP_B_POWER_FAIL_N")
	)
	(segment
		(start 298.7802 -72.263)
		(end 300.123352 -70.919848)
		(width 0.13335)
		(layer "In2.Cu")
		(net "COMP_B_POWER_FAIL_N")
	)
	(segment
		(start 303.178718 -71.839582)
		(end 340.779862 -71.839582)
		(width 0.13335)
		(layer "In2.Cu")
		(net "COMP_B_POWER_FAIL_N")
	)
	(segment
		(start 348.48165 -69.23405)
		(end 348.557596 -69.309996)
		(width 0.13335)
		(layer "In2.Cu")
		(net "COMP_B_POWER_FAIL_N")
	)
	(segment
		(start 355.29774 -41.502838)
		(end 348.557596 -48.242982)
		(width 0.12065)
		(layer "In4.Cu")
		(net "COMP_B_POWER_FAIL_N")
	)
	(segment
		(start 359.890568 -33.08477)
		(end 355.29774 -37.677598)
		(width 0.12065)
		(layer "In4.Cu")
		(net "COMP_B_POWER_FAIL_N")
	)
	(segment
		(start 355.29774 -37.677598)
		(end 355.29774 -41.502838)
		(width 0.12065)
		(layer "In4.Cu")
		(net "COMP_B_POWER_FAIL_N")
	)
	(segment
		(start 360.549952 -26.950162)
		(end 359.890568 -27.609546)
		(width 0.12065)
		(layer "In4.Cu")
		(net "COMP_B_POWER_FAIL_N")
	)
	(segment
		(start 348.557596 -48.242982)
		(end 348.557596 -69.309996)
		(width 0.12065)
		(layer "In4.Cu")
		(net "COMP_B_POWER_FAIL_N")
	)
	(segment
		(start 359.890568 -27.609546)
		(end 359.890568 -33.08477)
		(width 0.12065)
		(layer "In4.Cu")
		(net "COMP_B_POWER_FAIL_N")
	)
	(segment
		(start 282.037536 -141.499844)
		(end 282.894786 -140.642594)
		(width 0.17145)
		(layer "F.Cu")
		(net "COMP_B_FAST_THROTTLE_N")
	)
	(segment
		(start 308.748938 -66.483738)
		(end 308.7624 -66.4972)
		(width 0.17145)
		(layer "F.Cu")
		(net "COMP_B_FAST_THROTTLE_N")
	)
	(segment
		(start 308.748938 -66.510662)
		(end 308.7624 -66.4972)
		(width 0.17145)
		(layer "F.Cu")
		(net "COMP_B_FAST_THROTTLE_N")
	)
	(segment
		(start 308.748938 -67.093338)
		(end 308.748938 -66.510662)
		(width 0.17145)
		(layer "F.Cu")
		(net "COMP_B_FAST_THROTTLE_N")
	)
	(segment
		(start 280.75001 -141.499844)
		(end 282.037536 -141.499844)
		(width 0.17145)
		(layer "F.Cu")
		(net "COMP_B_FAST_THROTTLE_N")
	)
	(segment
		(start 311.6834 -89.6366)
		(end 311.6834 -70.0278)
		(width 0.17145)
		(layer "F.Cu")
		(net "COMP_B_FAST_THROTTLE_N")
	)
	(segment
		(start 309.270654 -92.049346)
		(end 311.6834 -89.6366)
		(width 0.17145)
		(layer "F.Cu")
		(net "COMP_B_FAST_THROTTLE_N")
	)
	(segment
		(start 344.026998 -20.697952)
		(end 345.02217 -20.697952)
		(width 0.17145)
		(layer "F.Cu")
		(net "COMP_B_FAST_THROTTLE_N")
	)
	(segment
		(start 308.748938 -65.21831)
		(end 308.748938 -66.483738)
		(width 0.17145)
		(layer "F.Cu")
		(net "COMP_B_FAST_THROTTLE_N")
	)
	(segment
		(start 311.6834 -70.0278)
		(end 309.9308 -68.2752)
		(width 0.17145)
		(layer "F.Cu")
		(net "COMP_B_FAST_THROTTLE_N")
	)
	(segment
		(start 283.68498 -140.642594)
		(end 284.684978 -139.642596)
		(width 0.17145)
		(layer "F.Cu")
		(net "COMP_B_FAST_THROTTLE_N")
	)
	(segment
		(start 309.270654 -117.062758)
		(end 309.270654 -92.049346)
		(width 0.17145)
		(layer "F.Cu")
		(net "COMP_B_FAST_THROTTLE_N")
	)
	(segment
		(start 286.690816 -139.642596)
		(end 309.270654 -117.062758)
		(width 0.17145)
		(layer "F.Cu")
		(net "COMP_B_FAST_THROTTLE_N")
	)
	(segment
		(start 284.684978 -139.642596)
		(end 286.690816 -139.642596)
		(width 0.17145)
		(layer "F.Cu")
		(net "COMP_B_FAST_THROTTLE_N")
	)
	(segment
		(start 309.9308 -68.2752)
		(end 308.748938 -67.093338)
		(width 0.17145)
		(layer "F.Cu")
		(net "COMP_B_FAST_THROTTLE_N")
	)
	(segment
		(start 282.894786 -140.642594)
		(end 283.68498 -140.642594)
		(width 0.17145)
		(layer "F.Cu")
		(net "COMP_B_FAST_THROTTLE_N")
	)
	(via
		(at 309.9308 -68.2752)
		(size 0.6604)
		(drill 0.3302)
		(layers "F.Cu" "B.Cu")
		(net "COMP_B_FAST_THROTTLE_N")
	)
	(via
		(at 308.7624 -66.4972)
		(size 0.5588)
		(drill 0.3048)
		(layers "F.Cu" "B.Cu")
		(net "COMP_B_FAST_THROTTLE_N")
	)
	(via
		(at 345.02217 -20.697952)
		(size 0.5588)
		(drill 0.3048)
		(layers "F.Cu" "B.Cu")
		(net "COMP_B_FAST_THROTTLE_N")
	)
	(segment
		(start 345.893644 -21.569426)
		(end 345.02217 -20.697952)
		(width 0.13335)
		(layer "In2.Cu")
		(net "COMP_B_FAST_THROTTLE_N")
	)
	(segment
		(start 357.413306 -32.768286)
		(end 353.66325 -32.768286)
		(width 0.13335)
		(layer "In2.Cu")
		(net "COMP_B_FAST_THROTTLE_N")
	)
	(segment
		(start 359.558336 -26.237946)
		(end 359.558336 -29.08173)
		(width 0.13335)
		(layer "In2.Cu")
		(net "COMP_B_FAST_THROTTLE_N")
	)
	(segment
		(start 360.549952 -25.550114)
		(end 360.246168 -25.550114)
		(width 0.13335)
		(layer "In2.Cu")
		(net "COMP_B_FAST_THROTTLE_N")
	)
	(segment
		(start 345.893644 -24.99868)
		(end 345.893644 -21.569426)
		(width 0.13335)
		(layer "In2.Cu")
		(net "COMP_B_FAST_THROTTLE_N")
	)
	(segment
		(start 359.018078 -31.354268)
		(end 358.827324 -31.354268)
		(width 0.13335)
		(layer "In2.Cu")
		(net "COMP_B_FAST_THROTTLE_N")
	)
	(segment
		(start 359.35158 -31.020766)
		(end 359.018078 -31.354268)
		(width 0.13335)
		(layer "In2.Cu")
		(net "COMP_B_FAST_THROTTLE_N")
	)
	(segment
		(start 353.66325 -32.768286)
		(end 345.893644 -24.99868)
		(width 0.13335)
		(layer "In2.Cu")
		(net "COMP_B_FAST_THROTTLE_N")
	)
	(segment
		(start 359.35158 -29.288486)
		(end 359.35158 -31.020766)
		(width 0.13335)
		(layer "In2.Cu")
		(net "COMP_B_FAST_THROTTLE_N")
	)
	(segment
		(start 360.246168 -25.550114)
		(end 359.558336 -26.237946)
		(width 0.13335)
		(layer "In2.Cu")
		(net "COMP_B_FAST_THROTTLE_N")
	)
	(segment
		(start 359.558336 -29.08173)
		(end 359.35158 -29.288486)
		(width 0.13335)
		(layer "In2.Cu")
		(net "COMP_B_FAST_THROTTLE_N")
	)
	(segment
		(start 358.827324 -31.354268)
		(end 357.413306 -32.768286)
		(width 0.13335)
		(layer "In2.Cu")
		(net "COMP_B_FAST_THROTTLE_N")
	)
	(segment
		(start 331.851254 -21.210524)
		(end 331.851254 -21.618448)
		(width 0.12065)
		(layer "In4.Cu")
		(net "COMP_B_FAST_THROTTLE_N")
	)
	(segment
		(start 331.851 -21.618702)
		(end 331.851 -23.466044)
		(width 0.12065)
		(layer "In4.Cu")
		(net "COMP_B_FAST_THROTTLE_N")
	)
	(segment
		(start 326.635618 -48.623982)
		(end 308.7624 -66.4972)
		(width 0.12065)
		(layer "In4.Cu")
		(net "COMP_B_FAST_THROTTLE_N")
	)
	(segment
		(start 331.851 -17.911318)
		(end 331.851 -21.21027)
		(width 0.12065)
		(layer "In4.Cu")
		(net "COMP_B_FAST_THROTTLE_N")
	)
	(segment
		(start 331.851 -38.43528)
		(end 326.635618 -43.650662)
		(width 0.12065)
		(layer "In4.Cu")
		(net "COMP_B_FAST_THROTTLE_N")
	)
	(segment
		(start 331.851 -23.466044)
		(end 331.79766 -23.519384)
		(width 0.12065)
		(layer "In4.Cu")
		(net "COMP_B_FAST_THROTTLE_N")
	)
	(segment
		(start 345.02217 -20.697952)
		(end 344.738452 -20.414234)
		(width 0.12065)
		(layer "In4.Cu")
		(net "COMP_B_FAST_THROTTLE_N")
	)
	(segment
		(start 344.738452 -20.414234)
		(end 344.738452 -18.261838)
		(width 0.12065)
		(layer "In4.Cu")
		(net "COMP_B_FAST_THROTTLE_N")
	)
	(segment
		(start 336.08137 -13.680948)
		(end 331.851 -17.911318)
		(width 0.12065)
		(layer "In4.Cu")
		(net "COMP_B_FAST_THROTTLE_N")
	)
	(segment
		(start 331.851 -25.80005)
		(end 331.851 -38.43528)
		(width 0.12065)
		(layer "In4.Cu")
		(net "COMP_B_FAST_THROTTLE_N")
	)
	(segment
		(start 344.738452 -18.261838)
		(end 340.157562 -13.680948)
		(width 0.12065)
		(layer "In4.Cu")
		(net "COMP_B_FAST_THROTTLE_N")
	)
	(segment
		(start 331.851254 -25.799796)
		(end 331.851 -25.80005)
		(width 0.12065)
		(layer "In4.Cu")
		(net "COMP_B_FAST_THROTTLE_N")
	)
	(segment
		(start 331.79766 -23.927308)
		(end 331.851 -23.980648)
		(width 0.12065)
		(layer "In4.Cu")
		(net "COMP_B_FAST_THROTTLE_N")
	)
	(segment
		(start 331.851 -23.980648)
		(end 331.851 -25.391618)
		(width 0.12065)
		(layer "In4.Cu")
		(net "COMP_B_FAST_THROTTLE_N")
	)
	(segment
		(start 326.635618 -43.650662)
		(end 326.635618 -48.623982)
		(width 0.12065)
		(layer "In4.Cu")
		(net "COMP_B_FAST_THROTTLE_N")
	)
	(segment
		(start 331.851254 -25.391872)
		(end 331.851254 -25.799796)
		(width 0.12065)
		(layer "In4.Cu")
		(net "COMP_B_FAST_THROTTLE_N")
	)
	(segment
		(start 331.851 -25.391618)
		(end 331.851254 -25.391872)
		(width 0.12065)
		(layer "In4.Cu")
		(net "COMP_B_FAST_THROTTLE_N")
	)
	(segment
		(start 331.79766 -23.519384)
		(end 331.79766 -23.927308)
		(width 0.12065)
		(layer "In4.Cu")
		(net "COMP_B_FAST_THROTTLE_N")
	)
	(segment
		(start 340.157562 -13.680948)
		(end 336.08137 -13.680948)
		(width 0.12065)
		(layer "In4.Cu")
		(net "COMP_B_FAST_THROTTLE_N")
	)
	(segment
		(start 331.851254 -21.618448)
		(end 331.851 -21.618702)
		(width 0.12065)
		(layer "In4.Cu")
		(net "COMP_B_FAST_THROTTLE_N")
	)
	(segment
		(start 331.851 -21.21027)
		(end 331.851254 -21.210524)
		(width 0.12065)
		(layer "In4.Cu")
		(net "COMP_B_FAST_THROTTLE_N")
	)
	(segment
		(start 238.05007 -3.41249)
		(end 236.405166 -5.057394)
		(width 0.17145)
		(layer "F.Cu")
		(net "COMP_A_SEC_INS_N")
	)
	(segment
		(start 224.903792 -9.49452)
		(end 224.8535 -9.544812)
		(width 0.17145)
		(layer "F.Cu")
		(net "COMP_A_SEC_INS_N")
	)
	(segment
		(start 238.05007 -3.200146)
		(end 238.05007 -3.41249)
		(width 0.17145)
		(layer "F.Cu")
		(net "COMP_A_SEC_INS_N")
	)
	(segment
		(start 236.405166 -5.057394)
		(end 235.478066 -5.057394)
		(width 0.17145)
		(layer "F.Cu")
		(net "COMP_A_SEC_INS_N")
	)
	(segment
		(start 91.891104 -17.993868)
		(end 90.837766 -16.94053)
		(width 0.17145)
		(layer "F.Cu")
		(net "COMP_A_SEC_INS_N")
	)
	(segment
		(start 224.8535 -9.544812)
		(end 224.8535 -10.541)
		(width 0.17145)
		(layer "F.Cu")
		(net "COMP_A_SEC_INS_N")
	)
	(segment
		(start 90.837766 -16.94053)
		(end 89.889076 -16.94053)
		(width 0.17145)
		(layer "F.Cu")
		(net "COMP_A_SEC_INS_N")
	)
	(segment
		(start 89.889076 -16.94053)
		(end 87.749634 -16.94053)
		(width 0.17145)
		(layer "F.Cu")
		(net "COMP_A_SEC_INS_N")
	)
	(segment
		(start 235.478066 -5.057394)
		(end 229.99446 -10.541)
		(width 0.17145)
		(layer "F.Cu")
		(net "COMP_A_SEC_INS_N")
	)
	(segment
		(start 229.99446 -10.541)
		(end 224.8535 -10.541)
		(width 0.17145)
		(layer "F.Cu")
		(net "COMP_A_SEC_INS_N")
	)
	(via
		(at 223.913446 -82.881216)
		(size 0.5588)
		(drill 0.3048)
		(layers "F.Cu" "B.Cu")
		(net "COMP_A_SEC_INS_N")
	)
	(via
		(at 91.891104 -17.993868)
		(size 0.5588)
		(drill 0.3048)
		(layers "F.Cu" "B.Cu")
		(net "COMP_A_SEC_INS_N")
	)
	(via
		(at 224.903792 -9.49452)
		(size 0.5588)
		(drill 0.3048)
		(layers "F.Cu" "B.Cu")
		(net "COMP_A_SEC_INS_N")
	)
	(via
		(at 89.889076 -16.94053)
		(size 0.6604)
		(drill 0.3302)
		(layers "F.Cu" "B.Cu")
		(net "COMP_A_SEC_INS_N")
	)
	(segment
		(start 187.84443 -75.868276)
		(end 187.84443 -59.738514)
		(width 0.13335)
		(layer "In2.Cu")
		(net "COMP_A_SEC_INS_N")
	)
	(segment
		(start 147.817332 -36.60775)
		(end 147.319238 -37.105844)
		(width 0.13335)
		(layer "In2.Cu")
		(net "COMP_A_SEC_INS_N")
	)
	(segment
		(start 104.729026 -35.220656)
		(end 91.2368 -21.72843)
		(width 0.13335)
		(layer "In2.Cu")
		(net "COMP_A_SEC_INS_N")
	)
	(segment
		(start 223.913446 -82.881216)
		(end 221.85122 -84.943442)
		(width 0.13335)
		(layer "In2.Cu")
		(net "COMP_A_SEC_INS_N")
	)
	(segment
		(start 200.859898 -84.943442)
		(end 200.826878 -84.910422)
		(width 0.13335)
		(layer "In2.Cu")
		(net "COMP_A_SEC_INS_N")
	)
	(segment
		(start 148.066252 -36.358576)
		(end 147.817332 -36.607496)
		(width 0.13335)
		(layer "In2.Cu")
		(net "COMP_A_SEC_INS_N")
	)
	(segment
		(start 91.2368 -21.72843)
		(end 91.2368 -18.648172)
		(width 0.13335)
		(layer "In2.Cu")
		(net "COMP_A_SEC_INS_N")
	)
	(segment
		(start 91.2368 -18.648172)
		(end 91.891104 -17.993868)
		(width 0.13335)
		(layer "In2.Cu")
		(net "COMP_A_SEC_INS_N")
	)
	(segment
		(start 182.776114 -49.029366)
		(end 170.105324 -36.358576)
		(width 0.13335)
		(layer "In2.Cu")
		(net "COMP_A_SEC_INS_N")
	)
	(segment
		(start 200.826878 -84.910422)
		(end 196.886576 -84.910422)
		(width 0.13335)
		(layer "In2.Cu")
		(net "COMP_A_SEC_INS_N")
	)
	(segment
		(start 147.319238 -37.106098)
		(end 146.69389 -37.731446)
		(width 0.13335)
		(layer "In2.Cu")
		(net "COMP_A_SEC_INS_N")
	)
	(segment
		(start 187.84443 -59.738514)
		(end 182.776114 -54.670198)
		(width 0.13335)
		(layer "In2.Cu")
		(net "COMP_A_SEC_INS_N")
	)
	(segment
		(start 221.85122 -84.943442)
		(end 200.859898 -84.943442)
		(width 0.13335)
		(layer "In2.Cu")
		(net "COMP_A_SEC_INS_N")
	)
	(segment
		(start 125.083824 -35.220656)
		(end 104.729026 -35.220656)
		(width 0.13335)
		(layer "In2.Cu")
		(net "COMP_A_SEC_INS_N")
	)
	(segment
		(start 147.319238 -37.105844)
		(end 147.319238 -37.106098)
		(width 0.13335)
		(layer "In2.Cu")
		(net "COMP_A_SEC_INS_N")
	)
	(segment
		(start 146.69389 -37.731446)
		(end 127.594614 -37.731446)
		(width 0.13335)
		(layer "In2.Cu")
		(net "COMP_A_SEC_INS_N")
	)
	(segment
		(start 196.886576 -84.910422)
		(end 187.84443 -75.868276)
		(width 0.13335)
		(layer "In2.Cu")
		(net "COMP_A_SEC_INS_N")
	)
	(segment
		(start 182.776114 -54.670198)
		(end 182.776114 -49.029366)
		(width 0.13335)
		(layer "In2.Cu")
		(net "COMP_A_SEC_INS_N")
	)
	(segment
		(start 127.594614 -37.731446)
		(end 125.083824 -35.220656)
		(width 0.13335)
		(layer "In2.Cu")
		(net "COMP_A_SEC_INS_N")
	)
	(segment
		(start 170.105324 -36.358576)
		(end 148.066252 -36.358576)
		(width 0.13335)
		(layer "In2.Cu")
		(net "COMP_A_SEC_INS_N")
	)
	(segment
		(start 147.817332 -36.607496)
		(end 147.817332 -36.60775)
		(width 0.13335)
		(layer "In2.Cu")
		(net "COMP_A_SEC_INS_N")
	)
	(segment
		(start 223.913446 -24.117554)
		(end 223.913446 -82.881216)
		(width 0.12065)
		(layer "In4.Cu")
		(net "COMP_A_SEC_INS_N")
	)
	(segment
		(start 226.374706 -12.738862)
		(end 226.374706 -21.656294)
		(width 0.12065)
		(layer "In4.Cu")
		(net "COMP_A_SEC_INS_N")
	)
	(segment
		(start 224.903792 -9.49452)
		(end 224.903792 -11.267948)
		(width 0.12065)
		(layer "In4.Cu")
		(net "COMP_A_SEC_INS_N")
	)
	(segment
		(start 224.903792 -11.267948)
		(end 226.374706 -12.738862)
		(width 0.12065)
		(layer "In4.Cu")
		(net "COMP_A_SEC_INS_N")
	)
	(segment
		(start 226.374706 -21.656294)
		(end 223.913446 -24.117554)
		(width 0.12065)
		(layer "In4.Cu")
		(net "COMP_A_SEC_INS_N")
	)
	(segment
		(start 132.382514 -138.449812)
		(end 132.382514 -138.737086)
		(width 0.17145)
		(layer "F.Cu")
		(net "COMP_A_PWR_EN")
	)
	(segment
		(start 133.592316 -138.342624)
		(end 136.365234 -138.342624)
		(width 0.17145)
		(layer "F.Cu")
		(net "COMP_A_PWR_EN")
	)
	(segment
		(start 133.497066 -138.437874)
		(end 133.592316 -138.342624)
		(width 0.17145)
		(layer "F.Cu")
		(net "COMP_A_PWR_EN")
	)
	(segment
		(start 132.382514 -138.449812)
		(end 133.497066 -138.449812)
		(width 0.17145)
		(layer "F.Cu")
		(net "COMP_A_PWR_EN")
	)
	(segment
		(start 132.382514 -138.737086)
		(end 131.7498 -139.3698)
		(width 0.17145)
		(layer "F.Cu")
		(net "COMP_A_PWR_EN")
	)
	(segment
		(start 133.497066 -138.449812)
		(end 133.497066 -138.437874)
		(width 0.17145)
		(layer "F.Cu")
		(net "COMP_A_PWR_EN")
	)
	(via
		(at 115.87226 -89.94267)
		(size 0.5588)
		(drill 0.3048)
		(layers "F.Cu" "B.Cu")
		(net "COMP_A_PWR_EN")
	)
	(via
		(at 135.86587 -89.94267)
		(size 0.5588)
		(drill 0.3048)
		(layers "F.Cu" "B.Cu")
		(net "COMP_A_PWR_EN")
	)
	(via
		(at 132.382514 -138.449812)
		(size 0.6604)
		(drill 0.3302)
		(layers "F.Cu" "B.Cu")
		(net "COMP_A_PWR_EN")
	)
	(via
		(at 131.7498 -139.3698)
		(size 0.5588)
		(drill 0.3048)
		(layers "F.Cu" "B.Cu")
		(net "COMP_A_PWR_EN")
	)
	(segment
		(start 115.87226 -89.94267)
		(end 135.86587 -89.94267)
		(width 0.13335)
		(layer "In2.Cu")
		(net "COMP_A_PWR_EN")
	)
	(segment
		(start 115.695476 -32.920686)
		(end 115.695476 -37.386006)
		(width 0.12065)
		(layer "In4.Cu")
		(net "COMP_A_PWR_EN")
	)
	(segment
		(start 135.86587 -127.53213)
		(end 135.86587 -124.42063)
		(width 0.12065)
		(layer "In4.Cu")
		(net "COMP_A_PWR_EN")
	)
	(segment
		(start 135.86587 -124.42063)
		(end 136.217152 -124.069348)
		(width 0.12065)
		(layer "In4.Cu")
		(net "COMP_A_PWR_EN")
	)
	(segment
		(start 136.217152 -124.069348)
		(end 136.217152 -123.661424)
		(width 0.12065)
		(layer "In4.Cu")
		(net "COMP_A_PWR_EN")
	)
	(segment
		(start 132.266436 -133.519164)
		(end 134.7216 -131.064)
		(width 0.12065)
		(layer "In4.Cu")
		(net "COMP_A_PWR_EN")
	)
	(segment
		(start 131.7498 -139.3698)
		(end 132.266436 -138.853164)
		(width 0.12065)
		(layer "In4.Cu")
		(net "COMP_A_PWR_EN")
	)
	(segment
		(start 135.86587 -123.310142)
		(end 135.86587 -89.94267)
		(width 0.12065)
		(layer "In4.Cu")
		(net "COMP_A_PWR_EN")
	)
	(segment
		(start 115.70335 -27.429968)
		(end 115.70335 -32.912812)
		(width 0.12065)
		(layer "In4.Cu")
		(net "COMP_A_PWR_EN")
	)
	(segment
		(start 134.7216 -128.6764)
		(end 135.86587 -127.53213)
		(width 0.12065)
		(layer "In4.Cu")
		(net "COMP_A_PWR_EN")
	)
	(segment
		(start 134.7216 -131.064)
		(end 134.7216 -128.6764)
		(width 0.12065)
		(layer "In4.Cu")
		(net "COMP_A_PWR_EN")
	)
	(segment
		(start 107.984544 -55.589932)
		(end 107.984544 -55.997856)
		(width 0.12065)
		(layer "In4.Cu")
		(net "COMP_A_PWR_EN")
	)
	(segment
		(start 115.552982 -27.2796)
		(end 115.70335 -27.429968)
		(width 0.12065)
		(layer "In4.Cu")
		(net "COMP_A_PWR_EN")
	)
	(segment
		(start 115.70335 -32.912812)
		(end 115.695476 -32.920686)
		(width 0.12065)
		(layer "In4.Cu")
		(net "COMP_A_PWR_EN")
	)
	(segment
		(start 107.995212 -55.579264)
		(end 107.984544 -55.589932)
		(width 0.12065)
		(layer "In4.Cu")
		(net "COMP_A_PWR_EN")
	)
	(segment
		(start 116.350034 -25.950164)
		(end 115.552982 -26.747216)
		(width 0.12065)
		(layer "In4.Cu")
		(net "COMP_A_PWR_EN")
	)
	(segment
		(start 115.695476 -37.386006)
		(end 107.995212 -45.08627)
		(width 0.12065)
		(layer "In4.Cu")
		(net "COMP_A_PWR_EN")
	)
	(segment
		(start 107.995212 -45.08627)
		(end 107.995212 -55.579264)
		(width 0.12065)
		(layer "In4.Cu")
		(net "COMP_A_PWR_EN")
	)
	(segment
		(start 132.266436 -138.853164)
		(end 132.266436 -133.519164)
		(width 0.12065)
		(layer "In4.Cu")
		(net "COMP_A_PWR_EN")
	)
	(segment
		(start 107.995212 -56.008524)
		(end 107.995212 -82.065622)
		(width 0.12065)
		(layer "In4.Cu")
		(net "COMP_A_PWR_EN")
	)
	(segment
		(start 115.552982 -26.747216)
		(end 115.552982 -27.2796)
		(width 0.12065)
		(layer "In4.Cu")
		(net "COMP_A_PWR_EN")
	)
	(segment
		(start 107.984544 -55.997856)
		(end 107.995212 -56.008524)
		(width 0.12065)
		(layer "In4.Cu")
		(net "COMP_A_PWR_EN")
	)
	(segment
		(start 107.995212 -82.065622)
		(end 115.87226 -89.94267)
		(width 0.12065)
		(layer "In4.Cu")
		(net "COMP_A_PWR_EN")
	)
	(segment
		(start 136.217152 -123.661424)
		(end 135.86587 -123.310142)
		(width 0.12065)
		(layer "In4.Cu")
		(net "COMP_A_PWR_EN")
	)
	(via
		(at 113.673382 -120.8786)
		(size 0.5588)
		(drill 0.3048)
		(layers "F.Cu" "B.Cu")
		(net "COMP_A_PWR_BTN_N")
	)
	(segment
		(start 236.402626 -107.350814)
		(end 235.995972 -107.350814)
		(width 0.13335)
		(layer "In2.Cu")
		(net "COMP_A_PWR_BTN_N")
	)
	(segment
		(start 180.066696 -120.8786)
		(end 113.673382 -120.8786)
		(width 0.13335)
		(layer "In2.Cu")
		(net "COMP_A_PWR_BTN_N")
	)
	(segment
		(start 234.6452 -109.676946)
		(end 234.645454 -109.6772)
		(width 0.13335)
		(layer "In2.Cu")
		(net "COMP_A_PWR_BTN_N")
	)
	(segment
		(start 230.976678 -114.430048)
		(end 230.976678 -115.987322)
		(width 0.13335)
		(layer "In2.Cu")
		(net "COMP_A_PWR_BTN_N")
	)
	(segment
		(start 234.6452 -110.440216)
		(end 234.6452 -110.761526)
		(width 0.13335)
		(layer "In2.Cu")
		(net "COMP_A_PWR_BTN_N")
	)
	(segment
		(start 242.549934 -106.499914)
		(end 237.253526 -106.499914)
		(width 0.13335)
		(layer "In2.Cu")
		(net "COMP_A_PWR_BTN_N")
	)
	(segment
		(start 230.976678 -115.987322)
		(end 222.34779 -124.61621)
		(width 0.13335)
		(layer "In2.Cu")
		(net "COMP_A_PWR_BTN_N")
	)
	(segment
		(start 237.253526 -106.499914)
		(end 236.402626 -107.350814)
		(width 0.13335)
		(layer "In2.Cu")
		(net "COMP_A_PWR_BTN_N")
	)
	(segment
		(start 234.645454 -110.439962)
		(end 234.6452 -110.440216)
		(width 0.13335)
		(layer "In2.Cu")
		(net "COMP_A_PWR_BTN_N")
	)
	(segment
		(start 234.645454 -109.6772)
		(end 234.645454 -110.439962)
		(width 0.13335)
		(layer "In2.Cu")
		(net "COMP_A_PWR_BTN_N")
	)
	(segment
		(start 222.34779 -124.61621)
		(end 183.804306 -124.61621)
		(width 0.13335)
		(layer "In2.Cu")
		(net "COMP_A_PWR_BTN_N")
	)
	(segment
		(start 235.995972 -107.350814)
		(end 234.6452 -108.701586)
		(width 0.13335)
		(layer "In2.Cu")
		(net "COMP_A_PWR_BTN_N")
	)
	(segment
		(start 183.804306 -124.61621)
		(end 180.066696 -120.8786)
		(width 0.13335)
		(layer "In2.Cu")
		(net "COMP_A_PWR_BTN_N")
	)
	(segment
		(start 234.6452 -110.761526)
		(end 230.976678 -114.430048)
		(width 0.13335)
		(layer "In2.Cu")
		(net "COMP_A_PWR_BTN_N")
	)
	(segment
		(start 234.6452 -108.701586)
		(end 234.6452 -109.676946)
		(width 0.13335)
		(layer "In2.Cu")
		(net "COMP_A_PWR_BTN_N")
	)
	(segment
		(start 112.954562 -31.911036)
		(end 112.954562 -37.681408)
		(width 0.12065)
		(layer "In4.Cu")
		(net "COMP_A_PWR_BTN_N")
	)
	(segment
		(start 113.673382 -90.805762)
		(end 113.673382 -120.8786)
		(width 0.12065)
		(layer "In4.Cu")
		(net "COMP_A_PWR_BTN_N")
	)
	(segment
		(start 113.402872 -31.462726)
		(end 112.954562 -31.911036)
		(width 0.12065)
		(layer "In4.Cu")
		(net "COMP_A_PWR_BTN_N")
	)
	(segment
		(start 105.3846 -82.51698)
		(end 113.673382 -90.805762)
		(width 0.12065)
		(layer "In4.Cu")
		(net "COMP_A_PWR_BTN_N")
	)
	(segment
		(start 112.954562 -37.681408)
		(end 105.3846 -45.25137)
		(width 0.12065)
		(layer "In4.Cu")
		(net "COMP_A_PWR_BTN_N")
	)
	(segment
		(start 105.3846 -45.25137)
		(end 105.3846 -82.51698)
		(width 0.12065)
		(layer "In4.Cu")
		(net "COMP_A_PWR_BTN_N")
	)
	(segment
		(start 112.750092 -24.689308)
		(end 113.402872 -25.342088)
		(width 0.12065)
		(layer "In4.Cu")
		(net "COMP_A_PWR_BTN_N")
	)
	(segment
		(start 112.750092 -24.550116)
		(end 112.750092 -24.689308)
		(width 0.12065)
		(layer "In4.Cu")
		(net "COMP_A_PWR_BTN_N")
	)
	(segment
		(start 113.402872 -25.342088)
		(end 113.402872 -31.462726)
		(width 0.12065)
		(layer "In4.Cu")
		(net "COMP_A_PWR_BTN_N")
	)
	(segment
		(start 234.687872 -96.13773)
		(end 225.425 -96.13773)
		(width 0.17145)
		(layer "F.Cu")
		(net "COMP_A_PRI_INS_N")
	)
	(segment
		(start 224.3328 -96.13773)
		(end 223.089978 -96.13773)
		(width 0.17145)
		(layer "F.Cu")
		(net "COMP_A_PRI_INS_N")
	)
	(segment
		(start 225.425 -96.13773)
		(end 224.3328 -96.13773)
		(width 0.17145)
		(layer "F.Cu")
		(net "COMP_A_PRI_INS_N")
	)
	(segment
		(start 89.42451 -16.29029)
		(end 87.749634 -16.29029)
		(width 0.17145)
		(layer "F.Cu")
		(net "COMP_A_PRI_INS_N")
	)
	(segment
		(start 238.05007 -99.499928)
		(end 234.687872 -96.13773)
		(width 0.17145)
		(layer "F.Cu")
		(net "COMP_A_PRI_INS_N")
	)
	(segment
		(start 89.9414 -15.7734)
		(end 89.42451 -16.29029)
		(width 0.17145)
		(layer "F.Cu")
		(net "COMP_A_PRI_INS_N")
	)
	(via
		(at 225.425 -96.13773)
		(size 0.5588)
		(drill 0.3048)
		(layers "F.Cu" "B.Cu")
		(net "COMP_A_PRI_INS_N")
	)
	(via
		(at 74.066654 -106.299762)
		(size 0.5588)
		(drill 0.3048)
		(layers "F.Cu" "B.Cu")
		(net "COMP_A_PRI_INS_N")
	)
	(via
		(at 224.3328 -96.13773)
		(size 0.6604)
		(drill 0.3302)
		(layers "F.Cu" "B.Cu")
		(net "COMP_A_PRI_INS_N")
	)
	(via
		(at 89.9414 -15.7734)
		(size 0.5588)
		(drill 0.3048)
		(layers "F.Cu" "B.Cu")
		(net "COMP_A_PRI_INS_N")
	)
	(segment
		(start 184.168796 -96.13773)
		(end 172.896276 -107.41025)
		(width 0.13335)
		(layer "In2.Cu")
		(net "COMP_A_PRI_INS_N")
	)
	(segment
		(start 172.896276 -107.41025)
		(end 114.06505 -107.41025)
		(width 0.13335)
		(layer "In2.Cu")
		(net "COMP_A_PRI_INS_N")
	)
	(segment
		(start 225.425 -96.13773)
		(end 184.168796 -96.13773)
		(width 0.13335)
		(layer "In2.Cu")
		(net "COMP_A_PRI_INS_N")
	)
	(segment
		(start 74.573892 -106.807)
		(end 74.066654 -106.299762)
		(width 0.13335)
		(layer "In2.Cu")
		(net "COMP_A_PRI_INS_N")
	)
	(segment
		(start 114.06505 -107.41025)
		(end 113.4618 -106.807)
		(width 0.13335)
		(layer "In2.Cu")
		(net "COMP_A_PRI_INS_N")
	)
	(segment
		(start 113.4618 -106.807)
		(end 74.573892 -106.807)
		(width 0.13335)
		(layer "In2.Cu")
		(net "COMP_A_PRI_INS_N")
	)
	(segment
		(start 74.091038 -53.848762)
		(end 90.636852 -37.302948)
		(width 0.12065)
		(layer "In4.Cu")
		(net "COMP_A_PRI_INS_N")
	)
	(segment
		(start 90.636852 -16.468852)
		(end 89.9414 -15.7734)
		(width 0.12065)
		(layer "In4.Cu")
		(net "COMP_A_PRI_INS_N")
	)
	(segment
		(start 74.066654 -106.299762)
		(end 74.091038 -106.275378)
		(width 0.12065)
		(layer "In4.Cu")
		(net "COMP_A_PRI_INS_N")
	)
	(segment
		(start 74.091038 -106.275378)
		(end 74.091038 -53.848762)
		(width 0.12065)
		(layer "In4.Cu")
		(net "COMP_A_PRI_INS_N")
	)
	(segment
		(start 90.636852 -37.302948)
		(end 90.636852 -16.468852)
		(width 0.12065)
		(layer "In4.Cu")
		(net "COMP_A_PRI_INS_N")
	)
	(segment
		(start 224.2566 -91.2114)
		(end 223.0882 -91.2114)
		(width 0.17145)
		(layer "F.Cu")
		(net "COMP_A_POWER_FAIL_N")
	)
	(segment
		(start 244.47754 -86.200234)
		(end 250.364752 -92.087446)
		(width 0.17145)
		(layer "F.Cu")
		(net "COMP_A_POWER_FAIL_N")
	)
	(segment
		(start 242.549934 -86.200234)
		(end 244.47754 -86.200234)
		(width 0.17145)
		(layer "F.Cu")
		(net "COMP_A_POWER_FAIL_N")
	)
	(segment
		(start 225.3234 -91.2114)
		(end 224.2566 -91.2114)
		(width 0.17145)
		(layer "F.Cu")
		(net "COMP_A_POWER_FAIL_N")
	)
	(via
		(at 250.364752 -92.087446)
		(size 0.5588)
		(drill 0.3048)
		(layers "F.Cu" "B.Cu")
		(net "COMP_A_POWER_FAIL_N")
	)
	(via
		(at 115.0112 -106.911648)
		(size 0.5588)
		(drill 0.3048)
		(layers "F.Cu" "B.Cu")
		(net "COMP_A_POWER_FAIL_N")
	)
	(via
		(at 224.2566 -91.2114)
		(size 0.6604)
		(drill 0.3302)
		(layers "F.Cu" "B.Cu")
		(net "COMP_A_POWER_FAIL_N")
	)
	(via
		(at 225.3234 -91.2114)
		(size 0.5588)
		(drill 0.3048)
		(layers "F.Cu" "B.Cu")
		(net "COMP_A_POWER_FAIL_N")
	)
	(segment
		(start 225.3234 -91.2114)
		(end 228.562662 -94.450662)
		(width 0.13335)
		(layer "In2.Cu")
		(net "COMP_A_POWER_FAIL_N")
	)
	(segment
		(start 247.092216 -94.450662)
		(end 249.455432 -92.087446)
		(width 0.13335)
		(layer "In2.Cu")
		(net "COMP_A_POWER_FAIL_N")
	)
	(segment
		(start 228.562662 -94.450662)
		(end 247.092216 -94.450662)
		(width 0.13335)
		(layer "In2.Cu")
		(net "COMP_A_POWER_FAIL_N")
	)
	(segment
		(start 225.117406 -91.417394)
		(end 225.3234 -91.2114)
		(width 0.13335)
		(layer "In2.Cu")
		(net "COMP_A_POWER_FAIL_N")
	)
	(segment
		(start 249.455432 -92.087446)
		(end 250.364752 -92.087446)
		(width 0.13335)
		(layer "In2.Cu")
		(net "COMP_A_POWER_FAIL_N")
	)
	(segment
		(start 115.0112 -106.911648)
		(end 172.793152 -106.911648)
		(width 0.13335)
		(layer "In2.Cu")
		(net "COMP_A_POWER_FAIL_N")
	)
	(segment
		(start 172.793152 -106.911648)
		(end 188.287406 -91.417394)
		(width 0.13335)
		(layer "In2.Cu")
		(net "COMP_A_POWER_FAIL_N")
	)
	(segment
		(start 188.287406 -91.417394)
		(end 225.117406 -91.417394)
		(width 0.13335)
		(layer "In2.Cu")
		(net "COMP_A_POWER_FAIL_N")
	)
	(segment
		(start 106.782616 -81.870804)
		(end 115.0112 -90.099388)
		(width 0.12065)
		(layer "In4.Cu")
		(net "COMP_A_POWER_FAIL_N")
	)
	(segment
		(start 114.549936 -26.950162)
		(end 115.2271 -27.627326)
		(width 0.12065)
		(layer "In4.Cu")
		(net "COMP_A_POWER_FAIL_N")
	)
	(segment
		(start 115.0112 -90.099388)
		(end 115.0112 -106.911648)
		(width 0.12065)
		(layer "In4.Cu")
		(net "COMP_A_POWER_FAIL_N")
	)
	(segment
		(start 115.2271 -27.627326)
		(end 115.2271 -37.262562)
		(width 0.12065)
		(layer "In4.Cu")
		(net "COMP_A_POWER_FAIL_N")
	)
	(segment
		(start 106.771948 -64.887856)
		(end 106.782616 -64.898524)
		(width 0.12065)
		(layer "In4.Cu")
		(net "COMP_A_POWER_FAIL_N")
	)
	(segment
		(start 106.771948 -64.479932)
		(end 106.771948 -64.887856)
		(width 0.12065)
		(layer "In4.Cu")
		(net "COMP_A_POWER_FAIL_N")
	)
	(segment
		(start 106.782616 -64.898524)
		(end 106.782616 -81.870804)
		(width 0.12065)
		(layer "In4.Cu")
		(net "COMP_A_POWER_FAIL_N")
	)
	(segment
		(start 106.782616 -64.469264)
		(end 106.771948 -64.479932)
		(width 0.12065)
		(layer "In4.Cu")
		(net "COMP_A_POWER_FAIL_N")
	)
	(segment
		(start 115.2271 -37.262562)
		(end 106.782616 -45.707046)
		(width 0.12065)
		(layer "In4.Cu")
		(net "COMP_A_POWER_FAIL_N")
	)
	(segment
		(start 106.782616 -45.707046)
		(end 106.782616 -64.469264)
		(width 0.12065)
		(layer "In4.Cu")
		(net "COMP_A_POWER_FAIL_N")
	)
	(segment
		(start 245.691406 -139.475718)
		(end 250.118118 -139.475718)
		(width 0.17145)
		(layer "F.Cu")
		(net "COMP_A_FAST_THROTTLE_N")
	)
	(segment
		(start 250.118118 -139.475718)
		(end 251.493528 -140.851128)
		(width 0.17145)
		(layer "F.Cu")
		(net "COMP_A_FAST_THROTTLE_N")
	)
	(segment
		(start 243.524532 -141.642592)
		(end 245.691406 -139.475718)
		(width 0.17145)
		(layer "F.Cu")
		(net "COMP_A_FAST_THROTTLE_N")
	)
	(segment
		(start 241.011202 -142.357094)
		(end 241.725704 -141.642592)
		(width 0.17145)
		(layer "F.Cu")
		(net "COMP_A_FAST_THROTTLE_N")
	)
	(segment
		(start 255.6256 -140.851128)
		(end 256.884424 -140.851128)
		(width 0.17145)
		(layer "F.Cu")
		(net "COMP_A_FAST_THROTTLE_N")
	)
	(segment
		(start 238.05007 -141.499844)
		(end 239.337596 -141.499844)
		(width 0.17145)
		(layer "F.Cu")
		(net "COMP_A_FAST_THROTTLE_N")
	)
	(segment
		(start 239.337596 -141.499844)
		(end 240.194846 -142.357094)
		(width 0.17145)
		(layer "F.Cu")
		(net "COMP_A_FAST_THROTTLE_N")
	)
	(segment
		(start 251.493528 -140.851128)
		(end 255.6256 -140.851128)
		(width 0.17145)
		(layer "F.Cu")
		(net "COMP_A_FAST_THROTTLE_N")
	)
	(segment
		(start 256.884424 -140.851128)
		(end 256.8956 -140.839952)
		(width 0.17145)
		(layer "F.Cu")
		(net "COMP_A_FAST_THROTTLE_N")
	)
	(segment
		(start 240.194846 -142.357094)
		(end 241.011202 -142.357094)
		(width 0.17145)
		(layer "F.Cu")
		(net "COMP_A_FAST_THROTTLE_N")
	)
	(segment
		(start 241.725704 -141.642592)
		(end 243.524532 -141.642592)
		(width 0.17145)
		(layer "F.Cu")
		(net "COMP_A_FAST_THROTTLE_N")
	)
	(segment
		(start 256.8956 -140.839952)
		(end 256.8956 -139.7)
		(width 0.17145)
		(layer "F.Cu")
		(net "COMP_A_FAST_THROTTLE_N")
	)
	(via
		(at 155.448 -127.5842)
		(size 0.5588)
		(drill 0.3048)
		(layers "F.Cu" "B.Cu")
		(net "COMP_A_FAST_THROTTLE_N")
	)
	(via
		(at 143.832834 -42.516298)
		(size 0.5588)
		(drill 0.3048)
		(layers "F.Cu" "B.Cu")
		(net "COMP_A_FAST_THROTTLE_N")
	)
	(via
		(at 255.6256 -140.851128)
		(size 0.6604)
		(drill 0.3302)
		(layers "F.Cu" "B.Cu")
		(net "COMP_A_FAST_THROTTLE_N")
	)
	(segment
		(start 235.327444 -141.499844)
		(end 238.05007 -141.499844)
		(width 0.13335)
		(layer "In2.Cu")
		(net "COMP_A_FAST_THROTTLE_N")
	)
	(segment
		(start 222.44304 -128.61544)
		(end 235.327444 -141.499844)
		(width 0.13335)
		(layer "In2.Cu")
		(net "COMP_A_FAST_THROTTLE_N")
	)
	(segment
		(start 155.448 -127.5842)
		(end 156.47924 -128.61544)
		(width 0.13335)
		(layer "In2.Cu")
		(net "COMP_A_FAST_THROTTLE_N")
	)
	(segment
		(start 156.47924 -128.61544)
		(end 222.44304 -128.61544)
		(width 0.13335)
		(layer "In2.Cu")
		(net "COMP_A_FAST_THROTTLE_N")
	)
	(segment
		(start 152.326594 -124.462794)
		(end 152.326594 -107.58678)
		(width 0.12065)
		(layer "In4.Cu")
		(net "COMP_A_FAST_THROTTLE_N")
	)
	(segment
		(start 155.448 -127.5842)
		(end 152.326594 -124.462794)
		(width 0.12065)
		(layer "In4.Cu")
		(net "COMP_A_FAST_THROTTLE_N")
	)
	(segment
		(start 146.518376 -101.778562)
		(end 146.518376 -54.7116)
		(width 0.12065)
		(layer "In4.Cu")
		(net "COMP_A_FAST_THROTTLE_N")
	)
	(segment
		(start 146.518376 -54.7116)
		(end 143.832834 -52.026058)
		(width 0.12065)
		(layer "In4.Cu")
		(net "COMP_A_FAST_THROTTLE_N")
	)
	(segment
		(start 143.832834 -52.026058)
		(end 143.832834 -42.516298)
		(width 0.12065)
		(layer "In4.Cu")
		(net "COMP_A_FAST_THROTTLE_N")
	)
	(segment
		(start 152.326594 -107.58678)
		(end 146.518376 -101.778562)
		(width 0.12065)
		(layer "In4.Cu")
		(net "COMP_A_FAST_THROTTLE_N")
	)
	(segment
		(start 115.20932 -26.452576)
		(end 115.20932 -34.699194)
		(width 0.12065)
		(layer "In7.Cu")
		(net "COMP_A_FAST_THROTTLE_N")
	)
	(segment
		(start 126.656846 -40.601392)
		(end 127.077978 -40.18026)
		(width 0.12065)
		(layer "In7.Cu")
		(net "COMP_A_FAST_THROTTLE_N")
	)
	(segment
		(start 139.837922 -42.516298)
		(end 143.832834 -42.516298)
		(width 0.12065)
		(layer "In7.Cu")
		(net "COMP_A_FAST_THROTTLE_N")
	)
	(segment
		(start 121.111518 -40.601392)
		(end 126.656846 -40.601392)
		(width 0.12065)
		(layer "In7.Cu")
		(net "COMP_A_FAST_THROTTLE_N")
	)
	(segment
		(start 127.077978 -40.18026)
		(end 137.501884 -40.18026)
		(width 0.12065)
		(layer "In7.Cu")
		(net "COMP_A_FAST_THROTTLE_N")
	)
	(segment
		(start 114.549936 -25.550114)
		(end 114.549936 -25.793192)
		(width 0.12065)
		(layer "In7.Cu")
		(net "COMP_A_FAST_THROTTLE_N")
	)
	(segment
		(start 137.501884 -40.18026)
		(end 139.837922 -42.516298)
		(width 0.12065)
		(layer "In7.Cu")
		(net "COMP_A_FAST_THROTTLE_N")
	)
	(segment
		(start 115.20932 -34.699194)
		(end 121.111518 -40.601392)
		(width 0.12065)
		(layer "In7.Cu")
		(net "COMP_A_FAST_THROTTLE_N")
	)
	(segment
		(start 114.549936 -25.793192)
		(end 115.20932 -26.452576)
		(width 0.12065)
		(layer "In7.Cu")
		(net "COMP_A_FAST_THROTTLE_N")
	)
	(segment
		(start 222.1611 -115.5446)
		(end 221.025466 -115.5446)
		(width 0.17145)
		(layer "F.Cu")
		(net "COMP_A_EXP_A_SPARE_0")
	)
	(segment
		(start 221.025466 -115.5446)
		(end 220.034104 -115.5446)
		(width 0.17145)
		(layer "F.Cu")
		(net "COMP_A_EXP_A_SPARE_0")
	)
	(via
		(at 264.541 -97.245932)
		(size 0.5588)
		(drill 0.3048)
		(layers "F.Cu" "B.Cu")
		(net "COMP_A_EXP_A_SPARE_0")
	)
	(via
		(at 220.034104 -115.5446)
		(size 0.5588)
		(drill 0.3048)
		(layers "F.Cu" "B.Cu")
		(net "COMP_A_EXP_A_SPARE_0")
	)
	(via
		(at 221.025466 -115.5446)
		(size 0.6604)
		(drill 0.3302)
		(layers "F.Cu" "B.Cu")
		(net "COMP_A_EXP_A_SPARE_0")
	)
	(segment
		(start 230.3526 -103.498396)
		(end 236.605064 -97.245932)
		(width 0.13335)
		(layer "In2.Cu")
		(net "COMP_A_EXP_A_SPARE_0")
	)
	(segment
		(start 220.034104 -115.5446)
		(end 222.9104 -115.5446)
		(width 0.13335)
		(layer "In2.Cu")
		(net "COMP_A_EXP_A_SPARE_0")
	)
	(segment
		(start 236.605064 -97.245932)
		(end 264.541 -97.245932)
		(width 0.13335)
		(layer "In2.Cu")
		(net "COMP_A_EXP_A_SPARE_0")
	)
	(segment
		(start 222.9104 -115.5446)
		(end 230.3526 -108.1024)
		(width 0.13335)
		(layer "In2.Cu")
		(net "COMP_A_EXP_A_SPARE_0")
	)
	(segment
		(start 230.3526 -108.1024)
		(end 230.3526 -103.498396)
		(width 0.13335)
		(layer "In2.Cu")
		(net "COMP_A_EXP_A_SPARE_0")
	)
	(segment
		(start 274.447 -241.783108)
		(end 278.906478 -237.32363)
		(width 0.12065)
		(layer "In4.Cu")
		(net "COMP_A_EXP_A_SPARE_0")
	)
	(segment
		(start 264.541 -107.075732)
		(end 264.541 -97.245932)
		(width 0.12065)
		(layer "In4.Cu")
		(net "COMP_A_EXP_A_SPARE_0")
	)
	(segment
		(start 276.266656 -124.958856)
		(end 267.3985 -116.0907)
		(width 0.12065)
		(layer "In4.Cu")
		(net "COMP_A_EXP_A_SPARE_0")
	)
	(segment
		(start 283.23667 -258.302252)
		(end 282.458922 -259.08)
		(width 0.12065)
		(layer "In4.Cu")
		(net "COMP_A_EXP_A_SPARE_0")
	)
	(segment
		(start 267.3985 -109.933232)
		(end 264.541 -107.075732)
		(width 0.12065)
		(layer "In4.Cu")
		(net "COMP_A_EXP_A_SPARE_0")
	)
	(segment
		(start 274.447 -257.048)
		(end 274.447 -241.783108)
		(width 0.12065)
		(layer "In4.Cu")
		(net "COMP_A_EXP_A_SPARE_0")
	)
	(segment
		(start 276.266656 -190.047626)
		(end 276.266656 -124.958856)
		(width 0.12065)
		(layer "In4.Cu")
		(net "COMP_A_EXP_A_SPARE_0")
	)
	(segment
		(start 278.906478 -192.687448)
		(end 276.266656 -190.047626)
		(width 0.12065)
		(layer "In4.Cu")
		(net "COMP_A_EXP_A_SPARE_0")
	)
	(segment
		(start 278.906478 -237.32363)
		(end 278.906478 -192.687448)
		(width 0.12065)
		(layer "In4.Cu")
		(net "COMP_A_EXP_A_SPARE_0")
	)
	(segment
		(start 267.3985 -116.0907)
		(end 267.3985 -109.933232)
		(width 0.12065)
		(layer "In4.Cu")
		(net "COMP_A_EXP_A_SPARE_0")
	)
	(segment
		(start 276.479 -259.08)
		(end 274.447 -257.048)
		(width 0.12065)
		(layer "In4.Cu")
		(net "COMP_A_EXP_A_SPARE_0")
	)
	(segment
		(start 282.458922 -259.08)
		(end 276.479 -259.08)
		(width 0.12065)
		(layer "In4.Cu")
		(net "COMP_A_EXP_A_SPARE_0")
	)
	(via
		(at 288.06394 -44.831)
		(size 0.5588)
		(drill 0.3048)
		(layers "F.Cu" "B.Cu")
		(net "BMC_B_HEARTBEAT")
	)
	(via
		(at 292.20668 -312.3692)
		(size 0.5588)
		(drill 0.3048)
		(layers "F.Cu" "B.Cu")
		(net "BMC_B_HEARTBEAT")
	)
	(via
		(at 274.18157 7.808468)
		(size 0.5588)
		(drill 0.3048)
		(layers "F.Cu" "B.Cu")
		(net "BMC_B_HEARTBEAT")
	)
	(segment
		(start 287.9598 -44.88815)
		(end 287.9598 -44.831)
		(width 0.13335)
		(layer "In2.Cu")
		(net "BMC_B_HEARTBEAT")
	)
	(segment
		(start 385.750054 -30.550104)
		(end 386.324856 -31.124906)
		(width 0.13335)
		(layer "In2.Cu")
		(net "BMC_B_HEARTBEAT")
	)
	(segment
		(start 311.836308 -44.88815)
		(end 287.9598 -44.88815)
		(width 0.13335)
		(layer "In2.Cu")
		(net "BMC_B_HEARTBEAT")
	)
	(segment
		(start 287.9598 -44.831)
		(end 288.06394 -44.831)
		(width 0.13335)
		(layer "In2.Cu")
		(net "BMC_B_HEARTBEAT")
	)
	(segment
		(start 320.396108 -53.44795)
		(end 311.836308 -44.88815)
		(width 0.13335)
		(layer "In2.Cu")
		(net "BMC_B_HEARTBEAT")
	)
	(segment
		(start 364.870238 -53.44795)
		(end 320.396108 -53.44795)
		(width 0.13335)
		(layer "In2.Cu")
		(net "BMC_B_HEARTBEAT")
	)
	(segment
		(start 386.324856 -31.993332)
		(end 364.870238 -53.44795)
		(width 0.13335)
		(layer "In2.Cu")
		(net "BMC_B_HEARTBEAT")
	)
	(segment
		(start 386.324856 -31.124906)
		(end 386.324856 -31.993332)
		(width 0.13335)
		(layer "In2.Cu")
		(net "BMC_B_HEARTBEAT")
	)
	(segment
		(start 277.195788 7.791958)
		(end 287.63595 -2.648204)
		(width 0.12065)
		(layer "In4.Cu")
		(net "BMC_B_HEARTBEAT")
	)
	(segment
		(start 274.18157 7.791958)
		(end 277.195788 7.791958)
		(width 0.12065)
		(layer "In4.Cu")
		(net "BMC_B_HEARTBEAT")
	)
	(segment
		(start 282.83662 -252.902212)
		(end 282.190444 -252.256036)
		(width 0.12065)
		(layer "In4.Cu")
		(net "BMC_B_HEARTBEAT")
	)
	(segment
		(start 283.7434 -282.0924)
		(end 292.000432 -290.349432)
		(width 0.12065)
		(layer "In4.Cu")
		(net "BMC_B_HEARTBEAT")
	)
	(segment
		(start 288.39414 -234.741212)
		(end 288.39414 -97.02546)
		(width 0.12065)
		(layer "In4.Cu")
		(net "BMC_B_HEARTBEAT")
	)
	(segment
		(start 282.190444 -252.256036)
		(end 277.486364 -252.256036)
		(width 0.12065)
		(layer "In4.Cu")
		(net "BMC_B_HEARTBEAT")
	)
	(segment
		(start 288.41065 -45.17771)
		(end 288.06394 -44.831)
		(width 0.12065)
		(layer "In4.Cu")
		(net "BMC_B_HEARTBEAT")
	)
	(segment
		(start 288.41065 -45.804328)
		(end 288.41065 -45.17771)
		(width 0.12065)
		(layer "In4.Cu")
		(net "BMC_B_HEARTBEAT")
	)
	(segment
		(start 276.568154 -251.337826)
		(end 276.568154 -246.567198)
		(width 0.12065)
		(layer "In4.Cu")
		(net "BMC_B_HEARTBEAT")
	)
	(segment
		(start 289.17265 -96.24695)
		(end 289.17265 -46.566328)
		(width 0.12065)
		(layer "In4.Cu")
		(net "BMC_B_HEARTBEAT")
	)
	(segment
		(start 277.486364 -252.256036)
		(end 276.568154 -251.337826)
		(width 0.12065)
		(layer "In4.Cu")
		(net "BMC_B_HEARTBEAT")
	)
	(segment
		(start 283.680408 -253.746)
		(end 287.784286 -253.746)
		(width 0.12065)
		(layer "In4.Cu")
		(net "BMC_B_HEARTBEAT")
	)
	(segment
		(start 282.83662 -252.902212)
		(end 283.680408 -253.746)
		(width 0.12065)
		(layer "In4.Cu")
		(net "BMC_B_HEARTBEAT")
	)
	(segment
		(start 283.7434 -275.8948)
		(end 283.7434 -282.0924)
		(width 0.12065)
		(layer "In4.Cu")
		(net "BMC_B_HEARTBEAT")
	)
	(segment
		(start 276.568154 -246.567198)
		(end 288.39414 -234.741212)
		(width 0.12065)
		(layer "In4.Cu")
		(net "BMC_B_HEARTBEAT")
	)
	(segment
		(start 289.493452 -270.144748)
		(end 283.7434 -275.8948)
		(width 0.12065)
		(layer "In4.Cu")
		(net "BMC_B_HEARTBEAT")
	)
	(segment
		(start 287.63595 -44.40301)
		(end 288.06394 -44.831)
		(width 0.12065)
		(layer "In4.Cu")
		(net "BMC_B_HEARTBEAT")
	)
	(segment
		(start 287.784286 -253.746)
		(end 289.493452 -255.455166)
		(width 0.12065)
		(layer "In4.Cu")
		(net "BMC_B_HEARTBEAT")
	)
	(segment
		(start 289.493452 -255.455166)
		(end 289.493452 -270.144748)
		(width 0.12065)
		(layer "In4.Cu")
		(net "BMC_B_HEARTBEAT")
	)
	(segment
		(start 274.18157 7.808468)
		(end 274.18157 7.791958)
		(width 0.12065)
		(layer "In4.Cu")
		(net "BMC_B_HEARTBEAT")
	)
	(segment
		(start 292.000432 -290.349432)
		(end 292.000432 -312.162952)
		(width 0.12065)
		(layer "In4.Cu")
		(net "BMC_B_HEARTBEAT")
	)
	(segment
		(start 287.63595 -2.648204)
		(end 287.63595 -44.40301)
		(width 0.12065)
		(layer "In4.Cu")
		(net "BMC_B_HEARTBEAT")
	)
	(segment
		(start 289.17265 -46.566328)
		(end 288.41065 -45.804328)
		(width 0.12065)
		(layer "In4.Cu")
		(net "BMC_B_HEARTBEAT")
	)
	(segment
		(start 288.39414 -97.02546)
		(end 289.17265 -96.24695)
		(width 0.12065)
		(layer "In4.Cu")
		(net "BMC_B_HEARTBEAT")
	)
	(segment
		(start 292.000432 -312.162952)
		(end 292.20668 -312.3692)
		(width 0.12065)
		(layer "In4.Cu")
		(net "BMC_B_HEARTBEAT")
	)
	(segment
		(start 144.336262 -33.794192)
		(end 160.217104 -17.91335)
		(width 0.12065)
		(layer "In7.Cu")
		(net "BMC_B_HEARTBEAT")
	)
	(segment
		(start 265.58875 -360.45775)
		(end 288.129726 -360.45775)
		(width 0.12065)
		(layer "In7.Cu")
		(net "BMC_B_HEARTBEAT")
	)
	(segment
		(start 231.599994 -415.699956)
		(end 234.345734 -412.954216)
		(width 0.12065)
		(layer "In7.Cu")
		(net "BMC_B_HEARTBEAT")
	)
	(segment
		(start 222.881698 -4.442968)
		(end 228.202236 -4.442968)
		(width 0.12065)
		(layer "In7.Cu")
		(net "BMC_B_HEARTBEAT")
	)
	(segment
		(start 230.811832 -379.932184)
		(end 233.359198 -377.384818)
		(width 0.12065)
		(layer "In7.Cu")
		(net "BMC_B_HEARTBEAT")
	)
	(segment
		(start 234.345734 -399.126964)
		(end 231.029002 -395.810232)
		(width 0.12065)
		(layer "In7.Cu")
		(net "BMC_B_HEARTBEAT")
	)
	(segment
		(start 138.628374 -30.27172)
		(end 138.628374 -32.088582)
		(width 0.12065)
		(layer "In7.Cu")
		(net "BMC_B_HEARTBEAT")
	)
	(segment
		(start 242.900962 0.199136)
		(end 263.894316 0.199136)
		(width 0.12065)
		(layer "In7.Cu")
		(net "BMC_B_HEARTBEAT")
	)
	(segment
		(start 140.333984 -33.794192)
		(end 144.336262 -33.794192)
		(width 0.12065)
		(layer "In7.Cu")
		(net "BMC_B_HEARTBEAT")
	)
	(segment
		(start 233.359198 -377.384818)
		(end 233.359198 -356.66299)
		(width 0.12065)
		(layer "In7.Cu")
		(net "BMC_B_HEARTBEAT")
	)
	(segment
		(start 222.473266 -4.8514)
		(end 222.881698 -4.442968)
		(width 0.12065)
		(layer "In7.Cu")
		(net "BMC_B_HEARTBEAT")
	)
	(segment
		(start 292.547294 -331.27696)
		(end 292.547294 -312.709814)
		(width 0.12065)
		(layer "In7.Cu")
		(net "BMC_B_HEARTBEAT")
	)
	(segment
		(start 180.168042 -4.8514)
		(end 222.473266 -4.8514)
		(width 0.12065)
		(layer "In7.Cu")
		(net "BMC_B_HEARTBEAT")
	)
	(segment
		(start 139.750038 -29.150056)
		(end 138.628374 -30.27172)
		(width 0.12065)
		(layer "In7.Cu")
		(net "BMC_B_HEARTBEAT")
	)
	(segment
		(start 264.183622 -359.052622)
		(end 265.58875 -360.45775)
		(width 0.12065)
		(layer "In7.Cu")
		(net "BMC_B_HEARTBEAT")
	)
	(segment
		(start 231.029002 -395.810232)
		(end 231.029002 -391.724642)
		(width 0.12065)
		(layer "In7.Cu")
		(net "BMC_B_HEARTBEAT")
	)
	(segment
		(start 167.106092 -17.91335)
		(end 180.168042 -4.8514)
		(width 0.12065)
		(layer "In7.Cu")
		(net "BMC_B_HEARTBEAT")
	)
	(segment
		(start 240.416334 2.683764)
		(end 242.900962 0.199136)
		(width 0.12065)
		(layer "In7.Cu")
		(net "BMC_B_HEARTBEAT")
	)
	(segment
		(start 231.029002 -391.724642)
		(end 230.811832 -391.507472)
		(width 0.12065)
		(layer "In7.Cu")
		(net "BMC_B_HEARTBEAT")
	)
	(segment
		(start 249.31878 -350.592898)
		(end 257.778504 -359.052622)
		(width 0.12065)
		(layer "In7.Cu")
		(net "BMC_B_HEARTBEAT")
	)
	(segment
		(start 292.547294 -312.709814)
		(end 292.20668 -312.3692)
		(width 0.12065)
		(layer "In7.Cu")
		(net "BMC_B_HEARTBEAT")
	)
	(segment
		(start 239.42929 -350.592898)
		(end 249.31878 -350.592898)
		(width 0.12065)
		(layer "In7.Cu")
		(net "BMC_B_HEARTBEAT")
	)
	(segment
		(start 228.202236 -4.442968)
		(end 235.328968 2.683764)
		(width 0.12065)
		(layer "In7.Cu")
		(net "BMC_B_HEARTBEAT")
	)
	(segment
		(start 233.359198 -356.66299)
		(end 239.42929 -350.592898)
		(width 0.12065)
		(layer "In7.Cu")
		(net "BMC_B_HEARTBEAT")
	)
	(segment
		(start 138.628374 -32.088582)
		(end 140.333984 -33.794192)
		(width 0.12065)
		(layer "In7.Cu")
		(net "BMC_B_HEARTBEAT")
	)
	(segment
		(start 160.217104 -17.91335)
		(end 167.106092 -17.91335)
		(width 0.12065)
		(layer "In7.Cu")
		(net "BMC_B_HEARTBEAT")
	)
	(segment
		(start 291.592 -356.995476)
		(end 291.592 -332.232254)
		(width 0.12065)
		(layer "In7.Cu")
		(net "BMC_B_HEARTBEAT")
	)
	(segment
		(start 235.328968 2.683764)
		(end 240.416334 2.683764)
		(width 0.12065)
		(layer "In7.Cu")
		(net "BMC_B_HEARTBEAT")
	)
	(segment
		(start 271.503648 7.808468)
		(end 274.18157 7.808468)
		(width 0.12065)
		(layer "In7.Cu")
		(net "BMC_B_HEARTBEAT")
	)
	(segment
		(start 234.345734 -412.954216)
		(end 234.345734 -399.126964)
		(width 0.12065)
		(layer "In7.Cu")
		(net "BMC_B_HEARTBEAT")
	)
	(segment
		(start 230.811832 -391.507472)
		(end 230.811832 -379.932184)
		(width 0.12065)
		(layer "In7.Cu")
		(net "BMC_B_HEARTBEAT")
	)
	(segment
		(start 257.778504 -359.052622)
		(end 264.183622 -359.052622)
		(width 0.12065)
		(layer "In7.Cu")
		(net "BMC_B_HEARTBEAT")
	)
	(segment
		(start 263.894316 0.199136)
		(end 271.503648 7.808468)
		(width 0.12065)
		(layer "In7.Cu")
		(net "BMC_B_HEARTBEAT")
	)
	(segment
		(start 288.129726 -360.45775)
		(end 291.592 -356.995476)
		(width 0.12065)
		(layer "In7.Cu")
		(net "BMC_B_HEARTBEAT")
	)
	(segment
		(start 291.592 -332.232254)
		(end 292.547294 -331.27696)
		(width 0.12065)
		(layer "In7.Cu")
		(net "BMC_B_HEARTBEAT")
	)
	(via
		(at 279.716484 7.87527)
		(size 0.5588)
		(drill 0.3048)
		(layers "F.Cu" "B.Cu")
		(net "BMC_A_HEARTBEAT")
	)
	(via
		(at 289.6997 -45.5168)
		(size 0.5588)
		(drill 0.3048)
		(layers "F.Cu" "B.Cu")
		(net "BMC_A_HEARTBEAT")
	)
	(via
		(at 262.382 -359.69575)
		(size 0.5588)
		(drill 0.3048)
		(layers "F.Cu" "B.Cu")
		(net "BMC_A_HEARTBEAT")
	)
	(via
		(at 308.81193 -46.035468)
		(size 0.5588)
		(drill 0.3048)
		(layers "F.Cu" "B.Cu")
		(net "BMC_A_HEARTBEAT")
	)
	(segment
		(start 312.278522 -46.035468)
		(end 308.81193 -46.035468)
		(width 0.13335)
		(layer "In2.Cu")
		(net "BMC_A_HEARTBEAT")
	)
	(segment
		(start 386.813806 -32.196024)
		(end 364.524036 -54.485794)
		(width 0.13335)
		(layer "In2.Cu")
		(net "BMC_A_HEARTBEAT")
	)
	(segment
		(start 302.72609 -45.5168)
		(end 289.6997 -45.5168)
		(width 0.13335)
		(layer "In2.Cu")
		(net "BMC_A_HEARTBEAT")
	)
	(segment
		(start 364.524036 -54.485794)
		(end 320.728848 -54.485794)
		(width 0.13335)
		(layer "In2.Cu")
		(net "BMC_A_HEARTBEAT")
	)
	(segment
		(start 386.813806 -30.213808)
		(end 386.813806 -32.196024)
		(width 0.13335)
		(layer "In2.Cu")
		(net "BMC_A_HEARTBEAT")
	)
	(segment
		(start 308.81193 -46.035468)
		(end 303.244758 -46.035468)
		(width 0.13335)
		(layer "In2.Cu")
		(net "BMC_A_HEARTBEAT")
	)
	(segment
		(start 320.728848 -54.485794)
		(end 312.278522 -46.035468)
		(width 0.13335)
		(layer "In2.Cu")
		(net "BMC_A_HEARTBEAT")
	)
	(segment
		(start 303.244758 -46.035468)
		(end 302.72609 -45.5168)
		(width 0.13335)
		(layer "In2.Cu")
		(net "BMC_A_HEARTBEAT")
	)
	(segment
		(start 385.750054 -29.150056)
		(end 386.813806 -30.213808)
		(width 0.13335)
		(layer "In2.Cu")
		(net "BMC_A_HEARTBEAT")
	)
	(segment
		(start 312.239152 -172.11929)
		(end 312.239152 -260.470142)
		(width 0.12065)
		(layer "In4.Cu")
		(net "BMC_A_HEARTBEAT")
	)
	(segment
		(start 311.31002 -58.62701)
		(end 311.31002 -61.695584)
		(width 0.12065)
		(layer "In4.Cu")
		(net "BMC_A_HEARTBEAT")
	)
	(segment
		(start 308.256686 -96.581976)
		(end 314.49264 -102.81793)
		(width 0.12065)
		(layer "In4.Cu")
		(net "BMC_A_HEARTBEAT")
	)
	(segment
		(start 289.6997 -44.5897)
		(end 289.6997 -45.5168)
		(width 0.12065)
		(layer "In4.Cu")
		(net "BMC_A_HEARTBEAT")
	)
	(segment
		(start 311.31002 -61.695584)
		(end 308.256686 -64.748918)
		(width 0.12065)
		(layer "In4.Cu")
		(net "BMC_A_HEARTBEAT")
	)
	(segment
		(start 283.747972 -356.7938)
		(end 282.83662 -357.705152)
		(width 0.12065)
		(layer "In4.Cu")
		(net "BMC_A_HEARTBEAT")
	)
	(segment
		(start 309.171848 -46.395386)
		(end 309.171848 -56.488838)
		(width 0.12065)
		(layer "In4.Cu")
		(net "BMC_A_HEARTBEAT")
	)
	(segment
		(start 262.382 -359.69575)
		(end 264.57275 -359.69575)
		(width 0.12065)
		(layer "In4.Cu")
		(net "BMC_A_HEARTBEAT")
	)
	(segment
		(start 279.099772 -361.442)
		(end 282.83662 -357.705152)
		(width 0.12065)
		(layer "In4.Cu")
		(net "BMC_A_HEARTBEAT")
	)
	(segment
		(start 308.256686 -64.748918)
		(end 308.256686 -96.581976)
		(width 0.12065)
		(layer "In4.Cu")
		(net "BMC_A_HEARTBEAT")
	)
	(segment
		(start 264.57275 -359.69575)
		(end 266.319 -361.442)
		(width 0.12065)
		(layer "In4.Cu")
		(net "BMC_A_HEARTBEAT")
	)
	(segment
		(start 279.716484 7.87527)
		(end 279.716484 7.125716)
		(width 0.12065)
		(layer "In4.Cu")
		(net "BMC_A_HEARTBEAT")
	)
	(segment
		(start 301.523654 -271.18564)
		(end 301.523654 -326.491346)
		(width 0.12065)
		(layer "In4.Cu")
		(net "BMC_A_HEARTBEAT")
	)
	(segment
		(start 266.319 -361.442)
		(end 279.099772 -361.442)
		(width 0.12065)
		(layer "In4.Cu")
		(net "BMC_A_HEARTBEAT")
	)
	(segment
		(start 309.171848 -56.488838)
		(end 311.31002 -58.62701)
		(width 0.12065)
		(layer "In4.Cu")
		(net "BMC_A_HEARTBEAT")
	)
	(segment
		(start 312.239152 -260.470142)
		(end 301.523654 -271.18564)
		(width 0.12065)
		(layer "In4.Cu")
		(net "BMC_A_HEARTBEAT")
	)
	(segment
		(start 314.264548 -170.093894)
		(end 312.239152 -172.11929)
		(width 0.12065)
		(layer "In4.Cu")
		(net "BMC_A_HEARTBEAT")
	)
	(segment
		(start 301.523654 -326.491346)
		(end 290.2712 -337.7438)
		(width 0.12065)
		(layer "In4.Cu")
		(net "BMC_A_HEARTBEAT")
	)
	(segment
		(start 279.716484 7.125716)
		(end 289.179 -2.3368)
		(width 0.12065)
		(layer "In4.Cu")
		(net "BMC_A_HEARTBEAT")
	)
	(segment
		(start 289.179 -44.069)
		(end 289.6997 -44.5897)
		(width 0.12065)
		(layer "In4.Cu")
		(net "BMC_A_HEARTBEAT")
	)
	(segment
		(start 289.179 -2.3368)
		(end 289.179 -44.069)
		(width 0.12065)
		(layer "In4.Cu")
		(net "BMC_A_HEARTBEAT")
	)
	(segment
		(start 308.81193 -46.035468)
		(end 309.171848 -46.395386)
		(width 0.12065)
		(layer "In4.Cu")
		(net "BMC_A_HEARTBEAT")
	)
	(segment
		(start 287.85185 -356.7938)
		(end 283.747972 -356.7938)
		(width 0.12065)
		(layer "In4.Cu")
		(net "BMC_A_HEARTBEAT")
	)
	(segment
		(start 314.264548 -132.953252)
		(end 314.264548 -170.093894)
		(width 0.12065)
		(layer "In4.Cu")
		(net "BMC_A_HEARTBEAT")
	)
	(segment
		(start 314.49264 -102.81793)
		(end 314.49264 -132.72516)
		(width 0.12065)
		(layer "In4.Cu")
		(net "BMC_A_HEARTBEAT")
	)
	(segment
		(start 290.2712 -354.37445)
		(end 287.85185 -356.7938)
		(width 0.12065)
		(layer "In4.Cu")
		(net "BMC_A_HEARTBEAT")
	)
	(segment
		(start 314.49264 -132.72516)
		(end 314.264548 -132.953252)
		(width 0.12065)
		(layer "In4.Cu")
		(net "BMC_A_HEARTBEAT")
	)
	(segment
		(start 290.2712 -337.7438)
		(end 290.2712 -354.37445)
		(width 0.12065)
		(layer "In4.Cu")
		(net "BMC_A_HEARTBEAT")
	)
	(segment
		(start 144.165066 -33.381442)
		(end 160.045908 -17.5006)
		(width 0.12065)
		(layer "In7.Cu")
		(net "BMC_A_HEARTBEAT")
	)
	(segment
		(start 227.98024 -4.030218)
		(end 235.114084 3.103626)
		(width 0.12065)
		(layer "In7.Cu")
		(net "BMC_A_HEARTBEAT")
	)
	(segment
		(start 257.837686 -359.69575)
		(end 262.382 -359.69575)
		(width 0.12065)
		(layer "In7.Cu")
		(net "BMC_A_HEARTBEAT")
	)
	(segment
		(start 249.147584 -351.005648)
		(end 257.837686 -359.69575)
		(width 0.12065)
		(layer "In7.Cu")
		(net "BMC_A_HEARTBEAT")
	)
	(segment
		(start 231.599994 -416.80003)
		(end 234.758484 -413.64154)
		(width 0.12065)
		(layer "In7.Cu")
		(net "BMC_A_HEARTBEAT")
	)
	(segment
		(start 271.41297 8.301736)
		(end 274.42668 8.301736)
		(width 0.12065)
		(layer "In7.Cu")
		(net "BMC_A_HEARTBEAT")
	)
	(segment
		(start 139.13739 -31.162752)
		(end 139.13739 -31.92399)
		(width 0.12065)
		(layer "In7.Cu")
		(net "BMC_A_HEARTBEAT")
	)
	(segment
		(start 233.771948 -377.556014)
		(end 233.771948 -356.834186)
		(width 0.12065)
		(layer "In7.Cu")
		(net "BMC_A_HEARTBEAT")
	)
	(segment
		(start 231.441752 -391.553446)
		(end 231.224582 -391.336276)
		(width 0.12065)
		(layer "In7.Cu")
		(net "BMC_A_HEARTBEAT")
	)
	(segment
		(start 234.758484 -398.751552)
		(end 231.441752 -395.43482)
		(width 0.12065)
		(layer "In7.Cu")
		(net "BMC_A_HEARTBEAT")
	)
	(segment
		(start 231.224582 -391.336276)
		(end 231.224582 -380.10338)
		(width 0.12065)
		(layer "In7.Cu")
		(net "BMC_A_HEARTBEAT")
	)
	(segment
		(start 240.580418 3.103626)
		(end 243.072158 0.611886)
		(width 0.12065)
		(layer "In7.Cu")
		(net "BMC_A_HEARTBEAT")
	)
	(segment
		(start 222.710502 -4.030218)
		(end 227.98024 -4.030218)
		(width 0.12065)
		(layer "In7.Cu")
		(net "BMC_A_HEARTBEAT")
	)
	(segment
		(start 231.224582 -380.10338)
		(end 233.771948 -377.556014)
		(width 0.12065)
		(layer "In7.Cu")
		(net "BMC_A_HEARTBEAT")
	)
	(segment
		(start 222.385382 -4.355338)
		(end 222.710502 -4.030218)
		(width 0.12065)
		(layer "In7.Cu")
		(net "BMC_A_HEARTBEAT")
	)
	(segment
		(start 180.080158 -4.355338)
		(end 222.385382 -4.355338)
		(width 0.12065)
		(layer "In7.Cu")
		(net "BMC_A_HEARTBEAT")
	)
	(segment
		(start 160.045908 -17.5006)
		(end 166.934896 -17.5006)
		(width 0.12065)
		(layer "In7.Cu")
		(net "BMC_A_HEARTBEAT")
	)
	(segment
		(start 233.771948 -356.834186)
		(end 239.600486 -351.005648)
		(width 0.12065)
		(layer "In7.Cu")
		(net "BMC_A_HEARTBEAT")
	)
	(segment
		(start 274.642072 8.086344)
		(end 279.50541 8.086344)
		(width 0.12065)
		(layer "In7.Cu")
		(net "BMC_A_HEARTBEAT")
	)
	(segment
		(start 243.072158 0.611886)
		(end 263.72312 0.611886)
		(width 0.12065)
		(layer "In7.Cu")
		(net "BMC_A_HEARTBEAT")
	)
	(segment
		(start 235.114084 3.103626)
		(end 240.580418 3.103626)
		(width 0.12065)
		(layer "In7.Cu")
		(net "BMC_A_HEARTBEAT")
	)
	(segment
		(start 231.441752 -395.43482)
		(end 231.441752 -391.553446)
		(width 0.12065)
		(layer "In7.Cu")
		(net "BMC_A_HEARTBEAT")
	)
	(segment
		(start 166.934896 -17.5006)
		(end 180.080158 -4.355338)
		(width 0.12065)
		(layer "In7.Cu")
		(net "BMC_A_HEARTBEAT")
	)
	(segment
		(start 139.13739 -31.92399)
		(end 140.594842 -33.381442)
		(width 0.12065)
		(layer "In7.Cu")
		(net "BMC_A_HEARTBEAT")
	)
	(segment
		(start 274.42668 8.301736)
		(end 274.642072 8.086344)
		(width 0.12065)
		(layer "In7.Cu")
		(net "BMC_A_HEARTBEAT")
	)
	(segment
		(start 139.750038 -30.550104)
		(end 139.13739 -31.162752)
		(width 0.12065)
		(layer "In7.Cu")
		(net "BMC_A_HEARTBEAT")
	)
	(segment
		(start 239.600486 -351.005648)
		(end 249.147584 -351.005648)
		(width 0.12065)
		(layer "In7.Cu")
		(net "BMC_A_HEARTBEAT")
	)
	(segment
		(start 263.72312 0.611886)
		(end 271.41297 8.301736)
		(width 0.12065)
		(layer "In7.Cu")
		(net "BMC_A_HEARTBEAT")
	)
	(segment
		(start 234.758484 -413.64154)
		(end 234.758484 -398.751552)
		(width 0.12065)
		(layer "In7.Cu")
		(net "BMC_A_HEARTBEAT")
	)
	(segment
		(start 140.594842 -33.381442)
		(end 144.165066 -33.381442)
		(width 0.12065)
		(layer "In7.Cu")
		(net "BMC_A_HEARTBEAT")
	)
	(segment
		(start 279.50541 8.086344)
		(end 279.716484 7.87527)
		(width 0.12065)
		(layer "In7.Cu")
		(net "BMC_A_HEARTBEAT")
	)
	(via
		(at 109.894878 -257.835908)
		(size 0.5588)
		(drill 0.3048)
		(layers "F.Cu" "B.Cu")
		(net "BMC_A_EXP_A_SPARE_1")
	)
	(segment
		(start 110.042198 -258.880102)
		(end 110.042198 -257.983228)
		(width 0.13335)
		(layer "In2.Cu")
		(net "BMC_A_EXP_A_SPARE_1")
	)
	(segment
		(start 244.417342 -258.765294)
		(end 244.417088 -258.765548)
		(width 0.13335)
		(layer "In2.Cu")
		(net "BMC_A_EXP_A_SPARE_1")
	)
	(segment
		(start 233.029252 -258.765548)
		(end 232.191052 -259.603748)
		(width 0.13335)
		(layer "In2.Cu")
		(net "BMC_A_EXP_A_SPARE_1")
	)
	(segment
		(start 268.454378 -255.3462)
		(end 263.220454 -260.580124)
		(width 0.13335)
		(layer "In2.Cu")
		(net "BMC_A_EXP_A_SPARE_1")
	)
	(segment
		(start 198.252334 -258.988052)
		(end 198.125334 -259.115052)
		(width 0.13335)
		(layer "In2.Cu")
		(net "BMC_A_EXP_A_SPARE_1")
	)
	(segment
		(start 245.182898 -258.765294)
		(end 244.417342 -258.765294)
		(width 0.13335)
		(layer "In2.Cu")
		(net "BMC_A_EXP_A_SPARE_1")
	)
	(segment
		(start 174.011336 -259.807202)
		(end 174.011082 -259.806948)
		(width 0.13335)
		(layer "In2.Cu")
		(net "BMC_A_EXP_A_SPARE_1")
	)
	(segment
		(start 193.955924 -259.807202)
		(end 174.011336 -259.807202)
		(width 0.13335)
		(layer "In2.Cu")
		(net "BMC_A_EXP_A_SPARE_1")
	)
	(segment
		(start 250.597924 -260.580124)
		(end 248.783348 -258.765548)
		(width 0.13335)
		(layer "In2.Cu")
		(net "BMC_A_EXP_A_SPARE_1")
	)
	(segment
		(start 263.220454 -260.580124)
		(end 250.597924 -260.580124)
		(width 0.13335)
		(layer "In2.Cu")
		(net "BMC_A_EXP_A_SPARE_1")
	)
	(segment
		(start 110.042198 -257.983228)
		(end 109.894878 -257.835908)
		(width 0.13335)
		(layer "In2.Cu")
		(net "BMC_A_EXP_A_SPARE_1")
	)
	(segment
		(start 198.125334 -259.115052)
		(end 194.648074 -259.115052)
		(width 0.13335)
		(layer "In2.Cu")
		(net "BMC_A_EXP_A_SPARE_1")
	)
	(segment
		(start 194.648074 -259.115052)
		(end 193.955924 -259.807202)
		(width 0.13335)
		(layer "In2.Cu")
		(net "BMC_A_EXP_A_SPARE_1")
	)
	(segment
		(start 248.783348 -258.765548)
		(end 245.183152 -258.765548)
		(width 0.13335)
		(layer "In2.Cu")
		(net "BMC_A_EXP_A_SPARE_1")
	)
	(segment
		(start 244.417088 -258.765548)
		(end 233.029252 -258.765548)
		(width 0.13335)
		(layer "In2.Cu")
		(net "BMC_A_EXP_A_SPARE_1")
	)
	(segment
		(start 110.969044 -259.806948)
		(end 110.042198 -258.880102)
		(width 0.13335)
		(layer "In2.Cu")
		(net "BMC_A_EXP_A_SPARE_1")
	)
	(segment
		(start 226.603052 -258.988052)
		(end 198.252334 -258.988052)
		(width 0.13335)
		(layer "In2.Cu")
		(net "BMC_A_EXP_A_SPARE_1")
	)
	(segment
		(start 281.192732 -255.3462)
		(end 268.454378 -255.3462)
		(width 0.13335)
		(layer "In2.Cu")
		(net "BMC_A_EXP_A_SPARE_1")
	)
	(segment
		(start 281.836622 -254.70231)
		(end 281.192732 -255.3462)
		(width 0.13335)
		(layer "In2.Cu")
		(net "BMC_A_EXP_A_SPARE_1")
	)
	(segment
		(start 232.191052 -259.603748)
		(end 227.218748 -259.603748)
		(width 0.13335)
		(layer "In2.Cu")
		(net "BMC_A_EXP_A_SPARE_1")
	)
	(segment
		(start 227.218748 -259.603748)
		(end 226.603052 -258.988052)
		(width 0.13335)
		(layer "In2.Cu")
		(net "BMC_A_EXP_A_SPARE_1")
	)
	(segment
		(start 245.183152 -258.765548)
		(end 245.182898 -258.765294)
		(width 0.13335)
		(layer "In2.Cu")
		(net "BMC_A_EXP_A_SPARE_1")
	)
	(segment
		(start 174.011082 -259.806948)
		(end 110.969044 -259.806948)
		(width 0.13335)
		(layer "In2.Cu")
		(net "BMC_A_EXP_A_SPARE_1")
	)
	(segment
		(start 108.204 -88.004142)
		(end 108.204 -124.04852)
		(width 0.12065)
		(layer "In4.Cu")
		(net "BMC_A_EXP_A_SPARE_1")
	)
	(segment
		(start 103.46436 -83.264502)
		(end 108.204 -88.004142)
		(width 0.12065)
		(layer "In4.Cu")
		(net "BMC_A_EXP_A_SPARE_1")
	)
	(segment
		(start 106.513884 -173.555406)
		(end 106.513884 -254.454914)
		(width 0.12065)
		(layer "In4.Cu")
		(net "BMC_A_EXP_A_SPARE_1")
	)
	(segment
		(start 103.669084 -128.583436)
		(end 103.669084 -129.624836)
		(width 0.12065)
		(layer "In4.Cu")
		(net "BMC_A_EXP_A_SPARE_1")
	)
	(segment
		(start 103.669084 -170.710606)
		(end 106.513884 -173.555406)
		(width 0.12065)
		(layer "In4.Cu")
		(net "BMC_A_EXP_A_SPARE_1")
	)
	(segment
		(start 110.949994 -30.550104)
		(end 110.341918 -31.15818)
		(width 0.12065)
		(layer "In4.Cu")
		(net "BMC_A_EXP_A_SPARE_1")
	)
	(segment
		(start 110.341918 -31.15818)
		(end 110.341918 -37.266372)
		(width 0.12065)
		(layer "In4.Cu")
		(net "BMC_A_EXP_A_SPARE_1")
	)
	(segment
		(start 106.513884 -254.454914)
		(end 109.894878 -257.835908)
		(width 0.12065)
		(layer "In4.Cu")
		(net "BMC_A_EXP_A_SPARE_1")
	)
	(segment
		(start 103.63581 -129.65811)
		(end 103.63581 -130.587242)
		(width 0.12065)
		(layer "In4.Cu")
		(net "BMC_A_EXP_A_SPARE_1")
	)
	(segment
		(start 108.204 -124.04852)
		(end 103.669084 -128.583436)
		(width 0.12065)
		(layer "In4.Cu")
		(net "BMC_A_EXP_A_SPARE_1")
	)
	(segment
		(start 103.46436 -44.14393)
		(end 103.46436 -83.264502)
		(width 0.12065)
		(layer "In4.Cu")
		(net "BMC_A_EXP_A_SPARE_1")
	)
	(segment
		(start 103.63581 -130.587242)
		(end 103.669084 -130.620516)
		(width 0.12065)
		(layer "In4.Cu")
		(net "BMC_A_EXP_A_SPARE_1")
	)
	(segment
		(start 110.341918 -37.266372)
		(end 103.46436 -44.14393)
		(width 0.12065)
		(layer "In4.Cu")
		(net "BMC_A_EXP_A_SPARE_1")
	)
	(segment
		(start 103.669084 -130.620516)
		(end 103.669084 -170.710606)
		(width 0.12065)
		(layer "In4.Cu")
		(net "BMC_A_EXP_A_SPARE_1")
	)
	(segment
		(start 103.669084 -129.624836)
		(end 103.63581 -129.65811)
		(width 0.12065)
		(layer "In4.Cu")
		(net "BMC_A_EXP_A_SPARE_1")
	)
	(via
		(at 109.121702 -258.55168)
		(size 0.5588)
		(drill 0.3048)
		(layers "F.Cu" "B.Cu")
		(net "BMC_A_EXP_A_SPARE_0")
	)
	(segment
		(start 173.834806 -260.232652)
		(end 173.834552 -260.232398)
		(width 0.13335)
		(layer "In2.Cu")
		(net "BMC_A_EXP_A_SPARE_0")
	)
	(segment
		(start 245.006876 -259.190998)
		(end 245.006622 -259.190744)
		(width 0.13335)
		(layer "In2.Cu")
		(net "BMC_A_EXP_A_SPARE_0")
	)
	(segment
		(start 263.39673 -261.005574)
		(end 249.473974 -261.005574)
		(width 0.13335)
		(layer "In2.Cu")
		(net "BMC_A_EXP_A_SPARE_0")
	)
	(segment
		(start 227.042472 -260.029198)
		(end 226.610672 -259.597398)
		(width 0.13335)
		(layer "In2.Cu")
		(net "BMC_A_EXP_A_SPARE_0")
	)
	(segment
		(start 244.593364 -259.190998)
		(end 233.213402 -259.190998)
		(width 0.13335)
		(layer "In2.Cu")
		(net "BMC_A_EXP_A_SPARE_0")
	)
	(segment
		(start 244.593618 -259.190744)
		(end 244.593364 -259.190998)
		(width 0.13335)
		(layer "In2.Cu")
		(net "BMC_A_EXP_A_SPARE_0")
	)
	(segment
		(start 283.23667 -254.70231)
		(end 282.072588 -255.866392)
		(width 0.13335)
		(layer "In2.Cu")
		(net "BMC_A_EXP_A_SPARE_0")
	)
	(segment
		(start 268.535912 -255.866392)
		(end 263.39673 -261.005574)
		(width 0.13335)
		(layer "In2.Cu")
		(net "BMC_A_EXP_A_SPARE_0")
	)
	(segment
		(start 194.770756 -259.597398)
		(end 194.135502 -260.232652)
		(width 0.13335)
		(layer "In2.Cu")
		(net "BMC_A_EXP_A_SPARE_0")
	)
	(segment
		(start 194.135502 -260.232652)
		(end 173.834806 -260.232652)
		(width 0.13335)
		(layer "In2.Cu")
		(net "BMC_A_EXP_A_SPARE_0")
	)
	(segment
		(start 247.659398 -259.190998)
		(end 245.006876 -259.190998)
		(width 0.13335)
		(layer "In2.Cu")
		(net "BMC_A_EXP_A_SPARE_0")
	)
	(segment
		(start 173.834552 -260.232398)
		(end 110.792768 -260.232398)
		(width 0.13335)
		(layer "In2.Cu")
		(net "BMC_A_EXP_A_SPARE_0")
	)
	(segment
		(start 245.006622 -259.190744)
		(end 244.593618 -259.190744)
		(width 0.13335)
		(layer "In2.Cu")
		(net "BMC_A_EXP_A_SPARE_0")
	)
	(segment
		(start 233.213402 -259.190998)
		(end 232.375202 -260.029198)
		(width 0.13335)
		(layer "In2.Cu")
		(net "BMC_A_EXP_A_SPARE_0")
	)
	(segment
		(start 282.072588 -255.866392)
		(end 268.535912 -255.866392)
		(width 0.13335)
		(layer "In2.Cu")
		(net "BMC_A_EXP_A_SPARE_0")
	)
	(segment
		(start 109.616748 -259.056378)
		(end 109.616748 -259.046726)
		(width 0.13335)
		(layer "In2.Cu")
		(net "BMC_A_EXP_A_SPARE_0")
	)
	(segment
		(start 109.616748 -259.046726)
		(end 109.121702 -258.55168)
		(width 0.13335)
		(layer "In2.Cu")
		(net "BMC_A_EXP_A_SPARE_0")
	)
	(segment
		(start 232.375202 -260.029198)
		(end 227.042472 -260.029198)
		(width 0.13335)
		(layer "In2.Cu")
		(net "BMC_A_EXP_A_SPARE_0")
	)
	(segment
		(start 226.610672 -259.597398)
		(end 194.770756 -259.597398)
		(width 0.13335)
		(layer "In2.Cu")
		(net "BMC_A_EXP_A_SPARE_0")
	)
	(segment
		(start 110.792768 -260.232398)
		(end 109.616748 -259.056378)
		(width 0.13335)
		(layer "In2.Cu")
		(net "BMC_A_EXP_A_SPARE_0")
	)
	(segment
		(start 249.473974 -261.005574)
		(end 247.659398 -259.190998)
		(width 0.13335)
		(layer "In2.Cu")
		(net "BMC_A_EXP_A_SPARE_0")
	)
	(segment
		(start 103.22306 -129.486914)
		(end 103.22306 -130.758438)
		(width 0.12065)
		(layer "In4.Cu")
		(net "BMC_A_EXP_A_SPARE_0")
	)
	(segment
		(start 107.7214 -88.105488)
		(end 107.7214 -123.94692)
		(width 0.12065)
		(layer "In4.Cu")
		(net "BMC_A_EXP_A_SPARE_0")
	)
	(segment
		(start 103.05161 -83.435698)
		(end 107.7214 -88.105488)
		(width 0.12065)
		(layer "In4.Cu")
		(net "BMC_A_EXP_A_SPARE_0")
	)
	(segment
		(start 103.256334 -129.45364)
		(end 103.22306 -129.486914)
		(width 0.12065)
		(layer "In4.Cu")
		(net "BMC_A_EXP_A_SPARE_0")
	)
	(segment
		(start 109.791246 -30.308804)
		(end 109.791246 -37.128958)
		(width 0.12065)
		(layer "In4.Cu")
		(net "BMC_A_EXP_A_SPARE_0")
	)
	(segment
		(start 106.101134 -173.726602)
		(end 106.101134 -255.531112)
		(width 0.12065)
		(layer "In4.Cu")
		(net "BMC_A_EXP_A_SPARE_0")
	)
	(segment
		(start 103.256334 -130.791712)
		(end 103.256334 -170.881802)
		(width 0.12065)
		(layer "In4.Cu")
		(net "BMC_A_EXP_A_SPARE_0")
	)
	(segment
		(start 103.256334 -170.881802)
		(end 106.101134 -173.726602)
		(width 0.12065)
		(layer "In4.Cu")
		(net "BMC_A_EXP_A_SPARE_0")
	)
	(segment
		(start 103.22306 -130.758438)
		(end 103.256334 -130.791712)
		(width 0.12065)
		(layer "In4.Cu")
		(net "BMC_A_EXP_A_SPARE_0")
	)
	(segment
		(start 106.101134 -255.531112)
		(end 109.121702 -258.55168)
		(width 0.12065)
		(layer "In4.Cu")
		(net "BMC_A_EXP_A_SPARE_0")
	)
	(segment
		(start 103.256334 -128.411986)
		(end 103.256334 -129.45364)
		(width 0.12065)
		(layer "In4.Cu")
		(net "BMC_A_EXP_A_SPARE_0")
	)
	(segment
		(start 110.949994 -29.150056)
		(end 109.791246 -30.308804)
		(width 0.12065)
		(layer "In4.Cu")
		(net "BMC_A_EXP_A_SPARE_0")
	)
	(segment
		(start 103.05161 -43.868594)
		(end 103.05161 -83.435698)
		(width 0.12065)
		(layer "In4.Cu")
		(net "BMC_A_EXP_A_SPARE_0")
	)
	(segment
		(start 109.791246 -37.128958)
		(end 103.05161 -43.868594)
		(width 0.12065)
		(layer "In4.Cu")
		(net "BMC_A_EXP_A_SPARE_0")
	)
	(segment
		(start 107.7214 -123.94692)
		(end 103.256334 -128.411986)
		(width 0.12065)
		(layer "In4.Cu")
		(net "BMC_A_EXP_A_SPARE_0")
	)
	(segment
		(start 381.13716 -132.93344)
		(end 381.1524 -132.9182)
		(width 0.508)
		(layer "F.Cu")
		(net "P12V_B")
	)
	(segment
		(start 381.13716 -134.154926)
		(end 381.13716 -132.93344)
		(width 0.508)
		(layer "F.Cu")
		(net "P12V_B")
	)
	(segment
		(start 382.787398 -134.087362)
		(end 381.204724 -134.087362)
		(width 0.508)
		(layer "F.Cu")
		(net "P12V_B")
	)
	(segment
		(start 362.0008 -137.1854)
		(end 362.9533 -137.1854)
		(width 0.508)
		(layer "F.Cu")
		(net "P12V_B")
	)
	(segment
		(start 359.237026 -133.0706)
		(end 359.237026 -134.075678)
		(width 0.508)
		(layer "F.Cu")
		(net "P12V_B")
	)
	(segment
		(start 359.237026 -132.196078)
		(end 359.237026 -133.0706)
		(width 0.508)
		(layer "F.Cu")
		(net "P12V_B")
	)
	(segment
		(start 381.204724 -134.087362)
		(end 381.13716 -134.154926)
		(width 0.508)
		(layer "F.Cu")
		(net "P12V_B")
	)
	(via
		(at 348.9198 -150.1902)
		(size 0.7112)
		(drill 0.4064)
		(layers "F.Cu" "B.Cu")
		(net "P12V_B")
	)
	(via
		(at 349.9866 -151.257)
		(size 0.7112)
		(drill 0.4064)
		(layers "F.Cu" "B.Cu")
		(net "P12V_B")
	)
	(via
		(at 362.0008 -137.1854)
		(size 0.5588)
		(drill 0.3048)
		(layers "F.Cu" "B.Cu")
		(net "P12V_B")
	)
	(via
		(at 348.9198 -149.1234)
		(size 0.7112)
		(drill 0.4064)
		(layers "F.Cu" "B.Cu")
		(net "P12V_B")
	)
	(via
		(at 348.9198 -152.3238)
		(size 0.7112)
		(drill 0.4064)
		(layers "F.Cu" "B.Cu")
		(net "P12V_B")
	)
	(via
		(at 349.9866 -150.1902)
		(size 0.7112)
		(drill 0.4064)
		(layers "F.Cu" "B.Cu")
		(net "P12V_B")
	)
	(via
		(at 347.8022 -146.9898)
		(size 0.6604)
		(drill 0.3302)
		(layers "F.Cu" "B.Cu")
		(net "P12V_B")
	)
	(via
		(at 348.9198 -148.0566)
		(size 0.7112)
		(drill 0.4064)
		(layers "F.Cu" "B.Cu")
		(net "P12V_B")
	)
	(via
		(at 347.853 -150.1902)
		(size 0.7112)
		(drill 0.4064)
		(layers "F.Cu" "B.Cu")
		(net "P12V_B")
	)
	(via
		(at 347.853 -149.1234)
		(size 0.7112)
		(drill 0.4064)
		(layers "F.Cu" "B.Cu")
		(net "P12V_B")
	)
	(via
		(at 341.898478 -134.583678)
		(size 0.5588)
		(drill 0.3048)
		(layers "F.Cu" "B.Cu")
		(net "P12V_B")
	)
	(via
		(at 359.237026 -133.0706)
		(size 0.5588)
		(drill 0.3048)
		(layers "F.Cu" "B.Cu")
		(net "P12V_B")
	)
	(via
		(at 351.0534 -149.1234)
		(size 0.7112)
		(drill 0.4064)
		(layers "F.Cu" "B.Cu")
		(net "P12V_B")
	)
	(via
		(at 349.9866 -149.1234)
		(size 0.7112)
		(drill 0.4064)
		(layers "F.Cu" "B.Cu")
		(net "P12V_B")
	)
	(via
		(at 352.1202 -149.1234)
		(size 0.7112)
		(drill 0.4064)
		(layers "F.Cu" "B.Cu")
		(net "P12V_B")
	)
	(via
		(at 347.853 -148.0566)
		(size 0.7112)
		(drill 0.4064)
		(layers "F.Cu" "B.Cu")
		(net "P12V_B")
	)
	(via
		(at 349.9866 -152.3238)
		(size 0.7112)
		(drill 0.4064)
		(layers "F.Cu" "B.Cu")
		(net "P12V_B")
	)
	(via
		(at 348.9198 -151.257)
		(size 0.7112)
		(drill 0.4064)
		(layers "F.Cu" "B.Cu")
		(net "P12V_B")
	)
	(via
		(at 381.1524 -132.9182)
		(size 0.5588)
		(drill 0.3048)
		(layers "F.Cu" "B.Cu")
		(net "P12V_B")
	)
	(via
		(at 347.853 -151.257)
		(size 0.7112)
		(drill 0.4064)
		(layers "F.Cu" "B.Cu")
		(net "P12V_B")
	)
	(via
		(at 347.853 -152.3238)
		(size 0.7112)
		(drill 0.4064)
		(layers "F.Cu" "B.Cu")
		(net "P12V_B")
	)
	(segment
		(start 345.8464 -134.583678)
		(end 341.898478 -134.583678)
		(width 0.508)
		(layer "B.Cu")
		(net "P12V_B")
	)
	(segment
		(start 359.237026 -133.0706)
		(end 357.723948 -134.583678)
		(width 0.508)
		(layer "B.Cu")
		(net "P12V_B")
	)
	(segment
		(start 346.521278 -133.9088)
		(end 345.8464 -134.583678)
		(width 0.508)
		(layer "B.Cu")
		(net "P12V_B")
	)
	(segment
		(start 359.3084 -135.3312)
		(end 361.1626 -137.1854)
		(width 0.508)
		(layer "B.Cu")
		(net "P12V_B")
	)
	(segment
		(start 381.1524 -132.9182)
		(end 378.8918 -132.9182)
		(width 0.508)
		(layer "B.Cu")
		(net "P12V_B")
	)
	(segment
		(start 377.9012 -131.9276)
		(end 367.2586 -131.9276)
		(width 0.508)
		(layer "B.Cu")
		(net "P12V_B")
	)
	(segment
		(start 357.723948 -134.583678)
		(end 353.1616 -134.583678)
		(width 0.508)
		(layer "B.Cu")
		(net "P12V_B")
	)
	(segment
		(start 352.486722 -133.9088)
		(end 346.521278 -133.9088)
		(width 0.508)
		(layer "B.Cu")
		(net "P12V_B")
	)
	(segment
		(start 367.2586 -131.9276)
		(end 362.0008 -137.1854)
		(width 0.508)
		(layer "B.Cu")
		(net "P12V_B")
	)
	(segment
		(start 361.1626 -137.1854)
		(end 362.0008 -137.1854)
		(width 0.508)
		(layer "B.Cu")
		(net "P12V_B")
	)
	(segment
		(start 353.1616 -134.583678)
		(end 352.486722 -133.9088)
		(width 0.508)
		(layer "B.Cu")
		(net "P12V_B")
	)
	(segment
		(start 378.8918 -132.9182)
		(end 377.9012 -131.9276)
		(width 0.508)
		(layer "B.Cu")
		(net "P12V_B")
	)
	(segment
		(start 359.237026 -133.0706)
		(end 359.3084 -133.141974)
		(width 0.508)
		(layer "B.Cu")
		(net "P12V_B")
	)
	(segment
		(start 359.3084 -133.141974)
		(end 359.3084 -135.3312)
		(width 0.508)
		(layer "B.Cu")
		(net "P12V_B")
	)
	(segment
		(start 376.750072 -24.550116)
		(end 376.750072 -25.950164)
		(width 0.508)
		(layer "In4.Cu")
		(net "P12V_B")
	)
	(segment
		(start 242.062 -394.3858)
		(end 240.9825 -394.3858)
		(width 0.254)
		(layer "F.Cu")
		(net "MB3_VCAP_R")
	)
	(segment
		(start 242.189 -394.5128)
		(end 242.062 -394.3858)
		(width 0.254)
		(layer "F.Cu")
		(net "MB3_VCAP_R")
	)
	(segment
		(start 238.9505 -393.4968)
		(end 238.9505 -394.3858)
		(width 0.254)
		(layer "F.Cu")
		(net "MB3_VCAP_R")
	)
	(segment
		(start 240.009934 -391.470134)
		(end 240.9825 -392.4427)
		(width 0.254)
		(layer "F.Cu")
		(net "MB3_VCAP_R")
	)
	(segment
		(start 242.316 -394.3858)
		(end 242.189 -394.5128)
		(width 0.254)
		(layer "F.Cu")
		(net "MB3_VCAP_R")
	)
	(segment
		(start 243.3955 -394.3858)
		(end 242.316 -394.3858)
		(width 0.254)
		(layer "F.Cu")
		(net "MB3_VCAP_R")
	)
	(segment
		(start 240.9825 -393.4968)
		(end 240.9825 -392.4427)
		(width 0.254)
		(layer "F.Cu")
		(net "MB3_VCAP_R")
	)
	(segment
		(start 240.9825 -394.3858)
		(end 240.9825 -393.4968)
		(width 0.254)
		(layer "F.Cu")
		(net "MB3_VCAP_R")
	)
	(segment
		(start 240.009934 -390.8933)
		(end 240.009934 -391.470134)
		(width 0.254)
		(layer "F.Cu")
		(net "MB3_VCAP_R")
	)
	(via
		(at 240.9825 -392.4427)
		(size 0.6604)
		(drill 0.3302)
		(layers "F.Cu" "B.Cu")
		(net "MB3_VCAP_R")
	)
	(via
		(at 238.9505 -393.4968)
		(size 0.5588)
		(drill 0.3048)
		(layers "F.Cu" "B.Cu")
		(net "MB3_VCAP_R")
	)
	(via
		(at 240.9825 -393.4968)
		(size 0.5588)
		(drill 0.3048)
		(layers "F.Cu" "B.Cu")
		(net "MB3_VCAP_R")
	)
	(segment
		(start 238.9505 -393.4968)
		(end 240.9825 -393.4968)
		(width 0.254)
		(layer "B.Cu")
		(net "MB3_VCAP_R")
	)
	(segment
		(start 237.2868 -392.557)
		(end 236.601 -393.2428)
		(width 0.254)
		(layer "F.Cu")
		(net "MB3_TIME_R")
	)
	(segment
		(start 238.510064 -390.8933)
		(end 238.510064 -391.523728)
		(width 0.254)
		(layer "F.Cu")
		(net "MB3_TIME_R")
	)
	(segment
		(start 238.510064 -391.523728)
		(end 237.476792 -392.557)
		(width 0.254)
		(layer "F.Cu")
		(net "MB3_TIME_R")
	)
	(segment
		(start 236.601 -393.2428)
		(end 236.601 -395.4653)
		(width 0.254)
		(layer "F.Cu")
		(net "MB3_TIME_R")
	)
	(segment
		(start 237.476792 -392.557)
		(end 237.2868 -392.557)
		(width 0.254)
		(layer "F.Cu")
		(net "MB3_TIME_R")
	)
	(via
		(at 236.601 -393.2428)
		(size 0.6604)
		(drill 0.3302)
		(layers "F.Cu" "B.Cu")
		(net "MB3_TIME_R")
	)
	(segment
		(start 244.600222 -386.329936)
		(end 243.382546 -386.329936)
		(width 0.254)
		(layer "F.Cu")
		(net "MB3_TEMP")
	)
	(segment
		(start 241.90071 -386.66674)
		(end 242.237514 -386.329936)
		(width 0.254)
		(layer "F.Cu")
		(net "MB3_TEMP")
	)
	(segment
		(start 242.237514 -386.329936)
		(end 243.382546 -386.329936)
		(width 0.254)
		(layer "F.Cu")
		(net "MB3_TEMP")
	)
	(segment
		(start 241.3127 -386.66674)
		(end 241.90071 -386.66674)
		(width 0.254)
		(layer "F.Cu")
		(net "MB3_TEMP")
	)
	(segment
		(start 244.725952 -386.204206)
		(end 244.600222 -386.329936)
		(width 0.254)
		(layer "F.Cu")
		(net "MB3_TEMP")
	)
	(via
		(at 243.382546 -386.329936)
		(size 0.6604)
		(drill 0.3302)
		(layers "F.Cu" "B.Cu")
		(net "MB3_TEMP")
	)
	(segment
		(start 234.87888 -390.16686)
		(end 234.72394 -390.3218)
		(width 0.254)
		(layer "F.Cu")
		(net "MB3_SPISS_PD")
	)
	(segment
		(start 233.6165 -390.9568)
		(end 234.08894 -390.9568)
		(width 0.254)
		(layer "F.Cu")
		(net "MB3_SPISS_PD")
	)
	(segment
		(start 234.08894 -390.9568)
		(end 234.72394 -390.3218)
		(width 0.254)
		(layer "F.Cu")
		(net "MB3_SPISS_PD")
	)
	(segment
		(start 236.2073 -390.16686)
		(end 234.87888 -390.16686)
		(width 0.254)
		(layer "F.Cu")
		(net "MB3_SPISS_PD")
	)
	(via
		(at 234.72394 -390.3218)
		(size 0.6604)
		(drill 0.3302)
		(layers "F.Cu" "B.Cu")
		(net "MB3_SPISS_PD")
	)
	(segment
		(start 233.299 -382.6383)
		(end 233.299 -383.5908)
		(width 0.254)
		(layer "F.Cu")
		(net "MB3_RETRY_R")
	)
	(segment
		(start 236.7153 -385.8641)
		(end 235.5215 -384.6703)
		(width 0.254)
		(layer "F.Cu")
		(net "MB3_RETRY_R")
	)
	(segment
		(start 237.00994 -385.8641)
		(end 236.7153 -385.8641)
		(width 0.254)
		(layer "F.Cu")
		(net "MB3_RETRY_R")
	)
	(segment
		(start 234.3785 -384.6703)
		(end 233.299 -383.5908)
		(width 0.254)
		(layer "F.Cu")
		(net "MB3_RETRY_R")
	)
	(segment
		(start 235.5215 -384.6703)
		(end 234.3785 -384.6703)
		(width 0.254)
		(layer "F.Cu")
		(net "MB3_RETRY_R")
	)
	(via
		(at 233.299 -383.5908)
		(size 0.6604)
		(drill 0.3302)
		(layers "F.Cu" "B.Cu")
		(net "MB3_RETRY_R")
	)
	(segment
		(start 244.348 -394.4493)
		(end 244.2845 -394.3858)
		(width 0.254)
		(layer "F.Cu")
		(net "MB3_PSET_R")
	)
	(segment
		(start 240.51006 -391.2743)
		(end 240.842292 -391.606532)
		(width 0.254)
		(layer "F.Cu")
		(net "MB3_PSET_R")
	)
	(segment
		(start 244.2845 -394.3858)
		(end 244.284246 -394.3858)
		(width 0.254)
		(layer "F.Cu")
		(net "MB3_PSET_R")
	)
	(segment
		(start 241.504978 -391.606532)
		(end 242.629944 -392.731498)
		(width 0.254)
		(layer "F.Cu")
		(net "MB3_PSET_R")
	)
	(segment
		(start 243.332 -395.4653)
		(end 244.348 -395.4653)
		(width 0.254)
		(layer "F.Cu")
		(net "MB3_PSET_R")
	)
	(segment
		(start 240.51006 -390.9695)
		(end 240.51006 -391.2743)
		(width 0.254)
		(layer "F.Cu")
		(net "MB3_PSET_R")
	)
	(segment
		(start 240.842292 -391.606532)
		(end 241.504978 -391.606532)
		(width 0.254)
		(layer "F.Cu")
		(net "MB3_PSET_R")
	)
	(segment
		(start 244.284246 -394.3858)
		(end 242.629944 -392.731498)
		(width 0.254)
		(layer "F.Cu")
		(net "MB3_PSET_R")
	)
	(segment
		(start 244.348 -395.4653)
		(end 244.348 -394.4493)
		(width 0.254)
		(layer "F.Cu")
		(net "MB3_PSET_R")
	)
	(via
		(at 242.629944 -392.731498)
		(size 0.6604)
		(drill 0.3302)
		(layers "F.Cu" "B.Cu")
		(net "MB3_PSET_R")
	)
	(segment
		(start 241.3762 -382.6383)
		(end 240.3602 -382.6383)
		(width 0.254)
		(layer "F.Cu")
		(net "MB3_P12V_PWGIN_R")
	)
	(segment
		(start 239.8268 -383.8448)
		(end 240.3602 -383.8448)
		(width 0.254)
		(layer "F.Cu")
		(net "MB3_P12V_PWGIN_R")
	)
	(segment
		(start 239.009936 -385.9403)
		(end 239.009936 -384.661664)
		(width 0.254)
		(layer "F.Cu")
		(net "MB3_P12V_PWGIN_R")
	)
	(segment
		(start 239.009936 -384.661664)
		(end 239.8268 -383.8448)
		(width 0.254)
		(layer "F.Cu")
		(net "MB3_P12V_PWGIN_R")
	)
	(segment
		(start 240.3602 -382.6383)
		(end 240.3602 -383.8448)
		(width 0.254)
		(layer "F.Cu")
		(net "MB3_P12V_PWGIN_R")
	)
	(via
		(at 240.3602 -383.8448)
		(size 0.6604)
		(drill 0.3302)
		(layers "F.Cu" "B.Cu")
		(net "MB3_P12V_PWGIN_R")
	)
	(segment
		(start 245.054628 -390.723628)
		(end 244.348254 -390.017254)
		(width 0.508)
		(layer "F.Cu")
		(net "MB3_P12V_HS")
	)
	(segment
		(start 241.2365 -389.166862)
		(end 242.158012 -389.166862)
		(width 0.254)
		(layer "F.Cu")
		(net "MB3_P12V_HS")
	)
	(segment
		(start 242.262152 -389.271002)
		(end 242.277138 -389.271002)
		(width 0.254)
		(layer "F.Cu")
		(net "MB3_P12V_HS")
	)
	(segment
		(start 244.348254 -390.017254)
		(end 244.348254 -389.617204)
		(width 0.508)
		(layer "F.Cu")
		(net "MB3_P12V_HS")
	)
	(segment
		(start 242.62334 -389.617204)
		(end 242.975638 -389.617204)
		(width 0.254)
		(layer "F.Cu")
		(net "MB3_P12V_HS")
	)
	(segment
		(start 242.277138 -389.271002)
		(end 242.62334 -389.617204)
		(width 0.254)
		(layer "F.Cu")
		(net "MB3_P12V_HS")
	)
	(segment
		(start 244.348254 -389.617204)
		(end 242.975638 -389.617204)
		(width 0.508)
		(layer "F.Cu")
		(net "MB3_P12V_HS")
	)
	(segment
		(start 242.158012 -389.166862)
		(end 242.262152 -389.271002)
		(width 0.254)
		(layer "F.Cu")
		(net "MB3_P12V_HS")
	)
	(via
		(at 242.975638 -389.617204)
		(size 0.6604)
		(drill 0.3302)
		(layers "F.Cu" "B.Cu")
		(net "MB3_P12V_HS")
	)
	(segment
		(start 238.0615 -395.4018)
		(end 238.0615 -394.3858)
		(width 0.254)
		(layer "F.Cu")
		(net "MB3_ISTART_R")
	)
	(segment
		(start 239.009936 -392.040364)
		(end 238.0615 -392.9888)
		(width 0.254)
		(layer "F.Cu")
		(net "MB3_ISTART_R")
	)
	(segment
		(start 239.009936 -390.8933)
		(end 239.009936 -392.040364)
		(width 0.254)
		(layer "F.Cu")
		(net "MB3_ISTART_R")
	)
	(segment
		(start 237.998 -395.4653)
		(end 238.0615 -395.4018)
		(width 0.254)
		(layer "F.Cu")
		(net "MB3_ISTART_R")
	)
	(segment
		(start 239.014 -395.4653)
		(end 237.998 -395.4653)
		(width 0.254)
		(layer "F.Cu")
		(net "MB3_ISTART_R")
	)
	(segment
		(start 238.0615 -394.3858)
		(end 238.0615 -392.9888)
		(width 0.254)
		(layer "F.Cu")
		(net "MB3_ISTART_R")
	)
	(via
		(at 238.0615 -392.9888)
		(size 0.6604)
		(drill 0.3302)
		(layers "F.Cu" "B.Cu")
		(net "MB3_ISTART_R")
	)
	(segment
		(start 240.0935 -394.3858)
		(end 240.0935 -393.0523)
		(width 0.254)
		(layer "F.Cu")
		(net "MB3_ISET_R")
	)
	(segment
		(start 239.510062 -391.960862)
		(end 240.0935 -392.5443)
		(width 0.254)
		(layer "F.Cu")
		(net "MB3_ISET_R")
	)
	(segment
		(start 239.510062 -390.8933)
		(end 239.510062 -391.960862)
		(width 0.254)
		(layer "F.Cu")
		(net "MB3_ISET_R")
	)
	(segment
		(start 240.03 -395.4653)
		(end 240.0935 -395.4018)
		(width 0.254)
		(layer "F.Cu")
		(net "MB3_ISET_R")
	)
	(segment
		(start 240.0935 -395.4018)
		(end 240.0935 -394.3858)
		(width 0.254)
		(layer "F.Cu")
		(net "MB3_ISET_R")
	)
	(segment
		(start 240.0935 -392.5443)
		(end 240.0935 -393.0523)
		(width 0.254)
		(layer "F.Cu")
		(net "MB3_ISET_R")
	)
	(segment
		(start 241.046 -395.4653)
		(end 240.03 -395.4653)
		(width 0.254)
		(layer "F.Cu")
		(net "MB3_ISET_R")
	)
	(via
		(at 240.0935 -393.0523)
		(size 0.6604)
		(drill 0.3302)
		(layers "F.Cu" "B.Cu")
		(net "MB3_ISET_R")
	)
	(segment
		(start 232.170224 -386.06476)
		(end 234.7722 -388.666736)
		(width 0.254)
		(layer "F.Cu")
		(net "MB3_HS_ENABLE")
	)
	(segment
		(start 232.2703 -386.06476)
		(end 232.170224 -386.06476)
		(width 0.254)
		(layer "F.Cu")
		(net "MB3_HS_ENABLE")
	)
	(segment
		(start 236.2835 -388.666736)
		(end 234.7722 -388.666736)
		(width 0.254)
		(layer "F.Cu")
		(net "MB3_HS_ENABLE")
	)
	(via
		(at 234.7722 -388.666736)
		(size 0.6604)
		(drill 0.3302)
		(layers "F.Cu" "B.Cu")
		(net "MB3_HS_ENABLE")
	)
	(segment
		(start 238.252 -385.1148)
		(end 238.252 -383.794)
		(width 0.254)
		(layer "F.Cu")
		(net "MB3_CM_VOUT_R")
	)
	(segment
		(start 239.268 -382.6383)
		(end 238.252 -382.6383)
		(width 0.254)
		(layer "F.Cu")
		(net "MB3_CM_VOUT_R")
	)
	(segment
		(start 238.510064 -385.372864)
		(end 238.252 -385.1148)
		(width 0.254)
		(layer "F.Cu")
		(net "MB3_CM_VOUT_R")
	)
	(segment
		(start 238.510064 -385.9403)
		(end 238.510064 -385.372864)
		(width 0.254)
		(layer "F.Cu")
		(net "MB3_CM_VOUT_R")
	)
	(segment
		(start 238.252 -382.6383)
		(end 238.252 -383.794)
		(width 0.254)
		(layer "F.Cu")
		(net "MB3_CM_VOUT_R")
	)
	(via
		(at 238.252 -383.794)
		(size 0.6604)
		(drill 0.3302)
		(layers "F.Cu" "B.Cu")
		(net "MB3_CM_VOUT_R")
	)
	(segment
		(start 245.824502 -393.488164)
		(end 245.824502 -393.48791)
		(width 0.254)
		(layer "F.Cu")
		(net "MB3_CM_UV_R")
	)
	(segment
		(start 248.021602 -393.538964)
		(end 248.008902 -393.551664)
		(width 0.254)
		(layer "F.Cu")
		(net "MB3_CM_UV_R")
	)
	(segment
		(start 241.2365 -389.666734)
		(end 242.003326 -389.666734)
		(width 0.254)
		(layer "F.Cu")
		(net "MB3_CM_UV_R")
	)
	(segment
		(start 248.008902 -393.551664)
		(end 246.992902 -393.551664)
		(width 0.254)
		(layer "F.Cu")
		(net "MB3_CM_UV_R")
	)
	(segment
		(start 245.824502 -393.48791)
		(end 243.836698 -391.500106)
		(width 0.254)
		(layer "F.Cu")
		(net "MB3_CM_UV_R")
	)
	(segment
		(start 246.992902 -393.551664)
		(end 245.888002 -393.551664)
		(width 0.254)
		(layer "F.Cu")
		(net "MB3_CM_UV_R")
	)
	(segment
		(start 245.888002 -393.551664)
		(end 245.824502 -393.488164)
		(width 0.254)
		(layer "F.Cu")
		(net "MB3_CM_UV_R")
	)
	(segment
		(start 242.003326 -389.666734)
		(end 243.836698 -391.500106)
		(width 0.254)
		(layer "F.Cu")
		(net "MB3_CM_UV_R")
	)
	(via
		(at 243.836698 -391.500106)
		(size 0.6604)
		(drill 0.3302)
		(layers "F.Cu" "B.Cu")
		(net "MB3_CM_UV_R")
	)
	(segment
		(start 248.631456 -388.12216)
		(end 247.915938 -388.12216)
		(width 0.254)
		(layer "F.Cu")
		(net "MB3_CM_SENSE_R1_P")
	)
	(segment
		(start 255.78054 -391.019538)
		(end 255.52654 -390.765538)
		(width 0.254)
		(layer "F.Cu")
		(net "MB3_CM_SENSE_R1_P")
	)
	(segment
		(start 247.595898 -388.4422)
		(end 247.570498 -388.4168)
		(width 0.254)
		(layer "F.Cu")
		(net "MB3_CM_SENSE_R1_P")
	)
	(segment
		(start 247.915938 -388.12216)
		(end 247.595898 -388.4422)
		(width 0.254)
		(layer "F.Cu")
		(net "MB3_CM_SENSE_R1_P")
	)
	(segment
		(start 255.52654 -390.765538)
		(end 251.274834 -390.765538)
		(width 0.254)
		(layer "F.Cu")
		(net "MB3_CM_SENSE_R1_P")
	)
	(segment
		(start 251.274834 -390.765538)
		(end 248.631456 -388.12216)
		(width 0.254)
		(layer "F.Cu")
		(net "MB3_CM_SENSE_R1_P")
	)
	(segment
		(start 255.78054 -394.651992)
		(end 255.78054 -391.019538)
		(width 0.254)
		(layer "F.Cu")
		(net "MB3_CM_SENSE_R1_P")
	)
	(segment
		(start 247.570498 -388.4168)
		(end 246.6975 -388.4168)
		(width 0.254)
		(layer "F.Cu")
		(net "MB3_CM_SENSE_R1_P")
	)
	(via
		(at 247.595898 -388.4422)
		(size 0.5588)
		(drill 0.3048)
		(layers "F.Cu" "B.Cu")
		(net "MB3_CM_SENSE_R1_P")
	)
	(segment
		(start 249.31116 -387.23824)
		(end 249.31116 -386.25272)
		(width 0.254)
		(layer "B.Cu")
		(net "MB3_CM_SENSE_R1_P")
	)
	(segment
		(start 248.5771 -385.51866)
		(end 247.32234 -385.51866)
		(width 0.254)
		(layer "B.Cu")
		(net "MB3_CM_SENSE_R1_P")
	)
	(segment
		(start 248.16054 -388.13486)
		(end 248.41454 -388.13486)
		(width 0.254)
		(layer "B.Cu")
		(net "MB3_CM_SENSE_R1_P")
	)
	(segment
		(start 249.31116 -386.25272)
		(end 248.5771 -385.51866)
		(width 0.254)
		(layer "B.Cu")
		(net "MB3_CM_SENSE_R1_P")
	)
	(segment
		(start 247.32234 -385.51866)
		(end 247.04548 -385.2418)
		(width 0.254)
		(layer "B.Cu")
		(net "MB3_CM_SENSE_R1_P")
	)
	(segment
		(start 247.595898 -388.4422)
		(end 247.72112 -388.316724)
		(width 0.254)
		(layer "B.Cu")
		(net "MB3_CM_SENSE_R1_P")
	)
	(segment
		(start 247.04548 -385.2418)
		(end 246.6975 -385.2418)
		(width 0.254)
		(layer "B.Cu")
		(net "MB3_CM_SENSE_R1_P")
	)
	(arc
		(start 248.41454 -388.13486)
		(mid 249.048546 -387.872246)
		(end 249.31116 -387.23824)
		(width 0.254)
		(layer "B.Cu")
		(net "MB3_CM_SENSE_R1_P")
	)
	(arc
		(start 247.72112 -388.316724)
		(mid 247.922743 -388.182097)
		(end 248.16054 -388.13486)
		(width 0.254)
		(layer "B.Cu")
		(net "MB3_CM_SENSE_R1_P")
	)
	(segment
		(start 255.78054 -390.054338)
		(end 255.52654 -390.308338)
		(width 0.254)
		(layer "F.Cu")
		(net "MB3_CM_SENSE_R1_N")
	)
	(segment
		(start 247.570498 -387.4008)
		(end 246.6975 -387.4008)
		(width 0.254)
		(layer "F.Cu")
		(net "MB3_CM_SENSE_R1_N")
	)
	(segment
		(start 247.885458 -387.66496)
		(end 247.595898 -387.3754)
		(width 0.254)
		(layer "F.Cu")
		(net "MB3_CM_SENSE_R1_N")
	)
	(segment
		(start 247.595898 -387.3754)
		(end 247.570498 -387.4008)
		(width 0.254)
		(layer "F.Cu")
		(net "MB3_CM_SENSE_R1_N")
	)
	(segment
		(start 251.464318 -390.308338)
		(end 248.82094 -387.66496)
		(width 0.254)
		(layer "F.Cu")
		(net "MB3_CM_SENSE_R1_N")
	)
	(segment
		(start 255.52654 -390.308338)
		(end 251.464318 -390.308338)
		(width 0.254)
		(layer "F.Cu")
		(net "MB3_CM_SENSE_R1_N")
	)
	(segment
		(start 255.78054 -386.421884)
		(end 255.78054 -390.054338)
		(width 0.254)
		(layer "F.Cu")
		(net "MB3_CM_SENSE_R1_N")
	)
	(segment
		(start 248.82094 -387.66496)
		(end 247.885458 -387.66496)
		(width 0.254)
		(layer "F.Cu")
		(net "MB3_CM_SENSE_R1_N")
	)
	(via
		(at 247.595898 -387.3754)
		(size 0.5588)
		(drill 0.3048)
		(layers "F.Cu" "B.Cu")
		(net "MB3_CM_SENSE_R1_N")
	)
	(segment
		(start 246.6975 -386.2578)
		(end 247.04802 -386.2578)
		(width 0.254)
		(layer "B.Cu")
		(net "MB3_CM_SENSE_R1_N")
	)
	(segment
		(start 248.41454 -387.67766)
		(end 248.16054 -387.67766)
		(width 0.254)
		(layer "B.Cu")
		(net "MB3_CM_SENSE_R1_N")
	)
	(segment
		(start 247.32996 -385.97586)
		(end 248.387616 -385.97586)
		(width 0.254)
		(layer "B.Cu")
		(net "MB3_CM_SENSE_R1_N")
	)
	(segment
		(start 247.04802 -386.2578)
		(end 247.32996 -385.97586)
		(width 0.254)
		(layer "B.Cu")
		(net "MB3_CM_SENSE_R1_N")
	)
	(segment
		(start 248.387616 -385.97586)
		(end 248.85396 -386.442204)
		(width 0.254)
		(layer "B.Cu")
		(net "MB3_CM_SENSE_R1_N")
	)
	(segment
		(start 248.85396 -386.442204)
		(end 248.85396 -387.23824)
		(width 0.254)
		(layer "B.Cu")
		(net "MB3_CM_SENSE_R1_N")
	)
	(segment
		(start 247.712484 -387.49224)
		(end 247.595898 -387.3754)
		(width 0.254)
		(layer "B.Cu")
		(net "MB3_CM_SENSE_R1_N")
	)
	(arc
		(start 248.16054 -387.67766)
		(mid 247.918066 -387.629522)
		(end 247.712484 -387.49224)
		(width 0.254)
		(layer "B.Cu")
		(net "MB3_CM_SENSE_R1_N")
	)
	(arc
		(start 248.85396 -387.23824)
		(mid 248.725257 -387.548957)
		(end 248.41454 -387.67766)
		(width 0.254)
		(layer "B.Cu")
		(net "MB3_CM_SENSE_R1_N")
	)
	(segment
		(start 242.448334 -388.666736)
		(end 241.2365 -388.666736)
		(width 0.254)
		(layer "F.Cu")
		(net "MB3_CM_SENSE_P")
	)
	(segment
		(start 242.4938 -388.712202)
		(end 242.448334 -388.666736)
		(width 0.254)
		(layer "F.Cu")
		(net "MB3_CM_SENSE_P")
	)
	(via
		(at 242.4938 -388.712202)
		(size 0.5588)
		(drill 0.3048)
		(layers "F.Cu" "B.Cu")
		(net "MB3_CM_SENSE_P")
	)
	(segment
		(start 244.832632 -385.5212)
		(end 244.616732 -385.3053)
		(width 0.254)
		(layer "B.Cu")
		(net "MB3_CM_SENSE_P")
	)
	(segment
		(start 240.8428 -386.3594)
		(end 240.8428 -387.32587)
		(width 0.254)
		(layer "B.Cu")
		(net "MB3_CM_SENSE_P")
	)
	(segment
		(start 244.616732 -385.3053)
		(end 244.094 -385.3053)
		(width 0.254)
		(layer "B.Cu")
		(net "MB3_CM_SENSE_P")
	)
	(segment
		(start 245.8085 -385.2418)
		(end 245.5291 -385.5212)
		(width 0.254)
		(layer "B.Cu")
		(net "MB3_CM_SENSE_P")
	)
	(segment
		(start 245.5291 -385.5212)
		(end 244.832632 -385.5212)
		(width 0.254)
		(layer "B.Cu")
		(net "MB3_CM_SENSE_P")
	)
	(segment
		(start 242.4938 -388.423658)
		(end 242.4938 -388.712202)
		(width 0.254)
		(layer "B.Cu")
		(net "MB3_CM_SENSE_P")
	)
	(segment
		(start 243.571268 -385.3053)
		(end 243.355368 -385.5212)
		(width 0.254)
		(layer "B.Cu")
		(net "MB3_CM_SENSE_P")
	)
	(segment
		(start 241.662458 -388.145528)
		(end 242.216686 -388.145528)
		(width 0.254)
		(layer "B.Cu")
		(net "MB3_CM_SENSE_P")
	)
	(segment
		(start 244.094 -385.3053)
		(end 243.571268 -385.3053)
		(width 0.254)
		(layer "B.Cu")
		(net "MB3_CM_SENSE_P")
	)
	(segment
		(start 243.355368 -385.5212)
		(end 241.681 -385.5212)
		(width 0.254)
		(layer "B.Cu")
		(net "MB3_CM_SENSE_P")
	)
	(segment
		(start 241.681 -385.5212)
		(end 240.8428 -386.3594)
		(width 0.254)
		(layer "B.Cu")
		(net "MB3_CM_SENSE_P")
	)
	(arc
		(start 242.337082 -388.173214)
		(mid 242.451425 -388.275927)
		(end 242.4938 -388.423658)
		(width 0.254)
		(layer "B.Cu")
		(net "MB3_CM_SENSE_P")
	)
	(arc
		(start 240.8428 -387.32587)
		(mid 241.082872 -387.905456)
		(end 241.662458 -388.145528)
		(width 0.254)
		(layer "B.Cu")
		(net "MB3_CM_SENSE_P")
	)
	(arc
		(start 242.216686 -388.145528)
		(mid 242.278452 -388.152545)
		(end 242.337082 -388.173214)
		(width 0.254)
		(layer "B.Cu")
		(net "MB3_CM_SENSE_P")
	)
	(segment
		(start 242.4938 -387.1214)
		(end 242.448334 -387.166866)
		(width 0.254)
		(layer "F.Cu")
		(net "MB3_CM_SENSE_N")
	)
	(segment
		(start 242.448334 -387.166866)
		(end 241.2365 -387.166866)
		(width 0.254)
		(layer "F.Cu")
		(net "MB3_CM_SENSE_N")
	)
	(via
		(at 242.4938 -387.1214)
		(size 0.5588)
		(drill 0.3048)
		(layers "F.Cu" "B.Cu")
		(net "MB3_CM_SENSE_N")
	)
	(segment
		(start 242.4938 -387.409944)
		(end 242.4938 -387.1214)
		(width 0.254)
		(layer "B.Cu")
		(net "MB3_CM_SENSE_N")
	)
	(segment
		(start 243.355368 -385.9784)
		(end 241.870484 -385.9784)
		(width 0.254)
		(layer "B.Cu")
		(net "MB3_CM_SENSE_N")
	)
	(segment
		(start 241.870484 -385.9784)
		(end 241.3 -386.548884)
		(width 0.254)
		(layer "B.Cu")
		(net "MB3_CM_SENSE_N")
	)
	(segment
		(start 243.571268 -386.1943)
		(end 243.355368 -385.9784)
		(width 0.254)
		(layer "B.Cu")
		(net "MB3_CM_SENSE_N")
	)
	(segment
		(start 244.094 -386.1943)
		(end 243.571268 -386.1943)
		(width 0.254)
		(layer "B.Cu")
		(net "MB3_CM_SENSE_N")
	)
	(segment
		(start 244.616732 -386.1943)
		(end 244.094 -386.1943)
		(width 0.254)
		(layer "B.Cu")
		(net "MB3_CM_SENSE_N")
	)
	(segment
		(start 241.662458 -387.688328)
		(end 242.215416 -387.688328)
		(width 0.254)
		(layer "B.Cu")
		(net "MB3_CM_SENSE_N")
	)
	(segment
		(start 245.5291 -385.9784)
		(end 244.832632 -385.9784)
		(width 0.254)
		(layer "B.Cu")
		(net "MB3_CM_SENSE_N")
	)
	(segment
		(start 245.8085 -386.2578)
		(end 245.5291 -385.9784)
		(width 0.254)
		(layer "B.Cu")
		(net "MB3_CM_SENSE_N")
	)
	(segment
		(start 244.832632 -385.9784)
		(end 244.616732 -386.1943)
		(width 0.254)
		(layer "B.Cu")
		(net "MB3_CM_SENSE_N")
	)
	(segment
		(start 241.3 -386.548884)
		(end 241.3 -387.32587)
		(width 0.254)
		(layer "B.Cu")
		(net "MB3_CM_SENSE_N")
	)
	(arc
		(start 241.3 -387.32587)
		(mid 241.406161 -387.582167)
		(end 241.662458 -387.688328)
		(width 0.254)
		(layer "B.Cu")
		(net "MB3_CM_SENSE_N")
	)
	(arc
		(start 242.215416 -387.688328)
		(mid 242.412263 -387.606791)
		(end 242.4938 -387.409944)
		(width 0.254)
		(layer "B.Cu")
		(net "MB3_CM_SENSE_N")
	)
	(segment
		(start 248.008902 -394.567664)
		(end 246.992902 -394.567664)
		(width 0.254)
		(layer "F.Cu")
		(net "MB3_CM_OV_R")
	)
	(segment
		(start 241.3127 -390.16686)
		(end 241.696494 -390.16686)
		(width 0.254)
		(layer "F.Cu")
		(net "MB3_CM_OV_R")
	)
	(segment
		(start 246.460518 -394.567664)
		(end 246.371618 -394.656564)
		(width 0.254)
		(layer "F.Cu")
		(net "MB3_CM_OV_R")
	)
	(segment
		(start 245.824502 -394.656564)
		(end 244.096032 -392.928094)
		(width 0.254)
		(layer "F.Cu")
		(net "MB3_CM_OV_R")
	)
	(segment
		(start 248.021602 -394.580364)
		(end 248.008902 -394.567664)
		(width 0.254)
		(layer "F.Cu")
		(net "MB3_CM_OV_R")
	)
	(segment
		(start 242.7732 -391.605262)
		(end 244.096032 -392.928094)
		(width 0.254)
		(layer "F.Cu")
		(net "MB3_CM_OV_R")
	)
	(segment
		(start 241.696494 -390.16686)
		(end 242.7732 -391.243566)
		(width 0.254)
		(layer "F.Cu")
		(net "MB3_CM_OV_R")
	)
	(segment
		(start 242.7732 -391.243566)
		(end 242.7732 -391.605262)
		(width 0.254)
		(layer "F.Cu")
		(net "MB3_CM_OV_R")
	)
	(segment
		(start 246.371618 -394.656564)
		(end 245.824502 -394.656564)
		(width 0.254)
		(layer "F.Cu")
		(net "MB3_CM_OV_R")
	)
	(segment
		(start 246.992902 -394.567664)
		(end 246.460518 -394.567664)
		(width 0.254)
		(layer "F.Cu")
		(net "MB3_CM_OV_R")
	)
	(via
		(at 244.096032 -392.928094)
		(size 0.6604)
		(drill 0.3302)
		(layers "F.Cu" "B.Cu")
		(net "MB3_CM_OV_R")
	)
	(via
		(at 265.342116 -369.58905)
		(size 0.5588)
		(drill 0.3048)
		(layers "F.Cu" "B.Cu")
		(net "MB3_CM_GATE_R")
	)
	(via
		(at 272.479516 -369.58905)
		(size 0.5588)
		(drill 0.3048)
		(layers "F.Cu" "B.Cu")
		(net "MB3_CM_GATE_R")
	)
	(via
		(at 258.280916 -369.58905)
		(size 0.5588)
		(drill 0.3048)
		(layers "F.Cu" "B.Cu")
		(net "MB3_CM_GATE_R")
	)
	(via
		(at 273.495516 -369.58905)
		(size 0.5588)
		(drill 0.3048)
		(layers "F.Cu" "B.Cu")
		(net "MB3_CM_GATE_R")
	)
	(via
		(at 246.245888 -381.502412)
		(size 0.5588)
		(drill 0.3048)
		(layers "F.Cu" "B.Cu")
		(net "MB3_CM_GATE_R")
	)
	(via
		(at 246.176292 -382.486154)
		(size 0.5588)
		(drill 0.3048)
		(layers "F.Cu" "B.Cu")
		(net "MB3_CM_GATE_R")
	)
	(via
		(at 266.358116 -369.58905)
		(size 0.5588)
		(drill 0.3048)
		(layers "F.Cu" "B.Cu")
		(net "MB3_CM_GATE_R")
	)
	(via
		(at 259.296916 -369.58905)
		(size 0.5588)
		(drill 0.3048)
		(layers "F.Cu" "B.Cu")
		(net "MB3_CM_GATE_R")
	)
	(via
		(at 244.962426 -383.352294)
		(size 0.6604)
		(drill 0.3302)
		(layers "F.Cu" "B.Cu")
		(net "MB3_CM_GATE_R")
	)
	(via
		(at 243.165884 -385.095496)
		(size 0.6604)
		(drill 0.3302)
		(layers "F.Cu" "B.Cu")
		(net "MB3_CM_GATE")
	)
	(segment
		(start 234.061 -392.2268)
		(end 232.8545 -392.2268)
		(width 0.254)
		(layer "F.Cu")
		(net "MB3_CM_ADR2_R")
	)
	(segment
		(start 235.077 -392.2268)
		(end 234.061 -392.2268)
		(width 0.254)
		(layer "F.Cu")
		(net "MB3_CM_ADR2_R")
	)
	(segment
		(start 236.3343 -390.9695)
		(end 235.077 -392.2268)
		(width 0.254)
		(layer "F.Cu")
		(net "MB3_CM_ADR2_R")
	)
	(segment
		(start 237.00994 -390.9695)
		(end 236.3343 -390.9695)
		(width 0.254)
		(layer "F.Cu")
		(net "MB3_CM_ADR2_R")
	)
	(via
		(at 234.061 -392.2268)
		(size 0.6604)
		(drill 0.3302)
		(layers "F.Cu" "B.Cu")
		(net "MB3_CM_ADR2_R")
	)
	(segment
		(start 235.331 -392.9888)
		(end 235.966 -392.3538)
		(width 0.254)
		(layer "F.Cu")
		(net "MB3_CM_ADR1_R")
	)
	(segment
		(start 237.510066 -391.444734)
		(end 236.601 -392.3538)
		(width 0.254)
		(layer "F.Cu")
		(net "MB3_CM_ADR1_R")
	)
	(segment
		(start 236.601 -392.3538)
		(end 235.966 -392.3538)
		(width 0.254)
		(layer "F.Cu")
		(net "MB3_CM_ADR1_R")
	)
	(segment
		(start 235.331 -393.6873)
		(end 235.331 -392.9888)
		(width 0.254)
		(layer "F.Cu")
		(net "MB3_CM_ADR1_R")
	)
	(segment
		(start 237.510066 -390.8933)
		(end 237.510066 -391.444734)
		(width 0.254)
		(layer "F.Cu")
		(net "MB3_CM_ADR1_R")
	)
	(via
		(at 235.966 -392.3538)
		(size 0.6604)
		(drill 0.3302)
		(layers "F.Cu" "B.Cu")
		(net "MB3_CM_ADR1_R")
	)
	(via
		(at 258.694682 -374.419622)
		(size 0.6604)
		(drill 0.3302)
		(layers "F.Cu" "B.Cu")
		(net "MB3_12V_CTRL_GATE3")
	)
	(via
		(at 265.755882 -374.419622)
		(size 0.6604)
		(drill 0.3302)
		(layers "F.Cu" "B.Cu")
		(net "MB3_12V_CTRL_GATE2")
	)
	(via
		(at 272.867882 -374.419622)
		(size 0.6604)
		(drill 0.3302)
		(layers "F.Cu" "B.Cu")
		(net "MB3_12V_CTRL_GATE1")
	)
	(segment
		(start 368.878866 -136.224264)
		(end 368.201956 -135.547354)
		(width 0.254)
		(layer "F.Cu")
		(net "MB1_VCAP_R")
	)
	(segment
		(start 367.9063 -134.5184)
		(end 367.9063 -135.251698)
		(width 0.254)
		(layer "F.Cu")
		(net "MB1_VCAP_R")
	)
	(segment
		(start 367.7793 -133.5024)
		(end 367.9063 -133.6294)
		(width 0.254)
		(layer "F.Cu")
		(net "MB1_VCAP_R")
	)
	(segment
		(start 368.878866 -137.1219)
		(end 368.878866 -136.224264)
		(width 0.254)
		(layer "F.Cu")
		(net "MB1_VCAP_R")
	)
	(segment
		(start 367.9063 -135.251698)
		(end 368.201956 -135.547354)
		(width 0.254)
		(layer "F.Cu")
		(net "MB1_VCAP_R")
	)
	(segment
		(start 365.6203 -133.5024)
		(end 366.6998 -133.5024)
		(width 0.254)
		(layer "F.Cu")
		(net "MB1_VCAP_R")
	)
	(segment
		(start 369.9383 -134.5184)
		(end 369.9383 -133.6294)
		(width 0.254)
		(layer "F.Cu")
		(net "MB1_VCAP_R")
	)
	(segment
		(start 367.9063 -133.6294)
		(end 367.9063 -134.5184)
		(width 0.254)
		(layer "F.Cu")
		(net "MB1_VCAP_R")
	)
	(segment
		(start 365.4933 -133.6294)
		(end 365.6203 -133.5024)
		(width 0.254)
		(layer "F.Cu")
		(net "MB1_VCAP_R")
	)
	(segment
		(start 366.6998 -133.5024)
		(end 367.7793 -133.5024)
		(width 0.254)
		(layer "F.Cu")
		(net "MB1_VCAP_R")
	)
	(via
		(at 368.201956 -135.547354)
		(size 0.6604)
		(drill 0.3302)
		(layers "F.Cu" "B.Cu")
		(net "MB1_VCAP_R")
	)
	(via
		(at 367.9063 -134.5184)
		(size 0.5588)
		(drill 0.3048)
		(layers "F.Cu" "B.Cu")
		(net "MB1_VCAP_R")
	)
	(via
		(at 369.9383 -134.5184)
		(size 0.5588)
		(drill 0.3048)
		(layers "F.Cu" "B.Cu")
		(net "MB1_VCAP_R")
	)
	(segment
		(start 367.9063 -134.5184)
		(end 369.9383 -134.5184)
		(width 0.254)
		(layer "B.Cu")
		(net "MB1_VCAP_R")
	)
	(segment
		(start 372.2878 -133.8834)
		(end 372.2878 -132.5499)
		(width 0.254)
		(layer "F.Cu")
		(net "MB1_TIME_R")
	)
	(segment
		(start 372.2878 -134.6454)
		(end 372.2878 -133.8834)
		(width 0.254)
		(layer "F.Cu")
		(net "MB1_TIME_R")
	)
	(segment
		(start 370.378736 -137.1219)
		(end 370.378736 -136.554464)
		(width 0.254)
		(layer "F.Cu")
		(net "MB1_TIME_R")
	)
	(segment
		(start 370.378736 -136.554464)
		(end 372.2878 -134.6454)
		(width 0.254)
		(layer "F.Cu")
		(net "MB1_TIME_R")
	)
	(via
		(at 372.2878 -133.8834)
		(size 0.6604)
		(drill 0.3302)
		(layers "F.Cu" "B.Cu")
		(net "MB1_TIME_R")
	)
	(segment
		(start 365.0488 -142.9639)
		(end 365.0488 -142.1892)
		(width 0.254)
		(layer "F.Cu")
		(net "MB1_TEMP")
	)
	(segment
		(start 367.5761 -141.34846)
		(end 367.36274 -141.34846)
		(width 0.254)
		(layer "F.Cu")
		(net "MB1_TEMP")
	)
	(segment
		(start 367.36274 -141.34846)
		(end 366.9792 -141.732)
		(width 0.254)
		(layer "F.Cu")
		(net "MB1_TEMP")
	)
	(segment
		(start 366.9792 -141.732)
		(end 365.506 -141.732)
		(width 0.254)
		(layer "F.Cu")
		(net "MB1_TEMP")
	)
	(segment
		(start 365.0488 -142.1892)
		(end 365.506 -141.732)
		(width 0.254)
		(layer "F.Cu")
		(net "MB1_TEMP")
	)
	(via
		(at 365.506 -141.732)
		(size 0.6604)
		(drill 0.3302)
		(layers "F.Cu" "B.Cu")
		(net "MB1_TEMP")
	)
	(segment
		(start 374.00992 -137.84834)
		(end 374.16486 -137.6934)
		(width 0.254)
		(layer "F.Cu")
		(net "MB1_SPISS_PD")
	)
	(segment
		(start 376.0089 -134.8486)
		(end 375.6406 -134.8486)
		(width 0.254)
		(layer "F.Cu")
		(net "MB1_SPISS_PD")
	)
	(segment
		(start 374.16486 -136.32434)
		(end 374.16486 -137.6934)
		(width 0.254)
		(layer "F.Cu")
		(net "MB1_SPISS_PD")
	)
	(segment
		(start 375.6406 -134.8486)
		(end 374.16486 -136.32434)
		(width 0.254)
		(layer "F.Cu")
		(net "MB1_SPISS_PD")
	)
	(segment
		(start 372.6815 -137.84834)
		(end 374.00992 -137.84834)
		(width 0.254)
		(layer "F.Cu")
		(net "MB1_SPISS_PD")
	)
	(via
		(at 374.16486 -137.6934)
		(size 0.6604)
		(drill 0.3302)
		(layers "F.Cu" "B.Cu")
		(net "MB1_SPISS_PD")
	)
	(segment
		(start 374.015 -143.5862)
		(end 375.0056 -143.5862)
		(width 0.254)
		(layer "F.Cu")
		(net "MB1_RETRY_R")
	)
	(segment
		(start 375.5898 -144.1704)
		(end 375.5898 -145.3769)
		(width 0.254)
		(layer "F.Cu")
		(net "MB1_RETRY_R")
	)
	(segment
		(start 372.5799 -142.1511)
		(end 374.015 -143.5862)
		(width 0.254)
		(layer "F.Cu")
		(net "MB1_RETRY_R")
	)
	(segment
		(start 371.87886 -142.1511)
		(end 372.5799 -142.1511)
		(width 0.254)
		(layer "F.Cu")
		(net "MB1_RETRY_R")
	)
	(segment
		(start 375.0056 -143.5862)
		(end 375.5898 -144.1704)
		(width 0.254)
		(layer "F.Cu")
		(net "MB1_RETRY_R")
	)
	(via
		(at 375.5898 -144.1704)
		(size 0.6604)
		(drill 0.3302)
		(layers "F.Cu" "B.Cu")
		(net "MB1_RETRY_R")
	)
	(segment
		(start 365.5568 -134.5184)
		(end 366.1918 -135.1534)
		(width 0.254)
		(layer "F.Cu")
		(net "MB1_PSET_R")
	)
	(segment
		(start 365.0488 -134.5184)
		(end 365.5568 -134.5184)
		(width 0.254)
		(layer "F.Cu")
		(net "MB1_PSET_R")
	)
	(segment
		(start 368.37874 -137.0457)
		(end 368.0841 -137.0457)
		(width 0.254)
		(layer "F.Cu")
		(net "MB1_PSET_R")
	)
	(segment
		(start 364.5408 -132.5499)
		(end 364.5408 -133.5659)
		(width 0.254)
		(layer "F.Cu")
		(net "MB1_PSET_R")
	)
	(segment
		(start 364.5408 -133.5659)
		(end 364.6043 -133.6294)
		(width 0.254)
		(layer "F.Cu")
		(net "MB1_PSET_R")
	)
	(segment
		(start 368.0841 -137.0457)
		(end 366.1918 -135.1534)
		(width 0.254)
		(layer "F.Cu")
		(net "MB1_PSET_R")
	)
	(segment
		(start 365.5568 -132.5499)
		(end 364.5408 -132.5499)
		(width 0.254)
		(layer "F.Cu")
		(net "MB1_PSET_R")
	)
	(segment
		(start 364.6043 -134.0739)
		(end 365.0488 -134.5184)
		(width 0.254)
		(layer "F.Cu")
		(net "MB1_PSET_R")
	)
	(segment
		(start 364.6043 -133.6294)
		(end 364.6043 -134.0739)
		(width 0.254)
		(layer "F.Cu")
		(net "MB1_PSET_R")
	)
	(via
		(at 366.1918 -135.1534)
		(size 0.6604)
		(drill 0.3302)
		(layers "F.Cu" "B.Cu")
		(net "MB1_PSET_R")
	)
	(segment
		(start 368.8588 -145.3769)
		(end 368.8588 -144.1704)
		(width 0.254)
		(layer "F.Cu")
		(net "MB1_P12V_PWGIN_R")
	)
	(segment
		(start 367.7158 -145.3769)
		(end 368.8588 -145.3769)
		(width 0.254)
		(layer "F.Cu")
		(net "MB1_P12V_PWGIN_R")
	)
	(segment
		(start 369.878864 -142.0749)
		(end 369.878864 -143.150336)
		(width 0.254)
		(layer "F.Cu")
		(net "MB1_P12V_PWGIN_R")
	)
	(segment
		(start 369.878864 -143.150336)
		(end 368.8588 -144.1704)
		(width 0.254)
		(layer "F.Cu")
		(net "MB1_P12V_PWGIN_R")
	)
	(via
		(at 368.8588 -144.1704)
		(size 0.6604)
		(drill 0.3302)
		(layers "F.Cu" "B.Cu")
		(net "MB1_P12V_PWGIN_R")
	)
	(segment
		(start 363.8423 -137.1854)
		(end 364.5408 -137.8839)
		(width 0.254)
		(layer "F.Cu")
		(net "MB1_P12V_HS")
	)
	(segment
		(start 366.787938 -138.848338)
		(end 366.268 -138.3284)
		(width 0.254)
		(layer "F.Cu")
		(net "MB1_P12V_HS")
	)
	(segment
		(start 366.268 -138.3284)
		(end 365.9378 -138.3284)
		(width 0.254)
		(layer "F.Cu")
		(net "MB1_P12V_HS")
	)
	(segment
		(start 367.6523 -138.848338)
		(end 366.787938 -138.848338)
		(width 0.254)
		(layer "F.Cu")
		(net "MB1_P12V_HS")
	)
	(segment
		(start 364.5408 -137.8839)
		(end 364.5408 -138.3284)
		(width 0.254)
		(layer "F.Cu")
		(net "MB1_P12V_HS")
	)
	(segment
		(start 364.5408 -138.3284)
		(end 365.9378 -138.3284)
		(width 0.254)
		(layer "F.Cu")
		(net "MB1_P12V_HS")
	)
	(via
		(at 365.9378 -138.3284)
		(size 0.6604)
		(drill 0.3302)
		(layers "F.Cu" "B.Cu")
		(net "MB1_P12V_HS")
	)
	(via
		(at 354.711 -142.2146)
		(size 0.7112)
		(drill 0.4064)
		(layers "F.Cu" "B.Cu")
		(net "MB1_P12V_B_R")
	)
	(via
		(at 354.711 -143.5354)
		(size 0.7112)
		(drill 0.4064)
		(layers "F.Cu" "B.Cu")
		(net "MB1_P12V_B_R")
	)
	(via
		(at 348.0308 -139.827)
		(size 0.7112)
		(drill 0.4064)
		(layers "F.Cu" "B.Cu")
		(net "MB1_P12V_B_R")
	)
	(via
		(at 346.964 -141.9606)
		(size 0.7112)
		(drill 0.4064)
		(layers "F.Cu" "B.Cu")
		(net "MB1_P12V_B_R")
	)
	(via
		(at 350.9264 -144.399)
		(size 0.7112)
		(drill 0.4064)
		(layers "F.Cu" "B.Cu")
		(net "MB1_P12V_B_R")
	)
	(via
		(at 354.711 -140.8938)
		(size 0.7112)
		(drill 0.4064)
		(layers "F.Cu" "B.Cu")
		(net "MB1_P12V_B_R")
	)
	(via
		(at 348.0308 -143.0274)
		(size 0.7112)
		(drill 0.4064)
		(layers "F.Cu" "B.Cu")
		(net "MB1_P12V_B_R")
	)
	(via
		(at 346.964 -139.827)
		(size 0.7112)
		(drill 0.4064)
		(layers "F.Cu" "B.Cu")
		(net "MB1_P12V_B_R")
	)
	(via
		(at 352.3742 -144.399)
		(size 0.7112)
		(drill 0.4064)
		(layers "F.Cu" "B.Cu")
		(net "MB1_P12V_B_R")
	)
	(via
		(at 346.964 -143.0274)
		(size 0.7112)
		(drill 0.4064)
		(layers "F.Cu" "B.Cu")
		(net "MB1_P12V_B_R")
	)
	(via
		(at 346.964 -140.8938)
		(size 0.7112)
		(drill 0.4064)
		(layers "F.Cu" "B.Cu")
		(net "MB1_P12V_B_R")
	)
	(via
		(at 353.822 -144.399)
		(size 0.7112)
		(drill 0.4064)
		(layers "F.Cu" "B.Cu")
		(net "MB1_P12V_B_R")
	)
	(via
		(at 348.0308 -141.9606)
		(size 0.7112)
		(drill 0.4064)
		(layers "F.Cu" "B.Cu")
		(net "MB1_P12V_B_R")
	)
	(via
		(at 345.821 -144.145)
		(size 0.6604)
		(drill 0.3302)
		(layers "F.Cu" "B.Cu")
		(net "MB1_P12V_B_R")
	)
	(via
		(at 354.711 -139.573)
		(size 0.7112)
		(drill 0.4064)
		(layers "F.Cu" "B.Cu")
		(net "MB1_P12V_B_R")
	)
	(via
		(at 349.4786 -144.399)
		(size 0.7112)
		(drill 0.4064)
		(layers "F.Cu" "B.Cu")
		(net "MB1_P12V_B_R")
	)
	(via
		(at 348.0308 -140.8938)
		(size 0.7112)
		(drill 0.4064)
		(layers "F.Cu" "B.Cu")
		(net "MB1_P12V_B_R")
	)
	(segment
		(start 370.8273 -133.0833)
		(end 370.8908 -133.0198)
		(width 0.254)
		(layer "F.Cu")
		(net "MB1_ISTART_R")
	)
	(segment
		(start 370.8908 -133.0198)
		(end 370.8908 -132.5499)
		(width 0.254)
		(layer "F.Cu")
		(net "MB1_ISTART_R")
	)
	(segment
		(start 370.8273 -133.6294)
		(end 370.8273 -133.0833)
		(width 0.254)
		(layer "F.Cu")
		(net "MB1_ISTART_R")
	)
	(segment
		(start 369.878864 -137.1219)
		(end 369.878864 -135.974836)
		(width 0.254)
		(layer "F.Cu")
		(net "MB1_ISTART_R")
	)
	(segment
		(start 370.8273 -135.0264)
		(end 370.8273 -133.6294)
		(width 0.254)
		(layer "F.Cu")
		(net "MB1_ISTART_R")
	)
	(segment
		(start 369.944142 -132.5499)
		(end 369.935506 -132.541264)
		(width 0.254)
		(layer "F.Cu")
		(net "MB1_ISTART_R")
	)
	(segment
		(start 369.878864 -135.974836)
		(end 370.8273 -135.0264)
		(width 0.254)
		(layer "F.Cu")
		(net "MB1_ISTART_R")
	)
	(segment
		(start 370.8908 -132.5499)
		(end 369.944142 -132.5499)
		(width 0.254)
		(layer "F.Cu")
		(net "MB1_ISTART_R")
	)
	(via
		(at 370.8273 -135.0264)
		(size 0.6604)
		(drill 0.3302)
		(layers "F.Cu" "B.Cu")
		(net "MB1_ISTART_R")
	)
	(segment
		(start 369.378738 -135.065262)
		(end 368.956336 -134.64286)
		(width 0.254)
		(layer "F.Cu")
		(net "MB1_ISET_R")
	)
	(segment
		(start 368.8588 -133.0198)
		(end 368.8588 -132.5499)
		(width 0.254)
		(layer "F.Cu")
		(net "MB1_ISET_R")
	)
	(segment
		(start 368.956336 -134.64286)
		(end 368.7953 -134.481824)
		(width 0.254)
		(layer "F.Cu")
		(net "MB1_ISET_R")
	)
	(segment
		(start 368.7953 -133.6294)
		(end 368.7953 -133.0833)
		(width 0.254)
		(layer "F.Cu")
		(net "MB1_ISET_R")
	)
	(segment
		(start 368.7953 -134.481824)
		(end 368.7953 -133.6294)
		(width 0.254)
		(layer "F.Cu")
		(net "MB1_ISET_R")
	)
	(segment
		(start 368.8588 -132.5499)
		(end 367.875058 -132.5499)
		(width 0.254)
		(layer "F.Cu")
		(net "MB1_ISET_R")
	)
	(segment
		(start 368.7953 -133.0833)
		(end 368.8588 -133.0198)
		(width 0.254)
		(layer "F.Cu")
		(net "MB1_ISET_R")
	)
	(segment
		(start 369.378738 -137.1219)
		(end 369.378738 -135.065262)
		(width 0.254)
		(layer "F.Cu")
		(net "MB1_ISET_R")
	)
	(segment
		(start 367.875058 -132.5499)
		(end 367.858294 -132.533136)
		(width 0.254)
		(layer "F.Cu")
		(net "MB1_ISET_R")
	)
	(via
		(at 368.956336 -134.64286)
		(size 0.6604)
		(drill 0.3302)
		(layers "F.Cu" "B.Cu")
		(net "MB1_ISET_R")
	)
	(segment
		(start 376.41149 -139.78509)
		(end 375.732802 -139.106402)
		(width 0.254)
		(layer "F.Cu")
		(net "MB1_HS_ENABLE")
	)
	(segment
		(start 377.090432 -139.78509)
		(end 376.41149 -139.78509)
		(width 0.254)
		(layer "F.Cu")
		(net "MB1_HS_ENABLE")
	)
	(segment
		(start 375.732802 -139.106402)
		(end 375.365772 -139.106402)
		(width 0.254)
		(layer "F.Cu")
		(net "MB1_HS_ENABLE")
	)
	(segment
		(start 372.6053 -139.348464)
		(end 374.142 -139.348464)
		(width 0.254)
		(layer "F.Cu")
		(net "MB1_HS_ENABLE")
	)
	(segment
		(start 374.142 -139.348464)
		(end 374.384062 -139.106402)
		(width 0.254)
		(layer "F.Cu")
		(net "MB1_HS_ENABLE")
	)
	(segment
		(start 374.384062 -139.106402)
		(end 375.365772 -139.106402)
		(width 0.254)
		(layer "F.Cu")
		(net "MB1_HS_ENABLE")
	)
	(via
		(at 375.365772 -139.106402)
		(size 0.6604)
		(drill 0.3302)
		(layers "F.Cu" "B.Cu")
		(net "MB1_HS_ENABLE")
	)
	(segment
		(start 370.6368 -144.3228)
		(end 370.6368 -145.3769)
		(width 0.254)
		(layer "F.Cu")
		(net "MB1_CM_VOUT_R")
	)
	(segment
		(start 370.6368 -143.4084)
		(end 370.6368 -144.3228)
		(width 0.254)
		(layer "F.Cu")
		(net "MB1_CM_VOUT_R")
	)
	(segment
		(start 370.378736 -143.150336)
		(end 370.6368 -143.4084)
		(width 0.254)
		(layer "F.Cu")
		(net "MB1_CM_VOUT_R")
	)
	(segment
		(start 345.561412 -137.746994)
		(end 344.758264 -137.746994)
		(width 0.254)
		(layer "F.Cu")
		(net "MB1_CM_VOUT_R")
	)
	(segment
		(start 370.6368 -145.3769)
		(end 369.7605 -145.3769)
		(width 0.254)
		(layer "F.Cu")
		(net "MB1_CM_VOUT_R")
	)
	(segment
		(start 370.378736 -142.0749)
		(end 370.378736 -143.150336)
		(width 0.254)
		(layer "F.Cu")
		(net "MB1_CM_VOUT_R")
	)
	(via
		(at 344.758264 -137.746994)
		(size 0.5588)
		(drill 0.3048)
		(layers "F.Cu" "B.Cu")
		(net "MB1_CM_VOUT_R")
	)
	(via
		(at 369.7605 -145.3769)
		(size 0.5588)
		(drill 0.3048)
		(layers "F.Cu" "B.Cu")
		(net "MB1_CM_VOUT_R")
	)
	(via
		(at 370.6368 -144.3228)
		(size 0.6604)
		(drill 0.3302)
		(layers "F.Cu" "B.Cu")
		(net "MB1_CM_VOUT_R")
	)
	(segment
		(start 358.215438 -137.692638)
		(end 359.4608 -138.938)
		(width 0.254)
		(layer "B.Cu")
		(net "MB1_CM_VOUT_R")
	)
	(segment
		(start 369.7605 -140.8557)
		(end 369.7605 -145.3769)
		(width 0.254)
		(layer "B.Cu")
		(net "MB1_CM_VOUT_R")
	)
	(segment
		(start 359.4608 -138.938)
		(end 363.2962 -138.938)
		(width 0.254)
		(layer "B.Cu")
		(net "MB1_CM_VOUT_R")
	)
	(segment
		(start 344.81262 -137.692638)
		(end 358.215438 -137.692638)
		(width 0.254)
		(layer "B.Cu")
		(net "MB1_CM_VOUT_R")
	)
	(segment
		(start 367.3348 -138.43)
		(end 369.7605 -140.8557)
		(width 0.254)
		(layer "B.Cu")
		(net "MB1_CM_VOUT_R")
	)
	(segment
		(start 363.2962 -138.938)
		(end 363.8042 -138.43)
		(width 0.254)
		(layer "B.Cu")
		(net "MB1_CM_VOUT_R")
	)
	(segment
		(start 344.758264 -137.746994)
		(end 344.81262 -137.692638)
		(width 0.254)
		(layer "B.Cu")
		(net "MB1_CM_VOUT_R")
	)
	(segment
		(start 363.8042 -138.43)
		(end 367.3348 -138.43)
		(width 0.254)
		(layer "B.Cu")
		(net "MB1_CM_VOUT_R")
	)
	(segment
		(start 360.126026 -134.075678)
		(end 360.138726 -134.088378)
		(width 0.254)
		(layer "F.Cu")
		(net "MB1_CM_UV_R")
	)
	(segment
		(start 361.472226 -133.796278)
		(end 362.310426 -133.796278)
		(width 0.254)
		(layer "F.Cu")
		(net "MB1_CM_UV_R")
	)
	(segment
		(start 363.19968 -134.685532)
		(end 363.19968 -135.23468)
		(width 0.254)
		(layer "F.Cu")
		(net "MB1_CM_UV_R")
	)
	(segment
		(start 361.180126 -134.088378)
		(end 361.472226 -133.796278)
		(width 0.254)
		(layer "F.Cu")
		(net "MB1_CM_UV_R")
	)
	(segment
		(start 366.973866 -138.348466)
		(end 367.6523 -138.348466)
		(width 0.254)
		(layer "F.Cu")
		(net "MB1_CM_UV_R")
	)
	(segment
		(start 365.0488 -137.0838)
		(end 365.7092 -137.0838)
		(width 0.254)
		(layer "F.Cu")
		(net "MB1_CM_UV_R")
	)
	(segment
		(start 363.19968 -135.23468)
		(end 363.9312 -135.9662)
		(width 0.254)
		(layer "F.Cu")
		(net "MB1_CM_UV_R")
	)
	(segment
		(start 363.9312 -135.9662)
		(end 365.0488 -137.0838)
		(width 0.254)
		(layer "F.Cu")
		(net "MB1_CM_UV_R")
	)
	(segment
		(start 365.7092 -137.0838)
		(end 366.973866 -138.348466)
		(width 0.254)
		(layer "F.Cu")
		(net "MB1_CM_UV_R")
	)
	(segment
		(start 360.138726 -134.088378)
		(end 361.180126 -134.088378)
		(width 0.254)
		(layer "F.Cu")
		(net "MB1_CM_UV_R")
	)
	(segment
		(start 362.310426 -133.796278)
		(end 363.19968 -134.685532)
		(width 0.254)
		(layer "F.Cu")
		(net "MB1_CM_UV_R")
	)
	(via
		(at 363.9312 -135.9662)
		(size 0.6604)
		(drill 0.3302)
		(layers "F.Cu" "B.Cu")
		(net "MB1_CM_UV_R")
	)
	(segment
		(start 359.109518 -140.430504)
		(end 359.662222 -139.8778)
		(width 0.254)
		(layer "F.Cu")
		(net "MB1_CM_SENSE_R1_P")
	)
	(segment
		(start 359.109518 -141.95933)
		(end 359.109518 -140.430504)
		(width 0.254)
		(layer "F.Cu")
		(net "MB1_CM_SENSE_R1_P")
	)
	(segment
		(start 359.651554 -142.501366)
		(end 359.109518 -141.95933)
		(width 0.254)
		(layer "F.Cu")
		(net "MB1_CM_SENSE_R1_P")
	)
	(segment
		(start 360.8959 -139.8778)
		(end 361.1753 -139.5984)
		(width 0.254)
		(layer "F.Cu")
		(net "MB1_CM_SENSE_R1_P")
	)
	(segment
		(start 353.682808 -147.269962)
		(end 354.659438 -147.269962)
		(width 0.254)
		(layer "F.Cu")
		(net "MB1_CM_SENSE_R1_P")
	)
	(segment
		(start 359.662222 -139.8778)
		(end 360.8959 -139.8778)
		(width 0.254)
		(layer "F.Cu")
		(net "MB1_CM_SENSE_R1_P")
	)
	(segment
		(start 360.689906 -142.501366)
		(end 359.651554 -142.501366)
		(width 0.254)
		(layer "F.Cu")
		(net "MB1_CM_SENSE_R1_P")
	)
	(segment
		(start 360.994706 -142.806166)
		(end 360.689906 -142.501366)
		(width 0.254)
		(layer "F.Cu")
		(net "MB1_CM_SENSE_R1_P")
	)
	(via
		(at 360.994706 -142.806166)
		(size 0.5588)
		(drill 0.3048)
		(layers "F.Cu" "B.Cu")
		(net "MB1_CM_SENSE_R1_P")
	)
	(via
		(at 354.659438 -147.269962)
		(size 0.5588)
		(drill 0.3048)
		(layers "F.Cu" "B.Cu")
		(net "MB1_CM_SENSE_R1_P")
	)
	(segment
		(start 355.2952 -146.6342)
		(end 354.659438 -147.269962)
		(width 0.254)
		(layer "B.Cu")
		(net "MB1_CM_SENSE_R1_P")
	)
	(segment
		(start 361.324906 -142.475966)
		(end 360.994706 -142.806166)
		(width 0.254)
		(layer "B.Cu")
		(net "MB1_CM_SENSE_R1_P")
	)
	(segment
		(start 359.649014 -142.501366)
		(end 358.9274 -143.22298)
		(width 0.254)
		(layer "B.Cu")
		(net "MB1_CM_SENSE_R1_P")
	)
	(segment
		(start 358.9274 -143.22298)
		(end 358.9274 -144.842484)
		(width 0.254)
		(layer "B.Cu")
		(net "MB1_CM_SENSE_R1_P")
	)
	(segment
		(start 361.893866 -142.475966)
		(end 361.324906 -142.475966)
		(width 0.254)
		(layer "B.Cu")
		(net "MB1_CM_SENSE_R1_P")
	)
	(segment
		(start 360.994706 -142.806166)
		(end 360.689906 -142.501366)
		(width 0.254)
		(layer "B.Cu")
		(net "MB1_CM_SENSE_R1_P")
	)
	(segment
		(start 360.689906 -142.501366)
		(end 359.649014 -142.501366)
		(width 0.254)
		(layer "B.Cu")
		(net "MB1_CM_SENSE_R1_P")
	)
	(segment
		(start 357.135684 -146.6342)
		(end 355.2952 -146.6342)
		(width 0.254)
		(layer "B.Cu")
		(net "MB1_CM_SENSE_R1_P")
	)
	(segment
		(start 362.1913 -142.7734)
		(end 361.893866 -142.475966)
		(width 0.254)
		(layer "B.Cu")
		(net "MB1_CM_SENSE_R1_P")
	)
	(segment
		(start 358.9274 -144.842484)
		(end 357.135684 -146.6342)
		(width 0.254)
		(layer "B.Cu")
		(net "MB1_CM_SENSE_R1_P")
	)
	(segment
		(start 359.566718 -141.769846)
		(end 359.566718 -140.619988)
		(width 0.254)
		(layer "F.Cu")
		(net "MB1_CM_SENSE_R1_N")
	)
	(segment
		(start 360.689906 -142.044166)
		(end 359.841038 -142.044166)
		(width 0.254)
		(layer "F.Cu")
		(net "MB1_CM_SENSE_R1_N")
	)
	(segment
		(start 360.8959 -140.335)
		(end 361.1753 -140.6144)
		(width 0.254)
		(layer "F.Cu")
		(net "MB1_CM_SENSE_R1_N")
	)
	(segment
		(start 359.566718 -140.619988)
		(end 359.851706 -140.335)
		(width 0.254)
		(layer "F.Cu")
		(net "MB1_CM_SENSE_R1_N")
	)
	(segment
		(start 359.841038 -142.044166)
		(end 359.566718 -141.769846)
		(width 0.254)
		(layer "F.Cu")
		(net "MB1_CM_SENSE_R1_N")
	)
	(segment
		(start 353.682808 -145.642838)
		(end 354.659438 -145.642838)
		(width 0.254)
		(layer "F.Cu")
		(net "MB1_CM_SENSE_R1_N")
	)
	(segment
		(start 359.851706 -140.335)
		(end 360.8959 -140.335)
		(width 0.254)
		(layer "F.Cu")
		(net "MB1_CM_SENSE_R1_N")
	)
	(segment
		(start 360.994706 -141.739366)
		(end 360.689906 -142.044166)
		(width 0.254)
		(layer "F.Cu")
		(net "MB1_CM_SENSE_R1_N")
	)
	(via
		(at 354.659438 -145.642838)
		(size 0.5588)
		(drill 0.3048)
		(layers "F.Cu" "B.Cu")
		(net "MB1_CM_SENSE_R1_N")
	)
	(via
		(at 360.994706 -141.739366)
		(size 0.5588)
		(drill 0.3048)
		(layers "F.Cu" "B.Cu")
		(net "MB1_CM_SENSE_R1_N")
	)
	(segment
		(start 360.689906 -142.044166)
		(end 359.45953 -142.044166)
		(width 0.254)
		(layer "B.Cu")
		(net "MB1_CM_SENSE_R1_N")
	)
	(segment
		(start 358.4702 -143.033496)
		(end 358.4702 -144.653)
		(width 0.254)
		(layer "B.Cu")
		(net "MB1_CM_SENSE_R1_N")
	)
	(segment
		(start 361.929934 -142.018766)
		(end 361.274106 -142.018766)
		(width 0.254)
		(layer "B.Cu")
		(net "MB1_CM_SENSE_R1_N")
	)
	(segment
		(start 361.274106 -142.018766)
		(end 360.994706 -141.739366)
		(width 0.254)
		(layer "B.Cu")
		(net "MB1_CM_SENSE_R1_N")
	)
	(segment
		(start 356.9462 -146.177)
		(end 355.1936 -146.177)
		(width 0.254)
		(layer "B.Cu")
		(net "MB1_CM_SENSE_R1_N")
	)
	(segment
		(start 362.1913 -141.7574)
		(end 361.929934 -142.018766)
		(width 0.254)
		(layer "B.Cu")
		(net "MB1_CM_SENSE_R1_N")
	)
	(segment
		(start 359.45953 -142.044166)
		(end 358.4702 -143.033496)
		(width 0.254)
		(layer "B.Cu")
		(net "MB1_CM_SENSE_R1_N")
	)
	(segment
		(start 360.994706 -141.739366)
		(end 360.689906 -142.044166)
		(width 0.254)
		(layer "B.Cu")
		(net "MB1_CM_SENSE_R1_N")
	)
	(segment
		(start 355.1936 -146.177)
		(end 354.659438 -145.642838)
		(width 0.254)
		(layer "B.Cu")
		(net "MB1_CM_SENSE_R1_N")
	)
	(segment
		(start 358.4702 -144.653)
		(end 356.9462 -146.177)
		(width 0.254)
		(layer "B.Cu")
		(net "MB1_CM_SENSE_R1_N")
	)
	(segment
		(start 366.449864 -139.348464)
		(end 367.6523 -139.348464)
		(width 0.254)
		(layer "F.Cu")
		(net "MB1_CM_SENSE_P")
	)
	(segment
		(start 366.395 -139.2936)
		(end 366.449864 -139.348464)
		(width 0.254)
		(layer "F.Cu")
		(net "MB1_CM_SENSE_P")
	)
	(via
		(at 366.395 -139.2936)
		(size 0.5588)
		(drill 0.3048)
		(layers "F.Cu" "B.Cu")
		(net "MB1_CM_SENSE_P")
	)
	(segment
		(start 363.3343 -142.5194)
		(end 364.6043 -142.5194)
		(width 0.254)
		(layer "B.Cu")
		(net "MB1_CM_SENSE_P")
	)
	(segment
		(start 364.7948 -142.7099)
		(end 365.0361 -142.4686)
		(width 0.254)
		(layer "B.Cu")
		(net "MB1_CM_SENSE_P")
	)
	(segment
		(start 367.250472 -139.793472)
		(end 366.6236 -139.793472)
		(width 0.254)
		(layer "B.Cu")
		(net "MB1_CM_SENSE_P")
	)
	(segment
		(start 365.0361 -142.4686)
		(end 367.17478 -142.4686)
		(width 0.254)
		(layer "B.Cu")
		(net "MB1_CM_SENSE_P")
	)
	(segment
		(start 363.0803 -142.7734)
		(end 363.3343 -142.5194)
		(width 0.254)
		(layer "B.Cu")
		(net "MB1_CM_SENSE_P")
	)
	(segment
		(start 366.395 -139.564872)
		(end 366.395 -139.2936)
		(width 0.254)
		(layer "B.Cu")
		(net "MB1_CM_SENSE_P")
	)
	(segment
		(start 366.6236 -139.793472)
		(end 366.395 -139.564872)
		(width 0.254)
		(layer "B.Cu")
		(net "MB1_CM_SENSE_P")
	)
	(segment
		(start 367.17478 -142.4686)
		(end 368.0206 -141.62278)
		(width 0.254)
		(layer "B.Cu")
		(net "MB1_CM_SENSE_P")
	)
	(segment
		(start 368.0206 -141.62278)
		(end 368.0206 -140.5636)
		(width 0.254)
		(layer "B.Cu")
		(net "MB1_CM_SENSE_P")
	)
	(segment
		(start 368.0206 -140.5636)
		(end 367.250472 -139.793472)
		(width 0.254)
		(layer "B.Cu")
		(net "MB1_CM_SENSE_P")
	)
	(segment
		(start 364.6043 -142.5194)
		(end 364.7948 -142.7099)
		(width 0.254)
		(layer "B.Cu")
		(net "MB1_CM_SENSE_P")
	)
	(segment
		(start 366.440466 -140.848334)
		(end 367.6523 -140.848334)
		(width 0.254)
		(layer "F.Cu")
		(net "MB1_CM_SENSE_N")
	)
	(segment
		(start 366.395 -140.8938)
		(end 366.440466 -140.848334)
		(width 0.254)
		(layer "F.Cu")
		(net "MB1_CM_SENSE_N")
	)
	(via
		(at 366.395 -140.8938)
		(size 0.5588)
		(drill 0.3048)
		(layers "F.Cu" "B.Cu")
		(net "MB1_CM_SENSE_N")
	)
	(segment
		(start 366.4966 -140.250672)
		(end 366.395 -140.352272)
		(width 0.254)
		(layer "B.Cu")
		(net "MB1_CM_SENSE_N")
	)
	(segment
		(start 367.060988 -140.250672)
		(end 366.4966 -140.250672)
		(width 0.254)
		(layer "B.Cu")
		(net "MB1_CM_SENSE_N")
	)
	(segment
		(start 364.7948 -141.8209)
		(end 364.9853 -142.0114)
		(width 0.254)
		(layer "B.Cu")
		(net "MB1_CM_SENSE_N")
	)
	(segment
		(start 367.5634 -141.433296)
		(end 367.5634 -140.753084)
		(width 0.254)
		(layer "B.Cu")
		(net "MB1_CM_SENSE_N")
	)
	(segment
		(start 366.395 -140.352272)
		(end 366.395 -140.8938)
		(width 0.254)
		(layer "B.Cu")
		(net "MB1_CM_SENSE_N")
	)
	(segment
		(start 364.5535 -142.0622)
		(end 364.7948 -141.8209)
		(width 0.254)
		(layer "B.Cu")
		(net "MB1_CM_SENSE_N")
	)
	(segment
		(start 364.9853 -142.0114)
		(end 366.985296 -142.0114)
		(width 0.254)
		(layer "B.Cu")
		(net "MB1_CM_SENSE_N")
	)
	(segment
		(start 363.0803 -141.7574)
		(end 363.3851 -142.0622)
		(width 0.254)
		(layer "B.Cu")
		(net "MB1_CM_SENSE_N")
	)
	(segment
		(start 366.985296 -142.0114)
		(end 367.5634 -141.433296)
		(width 0.254)
		(layer "B.Cu")
		(net "MB1_CM_SENSE_N")
	)
	(segment
		(start 363.3851 -142.0622)
		(end 364.5535 -142.0622)
		(width 0.254)
		(layer "B.Cu")
		(net "MB1_CM_SENSE_N")
	)
	(segment
		(start 367.5634 -140.753084)
		(end 367.060988 -140.250672)
		(width 0.254)
		(layer "B.Cu")
		(net "MB1_CM_SENSE_N")
	)
	(segment
		(start 360.138726 -132.208778)
		(end 361.180126 -132.208778)
		(width 0.254)
		(layer "F.Cu")
		(net "MB1_CM_OV_R")
	)
	(segment
		(start 365.8616 -136.4742)
		(end 365.8616 -136.508744)
		(width 0.254)
		(layer "F.Cu")
		(net "MB1_CM_OV_R")
	)
	(segment
		(start 365.8616 -136.4742)
		(end 363.347 -133.9596)
		(width 0.254)
		(layer "F.Cu")
		(net "MB1_CM_OV_R")
	)
	(segment
		(start 360.126026 -132.196078)
		(end 360.138726 -132.208778)
		(width 0.254)
		(layer "F.Cu")
		(net "MB1_CM_OV_R")
	)
	(segment
		(start 363.347 -133.9596)
		(end 363.347 -133.689852)
		(width 0.254)
		(layer "F.Cu")
		(net "MB1_CM_OV_R")
	)
	(segment
		(start 365.8616 -136.508744)
		(end 367.201196 -137.84834)
		(width 0.254)
		(layer "F.Cu")
		(net "MB1_CM_OV_R")
	)
	(segment
		(start 363.347 -133.689852)
		(end 362.310426 -132.653278)
		(width 0.254)
		(layer "F.Cu")
		(net "MB1_CM_OV_R")
	)
	(segment
		(start 361.624626 -132.653278)
		(end 362.310426 -132.653278)
		(width 0.254)
		(layer "F.Cu")
		(net "MB1_CM_OV_R")
	)
	(segment
		(start 367.201196 -137.84834)
		(end 367.5761 -137.84834)
		(width 0.254)
		(layer "F.Cu")
		(net "MB1_CM_OV_R")
	)
	(segment
		(start 361.180126 -132.208778)
		(end 361.624626 -132.653278)
		(width 0.254)
		(layer "F.Cu")
		(net "MB1_CM_OV_R")
	)
	(via
		(at 365.8616 -136.4742)
		(size 0.6604)
		(drill 0.3302)
		(layers "F.Cu" "B.Cu")
		(net "MB1_CM_OV_R")
	)
	(via
		(at 364.341156 -147.413726)
		(size 0.6604)
		(drill 0.3302)
		(layers "F.Cu" "B.Cu")
		(net "MB1_CM_GATE_R")
	)
	(via
		(at 364.348014 -149.967696)
		(size 0.7112)
		(drill 0.4064)
		(layers "F.Cu" "B.Cu")
		(net "MB1_CM_GATE_R")
	)
	(via
		(at 357.615744 -140.233146)
		(size 0.5588)
		(drill 0.3048)
		(layers "F.Cu" "B.Cu")
		(net "MB1_CM_GATE_R")
	)
	(via
		(at 364.383574 -148.878544)
		(size 0.7112)
		(drill 0.4064)
		(layers "F.Cu" "B.Cu")
		(net "MB1_CM_GATE_R")
	)
	(via
		(at 357.615744 -139.217146)
		(size 0.5588)
		(drill 0.3048)
		(layers "F.Cu" "B.Cu")
		(net "MB1_CM_GATE_R")
	)
	(via
		(at 366.776 -144.018)
		(size 0.6604)
		(drill 0.3302)
		(layers "F.Cu" "B.Cu")
		(net "MB1_CM_GATE")
	)
	(segment
		(start 376.7709 -133.5786)
		(end 374.8024 -133.5786)
		(width 0.254)
		(layer "F.Cu")
		(net "MB1_CM_ADR2_R")
	)
	(segment
		(start 371.87886 -137.0457)
		(end 372.3259 -137.0457)
		(width 0.254)
		(layer "F.Cu")
		(net "MB1_CM_ADR2_R")
	)
	(segment
		(start 374.8024 -134.5692)
		(end 374.8024 -133.5786)
		(width 0.254)
		(layer "F.Cu")
		(net "MB1_CM_ADR2_R")
	)
	(segment
		(start 372.3259 -137.0457)
		(end 374.8024 -134.5692)
		(width 0.254)
		(layer "F.Cu")
		(net "MB1_CM_ADR2_R")
	)
	(via
		(at 374.8024 -133.5786)
		(size 0.6604)
		(drill 0.3302)
		(layers "F.Cu" "B.Cu")
		(net "MB1_CM_ADR2_R")
	)
	(segment
		(start 371.378734 -136.418066)
		(end 372.237 -135.5598)
		(width 0.254)
		(layer "F.Cu")
		(net "MB1_CM_ADR1_R")
	)
	(segment
		(start 372.237 -135.5598)
		(end 372.618 -135.5598)
		(width 0.254)
		(layer "F.Cu")
		(net "MB1_CM_ADR1_R")
	)
	(segment
		(start 371.378734 -137.1219)
		(end 371.378734 -136.418066)
		(width 0.254)
		(layer "F.Cu")
		(net "MB1_CM_ADR1_R")
	)
	(segment
		(start 373.5578 -134.3279)
		(end 373.5578 -134.62)
		(width 0.254)
		(layer "F.Cu")
		(net "MB1_CM_ADR1_R")
	)
	(segment
		(start 373.5578 -134.62)
		(end 372.618 -135.5598)
		(width 0.254)
		(layer "F.Cu")
		(net "MB1_CM_ADR1_R")
	)
	(via
		(at 372.618 -135.5598)
		(size 0.6604)
		(drill 0.3302)
		(layers "F.Cu" "B.Cu")
		(net "MB1_CM_ADR1_R")
	)
	(via
		(at 356.329488 -136.123172)
		(size 0.6604)
		(drill 0.3302)
		(layers "F.Cu" "B.Cu")
		(net "MB1_12V_CTRL_GATE1")
	)
	(segment
		(start 145.168366 -142.989554)
		(end 145.168366 -143.848074)
		(width 0.254)
		(layer "F.Cu")
		(net "MB0_VCAP_R")
	)
	(segment
		(start 147.200366 -142.989554)
		(end 147.200366 -142.139416)
		(width 0.254)
		(layer "F.Cu")
		(net "MB0_VCAP_R")
	)
	(segment
		(start 148.406866 -143.975074)
		(end 148.279866 -143.848074)
		(width 0.254)
		(layer "F.Cu")
		(net "MB0_VCAP_R")
	)
	(segment
		(start 149.613366 -143.848074)
		(end 148.533866 -143.848074)
		(width 0.254)
		(layer "F.Cu")
		(net "MB0_VCAP_R")
	)
	(segment
		(start 147.200366 -142.139416)
		(end 147.333462 -142.00632)
		(width 0.254)
		(layer "F.Cu")
		(net "MB0_VCAP_R")
	)
	(segment
		(start 146.2278 -140.900658)
		(end 147.333462 -142.00632)
		(width 0.254)
		(layer "F.Cu")
		(net "MB0_VCAP_R")
	)
	(segment
		(start 146.2278 -140.355574)
		(end 146.2278 -140.900658)
		(width 0.254)
		(layer "F.Cu")
		(net "MB0_VCAP_R")
	)
	(segment
		(start 148.533866 -143.848074)
		(end 148.406866 -143.975074)
		(width 0.254)
		(layer "F.Cu")
		(net "MB0_VCAP_R")
	)
	(segment
		(start 147.200366 -143.848074)
		(end 147.200366 -142.989554)
		(width 0.254)
		(layer "F.Cu")
		(net "MB0_VCAP_R")
	)
	(segment
		(start 148.279866 -143.848074)
		(end 147.200366 -143.848074)
		(width 0.254)
		(layer "F.Cu")
		(net "MB0_VCAP_R")
	)
	(via
		(at 147.200366 -142.989554)
		(size 0.5588)
		(drill 0.3048)
		(layers "F.Cu" "B.Cu")
		(net "MB0_VCAP_R")
	)
	(via
		(at 145.168366 -142.989554)
		(size 0.5588)
		(drill 0.3048)
		(layers "F.Cu" "B.Cu")
		(net "MB0_VCAP_R")
	)
	(via
		(at 147.333462 -142.00632)
		(size 0.6604)
		(drill 0.3302)
		(layers "F.Cu" "B.Cu")
		(net "MB0_VCAP_R")
	)
	(segment
		(start 147.200366 -142.989554)
		(end 145.168366 -142.989554)
		(width 0.254)
		(layer "B.Cu")
		(net "MB0_VCAP_R")
	)
	(segment
		(start 142.818866 -143.594074)
		(end 142.818866 -144.927574)
		(width 0.254)
		(layer "F.Cu")
		(net "MB0_TIME_R")
	)
	(segment
		(start 142.818866 -142.832074)
		(end 142.818866 -143.594074)
		(width 0.254)
		(layer "F.Cu")
		(net "MB0_TIME_R")
	)
	(segment
		(start 144.72793 -140.355574)
		(end 144.72793 -140.92301)
		(width 0.254)
		(layer "F.Cu")
		(net "MB0_TIME_R")
	)
	(segment
		(start 144.72793 -140.92301)
		(end 142.818866 -142.832074)
		(width 0.254)
		(layer "F.Cu")
		(net "MB0_TIME_R")
	)
	(via
		(at 142.818866 -143.594074)
		(size 0.6604)
		(drill 0.3302)
		(layers "F.Cu" "B.Cu")
		(net "MB0_TIME_R")
	)
	(segment
		(start 150.943818 -135.66648)
		(end 150.818088 -135.79221)
		(width 0.254)
		(layer "F.Cu")
		(net "MB0_TEMP")
	)
	(segment
		(start 148.45538 -135.79221)
		(end 149.600412 -135.79221)
		(width 0.254)
		(layer "F.Cu")
		(net "MB0_TEMP")
	)
	(segment
		(start 148.118576 -136.129014)
		(end 148.45538 -135.79221)
		(width 0.254)
		(layer "F.Cu")
		(net "MB0_TEMP")
	)
	(segment
		(start 147.530566 -136.129014)
		(end 148.118576 -136.129014)
		(width 0.254)
		(layer "F.Cu")
		(net "MB0_TEMP")
	)
	(segment
		(start 150.818088 -135.79221)
		(end 149.600412 -135.79221)
		(width 0.254)
		(layer "F.Cu")
		(net "MB0_TEMP")
	)
	(via
		(at 149.600412 -135.79221)
		(size 0.6604)
		(drill 0.3302)
		(layers "F.Cu" "B.Cu")
		(net "MB0_TEMP")
	)
	(segment
		(start 139.097766 -142.628874)
		(end 139.466066 -142.628874)
		(width 0.254)
		(layer "F.Cu")
		(net "MB0_SPISS_PD")
	)
	(segment
		(start 140.941806 -141.153134)
		(end 140.941806 -139.784074)
		(width 0.254)
		(layer "F.Cu")
		(net "MB0_SPISS_PD")
	)
	(segment
		(start 142.425166 -139.629134)
		(end 141.096746 -139.629134)
		(width 0.254)
		(layer "F.Cu")
		(net "MB0_SPISS_PD")
	)
	(segment
		(start 141.096746 -139.629134)
		(end 140.941806 -139.784074)
		(width 0.254)
		(layer "F.Cu")
		(net "MB0_SPISS_PD")
	)
	(segment
		(start 139.466066 -142.628874)
		(end 140.941806 -141.153134)
		(width 0.254)
		(layer "F.Cu")
		(net "MB0_SPISS_PD")
	)
	(via
		(at 140.941806 -139.784074)
		(size 0.6604)
		(drill 0.3302)
		(layers "F.Cu" "B.Cu")
		(net "MB0_SPISS_PD")
	)
	(segment
		(start 143.227806 -135.326374)
		(end 142.526766 -135.326374)
		(width 0.254)
		(layer "F.Cu")
		(net "MB0_RETRY_R")
	)
	(segment
		(start 140.101066 -133.891274)
		(end 139.516866 -133.307074)
		(width 0.254)
		(layer "F.Cu")
		(net "MB0_RETRY_R")
	)
	(segment
		(start 142.526766 -135.326374)
		(end 141.091666 -133.891274)
		(width 0.254)
		(layer "F.Cu")
		(net "MB0_RETRY_R")
	)
	(segment
		(start 141.091666 -133.891274)
		(end 140.101066 -133.891274)
		(width 0.254)
		(layer "F.Cu")
		(net "MB0_RETRY_R")
	)
	(segment
		(start 139.516866 -133.307074)
		(end 139.516866 -132.100574)
		(width 0.254)
		(layer "F.Cu")
		(net "MB0_RETRY_R")
	)
	(via
		(at 139.516866 -133.307074)
		(size 0.6604)
		(drill 0.3302)
		(layers "F.Cu" "B.Cu")
		(net "MB0_RETRY_R")
	)
	(segment
		(start 149.549866 -144.927574)
		(end 150.565866 -144.927574)
		(width 0.254)
		(layer "F.Cu")
		(net "MB0_PSET_R")
	)
	(segment
		(start 146.727926 -140.431774)
		(end 147.022566 -140.431774)
		(width 0.254)
		(layer "F.Cu")
		(net "MB0_PSET_R")
	)
	(segment
		(start 150.565866 -143.911574)
		(end 150.502366 -143.848074)
		(width 0.254)
		(layer "F.Cu")
		(net "MB0_PSET_R")
	)
	(segment
		(start 149.549866 -142.959074)
		(end 148.914866 -142.324074)
		(width 0.254)
		(layer "F.Cu")
		(net "MB0_PSET_R")
	)
	(segment
		(start 150.565866 -144.927574)
		(end 150.565866 -143.911574)
		(width 0.254)
		(layer "F.Cu")
		(net "MB0_PSET_R")
	)
	(segment
		(start 150.057866 -142.959074)
		(end 149.549866 -142.959074)
		(width 0.254)
		(layer "F.Cu")
		(net "MB0_PSET_R")
	)
	(segment
		(start 147.022566 -140.431774)
		(end 148.914866 -142.324074)
		(width 0.254)
		(layer "F.Cu")
		(net "MB0_PSET_R")
	)
	(segment
		(start 150.502366 -143.848074)
		(end 150.502366 -143.403574)
		(width 0.254)
		(layer "F.Cu")
		(net "MB0_PSET_R")
	)
	(segment
		(start 150.502366 -143.403574)
		(end 150.057866 -142.959074)
		(width 0.254)
		(layer "F.Cu")
		(net "MB0_PSET_R")
	)
	(via
		(at 148.914866 -142.324074)
		(size 0.6604)
		(drill 0.3302)
		(layers "F.Cu" "B.Cu")
		(net "MB0_PSET_R")
	)
	(via
		(at 167.914828 -155.939236)
		(size 0.7112)
		(drill 0.4064)
		(layers "F.Cu" "B.Cu")
		(net "MB0_P12V_R")
	)
	(via
		(at 168.981628 -154.872436)
		(size 0.7112)
		(drill 0.4064)
		(layers "F.Cu" "B.Cu")
		(net "MB0_P12V_R")
	)
	(via
		(at 171.681902 -151.93137)
		(size 0.7112)
		(drill 0.4064)
		(layers "F.Cu" "B.Cu")
		(net "MB0_P12V_R")
	)
	(via
		(at 172.520102 -155.53817)
		(size 0.6604)
		(drill 0.3302)
		(layers "F.Cu" "B.Cu")
		(net "MB0_P12V_R")
	)
	(via
		(at 168.981628 -155.939236)
		(size 0.7112)
		(drill 0.4064)
		(layers "F.Cu" "B.Cu")
		(net "MB0_P12V_R")
	)
	(via
		(at 166.746428 -148.039836)
		(size 0.7112)
		(drill 0.4064)
		(layers "F.Cu" "B.Cu")
		(net "MB0_P12V_R")
	)
	(via
		(at 171.681902 -150.61057)
		(size 0.7112)
		(drill 0.4064)
		(layers "F.Cu" "B.Cu")
		(net "MB0_P12V_R")
	)
	(via
		(at 167.914828 -154.872436)
		(size 0.7112)
		(drill 0.4064)
		(layers "F.Cu" "B.Cu")
		(net "MB0_P12V_R")
	)
	(via
		(at 166.848028 -155.939236)
		(size 0.7112)
		(drill 0.4064)
		(layers "F.Cu" "B.Cu")
		(net "MB0_P12V_R")
	)
	(via
		(at 170.048428 -155.939236)
		(size 0.7112)
		(drill 0.4064)
		(layers "F.Cu" "B.Cu")
		(net "MB0_P12V_R")
	)
	(via
		(at 171.681902 -153.25217)
		(size 0.7112)
		(drill 0.4064)
		(layers "F.Cu" "B.Cu")
		(net "MB0_P12V_R")
	)
	(via
		(at 166.848028 -154.872436)
		(size 0.7112)
		(drill 0.4064)
		(layers "F.Cu" "B.Cu")
		(net "MB0_P12V_R")
	)
	(via
		(at 171.681902 -148.98497)
		(size 0.7112)
		(drill 0.4064)
		(layers "F.Cu" "B.Cu")
		(net "MB0_P12V_R")
	)
	(via
		(at 170.708828 -148.039836)
		(size 0.7112)
		(drill 0.4064)
		(layers "F.Cu" "B.Cu")
		(net "MB0_P12V_R")
	)
	(via
		(at 169.388028 -148.039836)
		(size 0.7112)
		(drill 0.4064)
		(layers "F.Cu" "B.Cu")
		(net "MB0_P12V_R")
	)
	(via
		(at 170.048428 -154.872436)
		(size 0.7112)
		(drill 0.4064)
		(layers "F.Cu" "B.Cu")
		(net "MB0_P12V_R")
	)
	(via
		(at 168.067228 -148.039836)
		(size 0.7112)
		(drill 0.4064)
		(layers "F.Cu" "B.Cu")
		(net "MB0_P12V_R")
	)
	(segment
		(start 145.227802 -135.402574)
		(end 145.227802 -134.327138)
		(width 0.254)
		(layer "F.Cu")
		(net "MB0_P12V_PWGIN_R")
	)
	(segment
		(start 146.247866 -132.100574)
		(end 146.247866 -133.307074)
		(width 0.254)
		(layer "F.Cu")
		(net "MB0_P12V_PWGIN_R")
	)
	(segment
		(start 145.227802 -134.327138)
		(end 146.247866 -133.307074)
		(width 0.254)
		(layer "F.Cu")
		(net "MB0_P12V_PWGIN_R")
	)
	(segment
		(start 147.390866 -132.100574)
		(end 146.247866 -132.100574)
		(width 0.254)
		(layer "F.Cu")
		(net "MB0_P12V_PWGIN_R")
	)
	(via
		(at 146.247866 -133.307074)
		(size 0.6604)
		(drill 0.3302)
		(layers "F.Cu" "B.Cu")
		(net "MB0_P12V_PWGIN_R")
	)
	(segment
		(start 150.565866 -139.593574)
		(end 150.565866 -139.149074)
		(width 0.254)
		(layer "F.Cu")
		(net "MB0_P12V_HS")
	)
	(segment
		(start 148.318728 -138.629136)
		(end 148.838666 -139.149074)
		(width 0.254)
		(layer "F.Cu")
		(net "MB0_P12V_HS")
	)
	(segment
		(start 151.264366 -140.292074)
		(end 150.565866 -139.593574)
		(width 0.254)
		(layer "F.Cu")
		(net "MB0_P12V_HS")
	)
	(segment
		(start 147.454366 -138.629136)
		(end 148.318728 -138.629136)
		(width 0.254)
		(layer "F.Cu")
		(net "MB0_P12V_HS")
	)
	(segment
		(start 150.565866 -139.149074)
		(end 149.168866 -139.149074)
		(width 0.254)
		(layer "F.Cu")
		(net "MB0_P12V_HS")
	)
	(segment
		(start 148.838666 -139.149074)
		(end 149.168866 -139.149074)
		(width 0.254)
		(layer "F.Cu")
		(net "MB0_P12V_HS")
	)
	(via
		(at 149.168866 -139.149074)
		(size 0.6604)
		(drill 0.3302)
		(layers "F.Cu" "B.Cu")
		(net "MB0_P12V_HS")
	)
	(segment
		(start 144.215866 -144.927574)
		(end 145.162524 -144.927574)
		(width 0.254)
		(layer "F.Cu")
		(net "MB0_ISTART_R")
	)
	(segment
		(start 145.227802 -141.502638)
		(end 144.279366 -142.451074)
		(width 0.254)
		(layer "F.Cu")
		(net "MB0_ISTART_R")
	)
	(segment
		(start 144.279366 -144.394174)
		(end 144.215866 -144.457674)
		(width 0.254)
		(layer "F.Cu")
		(net "MB0_ISTART_R")
	)
	(segment
		(start 144.215866 -144.457674)
		(end 144.215866 -144.927574)
		(width 0.254)
		(layer "F.Cu")
		(net "MB0_ISTART_R")
	)
	(segment
		(start 144.279366 -142.451074)
		(end 144.279366 -143.848074)
		(width 0.254)
		(layer "F.Cu")
		(net "MB0_ISTART_R")
	)
	(segment
		(start 145.162524 -144.927574)
		(end 145.17116 -144.93621)
		(width 0.254)
		(layer "F.Cu")
		(net "MB0_ISTART_R")
	)
	(segment
		(start 144.279366 -143.848074)
		(end 144.279366 -144.394174)
		(width 0.254)
		(layer "F.Cu")
		(net "MB0_ISTART_R")
	)
	(segment
		(start 145.227802 -140.355574)
		(end 145.227802 -141.502638)
		(width 0.254)
		(layer "F.Cu")
		(net "MB0_ISTART_R")
	)
	(via
		(at 144.279366 -142.451074)
		(size 0.6604)
		(drill 0.3302)
		(layers "F.Cu" "B.Cu")
		(net "MB0_ISTART_R")
	)
	(segment
		(start 146.311366 -142.539974)
		(end 146.311366 -143.848074)
		(width 0.254)
		(layer "F.Cu")
		(net "MB0_ISET_R")
	)
	(segment
		(start 146.247866 -144.927574)
		(end 147.231608 -144.927574)
		(width 0.254)
		(layer "F.Cu")
		(net "MB0_ISET_R")
	)
	(segment
		(start 146.311366 -142.006574)
		(end 146.311366 -142.539974)
		(width 0.254)
		(layer "F.Cu")
		(net "MB0_ISET_R")
	)
	(segment
		(start 145.727928 -141.423136)
		(end 146.311366 -142.006574)
		(width 0.254)
		(layer "F.Cu")
		(net "MB0_ISET_R")
	)
	(segment
		(start 145.727928 -140.355574)
		(end 145.727928 -141.423136)
		(width 0.254)
		(layer "F.Cu")
		(net "MB0_ISET_R")
	)
	(segment
		(start 147.231608 -144.927574)
		(end 147.248372 -144.944338)
		(width 0.254)
		(layer "F.Cu")
		(net "MB0_ISET_R")
	)
	(segment
		(start 146.247866 -144.457674)
		(end 146.247866 -144.927574)
		(width 0.254)
		(layer "F.Cu")
		(net "MB0_ISET_R")
	)
	(segment
		(start 146.311366 -143.848074)
		(end 146.311366 -144.394174)
		(width 0.254)
		(layer "F.Cu")
		(net "MB0_ISET_R")
	)
	(segment
		(start 146.311366 -144.394174)
		(end 146.247866 -144.457674)
		(width 0.254)
		(layer "F.Cu")
		(net "MB0_ISET_R")
	)
	(via
		(at 146.311366 -142.539974)
		(size 0.6604)
		(drill 0.3302)
		(layers "F.Cu" "B.Cu")
		(net "MB0_ISET_R")
	)
	(segment
		(start 138.695176 -137.692384)
		(end 139.373864 -138.371072)
		(width 0.254)
		(layer "F.Cu")
		(net "MB0_HS_ENABLE")
	)
	(segment
		(start 138.016234 -137.692384)
		(end 138.695176 -137.692384)
		(width 0.254)
		(layer "F.Cu")
		(net "MB0_HS_ENABLE")
	)
	(segment
		(start 139.373864 -138.371072)
		(end 139.740894 -138.371072)
		(width 0.254)
		(layer "F.Cu")
		(net "MB0_HS_ENABLE")
	)
	(segment
		(start 140.964666 -138.12901)
		(end 140.722604 -138.371072)
		(width 0.254)
		(layer "F.Cu")
		(net "MB0_HS_ENABLE")
	)
	(segment
		(start 142.501366 -138.12901)
		(end 140.964666 -138.12901)
		(width 0.254)
		(layer "F.Cu")
		(net "MB0_HS_ENABLE")
	)
	(segment
		(start 140.722604 -138.371072)
		(end 139.740894 -138.371072)
		(width 0.254)
		(layer "F.Cu")
		(net "MB0_HS_ENABLE")
	)
	(via
		(at 139.740894 -138.371072)
		(size 0.6604)
		(drill 0.3302)
		(layers "F.Cu" "B.Cu")
		(net "MB0_HS_ENABLE")
	)
	(segment
		(start 144.469866 -133.078474)
		(end 144.469866 -132.100574)
		(width 0.17145)
		(layer "F.Cu")
		(net "MB0_CM_VOUT_R")
	)
	(segment
		(start 144.72793 -135.402574)
		(end 144.72793 -133.336538)
		(width 0.17145)
		(layer "F.Cu")
		(net "MB0_CM_VOUT_R")
	)
	(segment
		(start 161.852102 -148.81987)
		(end 161.852102 -147.86737)
		(width 0.17145)
		(layer "F.Cu")
		(net "MB0_CM_VOUT_R")
	)
	(segment
		(start 144.72793 -133.336538)
		(end 144.614138 -133.222746)
		(width 0.17145)
		(layer "F.Cu")
		(net "MB0_CM_VOUT_R")
	)
	(segment
		(start 144.469866 -132.100574)
		(end 145.346166 -132.100574)
		(width 0.17145)
		(layer "F.Cu")
		(net "MB0_CM_VOUT_R")
	)
	(segment
		(start 144.614138 -133.222746)
		(end 144.469866 -133.078474)
		(width 0.17145)
		(layer "F.Cu")
		(net "MB0_CM_VOUT_R")
	)
	(via
		(at 145.346166 -132.100574)
		(size 0.5588)
		(drill 0.3048)
		(layers "F.Cu" "B.Cu")
		(net "MB0_CM_VOUT_R")
	)
	(via
		(at 144.614138 -133.222746)
		(size 0.6604)
		(drill 0.3302)
		(layers "F.Cu" "B.Cu")
		(net "MB0_CM_VOUT_R")
	)
	(via
		(at 161.852102 -147.86737)
		(size 0.5588)
		(drill 0.3048)
		(layers "F.Cu" "B.Cu")
		(net "MB0_CM_VOUT_R")
	)
	(segment
		(start 147.435824 -134.190232)
		(end 145.346166 -132.100574)
		(width 0.17145)
		(layer "B.Cu")
		(net "MB0_CM_VOUT_R")
	)
	(segment
		(start 147.435824 -138.75258)
		(end 147.435824 -134.190232)
		(width 0.17145)
		(layer "B.Cu")
		(net "MB0_CM_VOUT_R")
	)
	(segment
		(start 156.550614 -147.86737)
		(end 147.435824 -138.75258)
		(width 0.17145)
		(layer "B.Cu")
		(net "MB0_CM_VOUT_R")
	)
	(segment
		(start 161.852102 -147.86737)
		(end 156.550614 -147.86737)
		(width 0.17145)
		(layer "B.Cu")
		(net "MB0_CM_VOUT_R")
	)
	(segment
		(start 154.29484 -141.293596)
		(end 150.819866 -141.293596)
		(width 0.17145)
		(layer "F.Cu")
		(net "MB0_CM_UV_R")
	)
	(segment
		(start 155.13304 -141.293596)
		(end 154.29484 -141.293596)
		(width 0.17145)
		(layer "F.Cu")
		(net "MB0_CM_UV_R")
	)
	(segment
		(start 147.454366 -139.129008)
		(end 148.1328 -139.129008)
		(width 0.17145)
		(layer "F.Cu")
		(net "MB0_CM_UV_R")
	)
	(segment
		(start 156.47924 -141.014196)
		(end 156.46654 -141.001496)
		(width 0.17145)
		(layer "F.Cu")
		(net "MB0_CM_UV_R")
	)
	(segment
		(start 148.1328 -139.129008)
		(end 150.297388 -141.293596)
		(width 0.17145)
		(layer "F.Cu")
		(net "MB0_CM_UV_R")
	)
	(segment
		(start 156.46654 -141.001496)
		(end 155.42514 -141.001496)
		(width 0.17145)
		(layer "F.Cu")
		(net "MB0_CM_UV_R")
	)
	(segment
		(start 150.297388 -141.293596)
		(end 150.819866 -141.293596)
		(width 0.17145)
		(layer "F.Cu")
		(net "MB0_CM_UV_R")
	)
	(segment
		(start 155.42514 -141.001496)
		(end 155.13304 -141.293596)
		(width 0.17145)
		(layer "F.Cu")
		(net "MB0_CM_UV_R")
	)
	(via
		(at 150.819866 -141.293596)
		(size 0.6604)
		(drill 0.3302)
		(layers "F.Cu" "B.Cu")
		(net "MB0_CM_UV_R")
	)
	(segment
		(start 154.370786 -137.599674)
		(end 154.770836 -137.999724)
		(width 0.254)
		(layer "F.Cu")
		(net "MB0_CM_SENSE_R1_P")
	)
	(segment
		(start 175.195738 -148.926296)
		(end 175.195738 -147.441666)
		(width 0.254)
		(layer "F.Cu")
		(net "MB0_CM_SENSE_R1_P")
	)
	(segment
		(start 155.170886 -137.599674)
		(end 154.770836 -137.999724)
		(width 0.254)
		(layer "F.Cu")
		(net "MB0_CM_SENSE_R1_P")
	)
	(segment
		(start 155.831032 -137.85723)
		(end 155.573476 -137.599674)
		(width 0.254)
		(layer "F.Cu")
		(net "MB0_CM_SENSE_R1_P")
	)
	(segment
		(start 153.677366 -137.879074)
		(end 153.956766 -137.599674)
		(width 0.254)
		(layer "F.Cu")
		(net "MB0_CM_SENSE_R1_P")
	)
	(segment
		(start 155.573476 -137.599674)
		(end 155.170886 -137.599674)
		(width 0.254)
		(layer "F.Cu")
		(net "MB0_CM_SENSE_R1_P")
	)
	(segment
		(start 153.956766 -137.599674)
		(end 154.370786 -137.599674)
		(width 0.254)
		(layer "F.Cu")
		(net "MB0_CM_SENSE_R1_P")
	)
	(via
		(at 154.770836 -137.999724)
		(size 0.5588)
		(drill 0.3048)
		(layers "F.Cu" "B.Cu")
		(net "MB0_CM_SENSE_R1_P")
	)
	(via
		(at 175.195738 -147.441666)
		(size 0.5588)
		(drill 0.3048)
		(layers "F.Cu" "B.Cu")
		(net "MB0_CM_SENSE_R1_P")
	)
	(segment
		(start 156.310076 -140.999718)
		(end 153.994866 -138.684508)
		(width 0.254)
		(layer "B.Cu")
		(net "MB0_CM_SENSE_R1_P")
	)
	(segment
		(start 153.994866 -138.684508)
		(end 153.994866 -137.708894)
		(width 0.254)
		(layer "B.Cu")
		(net "MB0_CM_SENSE_R1_P")
	)
	(segment
		(start 174.610776 -145.861278)
		(end 169.749216 -140.999718)
		(width 0.254)
		(layer "B.Cu")
		(net "MB0_CM_SENSE_R1_P")
	)
	(segment
		(start 175.195738 -147.441666)
		(end 174.610776 -146.856704)
		(width 0.254)
		(layer "B.Cu")
		(net "MB0_CM_SENSE_R1_P")
	)
	(segment
		(start 174.610776 -146.856704)
		(end 174.610776 -145.861278)
		(width 0.254)
		(layer "B.Cu")
		(net "MB0_CM_SENSE_R1_P")
	)
	(segment
		(start 169.749216 -140.999718)
		(end 156.310076 -140.999718)
		(width 0.254)
		(layer "B.Cu")
		(net "MB0_CM_SENSE_R1_P")
	)
	(segment
		(start 154.110436 -137.593324)
		(end 154.364436 -137.593324)
		(width 0.254)
		(layer "B.Cu")
		(net "MB0_CM_SENSE_R1_P")
	)
	(segment
		(start 153.994866 -137.708894)
		(end 154.110436 -137.593324)
		(width 0.254)
		(layer "B.Cu")
		(net "MB0_CM_SENSE_R1_P")
	)
	(segment
		(start 154.364436 -137.593324)
		(end 154.770836 -137.999724)
		(width 0.254)
		(layer "B.Cu")
		(net "MB0_CM_SENSE_R1_P")
	)
	(segment
		(start 153.677366 -136.863074)
		(end 153.956766 -137.142474)
		(width 0.254)
		(layer "F.Cu")
		(net "MB0_CM_SENSE_R1_N")
	)
	(segment
		(start 153.956766 -137.142474)
		(end 154.358086 -137.142474)
		(width 0.254)
		(layer "F.Cu")
		(net "MB0_CM_SENSE_R1_N")
	)
	(segment
		(start 155.529788 -137.142474)
		(end 155.183586 -137.142474)
		(width 0.254)
		(layer "F.Cu")
		(net "MB0_CM_SENSE_R1_N")
	)
	(segment
		(start 155.831032 -136.84123)
		(end 155.529788 -137.142474)
		(width 0.254)
		(layer "F.Cu")
		(net "MB0_CM_SENSE_R1_N")
	)
	(segment
		(start 155.183586 -137.142474)
		(end 154.770836 -136.729724)
		(width 0.254)
		(layer "F.Cu")
		(net "MB0_CM_SENSE_R1_N")
	)
	(segment
		(start 173.568614 -148.926296)
		(end 173.568614 -147.441666)
		(width 0.254)
		(layer "F.Cu")
		(net "MB0_CM_SENSE_R1_N")
	)
	(segment
		(start 154.358086 -137.142474)
		(end 154.770836 -136.729724)
		(width 0.254)
		(layer "F.Cu")
		(net "MB0_CM_SENSE_R1_N")
	)
	(via
		(at 173.568614 -147.441666)
		(size 0.5588)
		(drill 0.3048)
		(layers "F.Cu" "B.Cu")
		(net "MB0_CM_SENSE_R1_N")
	)
	(via
		(at 154.770836 -136.729724)
		(size 0.5588)
		(drill 0.3048)
		(layers "F.Cu" "B.Cu")
		(net "MB0_CM_SENSE_R1_N")
	)
	(segment
		(start 153.537666 -138.873992)
		(end 153.537666 -137.51941)
		(width 0.254)
		(layer "B.Cu")
		(net "MB0_CM_SENSE_R1_N")
	)
	(segment
		(start 154.364436 -137.136124)
		(end 154.770836 -136.729724)
		(width 0.254)
		(layer "B.Cu")
		(net "MB0_CM_SENSE_R1_N")
	)
	(segment
		(start 156.120592 -141.456918)
		(end 153.537666 -138.873992)
		(width 0.254)
		(layer "B.Cu")
		(net "MB0_CM_SENSE_R1_N")
	)
	(segment
		(start 173.568614 -147.441666)
		(end 174.153576 -146.856704)
		(width 0.254)
		(layer "B.Cu")
		(net "MB0_CM_SENSE_R1_N")
	)
	(segment
		(start 169.559732 -141.456918)
		(end 156.120592 -141.456918)
		(width 0.254)
		(layer "B.Cu")
		(net "MB0_CM_SENSE_R1_N")
	)
	(segment
		(start 153.920952 -137.136124)
		(end 154.364436 -137.136124)
		(width 0.254)
		(layer "B.Cu")
		(net "MB0_CM_SENSE_R1_N")
	)
	(segment
		(start 174.153576 -146.856704)
		(end 174.153576 -146.050762)
		(width 0.254)
		(layer "B.Cu")
		(net "MB0_CM_SENSE_R1_N")
	)
	(segment
		(start 174.153576 -146.050762)
		(end 169.559732 -141.456918)
		(width 0.254)
		(layer "B.Cu")
		(net "MB0_CM_SENSE_R1_N")
	)
	(segment
		(start 153.537666 -137.51941)
		(end 153.920952 -137.136124)
		(width 0.254)
		(layer "B.Cu")
		(net "MB0_CM_SENSE_R1_N")
	)
	(segment
		(start 148.711666 -138.174476)
		(end 148.6662 -138.12901)
		(width 0.254)
		(layer "F.Cu")
		(net "MB0_CM_SENSE_P")
	)
	(segment
		(start 158.936944 -137.57783)
		(end 158.487364 -137.57783)
		(width 0.254)
		(layer "F.Cu")
		(net "MB0_CM_SENSE_P")
	)
	(segment
		(start 157.532832 -137.57783)
		(end 156.999432 -137.57783)
		(width 0.254)
		(layer "F.Cu")
		(net "MB0_CM_SENSE_P")
	)
	(segment
		(start 148.6662 -138.12901)
		(end 147.454366 -138.12901)
		(width 0.254)
		(layer "F.Cu")
		(net "MB0_CM_SENSE_P")
	)
	(segment
		(start 156.999432 -137.57783)
		(end 156.720032 -137.85723)
		(width 0.254)
		(layer "F.Cu")
		(net "MB0_CM_SENSE_P")
	)
	(segment
		(start 158.487364 -137.57783)
		(end 158.271464 -137.79373)
		(width 0.254)
		(layer "F.Cu")
		(net "MB0_CM_SENSE_P")
	)
	(segment
		(start 157.748732 -137.79373)
		(end 157.532832 -137.57783)
		(width 0.254)
		(layer "F.Cu")
		(net "MB0_CM_SENSE_P")
	)
	(segment
		(start 159.258 -137.898886)
		(end 158.936944 -137.57783)
		(width 0.254)
		(layer "F.Cu")
		(net "MB0_CM_SENSE_P")
	)
	(segment
		(start 158.271464 -137.79373)
		(end 157.748732 -137.79373)
		(width 0.254)
		(layer "F.Cu")
		(net "MB0_CM_SENSE_P")
	)
	(via
		(at 159.258 -137.898886)
		(size 0.5588)
		(drill 0.3048)
		(layers "F.Cu" "B.Cu")
		(net "MB0_CM_SENSE_P")
	)
	(via
		(at 148.711666 -138.174476)
		(size 0.5588)
		(drill 0.3048)
		(layers "F.Cu" "B.Cu")
		(net "MB0_CM_SENSE_P")
	)
	(segment
		(start 158.936944 -137.57783)
		(end 158.120588 -137.57783)
		(width 0.254)
		(layer "B.Cu")
		(net "MB0_CM_SENSE_P")
	)
	(segment
		(start 155.49245 -134.949692)
		(end 152.914096 -134.949692)
		(width 0.254)
		(layer "B.Cu")
		(net "MB0_CM_SENSE_P")
	)
	(segment
		(start 150.255986 -137.607802)
		(end 149.27834 -137.607802)
		(width 0.254)
		(layer "B.Cu")
		(net "MB0_CM_SENSE_P")
	)
	(segment
		(start 149.27834 -137.607802)
		(end 148.711666 -138.174476)
		(width 0.254)
		(layer "B.Cu")
		(net "MB0_CM_SENSE_P")
	)
	(segment
		(start 158.120588 -137.57783)
		(end 155.49245 -134.949692)
		(width 0.254)
		(layer "B.Cu")
		(net "MB0_CM_SENSE_P")
	)
	(segment
		(start 159.258 -137.898886)
		(end 158.936944 -137.57783)
		(width 0.254)
		(layer "B.Cu")
		(net "MB0_CM_SENSE_P")
	)
	(segment
		(start 152.914096 -134.949692)
		(end 150.255986 -137.607802)
		(width 0.254)
		(layer "B.Cu")
		(net "MB0_CM_SENSE_P")
	)
	(segment
		(start 156.999432 -137.12063)
		(end 156.720032 -136.84123)
		(width 0.254)
		(layer "F.Cu")
		(net "MB0_CM_SENSE_N")
	)
	(segment
		(start 158.487364 -137.12063)
		(end 158.271464 -136.90473)
		(width 0.254)
		(layer "F.Cu")
		(net "MB0_CM_SENSE_N")
	)
	(segment
		(start 157.532832 -137.12063)
		(end 156.999432 -137.12063)
		(width 0.254)
		(layer "F.Cu")
		(net "MB0_CM_SENSE_N")
	)
	(segment
		(start 158.936944 -137.12063)
		(end 158.487364 -137.12063)
		(width 0.254)
		(layer "F.Cu")
		(net "MB0_CM_SENSE_N")
	)
	(segment
		(start 148.6662 -136.62914)
		(end 147.454366 -136.62914)
		(width 0.254)
		(layer "F.Cu")
		(net "MB0_CM_SENSE_N")
	)
	(segment
		(start 159.258 -136.799574)
		(end 158.936944 -137.12063)
		(width 0.254)
		(layer "F.Cu")
		(net "MB0_CM_SENSE_N")
	)
	(segment
		(start 158.271464 -136.90473)
		(end 157.748732 -136.90473)
		(width 0.254)
		(layer "F.Cu")
		(net "MB0_CM_SENSE_N")
	)
	(segment
		(start 157.748732 -136.90473)
		(end 157.532832 -137.12063)
		(width 0.254)
		(layer "F.Cu")
		(net "MB0_CM_SENSE_N")
	)
	(segment
		(start 148.711666 -136.583674)
		(end 148.6662 -136.62914)
		(width 0.254)
		(layer "F.Cu")
		(net "MB0_CM_SENSE_N")
	)
	(via
		(at 159.258 -136.799574)
		(size 0.5588)
		(drill 0.3048)
		(layers "F.Cu" "B.Cu")
		(net "MB0_CM_SENSE_N")
	)
	(via
		(at 148.711666 -136.583674)
		(size 0.5588)
		(drill 0.3048)
		(layers "F.Cu" "B.Cu")
		(net "MB0_CM_SENSE_N")
	)
	(segment
		(start 158.310072 -137.12063)
		(end 155.681934 -134.492492)
		(width 0.254)
		(layer "B.Cu")
		(net "MB0_CM_SENSE_N")
	)
	(segment
		(start 159.258 -136.799574)
		(end 158.936944 -137.12063)
		(width 0.254)
		(layer "B.Cu")
		(net "MB0_CM_SENSE_N")
	)
	(segment
		(start 158.936944 -137.12063)
		(end 158.310072 -137.12063)
		(width 0.254)
		(layer "B.Cu")
		(net "MB0_CM_SENSE_N")
	)
	(segment
		(start 150.066502 -137.150602)
		(end 149.278594 -137.150602)
		(width 0.254)
		(layer "B.Cu")
		(net "MB0_CM_SENSE_N")
	)
	(segment
		(start 155.681934 -134.492492)
		(end 152.724612 -134.492492)
		(width 0.254)
		(layer "B.Cu")
		(net "MB0_CM_SENSE_N")
	)
	(segment
		(start 152.724612 -134.492492)
		(end 150.066502 -137.150602)
		(width 0.254)
		(layer "B.Cu")
		(net "MB0_CM_SENSE_N")
	)
	(segment
		(start 149.278594 -137.150602)
		(end 148.711666 -136.583674)
		(width 0.254)
		(layer "B.Cu")
		(net "MB0_CM_SENSE_N")
	)
	(segment
		(start 154.29484 -142.436596)
		(end 153.960068 -142.101824)
		(width 0.17145)
		(layer "F.Cu")
		(net "MB0_CM_OV_R")
	)
	(segment
		(start 154.98064 -142.436596)
		(end 154.29484 -142.436596)
		(width 0.17145)
		(layer "F.Cu")
		(net "MB0_CM_OV_R")
	)
	(segment
		(start 155.42514 -142.881096)
		(end 154.98064 -142.436596)
		(width 0.17145)
		(layer "F.Cu")
		(net "MB0_CM_OV_R")
	)
	(segment
		(start 150.37816 -142.101824)
		(end 152.902666 -142.101824)
		(width 0.17145)
		(layer "F.Cu")
		(net "MB0_CM_OV_R")
	)
	(segment
		(start 147.90547 -139.629134)
		(end 150.37816 -142.101824)
		(width 0.17145)
		(layer "F.Cu")
		(net "MB0_CM_OV_R")
	)
	(segment
		(start 147.530566 -139.629134)
		(end 147.90547 -139.629134)
		(width 0.17145)
		(layer "F.Cu")
		(net "MB0_CM_OV_R")
	)
	(segment
		(start 156.46654 -142.881096)
		(end 155.42514 -142.881096)
		(width 0.17145)
		(layer "F.Cu")
		(net "MB0_CM_OV_R")
	)
	(segment
		(start 153.960068 -142.101824)
		(end 152.902666 -142.101824)
		(width 0.17145)
		(layer "F.Cu")
		(net "MB0_CM_OV_R")
	)
	(segment
		(start 156.47924 -142.893796)
		(end 156.46654 -142.881096)
		(width 0.17145)
		(layer "F.Cu")
		(net "MB0_CM_OV_R")
	)
	(via
		(at 152.902666 -142.101824)
		(size 0.6604)
		(drill 0.3302)
		(layers "F.Cu" "B.Cu")
		(net "MB0_CM_OV_R")
	)
	(via
		(at 150.642066 -130.182874)
		(size 0.5588)
		(drill 0.3048)
		(layers "F.Cu" "B.Cu")
		(net "MB0_CM_GATE_R")
	)
	(via
		(at 151.07793 -128.26111)
		(size 0.6604)
		(drill 0.3302)
		(layers "F.Cu" "B.Cu")
		(net "MB0_CM_GATE_R")
	)
	(via
		(at 167.304974 -145.236692)
		(size 0.5588)
		(drill 0.3048)
		(layers "F.Cu" "B.Cu")
		(net "MB0_CM_GATE_R")
	)
	(via
		(at 166.288974 -145.236692)
		(size 0.5588)
		(drill 0.3048)
		(layers "F.Cu" "B.Cu")
		(net "MB0_CM_GATE_R")
	)
	(via
		(at 150.642066 -131.198874)
		(size 0.5588)
		(drill 0.3048)
		(layers "F.Cu" "B.Cu")
		(net "MB0_CM_GATE_R")
	)
	(via
		(at 149.358604 -133.847078)
		(size 0.6604)
		(drill 0.3302)
		(layers "F.Cu" "B.Cu")
		(net "MB0_CM_GATE")
	)
	(segment
		(start 142.780766 -140.431774)
		(end 140.304266 -142.908274)
		(width 0.17145)
		(layer "F.Cu")
		(net "MB0_CM_ADR2_R")
	)
	(segment
		(start 143.227806 -140.431774)
		(end 142.780766 -140.431774)
		(width 0.17145)
		(layer "F.Cu")
		(net "MB0_CM_ADR2_R")
	)
	(segment
		(start 140.304266 -142.908274)
		(end 140.304266 -143.898874)
		(width 0.17145)
		(layer "F.Cu")
		(net "MB0_CM_ADR2_R")
	)
	(segment
		(start 139.097766 -143.898874)
		(end 140.304266 -143.898874)
		(width 0.17145)
		(layer "F.Cu")
		(net "MB0_CM_ADR2_R")
	)
	(via
		(at 140.304266 -143.898874)
		(size 0.6604)
		(drill 0.3302)
		(layers "F.Cu" "B.Cu")
		(net "MB0_CM_ADR2_R")
	)
	(segment
		(start 143.727932 -140.355574)
		(end 143.727932 -141.285468)
		(width 0.17145)
		(layer "F.Cu")
		(net "MB0_CM_ADR1_R")
	)
	(segment
		(start 141.548866 -142.397734)
		(end 142.0622 -141.8844)
		(width 0.17145)
		(layer "F.Cu")
		(net "MB0_CM_ADR1_R")
	)
	(segment
		(start 141.548866 -143.149574)
		(end 141.548866 -142.397734)
		(width 0.17145)
		(layer "F.Cu")
		(net "MB0_CM_ADR1_R")
	)
	(segment
		(start 143.129 -141.8844)
		(end 142.367 -141.8844)
		(width 0.17145)
		(layer "F.Cu")
		(net "MB0_CM_ADR1_R")
	)
	(segment
		(start 142.0622 -141.8844)
		(end 142.367 -141.8844)
		(width 0.17145)
		(layer "F.Cu")
		(net "MB0_CM_ADR1_R")
	)
	(segment
		(start 143.727932 -141.285468)
		(end 143.129 -141.8844)
		(width 0.17145)
		(layer "F.Cu")
		(net "MB0_CM_ADR1_R")
	)
	(via
		(at 142.367 -141.8844)
		(size 0.6604)
		(drill 0.3302)
		(layers "F.Cu" "B.Cu")
		(net "MB0_CM_ADR1_R")
	)
	(via
		(at 163.106608 -147.053808)
		(size 0.6604)
		(drill 0.3302)
		(layers "F.Cu" "B.Cu")
		(net "MB0_12V_CTRL_GATE1")
	)
	(segment
		(start 376.8979 -134.8486)
		(end 377.9774 -134.8486)
		(width 0.508)
		(layer "F.Cu")
		(net "AGND_CURRENT_MONOB")
	)
	(segment
		(start 360.300778 -131.319778)
		(end 361.180126 -131.319778)
		(width 0.508)
		(layer "F.Cu")
		(net "AGND_CURRENT_MONOB")
	)
	(segment
		(start 361.180126 -134.977378)
		(end 361.967526 -134.977378)
		(width 0.508)
		(layer "F.Cu")
		(net "AGND_CURRENT_MONOB")
	)
	(segment
		(start 370.1288 -139.5984)
		(end 369.378738 -140.348462)
		(width 0.254)
		(layer "F.Cu")
		(net "AGND_CURRENT_MONOB")
	)
	(segment
		(start 377.6599 -132.906262)
		(end 377.426728 -132.67309)
		(width 0.508)
		(layer "F.Cu")
		(net "AGND_CURRENT_MONOB")
	)
	(segment
		(start 368.8588 -147.2184)
		(end 368.8588 -146.2659)
		(width 0.254)
		(layer "F.Cu")
		(net "AGND_CURRENT_MONOB")
	)
	(segment
		(start 366.6998 -130.81)
		(end 366.6998 -131.9784)
		(width 0.254)
		(layer "F.Cu")
		(net "AGND_CURRENT_MONOB")
	)
	(segment
		(start 368.8588 -130.81)
		(end 368.8588 -131.6609)
		(width 0.254)
		(layer "F.Cu")
		(net "AGND_CURRENT_MONOB")
	)
	(segment
		(start 361.967526 -134.977378)
		(end 362.310426 -135.320278)
		(width 0.508)
		(layer "F.Cu")
		(net "AGND_CURRENT_MONOB")
	)
	(segment
		(start 372.2878 -130.81)
		(end 372.2878 -131.6609)
		(width 0.254)
		(layer "F.Cu")
		(net "AGND_CURRENT_MONOB")
	)
	(segment
		(start 370.6368 -147.2184)
		(end 370.6368 -146.2659)
		(width 0.254)
		(layer "F.Cu")
		(net "AGND_CURRENT_MONOB")
	)
	(segment
		(start 369.378738 -140.348462)
		(end 369.378738 -142.0749)
		(width 0.254)
		(layer "F.Cu")
		(net "AGND_CURRENT_MONOB")
	)
	(segment
		(start 377.6599 -133.5786)
		(end 377.6599 -132.906262)
		(width 0.508)
		(layer "F.Cu")
		(net "AGND_CURRENT_MONOB")
	)
	(segment
		(start 361.180126 -131.319778)
		(end 362.119926 -131.319778)
		(width 0.508)
		(layer "F.Cu")
		(net "AGND_CURRENT_MONOB")
	)
	(segment
		(start 369.935506 -130.81)
		(end 369.935506 -131.652264)
		(width 0.254)
		(layer "F.Cu")
		(net "AGND_CURRENT_MONOB")
	)
	(segment
		(start 365.5568 -130.81)
		(end 365.5568 -131.6609)
		(width 0.254)
		(layer "F.Cu")
		(net "AGND_CURRENT_MONOB")
	)
	(segment
		(start 360.297222 -134.977378)
		(end 361.180126 -134.977378)
		(width 0.508)
		(layer "F.Cu")
		(net "AGND_CURRENT_MONOB")
	)
	(segment
		(start 370.8908 -130.81)
		(end 370.8908 -131.6609)
		(width 0.254)
		(layer "F.Cu")
		(net "AGND_CURRENT_MONOB")
	)
	(segment
		(start 377.9774 -134.8486)
		(end 377.9774 -133.8961)
		(width 0.508)
		(layer "F.Cu")
		(net "AGND_CURRENT_MONOB")
	)
	(segment
		(start 364.5408 -131.6609)
		(end 364.5408 -130.81)
		(width 0.508)
		(layer "F.Cu")
		(net "AGND_CURRENT_MONOB")
	)
	(segment
		(start 362.1024 -138.3284)
		(end 363.0168 -138.3284)
		(width 0.254)
		(layer "F.Cu")
		(net "AGND_CURRENT_MONOB")
	)
	(segment
		(start 377.9774 -133.8961)
		(end 377.6599 -133.5786)
		(width 0.508)
		(layer "F.Cu")
		(net "AGND_CURRENT_MONOB")
	)
	(segment
		(start 367.858294 -130.81)
		(end 367.858294 -131.644136)
		(width 0.254)
		(layer "F.Cu")
		(net "AGND_CURRENT_MONOB")
	)
	(segment
		(start 362.119926 -131.319778)
		(end 362.310426 -131.129278)
		(width 0.508)
		(layer "F.Cu")
		(net "AGND_CURRENT_MONOB")
	)
	(segment
		(start 373.5578 -133.4389)
		(end 373.5578 -132.6134)
		(width 0.508)
		(layer "F.Cu")
		(net "AGND_CURRENT_MONOB")
	)
	(via
		(at 362.1024 -138.3284)
		(size 0.5588)
		(drill 0.3048)
		(layers "F.Cu" "B.Cu")
		(net "AGND_CURRENT_MONOB")
	)
	(via
		(at 364.5408 -130.81)
		(size 0.5588)
		(drill 0.3048)
		(layers "F.Cu" "B.Cu")
		(net "AGND_CURRENT_MONOB")
	)
	(via
		(at 360.300778 -131.319778)
		(size 0.5588)
		(drill 0.3048)
		(layers "F.Cu" "B.Cu")
		(net "AGND_CURRENT_MONOB")
	)
	(via
		(at 371.563392 -130.090926)
		(size 0.6604)
		(drill 0.3302)
		(layers "F.Cu" "B.Cu")
		(net "AGND_CURRENT_MONOB")
	)
	(via
		(at 370.8908 -130.81)
		(size 0.5588)
		(drill 0.3048)
		(layers "F.Cu" "B.Cu")
		(net "AGND_CURRENT_MONOB")
	)
	(via
		(at 377.426728 -132.67309)
		(size 0.5588)
		(drill 0.3048)
		(layers "F.Cu" "B.Cu")
		(net "AGND_CURRENT_MONOB")
	)
	(via
		(at 370.6368 -147.2184)
		(size 0.5588)
		(drill 0.3048)
		(layers "F.Cu" "B.Cu")
		(net "AGND_CURRENT_MONOB")
	)
	(via
		(at 369.935506 -130.81)
		(size 0.5588)
		(drill 0.3048)
		(layers "F.Cu" "B.Cu")
		(net "AGND_CURRENT_MONOB")
	)
	(via
		(at 373.5578 -132.6134)
		(size 0.5588)
		(drill 0.3048)
		(layers "F.Cu" "B.Cu")
		(net "AGND_CURRENT_MONOB")
	)
	(via
		(at 368.8588 -130.81)
		(size 0.5588)
		(drill 0.3048)
		(layers "F.Cu" "B.Cu")
		(net "AGND_CURRENT_MONOB")
	)
	(via
		(at 366.6998 -130.81)
		(size 0.5588)
		(drill 0.3048)
		(layers "F.Cu" "B.Cu")
		(net "AGND_CURRENT_MONOB")
	)
	(via
		(at 367.858294 -130.81)
		(size 0.5588)
		(drill 0.3048)
		(layers "F.Cu" "B.Cu")
		(net "AGND_CURRENT_MONOB")
	)
	(via
		(at 372.2878 -130.81)
		(size 0.5588)
		(drill 0.3048)
		(layers "F.Cu" "B.Cu")
		(net "AGND_CURRENT_MONOB")
	)
	(via
		(at 360.297222 -134.977378)
		(size 0.5588)
		(drill 0.3048)
		(layers "F.Cu" "B.Cu")
		(net "AGND_CURRENT_MONOB")
	)
	(via
		(at 365.5568 -130.81)
		(size 0.5588)
		(drill 0.3048)
		(layers "F.Cu" "B.Cu")
		(net "AGND_CURRENT_MONOB")
	)
	(via
		(at 370.1288 -139.5984)
		(size 0.5588)
		(drill 0.3048)
		(layers "F.Cu" "B.Cu")
		(net "AGND_CURRENT_MONOB")
	)
	(via
		(at 368.8588 -147.2184)
		(size 0.5588)
		(drill 0.3048)
		(layers "F.Cu" "B.Cu")
		(net "AGND_CURRENT_MONOB")
	)
	(segment
		(start 141.548866 -144.038574)
		(end 141.548866 -144.864074)
		(width 0.508)
		(layer "F.Cu")
		(net "AGND_CURRENT_MONOA")
	)
	(segment
		(start 155.42514 -140.112496)
		(end 156.240226 -140.112496)
		(width 0.508)
		(layer "F.Cu")
		(net "AGND_CURRENT_MONOA")
	)
	(segment
		(start 153.004266 -139.149074)
		(end 152.089866 -139.149074)
		(width 0.254)
		(layer "F.Cu")
		(net "AGND_CURRENT_MONOA")
	)
	(segment
		(start 154.63774 -140.112496)
		(end 155.42514 -140.112496)
		(width 0.508)
		(layer "F.Cu")
		(net "AGND_CURRENT_MONOA")
	)
	(segment
		(start 144.977866 -137.879074)
		(end 145.727928 -137.129012)
		(width 0.254)
		(layer "F.Cu")
		(net "AGND_CURRENT_MONOA")
	)
	(segment
		(start 156.240226 -140.112496)
		(end 156.240226 -140.102844)
		(width 0.508)
		(layer "F.Cu")
		(net "AGND_CURRENT_MONOA")
	)
	(segment
		(start 144.469866 -131.211574)
		(end 144.469866 -130.259074)
		(width 0.508)
		(layer "F.Cu")
		(net "AGND_CURRENT_MONOA")
	)
	(segment
		(start 146.247866 -131.211574)
		(end 146.247866 -130.259074)
		(width 0.508)
		(layer "F.Cu")
		(net "AGND_CURRENT_MONOA")
	)
	(segment
		(start 156.247338 -143.770096)
		(end 156.247338 -143.752824)
		(width 0.508)
		(layer "F.Cu")
		(net "AGND_CURRENT_MONOA")
	)
	(segment
		(start 155.42514 -143.770096)
		(end 156.247338 -143.770096)
		(width 0.508)
		(layer "F.Cu")
		(net "AGND_CURRENT_MONOA")
	)
	(segment
		(start 154.48534 -143.770096)
		(end 155.42514 -143.770096)
		(width 0.508)
		(layer "F.Cu")
		(net "AGND_CURRENT_MONOA")
	)
	(segment
		(start 154.29484 -143.960596)
		(end 154.48534 -143.770096)
		(width 0.508)
		(layer "F.Cu")
		(net "AGND_CURRENT_MONOA")
	)
	(segment
		(start 145.727928 -137.129012)
		(end 145.727928 -135.402574)
		(width 0.254)
		(layer "F.Cu")
		(net "AGND_CURRENT_MONOA")
	)
	(segment
		(start 154.29484 -139.769596)
		(end 154.63774 -140.112496)
		(width 0.508)
		(layer "F.Cu")
		(net "AGND_CURRENT_MONOA")
	)
	(via
		(at 146.247866 -130.259074)
		(size 0.5588)
		(drill 0.3048)
		(layers "F.Cu" "B.Cu")
		(net "AGND_CURRENT_MONOA")
	)
	(via
		(at 147.248372 -146.667474)
		(size 0.5588)
		(drill 0.3048)
		(layers "F.Cu" "B.Cu")
		(net "AGND_CURRENT_MONOA")
	)
	(via
		(at 153.004266 -139.149074)
		(size 0.5588)
		(drill 0.3048)
		(layers "F.Cu" "B.Cu")
		(net "AGND_CURRENT_MONOA")
	)
	(via
		(at 148.406866 -146.667474)
		(size 0.5588)
		(drill 0.3048)
		(layers "F.Cu" "B.Cu")
		(net "AGND_CURRENT_MONOA")
	)
	(via
		(at 144.180814 -146.678142)
		(size 0.5588)
		(drill 0.3048)
		(layers "F.Cu" "B.Cu")
		(net "AGND_CURRENT_MONOA")
	)
	(via
		(at 144.977866 -137.879074)
		(size 0.5588)
		(drill 0.3048)
		(layers "F.Cu" "B.Cu")
		(net "AGND_CURRENT_MONOA")
	)
	(via
		(at 156.240226 -140.102844)
		(size 0.5588)
		(drill 0.3048)
		(layers "F.Cu" "B.Cu")
		(net "AGND_CURRENT_MONOA")
	)
	(via
		(at 144.469866 -130.259074)
		(size 0.5588)
		(drill 0.3048)
		(layers "F.Cu" "B.Cu")
		(net "AGND_CURRENT_MONOA")
	)
	(via
		(at 156.247338 -143.752824)
		(size 0.5588)
		(drill 0.3048)
		(layers "F.Cu" "B.Cu")
		(net "AGND_CURRENT_MONOA")
	)
	(via
		(at 140.72997 -146.422364)
		(size 0.6604)
		(drill 0.3302)
		(layers "F.Cu" "B.Cu")
		(net "AGND_CURRENT_MONOA")
	)
	(via
		(at 141.548866 -144.864074)
		(size 0.5588)
		(drill 0.3048)
		(layers "F.Cu" "B.Cu")
		(net "AGND_CURRENT_MONOA")
	)
	(via
		(at 150.565866 -146.667474)
		(size 0.5588)
		(drill 0.3048)
		(layers "F.Cu" "B.Cu")
		(net "AGND_CURRENT_MONOA")
	)
	(via
		(at 146.247866 -146.667474)
		(size 0.5588)
		(drill 0.3048)
		(layers "F.Cu" "B.Cu")
		(net "AGND_CURRENT_MONOA")
	)
	(via
		(at 142.818866 -146.667474)
		(size 0.5588)
		(drill 0.3048)
		(layers "F.Cu" "B.Cu")
		(net "AGND_CURRENT_MONOA")
	)
	(via
		(at 149.549866 -146.667474)
		(size 0.5588)
		(drill 0.3048)
		(layers "F.Cu" "B.Cu")
		(net "AGND_CURRENT_MONOA")
	)
	(via
		(at 145.137632 -146.6723)
		(size 0.5588)
		(drill 0.3048)
		(layers "F.Cu" "B.Cu")
		(net "AGND_CURRENT_MONOA")
	)
	(segment
		(start 239.014 -396.3543)
		(end 239.014 -397.3068)
		(width 0.508)
		(layer "F.Cu")
		(net "AGND_CURRENT_DPB")
	)
	(segment
		(start 246.928132 -391.736834)
		(end 246.928132 -391.735564)
		(width 0.508)
		(layer "F.Cu")
		(net "AGND_CURRENT_DPB")
	)
	(segment
		(start 240.3602 -381.7493)
		(end 240.3602 -380.8222)
		(width 0.508)
		(layer "F.Cu")
		(net "AGND_CURRENT_DPB")
	)
	(segment
		(start 245.872254 -389.617204)
		(end 246.888254 -389.617204)
		(width 0.508)
		(layer "F.Cu")
		(net "AGND_CURRENT_DPB")
	)
	(segment
		(start 245.824502 -391.964164)
		(end 246.051832 -391.736834)
		(width 0.508)
		(layer "F.Cu")
		(net "AGND_CURRENT_DPB")
	)
	(segment
		(start 240.03 -396.3543)
		(end 240.03 -397.3068)
		(width 0.508)
		(layer "F.Cu")
		(net "AGND_CURRENT_DPB")
	)
	(segment
		(start 246.992902 -391.801604)
		(end 246.928132 -391.736834)
		(width 0.508)
		(layer "F.Cu")
		(net "AGND_CURRENT_DPB")
	)
	(segment
		(start 241.046 -396.3543)
		(end 241.046 -397.3068)
		(width 0.508)
		(layer "F.Cu")
		(net "AGND_CURRENT_DPB")
	)
	(segment
		(start 247.856502 -392.662664)
		(end 246.992902 -392.662664)
		(width 0.508)
		(layer "F.Cu")
		(net "AGND_CURRENT_DPB")
	)
	(segment
		(start 247.856502 -395.456664)
		(end 246.992902 -395.456664)
		(width 0.508)
		(layer "F.Cu")
		(net "AGND_CURRENT_DPB")
	)
	(segment
		(start 246.051832 -391.736834)
		(end 246.928132 -391.736834)
		(width 0.508)
		(layer "F.Cu")
		(net "AGND_CURRENT_DPB")
	)
	(segment
		(start 244.348 -396.3543)
		(end 244.348 -397.3068)
		(width 0.508)
		(layer "F.Cu")
		(net "AGND_CURRENT_DPB")
	)
	(segment
		(start 239.510062 -387.666738)
		(end 239.510062 -385.9403)
		(width 0.254)
		(layer "F.Cu")
		(net "AGND_CURRENT_DPB")
	)
	(segment
		(start 231.9655 -392.2268)
		(end 231.9655 -393.1158)
		(width 0.508)
		(layer "F.Cu")
		(net "AGND_CURRENT_DPB")
	)
	(segment
		(start 232.7275 -390.9568)
		(end 231.6988 -390.9568)
		(width 0.508)
		(layer "F.Cu")
		(net "AGND_CURRENT_DPB")
	)
	(segment
		(start 231.6988 -390.9568)
		(end 231.6226 -391.033)
		(width 0.508)
		(layer "F.Cu")
		(net "AGND_CURRENT_DPB")
	)
	(segment
		(start 246.992902 -395.456664)
		(end 246.269002 -396.180564)
		(width 0.508)
		(layer "F.Cu")
		(net "AGND_CURRENT_DPB")
	)
	(segment
		(start 238.76 -388.4168)
		(end 239.510062 -387.666738)
		(width 0.254)
		(layer "F.Cu")
		(net "AGND_CURRENT_DPB")
	)
	(segment
		(start 238.252 -381.7493)
		(end 238.252 -380.7968)
		(width 0.508)
		(layer "F.Cu")
		(net "AGND_CURRENT_DPB")
	)
	(segment
		(start 231.6226 -391.8839)
		(end 231.9655 -392.2268)
		(width 0.508)
		(layer "F.Cu")
		(net "AGND_CURRENT_DPB")
	)
	(segment
		(start 231.6226 -391.033)
		(end 231.6226 -391.8839)
		(width 0.508)
		(layer "F.Cu")
		(net "AGND_CURRENT_DPB")
	)
	(segment
		(start 235.331 -394.5763)
		(end 235.331 -395.4018)
		(width 0.508)
		(layer "F.Cu")
		(net "AGND_CURRENT_DPB")
	)
	(segment
		(start 243.332 -396.3543)
		(end 243.332 -397.3068)
		(width 0.508)
		(layer "F.Cu")
		(net "AGND_CURRENT_DPB")
	)
	(segment
		(start 246.992902 -392.662664)
		(end 246.992902 -391.801604)
		(width 0.508)
		(layer "F.Cu")
		(net "AGND_CURRENT_DPB")
	)
	(segment
		(start 237.998 -396.3543)
		(end 237.998 -397.3068)
		(width 0.508)
		(layer "F.Cu")
		(net "AGND_CURRENT_DPB")
	)
	(segment
		(start 246.269002 -396.180564)
		(end 245.824502 -396.180564)
		(width 0.508)
		(layer "F.Cu")
		(net "AGND_CURRENT_DPB")
	)
	(segment
		(start 242.189 -396.0368)
		(end 242.189 -397.0528)
		(width 0.508)
		(layer "F.Cu")
		(net "AGND_CURRENT_DPB")
	)
	(segment
		(start 236.601 -396.3543)
		(end 236.601 -397.3068)
		(width 0.508)
		(layer "F.Cu")
		(net "AGND_CURRENT_DPB")
	)
	(via
		(at 238.76 -388.4168)
		(size 0.5588)
		(drill 0.3048)
		(layers "F.Cu" "B.Cu")
		(net "AGND_CURRENT_DPB")
	)
	(via
		(at 241.046 -397.3068)
		(size 0.5588)
		(drill 0.3048)
		(layers "F.Cu" "B.Cu")
		(net "AGND_CURRENT_DPB")
	)
	(via
		(at 235.331 -395.4018)
		(size 0.5588)
		(drill 0.3048)
		(layers "F.Cu" "B.Cu")
		(net "AGND_CURRENT_DPB")
	)
	(via
		(at 231.9655 -393.1158)
		(size 0.5588)
		(drill 0.3048)
		(layers "F.Cu" "B.Cu")
		(net "AGND_CURRENT_DPB")
	)
	(via
		(at 239.014 -397.3068)
		(size 0.5588)
		(drill 0.3048)
		(layers "F.Cu" "B.Cu")
		(net "AGND_CURRENT_DPB")
	)
	(via
		(at 237.998 -397.3068)
		(size 0.5588)
		(drill 0.3048)
		(layers "F.Cu" "B.Cu")
		(net "AGND_CURRENT_DPB")
	)
	(via
		(at 236.601 -397.3068)
		(size 0.5588)
		(drill 0.3048)
		(layers "F.Cu" "B.Cu")
		(net "AGND_CURRENT_DPB")
	)
	(via
		(at 246.888254 -389.617204)
		(size 0.5588)
		(drill 0.3048)
		(layers "F.Cu" "B.Cu")
		(net "AGND_CURRENT_DPB")
	)
	(via
		(at 240.03 -397.3068)
		(size 0.5588)
		(drill 0.3048)
		(layers "F.Cu" "B.Cu")
		(net "AGND_CURRENT_DPB")
	)
	(via
		(at 243.332 -397.3068)
		(size 0.5588)
		(drill 0.3048)
		(layers "F.Cu" "B.Cu")
		(net "AGND_CURRENT_DPB")
	)
	(via
		(at 244.348 -397.3068)
		(size 0.5588)
		(drill 0.3048)
		(layers "F.Cu" "B.Cu")
		(net "AGND_CURRENT_DPB")
	)
	(via
		(at 238.252 -380.7968)
		(size 0.5588)
		(drill 0.3048)
		(layers "F.Cu" "B.Cu")
		(net "AGND_CURRENT_DPB")
	)
	(via
		(at 247.856502 -395.456664)
		(size 0.5588)
		(drill 0.3048)
		(layers "F.Cu" "B.Cu")
		(net "AGND_CURRENT_DPB")
	)
	(via
		(at 242.189 -397.0528)
		(size 0.5588)
		(drill 0.3048)
		(layers "F.Cu" "B.Cu")
		(net "AGND_CURRENT_DPB")
	)
	(via
		(at 247.856502 -392.662664)
		(size 0.5588)
		(drill 0.3048)
		(layers "F.Cu" "B.Cu")
		(net "AGND_CURRENT_DPB")
	)
	(via
		(at 246.928132 -391.735564)
		(size 0.6604)
		(drill 0.3302)
		(layers "F.Cu" "B.Cu")
		(net "AGND_CURRENT_DPB")
	)
	(via
		(at 240.3602 -380.8222)
		(size 0.5588)
		(drill 0.3048)
		(layers "F.Cu" "B.Cu")
		(net "AGND_CURRENT_DPB")
	)
	(segment
		(start 236.050074 -108.49991)
		(end 233.20629 -108.49991)
		(width 0.17145)
		(layer "F.Cu")
		(net "SLOT3_SVR_ID0_GPIO3")
	)
	(segment
		(start 233.20629 -108.49991)
		(end 224.977452 -116.728748)
		(width 0.17145)
		(layer "F.Cu")
		(net "SLOT3_SVR_ID0_GPIO3")
	)
	(segment
		(start 224.977452 -116.728748)
		(end 224.1804 -116.728748)
		(width 0.17145)
		(layer "F.Cu")
		(net "SLOT3_SVR_ID0_GPIO3")
	)
	(segment
		(start 223.063816 -116.728748)
		(end 224.1804 -116.728748)
		(width 0.17145)
		(layer "F.Cu")
		(net "SLOT3_SVR_ID0_GPIO3")
	)
	(via
		(at 224.1804 -116.728748)
		(size 0.6604)
		(drill 0.3302)
		(layers "F.Cu" "B.Cu")
		(net "SLOT3_SVR_ID0_GPIO3")
	)
	(segment
		(start 223.0501 -115.5446)
		(end 224.155 -115.5446)
		(width 0.17145)
		(layer "F.Cu")
		(net "SLOT3_SVR_ID0_GPIO2")
	)
	(segment
		(start 238.05007 -107.499912)
		(end 233.063288 -107.499912)
		(width 0.17145)
		(layer "F.Cu")
		(net "SLOT3_SVR_ID0_GPIO2")
	)
	(segment
		(start 225.0186 -115.5446)
		(end 224.155 -115.5446)
		(width 0.17145)
		(layer "F.Cu")
		(net "SLOT3_SVR_ID0_GPIO2")
	)
	(segment
		(start 233.063288 -107.499912)
		(end 225.0186 -115.5446)
		(width 0.17145)
		(layer "F.Cu")
		(net "SLOT3_SVR_ID0_GPIO2")
	)
	(via
		(at 224.155 -115.5446)
		(size 0.6604)
		(drill 0.3302)
		(layers "F.Cu" "B.Cu")
		(net "SLOT3_SVR_ID0_GPIO2")
	)
	(segment
		(start 234.920282 -104.499918)
		(end 236.050074 -104.499918)
		(width 0.17145)
		(layer "F.Cu")
		(net "SLOT3_SVR_ID0_GPIO1")
	)
	(segment
		(start 224.155 -114.3508)
		(end 225.0694 -114.3508)
		(width 0.17145)
		(layer "F.Cu")
		(net "SLOT3_SVR_ID0_GPIO1")
	)
	(segment
		(start 225.0694 -114.3508)
		(end 234.920282 -104.499918)
		(width 0.17145)
		(layer "F.Cu")
		(net "SLOT3_SVR_ID0_GPIO1")
	)
	(segment
		(start 223.0501 -114.3508)
		(end 224.155 -114.3508)
		(width 0.17145)
		(layer "F.Cu")
		(net "SLOT3_SVR_ID0_GPIO1")
	)
	(via
		(at 224.155 -114.3508)
		(size 0.6604)
		(drill 0.3302)
		(layers "F.Cu" "B.Cu")
		(net "SLOT3_SVR_ID0_GPIO1")
	)
	(segment
		(start 224.1296 -113.147348)
		(end 224.952052 -113.147348)
		(width 0.17145)
		(layer "F.Cu")
		(net "SLOT3_SVR_ID0_GPIO0")
	)
	(segment
		(start 223.038416 -113.147348)
		(end 224.1296 -113.147348)
		(width 0.17145)
		(layer "F.Cu")
		(net "SLOT3_SVR_ID0_GPIO0")
	)
	(segment
		(start 224.952052 -113.147348)
		(end 234.59948 -103.49992)
		(width 0.17145)
		(layer "F.Cu")
		(net "SLOT3_SVR_ID0_GPIO0")
	)
	(segment
		(start 234.59948 -103.49992)
		(end 238.05007 -103.49992)
		(width 0.17145)
		(layer "F.Cu")
		(net "SLOT3_SVR_ID0_GPIO0")
	)
	(via
		(at 224.1296 -113.147348)
		(size 0.6604)
		(drill 0.3302)
		(layers "F.Cu" "B.Cu")
		(net "SLOT3_SVR_ID0_GPIO0")
	)
	(segment
		(start 299.962062 -77.09408)
		(end 299.239432 -77.81671)
		(width 0.17145)
		(layer "F.Cu")
		(net "SLOT1_SVR_ID0_GPIO3")
	)
	(segment
		(start 298.66209 -77.81671)
		(end 277.021798 -99.457002)
		(width 0.17145)
		(layer "F.Cu")
		(net "SLOT1_SVR_ID0_GPIO3")
	)
	(segment
		(start 299.962062 -75.24369)
		(end 299.962062 -77.09408)
		(width 0.17145)
		(layer "F.Cu")
		(net "SLOT1_SVR_ID0_GPIO3")
	)
	(segment
		(start 299.239432 -77.81671)
		(end 298.66209 -77.81671)
		(width 0.17145)
		(layer "F.Cu")
		(net "SLOT1_SVR_ID0_GPIO3")
	)
	(segment
		(start 277.021798 -106.771694)
		(end 278.750014 -108.49991)
		(width 0.17145)
		(layer "F.Cu")
		(net "SLOT1_SVR_ID0_GPIO3")
	)
	(segment
		(start 277.021798 -99.457002)
		(end 277.021798 -106.771694)
		(width 0.17145)
		(layer "F.Cu")
		(net "SLOT1_SVR_ID0_GPIO3")
	)
	(via
		(at 299.962062 -77.09408)
		(size 0.6604)
		(drill 0.3302)
		(layers "F.Cu" "B.Cu")
		(net "SLOT1_SVR_ID0_GPIO3")
	)
	(segment
		(start 278.9428 -109.7534)
		(end 269.052294 -109.7534)
		(width 0.17145)
		(layer "F.Cu")
		(net "SLOT1_SVR_ID0_GPIO2")
	)
	(segment
		(start 280.75001 -107.499912)
		(end 280.75001 -107.94619)
		(width 0.17145)
		(layer "F.Cu")
		(net "SLOT1_SVR_ID0_GPIO2")
	)
	(segment
		(start 269.052294 -109.7534)
		(end 268.456156 -109.157262)
		(width 0.17145)
		(layer "F.Cu")
		(net "SLOT1_SVR_ID0_GPIO2")
	)
	(segment
		(start 266.645898 -109.157262)
		(end 267.658596 -109.157262)
		(width 0.17145)
		(layer "F.Cu")
		(net "SLOT1_SVR_ID0_GPIO2")
	)
	(segment
		(start 268.456156 -109.157262)
		(end 267.658596 -109.157262)
		(width 0.17145)
		(layer "F.Cu")
		(net "SLOT1_SVR_ID0_GPIO2")
	)
	(segment
		(start 280.75001 -107.94619)
		(end 278.9428 -109.7534)
		(width 0.17145)
		(layer "F.Cu")
		(net "SLOT1_SVR_ID0_GPIO2")
	)
	(via
		(at 267.658596 -109.157262)
		(size 0.6604)
		(drill 0.3302)
		(layers "F.Cu" "B.Cu")
		(net "SLOT1_SVR_ID0_GPIO2")
	)
	(segment
		(start 277.725378 -103.475282)
		(end 278.750014 -104.499918)
		(width 0.17145)
		(layer "F.Cu")
		(net "SLOT1_SVR_ID0_GPIO1")
	)
	(segment
		(start 301.139352 -76.572872)
		(end 301.139352 -77.474064)
		(width 0.17145)
		(layer "F.Cu")
		(net "SLOT1_SVR_ID0_GPIO1")
	)
	(segment
		(start 298.92244 -78.429866)
		(end 277.725378 -99.626928)
		(width 0.17145)
		(layer "F.Cu")
		(net "SLOT1_SVR_ID0_GPIO1")
	)
	(segment
		(start 301.139352 -75.2348)
		(end 301.139352 -76.572872)
		(width 0.17145)
		(layer "F.Cu")
		(net "SLOT1_SVR_ID0_GPIO1")
	)
	(segment
		(start 300.18355 -78.429866)
		(end 298.92244 -78.429866)
		(width 0.17145)
		(layer "F.Cu")
		(net "SLOT1_SVR_ID0_GPIO1")
	)
	(segment
		(start 301.139352 -77.474064)
		(end 300.18355 -78.429866)
		(width 0.17145)
		(layer "F.Cu")
		(net "SLOT1_SVR_ID0_GPIO1")
	)
	(segment
		(start 277.725378 -99.626928)
		(end 277.725378 -103.475282)
		(width 0.17145)
		(layer "F.Cu")
		(net "SLOT1_SVR_ID0_GPIO1")
	)
	(via
		(at 301.139352 -76.572872)
		(size 0.6604)
		(drill 0.3302)
		(layers "F.Cu" "B.Cu")
		(net "SLOT1_SVR_ID0_GPIO1")
	)
	(segment
		(start 302.3108 -75.2221)
		(end 302.3108 -76.496672)
		(width 0.17145)
		(layer "F.Cu")
		(net "SLOT1_SVR_ID0_GPIO0")
	)
	(segment
		(start 279.759918 -98.771202)
		(end 279.759918 -102.509828)
		(width 0.17145)
		(layer "F.Cu")
		(net "SLOT1_SVR_ID0_GPIO0")
	)
	(segment
		(start 302.3108 -77.030072)
		(end 300.322488 -79.018384)
		(width 0.17145)
		(layer "F.Cu")
		(net "SLOT1_SVR_ID0_GPIO0")
	)
	(segment
		(start 299.512736 -79.018384)
		(end 279.759918 -98.771202)
		(width 0.17145)
		(layer "F.Cu")
		(net "SLOT1_SVR_ID0_GPIO0")
	)
	(segment
		(start 279.759918 -102.509828)
		(end 280.75001 -103.49992)
		(width 0.17145)
		(layer "F.Cu")
		(net "SLOT1_SVR_ID0_GPIO0")
	)
	(segment
		(start 302.3108 -76.496672)
		(end 302.3108 -77.030072)
		(width 0.17145)
		(layer "F.Cu")
		(net "SLOT1_SVR_ID0_GPIO0")
	)
	(segment
		(start 300.322488 -79.018384)
		(end 299.512736 -79.018384)
		(width 0.17145)
		(layer "F.Cu")
		(net "SLOT1_SVR_ID0_GPIO0")
	)
	(via
		(at 302.3108 -76.496672)
		(size 0.6604)
		(drill 0.3302)
		(layers "F.Cu" "B.Cu")
		(net "SLOT1_SVR_ID0_GPIO0")
	)
	(segment
		(start 284.22092 -282.64866)
		(end 284.22092 -281.2034)
		(width 0.17145)
		(layer "F.Cu")
		(net "IO_EXP2_LED_SDA")
	)
	(segment
		(start 283.21 -283.65958)
		(end 283.972 -282.89758)
		(width 0.17145)
		(layer "F.Cu")
		(net "IO_EXP2_LED_SDA")
	)
	(segment
		(start 283.21 -284.0863)
		(end 283.21 -283.65958)
		(width 0.17145)
		(layer "F.Cu")
		(net "IO_EXP2_LED_SDA")
	)
	(segment
		(start 283.972 -282.89758)
		(end 284.22092 -282.64866)
		(width 0.17145)
		(layer "F.Cu")
		(net "IO_EXP2_LED_SDA")
	)
	(via
		(at 283.972 -282.89758)
		(size 0.6604)
		(drill 0.3302)
		(layers "F.Cu" "B.Cu")
		(net "IO_EXP2_LED_SDA")
	)
	(segment
		(start 285.115 -282.426918)
		(end 285.115 -282.89758)
		(width 0.17145)
		(layer "F.Cu")
		(net "IO_EXP2_LED_SCL")
	)
	(segment
		(start 284.87116 -282.183078)
		(end 285.115 -282.426918)
		(width 0.17145)
		(layer "F.Cu")
		(net "IO_EXP2_LED_SCL")
	)
	(segment
		(start 285.115 -283.3243)
		(end 284.353 -284.0863)
		(width 0.17145)
		(layer "F.Cu")
		(net "IO_EXP2_LED_SCL")
	)
	(segment
		(start 284.87116 -281.2034)
		(end 284.87116 -282.183078)
		(width 0.17145)
		(layer "F.Cu")
		(net "IO_EXP2_LED_SCL")
	)
	(segment
		(start 285.115 -282.89758)
		(end 285.115 -283.3243)
		(width 0.17145)
		(layer "F.Cu")
		(net "IO_EXP2_LED_SCL")
	)
	(via
		(at 285.115 -282.89758)
		(size 0.6604)
		(drill 0.3302)
		(layers "F.Cu" "B.Cu")
		(net "IO_EXP2_LED_SCL")
	)
	(segment
		(start 285.623 -273.717004)
		(end 285.841948 -273.935952)
		(width 0.17145)
		(layer "F.Cu")
		(net "IO_EXP2_HDD_FAULT_A2")
	)
	(segment
		(start 285.623 -272.7579)
		(end 285.623 -273.717004)
		(width 0.17145)
		(layer "F.Cu")
		(net "IO_EXP2_HDD_FAULT_A2")
	)
	(segment
		(start 284.87116 -275.5646)
		(end 284.87116 -274.90674)
		(width 0.17145)
		(layer "F.Cu")
		(net "IO_EXP2_HDD_FAULT_A2")
	)
	(segment
		(start 284.87116 -274.90674)
		(end 285.841948 -273.935952)
		(width 0.17145)
		(layer "F.Cu")
		(net "IO_EXP2_HDD_FAULT_A2")
	)
	(segment
		(start 286.7406 -272.7579)
		(end 285.623 -272.7579)
		(width 0.17145)
		(layer "F.Cu")
		(net "IO_EXP2_HDD_FAULT_A2")
	)
	(via
		(at 285.841948 -273.935952)
		(size 0.6604)
		(drill 0.3302)
		(layers "F.Cu" "B.Cu")
		(net "IO_EXP2_HDD_FAULT_A2")
	)
	(segment
		(start 284.525466 -272.879566)
		(end 284.4038 -272.7579)
		(width 0.17145)
		(layer "F.Cu")
		(net "IO_EXP2_HDD_FAULT_A1")
	)
	(segment
		(start 284.525466 -273.8755)
		(end 284.525466 -272.879566)
		(width 0.17145)
		(layer "F.Cu")
		(net "IO_EXP2_HDD_FAULT_A1")
	)
	(segment
		(start 284.4038 -272.7579)
		(end 283.2608 -272.7579)
		(width 0.17145)
		(layer "F.Cu")
		(net "IO_EXP2_HDD_FAULT_A1")
	)
	(segment
		(start 284.22092 -274.180046)
		(end 284.525466 -273.8755)
		(width 0.17145)
		(layer "F.Cu")
		(net "IO_EXP2_HDD_FAULT_A1")
	)
	(segment
		(start 284.22092 -275.5646)
		(end 284.22092 -274.180046)
		(width 0.17145)
		(layer "F.Cu")
		(net "IO_EXP2_HDD_FAULT_A1")
	)
	(via
		(at 284.525466 -273.8755)
		(size 0.6604)
		(drill 0.3302)
		(layers "F.Cu" "B.Cu")
		(net "IO_EXP2_HDD_FAULT_A1")
	)
	(segment
		(start 286.2834 -283.3243)
		(end 286.2834 -282.889452)
		(width 0.17145)
		(layer "F.Cu")
		(net "IO_EXP2_HDD_FAULT_A0")
	)
	(segment
		(start 285.5214 -281.2034)
		(end 285.5214 -282.127452)
		(width 0.17145)
		(layer "F.Cu")
		(net "IO_EXP2_HDD_FAULT_A0")
	)
	(segment
		(start 285.5214 -284.0863)
		(end 286.2834 -283.3243)
		(width 0.17145)
		(layer "F.Cu")
		(net "IO_EXP2_HDD_FAULT_A0")
	)
	(segment
		(start 285.5214 -282.127452)
		(end 286.2834 -282.889452)
		(width 0.17145)
		(layer "F.Cu")
		(net "IO_EXP2_HDD_FAULT_A0")
	)
	(segment
		(start 286.7152 -284.0863)
		(end 285.5214 -284.0863)
		(width 0.17145)
		(layer "F.Cu")
		(net "IO_EXP2_HDD_FAULT_A0")
	)
	(via
		(at 286.2834 -282.889452)
		(size 0.6604)
		(drill 0.3302)
		(layers "F.Cu" "B.Cu")
		(net "IO_EXP2_HDD_FAULT_A0")
	)
	(segment
		(start 273.29892 -281.2034)
		(end 273.29892 -282.480258)
		(width 0.17145)
		(layer "F.Cu")
		(net "IO_EXP1_LED_SDA")
	)
	(segment
		(start 272.923 -282.856178)
		(end 272.923 -283.309822)
		(width 0.17145)
		(layer "F.Cu")
		(net "IO_EXP1_LED_SDA")
	)
	(segment
		(start 273.29892 -282.480258)
		(end 272.923 -282.856178)
		(width 0.17145)
		(layer "F.Cu")
		(net "IO_EXP1_LED_SDA")
	)
	(segment
		(start 272.923 -283.309822)
		(end 272.923 -284.2895)
		(width 0.17145)
		(layer "F.Cu")
		(net "IO_EXP1_LED_SDA")
	)
	(via
		(at 272.923 -283.309822)
		(size 0.6604)
		(drill 0.3302)
		(layers "F.Cu" "B.Cu")
		(net "IO_EXP1_LED_SDA")
	)
	(segment
		(start 274.066 -283.334206)
		(end 274.066 -284.2895)
		(width 0.17145)
		(layer "F.Cu")
		(net "IO_EXP1_LED_SCL")
	)
	(segment
		(start 274.066 -282.605226)
		(end 274.066 -283.334206)
		(width 0.17145)
		(layer "F.Cu")
		(net "IO_EXP1_LED_SCL")
	)
	(segment
		(start 273.94916 -281.2034)
		(end 273.94916 -282.488386)
		(width 0.17145)
		(layer "F.Cu")
		(net "IO_EXP1_LED_SCL")
	)
	(segment
		(start 273.94916 -282.488386)
		(end 274.066 -282.605226)
		(width 0.17145)
		(layer "F.Cu")
		(net "IO_EXP1_LED_SCL")
	)
	(via
		(at 274.066 -283.334206)
		(size 0.6604)
		(drill 0.3302)
		(layers "F.Cu" "B.Cu")
		(net "IO_EXP1_LED_SCL")
	)
	(segment
		(start 276.098 -272.7325)
		(end 274.955 -272.7325)
		(width 0.17145)
		(layer "F.Cu")
		(net "IO_EXP1_HDD_FAULT_A2")
	)
	(segment
		(start 273.947636 -275.5646)
		(end 273.947636 -273.73961)
		(width 0.17145)
		(layer "F.Cu")
		(net "IO_EXP1_HDD_FAULT_A2")
	)
	(segment
		(start 273.94916 -275.5646)
		(end 273.947636 -275.5646)
		(width 0.17145)
		(layer "F.Cu")
		(net "IO_EXP1_HDD_FAULT_A2")
	)
	(segment
		(start 274.954746 -272.7325)
		(end 273.947636 -273.73961)
		(width 0.17145)
		(layer "F.Cu")
		(net "IO_EXP1_HDD_FAULT_A2")
	)
	(segment
		(start 274.955 -272.7325)
		(end 274.954746 -272.7325)
		(width 0.17145)
		(layer "F.Cu")
		(net "IO_EXP1_HDD_FAULT_A2")
	)
	(via
		(at 273.947636 -273.73961)
		(size 0.6604)
		(drill 0.3302)
		(layers "F.Cu" "B.Cu")
		(net "IO_EXP1_HDD_FAULT_A2")
	)
	(segment
		(start 273.29892 -275.5646)
		(end 273.29892 -274.165568)
		(width 0.17145)
		(layer "F.Cu")
		(net "IO_EXP1_HDD_FAULT_A1")
	)
	(segment
		(start 273.812 -272.7325)
		(end 272.669 -272.7325)
		(width 0.17145)
		(layer "F.Cu")
		(net "IO_EXP1_HDD_FAULT_A1")
	)
	(segment
		(start 273.29892 -274.165568)
		(end 272.870168 -273.736816)
		(width 0.17145)
		(layer "F.Cu")
		(net "IO_EXP1_HDD_FAULT_A1")
	)
	(segment
		(start 272.669 -272.7325)
		(end 272.669 -273.535648)
		(width 0.17145)
		(layer "F.Cu")
		(net "IO_EXP1_HDD_FAULT_A1")
	)
	(segment
		(start 272.669 -273.535648)
		(end 272.870168 -273.736816)
		(width 0.17145)
		(layer "F.Cu")
		(net "IO_EXP1_HDD_FAULT_A1")
	)
	(via
		(at 272.870168 -273.736816)
		(size 0.6604)
		(drill 0.3302)
		(layers "F.Cu" "B.Cu")
		(net "IO_EXP1_HDD_FAULT_A1")
	)
	(segment
		(start 275.745448 -282.730448)
		(end 276.057868 -283.042868)
		(width 0.17145)
		(layer "F.Cu")
		(net "IO_EXP1_HDD_FAULT_A0")
	)
	(segment
		(start 274.5994 -282.4734)
		(end 274.856448 -282.730448)
		(width 0.17145)
		(layer "F.Cu")
		(net "IO_EXP1_HDD_FAULT_A0")
	)
	(segment
		(start 274.856448 -282.730448)
		(end 275.745448 -282.730448)
		(width 0.17145)
		(layer "F.Cu")
		(net "IO_EXP1_HDD_FAULT_A0")
	)
	(segment
		(start 277.4188 -284.2641)
		(end 276.2758 -284.2641)
		(width 0.17145)
		(layer "F.Cu")
		(net "IO_EXP1_HDD_FAULT_A0")
	)
	(segment
		(start 276.2758 -284.2641)
		(end 276.2758 -283.2608)
		(width 0.17145)
		(layer "F.Cu")
		(net "IO_EXP1_HDD_FAULT_A0")
	)
	(segment
		(start 276.2758 -283.2608)
		(end 276.057868 -283.042868)
		(width 0.17145)
		(layer "F.Cu")
		(net "IO_EXP1_HDD_FAULT_A0")
	)
	(segment
		(start 274.5994 -281.2034)
		(end 274.5994 -282.4734)
		(width 0.17145)
		(layer "F.Cu")
		(net "IO_EXP1_HDD_FAULT_A0")
	)
	(via
		(at 276.057868 -283.042868)
		(size 0.6604)
		(drill 0.3302)
		(layers "F.Cu" "B.Cu")
		(net "IO_EXP1_HDD_FAULT_A0")
	)
	(segment
		(start 260.83895 -282.00985)
		(end 260.681724 -282.00985)
		(width 0.17145)
		(layer "F.Cu")
		(net "IO_EXP0_LED_SDA")
	)
	(segment
		(start 261.23392 -280.9494)
		(end 261.23392 -281.61488)
		(width 0.17145)
		(layer "F.Cu")
		(net "IO_EXP0_LED_SDA")
	)
	(segment
		(start 261.23392 -281.61488)
		(end 260.83895 -282.00985)
		(width 0.17145)
		(layer "F.Cu")
		(net "IO_EXP0_LED_SDA")
	)
	(segment
		(start 259.6896 -283.9847)
		(end 259.6896 -283.001974)
		(width 0.17145)
		(layer "F.Cu")
		(net "IO_EXP0_LED_SDA")
	)
	(segment
		(start 260.681724 -282.00985)
		(end 259.6896 -283.001974)
		(width 0.17145)
		(layer "F.Cu")
		(net "IO_EXP0_LED_SDA")
	)
	(via
		(at 259.6896 -283.001974)
		(size 0.6604)
		(drill 0.3302)
		(layers "F.Cu" "B.Cu")
		(net "IO_EXP0_LED_SDA")
	)
	(segment
		(start 260.8326 -283.9847)
		(end 260.8326 -282.983178)
		(width 0.17145)
		(layer "F.Cu")
		(net "IO_EXP0_LED_SCL")
	)
	(segment
		(start 260.8326 -282.7274)
		(end 260.8326 -282.983178)
		(width 0.17145)
		(layer "F.Cu")
		(net "IO_EXP0_LED_SCL")
	)
	(segment
		(start 261.88416 -281.67584)
		(end 260.8326 -282.7274)
		(width 0.17145)
		(layer "F.Cu")
		(net "IO_EXP0_LED_SCL")
	)
	(segment
		(start 261.88416 -280.9494)
		(end 261.88416 -281.67584)
		(width 0.17145)
		(layer "F.Cu")
		(net "IO_EXP0_LED_SCL")
	)
	(via
		(at 260.8326 -282.983178)
		(size 0.6604)
		(drill 0.3302)
		(layers "F.Cu" "B.Cu")
		(net "IO_EXP0_LED_SCL")
	)
	(segment
		(start 261.88416 -275.3106)
		(end 261.88416 -274.55114)
		(width 0.17145)
		(layer "F.Cu")
		(net "IO_EXP0_HDD_FAULT_A2")
	)
	(segment
		(start 264.541 -272.7325)
		(end 263.398 -272.7325)
		(width 0.17145)
		(layer "F.Cu")
		(net "IO_EXP0_HDD_FAULT_A2")
	)
	(segment
		(start 263.398 -273.0373)
		(end 262.653526 -273.781774)
		(width 0.17145)
		(layer "F.Cu")
		(net "IO_EXP0_HDD_FAULT_A2")
	)
	(segment
		(start 261.88416 -274.55114)
		(end 262.653526 -273.781774)
		(width 0.17145)
		(layer "F.Cu")
		(net "IO_EXP0_HDD_FAULT_A2")
	)
	(segment
		(start 263.398 -272.7325)
		(end 263.398 -273.0373)
		(width 0.17145)
		(layer "F.Cu")
		(net "IO_EXP0_HDD_FAULT_A2")
	)
	(via
		(at 262.653526 -273.781774)
		(size 0.6604)
		(drill 0.3302)
		(layers "F.Cu" "B.Cu")
		(net "IO_EXP0_HDD_FAULT_A2")
	)
	(segment
		(start 261.23392 -274.00758)
		(end 261.452106 -273.789394)
		(width 0.17145)
		(layer "F.Cu")
		(net "IO_EXP0_HDD_FAULT_A1")
	)
	(segment
		(start 262.255 -272.7325)
		(end 262.255 -272.9865)
		(width 0.17145)
		(layer "F.Cu")
		(net "IO_EXP0_HDD_FAULT_A1")
	)
	(segment
		(start 261.112 -272.7325)
		(end 262.255 -272.7325)
		(width 0.17145)
		(layer "F.Cu")
		(net "IO_EXP0_HDD_FAULT_A1")
	)
	(segment
		(start 262.255 -272.9865)
		(end 261.452106 -273.789394)
		(width 0.17145)
		(layer "F.Cu")
		(net "IO_EXP0_HDD_FAULT_A1")
	)
	(segment
		(start 261.23392 -275.3106)
		(end 261.23392 -274.00758)
		(width 0.17145)
		(layer "F.Cu")
		(net "IO_EXP0_HDD_FAULT_A1")
	)
	(via
		(at 261.452106 -273.789394)
		(size 0.6604)
		(drill 0.3302)
		(layers "F.Cu" "B.Cu")
		(net "IO_EXP0_HDD_FAULT_A1")
	)
	(segment
		(start 261.9756 -283.9847)
		(end 261.9756 -282.616656)
		(width 0.17145)
		(layer "F.Cu")
		(net "IO_EXP0_HDD_FAULT_A0")
	)
	(segment
		(start 262.5344 -280.9494)
		(end 262.5344 -282.057856)
		(width 0.17145)
		(layer "F.Cu")
		(net "IO_EXP0_HDD_FAULT_A0")
	)
	(segment
		(start 263.1186 -283.9847)
		(end 261.9756 -283.9847)
		(width 0.17145)
		(layer "F.Cu")
		(net "IO_EXP0_HDD_FAULT_A0")
	)
	(segment
		(start 262.5344 -282.057856)
		(end 261.9756 -282.616656)
		(width 0.17145)
		(layer "F.Cu")
		(net "IO_EXP0_HDD_FAULT_A0")
	)
	(via
		(at 261.9756 -282.616656)
		(size 0.6604)
		(drill 0.3302)
		(layers "F.Cu" "B.Cu")
		(net "IO_EXP0_HDD_FAULT_A0")
	)
	(segment
		(start 409.299664 -210.130136)
		(end 409.299664 -222.8596)
		(width 0.17145)
		(layer "F.Cu")
		(net "FLT_HDD9")
	)
	(segment
		(start 409.144978 -241.49177)
		(end 409.299664 -241.337084)
		(width 0.17145)
		(layer "F.Cu")
		(net "FLT_HDD9")
	)
	(segment
		(start 409.299664 -241.337084)
		(end 409.299664 -222.8596)
		(width 0.17145)
		(layer "F.Cu")
		(net "FLT_HDD9")
	)
	(via
		(at 409.299664 -222.8596)
		(size 0.6604)
		(drill 0.3302)
		(layers "F.Cu" "B.Cu")
		(net "FLT_HDD9")
	)
	(segment
		(start 377.749562 -241.337084)
		(end 377.594876 -241.49177)
		(width 0.17145)
		(layer "F.Cu")
		(net "FLT_HDD8")
	)
	(segment
		(start 377.749562 -210.130136)
		(end 377.749562 -225.5266)
		(width 0.17145)
		(layer "F.Cu")
		(net "FLT_HDD8")
	)
	(segment
		(start 377.749562 -225.5266)
		(end 377.749562 -241.337084)
		(width 0.17145)
		(layer "F.Cu")
		(net "FLT_HDD8")
	)
	(via
		(at 377.749562 -225.5266)
		(size 0.6604)
		(drill 0.3302)
		(layers "F.Cu" "B.Cu")
		(net "FLT_HDD8")
	)
	(segment
		(start 346.045028 -241.49177)
		(end 346.199714 -241.337084)
		(width 0.17145)
		(layer "F.Cu")
		(net "FLT_HDD7")
	)
	(segment
		(start 346.199714 -210.130136)
		(end 346.199714 -225.6536)
		(width 0.17145)
		(layer "F.Cu")
		(net "FLT_HDD7")
	)
	(segment
		(start 346.199714 -241.337084)
		(end 346.199714 -225.6536)
		(width 0.17145)
		(layer "F.Cu")
		(net "FLT_HDD7")
	)
	(via
		(at 346.199714 -225.6536)
		(size 0.6604)
		(drill 0.3302)
		(layers "F.Cu" "B.Cu")
		(net "FLT_HDD7")
	)
	(segment
		(start 320.990468 -230.591868)
		(end 314.649612 -224.251012)
		(width 0.17145)
		(layer "F.Cu")
		(net "FLT_HDD6")
	)
	(segment
		(start 314.649612 -224.251012)
		(end 314.649612 -210.130136)
		(width 0.17145)
		(layer "F.Cu")
		(net "FLT_HDD6")
	)
	(segment
		(start 320.990468 -238.327692)
		(end 320.990468 -241.448844)
		(width 0.17145)
		(layer "F.Cu")
		(net "FLT_HDD6")
	)
	(segment
		(start 320.990468 -238.327692)
		(end 320.990468 -230.591868)
		(width 0.17145)
		(layer "F.Cu")
		(net "FLT_HDD6")
	)
	(via
		(at 320.990468 -238.327692)
		(size 0.6604)
		(drill 0.3302)
		(layers "F.Cu" "B.Cu")
		(net "FLT_HDD6")
	)
	(segment
		(start 175.049688 -241.337084)
		(end 175.049688 -235.8136)
		(width 0.17145)
		(layer "F.Cu")
		(net "FLT_HDD5")
	)
	(segment
		(start 174.895002 -241.49177)
		(end 175.049688 -241.337084)
		(width 0.17145)
		(layer "F.Cu")
		(net "FLT_HDD5")
	)
	(segment
		(start 175.049688 -210.130136)
		(end 175.049688 -235.8136)
		(width 0.17145)
		(layer "F.Cu")
		(net "FLT_HDD5")
	)
	(via
		(at 175.049688 -235.8136)
		(size 0.6604)
		(drill 0.3302)
		(layers "F.Cu" "B.Cu")
		(net "FLT_HDD5")
	)
	(segment
		(start 143.3449 -240.28273)
		(end 143.3449 -239.17656)
		(width 0.17145)
		(layer "F.Cu")
		(net "FLT_HDD4")
	)
	(segment
		(start 143.499586 -210.130136)
		(end 143.499586 -211.386166)
		(width 0.17145)
		(layer "F.Cu")
		(net "FLT_HDD4")
	)
	(segment
		(start 143.3449 -241.49177)
		(end 143.3449 -240.28273)
		(width 0.17145)
		(layer "F.Cu")
		(net "FLT_HDD4")
	)
	(via
		(at 143.3449 -239.17656)
		(size 0.5588)
		(drill 0.3048)
		(layers "F.Cu" "B.Cu")
		(net "FLT_HDD4")
	)
	(via
		(at 143.499586 -211.386166)
		(size 0.5588)
		(drill 0.3048)
		(layers "F.Cu" "B.Cu")
		(net "FLT_HDD4")
	)
	(via
		(at 143.3449 -240.28273)
		(size 0.6604)
		(drill 0.3302)
		(layers "F.Cu" "B.Cu")
		(net "FLT_HDD4")
	)
	(segment
		(start 143.3449 -239.17656)
		(end 143.499586 -239.021874)
		(width 0.13335)
		(layer "In9.Cu")
		(net "FLT_HDD4")
	)
	(segment
		(start 143.499586 -239.021874)
		(end 143.499586 -211.386166)
		(width 0.13335)
		(layer "In9.Cu")
		(net "FLT_HDD4")
	)
	(segment
		(start 472.1352 -327.279)
		(end 470.9922 -327.279)
		(width 0.17145)
		(layer "F.Cu")
		(net "FLT_HDD35")
	)
	(segment
		(start 472.5924 -325.9328)
		(end 472.5924 -326.8218)
		(width 0.17145)
		(layer "F.Cu")
		(net "FLT_HDD35")
	)
	(segment
		(start 470.4588 -326.7456)
		(end 470.4588 -315.1632)
		(width 0.17145)
		(layer "F.Cu")
		(net "FLT_HDD35")
	)
	(segment
		(start 472.5924 -326.8218)
		(end 472.1352 -327.279)
		(width 0.17145)
		(layer "F.Cu")
		(net "FLT_HDD35")
	)
	(segment
		(start 470.4588 -315.1632)
		(end 468.84463 -313.54903)
		(width 0.17145)
		(layer "F.Cu")
		(net "FLT_HDD35")
	)
	(segment
		(start 472.399614 -325.740014)
		(end 472.5924 -325.9328)
		(width 0.17145)
		(layer "F.Cu")
		(net "FLT_HDD35")
	)
	(segment
		(start 467.635336 -295.077134)
		(end 467.279736 -295.432734)
		(width 0.17145)
		(layer "F.Cu")
		(net "FLT_HDD35")
	)
	(segment
		(start 467.279736 -295.432734)
		(end 467.279736 -311.984136)
		(width 0.17145)
		(layer "F.Cu")
		(net "FLT_HDD35")
	)
	(segment
		(start 472.399614 -325.13016)
		(end 472.399614 -325.740014)
		(width 0.17145)
		(layer "F.Cu")
		(net "FLT_HDD35")
	)
	(segment
		(start 467.279736 -311.984136)
		(end 468.84463 -313.54903)
		(width 0.17145)
		(layer "F.Cu")
		(net "FLT_HDD35")
	)
	(segment
		(start 470.9922 -327.279)
		(end 470.4588 -326.7456)
		(width 0.17145)
		(layer "F.Cu")
		(net "FLT_HDD35")
	)
	(via
		(at 468.84463 -313.54903)
		(size 0.6604)
		(drill 0.3302)
		(layers "F.Cu" "B.Cu")
		(net "FLT_HDD35")
	)
	(segment
		(start 441.0456 -326.009)
		(end 441.0456 -326.7964)
		(width 0.17145)
		(layer "F.Cu")
		(net "FLT_HDD34")
	)
	(segment
		(start 440.849512 -325.812912)
		(end 441.0456 -326.009)
		(width 0.17145)
		(layer "F.Cu")
		(net "FLT_HDD34")
	)
	(segment
		(start 440.849512 -325.13016)
		(end 440.849512 -325.812912)
		(width 0.17145)
		(layer "F.Cu")
		(net "FLT_HDD34")
	)
	(segment
		(start 437.671718 -326.54113)
		(end 437.671718 -321.6656)
		(width 0.17145)
		(layer "F.Cu")
		(net "FLT_HDD34")
	)
	(segment
		(start 441.0456 -326.7964)
		(end 440.5122 -327.3298)
		(width 0.17145)
		(layer "F.Cu")
		(net "FLT_HDD34")
	)
	(segment
		(start 440.5122 -327.3298)
		(end 438.460388 -327.3298)
		(width 0.17145)
		(layer "F.Cu")
		(net "FLT_HDD34")
	)
	(segment
		(start 438.460388 -327.3298)
		(end 437.671718 -326.54113)
		(width 0.17145)
		(layer "F.Cu")
		(net "FLT_HDD34")
	)
	(segment
		(start 437.671718 -295.186862)
		(end 437.671718 -321.6656)
		(width 0.17145)
		(layer "F.Cu")
		(net "FLT_HDD34")
	)
	(via
		(at 437.671718 -321.6656)
		(size 0.6604)
		(drill 0.3302)
		(layers "F.Cu" "B.Cu")
		(net "FLT_HDD34")
	)
	(segment
		(start 409.299664 -325.13016)
		(end 409.299664 -325.812912)
		(width 0.17145)
		(layer "F.Cu")
		(net "FLT_HDD33")
	)
	(segment
		(start 407.870152 -327.8632)
		(end 407.387552 -327.3806)
		(width 0.17145)
		(layer "F.Cu")
		(net "FLT_HDD33")
	)
	(segment
		(start 408.962352 -327.8632)
		(end 407.870152 -327.8632)
		(width 0.17145)
		(layer "F.Cu")
		(net "FLT_HDD33")
	)
	(segment
		(start 409.299664 -325.812912)
		(end 409.495752 -326.009)
		(width 0.17145)
		(layer "F.Cu")
		(net "FLT_HDD33")
	)
	(segment
		(start 411.539944 -295.200324)
		(end 411.539944 -296.95648)
		(width 0.17145)
		(layer "F.Cu")
		(net "FLT_HDD33")
	)
	(segment
		(start 409.495752 -327.3298)
		(end 408.962352 -327.8632)
		(width 0.17145)
		(layer "F.Cu")
		(net "FLT_HDD33")
	)
	(segment
		(start 410.4386 -309.0418)
		(end 410.4386 -304.8508)
		(width 0.17145)
		(layer "F.Cu")
		(net "FLT_HDD33")
	)
	(segment
		(start 410.4386 -298.057824)
		(end 410.4386 -304.8508)
		(width 0.17145)
		(layer "F.Cu")
		(net "FLT_HDD33")
	)
	(segment
		(start 411.539944 -296.95648)
		(end 410.4386 -298.057824)
		(width 0.17145)
		(layer "F.Cu")
		(net "FLT_HDD33")
	)
	(segment
		(start 407.387552 -327.3806)
		(end 407.387552 -312.092848)
		(width 0.17145)
		(layer "F.Cu")
		(net "FLT_HDD33")
	)
	(segment
		(start 407.387552 -312.092848)
		(end 410.4386 -309.0418)
		(width 0.17145)
		(layer "F.Cu")
		(net "FLT_HDD33")
	)
	(segment
		(start 409.495752 -326.009)
		(end 409.495752 -327.3298)
		(width 0.17145)
		(layer "F.Cu")
		(net "FLT_HDD33")
	)
	(via
		(at 410.4386 -304.8508)
		(size 0.6604)
		(drill 0.3302)
		(layers "F.Cu" "B.Cu")
		(net "FLT_HDD33")
	)
	(segment
		(start 377.94565 -326.7964)
		(end 377.41225 -327.3298)
		(width 0.17145)
		(layer "F.Cu")
		(net "FLT_HDD32")
	)
	(segment
		(start 377.749562 -325.13016)
		(end 377.749562 -325.812912)
		(width 0.17145)
		(layer "F.Cu")
		(net "FLT_HDD32")
	)
	(segment
		(start 377.749562 -325.812912)
		(end 377.94565 -326.009)
		(width 0.17145)
		(layer "F.Cu")
		(net "FLT_HDD32")
	)
	(segment
		(start 374.892062 -295.154858)
		(end 374.892062 -312.335926)
		(width 0.17145)
		(layer "F.Cu")
		(net "FLT_HDD32")
	)
	(segment
		(start 376.21845 -326.6694)
		(end 376.21845 -317.9318)
		(width 0.17145)
		(layer "F.Cu")
		(net "FLT_HDD32")
	)
	(segment
		(start 376.21845 -313.662314)
		(end 376.21845 -317.9318)
		(width 0.17145)
		(layer "F.Cu")
		(net "FLT_HDD32")
	)
	(segment
		(start 374.892062 -312.335926)
		(end 376.21845 -313.662314)
		(width 0.17145)
		(layer "F.Cu")
		(net "FLT_HDD32")
	)
	(segment
		(start 377.94565 -326.009)
		(end 377.94565 -326.7964)
		(width 0.17145)
		(layer "F.Cu")
		(net "FLT_HDD32")
	)
	(segment
		(start 376.87885 -327.3298)
		(end 376.21845 -326.6694)
		(width 0.17145)
		(layer "F.Cu")
		(net "FLT_HDD32")
	)
	(segment
		(start 377.41225 -327.3298)
		(end 376.87885 -327.3298)
		(width 0.17145)
		(layer "F.Cu")
		(net "FLT_HDD32")
	)
	(via
		(at 376.21845 -317.9318)
		(size 0.6604)
		(drill 0.3302)
		(layers "F.Cu" "B.Cu")
		(net "FLT_HDD32")
	)
	(segment
		(start 344.948002 -327.3298)
		(end 345.862402 -327.3298)
		(width 0.17145)
		(layer "F.Cu")
		(net "FLT_HDD31")
	)
	(segment
		(start 343.235534 -295.186862)
		(end 343.235534 -307.8226)
		(width 0.17145)
		(layer "F.Cu")
		(net "FLT_HDD31")
	)
	(segment
		(start 343.235534 -307.8226)
		(end 343.235534 -325.617332)
		(width 0.17145)
		(layer "F.Cu")
		(net "FLT_HDD31")
	)
	(segment
		(start 346.199714 -325.812912)
		(end 346.199714 -325.13016)
		(width 0.17145)
		(layer "F.Cu")
		(net "FLT_HDD31")
	)
	(segment
		(start 345.862402 -327.3298)
		(end 346.395802 -326.7964)
		(width 0.17145)
		(layer "F.Cu")
		(net "FLT_HDD31")
	)
	(segment
		(start 346.395802 -326.009)
		(end 346.199714 -325.812912)
		(width 0.17145)
		(layer "F.Cu")
		(net "FLT_HDD31")
	)
	(segment
		(start 346.395802 -326.7964)
		(end 346.395802 -326.009)
		(width 0.17145)
		(layer "F.Cu")
		(net "FLT_HDD31")
	)
	(segment
		(start 343.235534 -325.617332)
		(end 344.948002 -327.3298)
		(width 0.17145)
		(layer "F.Cu")
		(net "FLT_HDD31")
	)
	(via
		(at 343.235534 -307.8226)
		(size 0.6604)
		(drill 0.3302)
		(layers "F.Cu" "B.Cu")
		(net "FLT_HDD31")
	)
	(segment
		(start 314.649612 -325.13016)
		(end 314.649612 -325.812912)
		(width 0.17145)
		(layer "F.Cu")
		(net "FLT_HDD30")
	)
	(segment
		(start 314.8457 -326.009)
		(end 314.8457 -326.7964)
		(width 0.17145)
		(layer "F.Cu")
		(net "FLT_HDD30")
	)
	(segment
		(start 314.649612 -325.812912)
		(end 314.8457 -326.009)
		(width 0.17145)
		(layer "F.Cu")
		(net "FLT_HDD30")
	)
	(segment
		(start 314.3123 -327.3298)
		(end 310.062626 -327.3298)
		(width 0.17145)
		(layer "F.Cu")
		(net "FLT_HDD30")
	)
	(segment
		(start 310.062626 -327.3298)
		(end 308.91607 -326.183244)
		(width 0.17145)
		(layer "F.Cu")
		(net "FLT_HDD30")
	)
	(segment
		(start 314.8457 -326.7964)
		(end 314.3123 -327.3298)
		(width 0.17145)
		(layer "F.Cu")
		(net "FLT_HDD30")
	)
	(segment
		(start 308.91607 -326.183244)
		(end 308.91607 -300.342554)
		(width 0.17145)
		(layer "F.Cu")
		(net "FLT_HDD30")
	)
	(segment
		(start 308.91607 -295.197276)
		(end 308.91607 -300.342554)
		(width 0.17145)
		(layer "F.Cu")
		(net "FLT_HDD30")
	)
	(via
		(at 308.91607 -300.342554)
		(size 0.6604)
		(drill 0.3302)
		(layers "F.Cu" "B.Cu")
		(net "FLT_HDD30")
	)
	(segment
		(start 111.949738 -210.130136)
		(end 111.949738 -211.386166)
		(width 0.17145)
		(layer "F.Cu")
		(net "FLT_HDD3")
	)
	(segment
		(start 111.795052 -241.49177)
		(end 111.795052 -239.64773)
		(width 0.17145)
		(layer "F.Cu")
		(net "FLT_HDD3")
	)
	(segment
		(start 111.795052 -239.64773)
		(end 111.795052 -238.28756)
		(width 0.17145)
		(layer "F.Cu")
		(net "FLT_HDD3")
	)
	(via
		(at 111.795052 -239.64773)
		(size 0.6604)
		(drill 0.3302)
		(layers "F.Cu" "B.Cu")
		(net "FLT_HDD3")
	)
	(via
		(at 111.949738 -211.386166)
		(size 0.5588)
		(drill 0.3048)
		(layers "F.Cu" "B.Cu")
		(net "FLT_HDD3")
	)
	(via
		(at 111.795052 -238.28756)
		(size 0.5588)
		(drill 0.3048)
		(layers "F.Cu" "B.Cu")
		(net "FLT_HDD3")
	)
	(segment
		(start 111.949738 -238.132874)
		(end 111.949738 -211.386166)
		(width 0.13335)
		(layer "In9.Cu")
		(net "FLT_HDD3")
	)
	(segment
		(start 111.795052 -238.28756)
		(end 111.949738 -238.132874)
		(width 0.13335)
		(layer "In9.Cu")
		(net "FLT_HDD3")
	)
	(segment
		(start 170.8658 -326.9488)
		(end 170.053 -326.136)
		(width 0.17145)
		(layer "F.Cu")
		(net "FLT_HDD29")
	)
	(segment
		(start 161.878264 -305.072796)
		(end 161.878264 -306.682902)
		(width 0.17145)
		(layer "F.Cu")
		(net "FLT_HDD29")
	)
	(segment
		(start 174.625 -326.9488)
		(end 170.8658 -326.9488)
		(width 0.17145)
		(layer "F.Cu")
		(net "FLT_HDD29")
	)
	(segment
		(start 170.053 -314.857638)
		(end 167.193214 -311.997852)
		(width 0.17145)
		(layer "F.Cu")
		(net "FLT_HDD29")
	)
	(segment
		(start 175.3108 -326.263)
		(end 174.625 -326.9488)
		(width 0.17145)
		(layer "F.Cu")
		(net "FLT_HDD29")
	)
	(segment
		(start 170.053 -326.136)
		(end 170.053 -314.857638)
		(width 0.17145)
		(layer "F.Cu")
		(net "FLT_HDD29")
	)
	(segment
		(start 175.049688 -325.13016)
		(end 175.049688 -325.595488)
		(width 0.17145)
		(layer "F.Cu")
		(net "FLT_HDD29")
	)
	(segment
		(start 175.3108 -325.8566)
		(end 175.3108 -326.263)
		(width 0.17145)
		(layer "F.Cu")
		(net "FLT_HDD29")
	)
	(segment
		(start 161.878264 -306.682902)
		(end 167.193214 -311.997852)
		(width 0.17145)
		(layer "F.Cu")
		(net "FLT_HDD29")
	)
	(segment
		(start 175.049688 -325.595488)
		(end 175.3108 -325.8566)
		(width 0.17145)
		(layer "F.Cu")
		(net "FLT_HDD29")
	)
	(via
		(at 167.193214 -311.997852)
		(size 0.6604)
		(drill 0.3302)
		(layers "F.Cu" "B.Cu")
		(net "FLT_HDD29")
	)
	(segment
		(start 140.980922 -323.327776)
		(end 135.822182 -318.169036)
		(width 0.17145)
		(layer "F.Cu")
		(net "FLT_HDD28")
	)
	(segment
		(start 130.328162 -312.675016)
		(end 130.328162 -305.093878)
		(width 0.17145)
		(layer "F.Cu")
		(net "FLT_HDD28")
	)
	(segment
		(start 140.980922 -324.597522)
		(end 140.980922 -323.327776)
		(width 0.17145)
		(layer "F.Cu")
		(net "FLT_HDD28")
	)
	(segment
		(start 143.728186 -326.295512)
		(end 143.544798 -326.4789)
		(width 0.17145)
		(layer "F.Cu")
		(net "FLT_HDD28")
	)
	(segment
		(start 143.544798 -326.4789)
		(end 142.8623 -326.4789)
		(width 0.17145)
		(layer "F.Cu")
		(net "FLT_HDD28")
	)
	(segment
		(start 143.728186 -325.846186)
		(end 143.728186 -326.295512)
		(width 0.17145)
		(layer "F.Cu")
		(net "FLT_HDD28")
	)
	(segment
		(start 142.8623 -326.4789)
		(end 140.980922 -324.597522)
		(width 0.17145)
		(layer "F.Cu")
		(net "FLT_HDD28")
	)
	(segment
		(start 143.499586 -325.617586)
		(end 143.728186 -325.846186)
		(width 0.17145)
		(layer "F.Cu")
		(net "FLT_HDD28")
	)
	(segment
		(start 143.499586 -325.13016)
		(end 143.499586 -325.617586)
		(width 0.17145)
		(layer "F.Cu")
		(net "FLT_HDD28")
	)
	(segment
		(start 135.822182 -318.169036)
		(end 130.328162 -312.675016)
		(width 0.17145)
		(layer "F.Cu")
		(net "FLT_HDD28")
	)
	(via
		(at 135.822182 -318.169036)
		(size 0.6604)
		(drill 0.3302)
		(layers "F.Cu" "B.Cu")
		(net "FLT_HDD28")
	)
	(segment
		(start 111.949738 -325.595488)
		(end 111.949738 -325.13016)
		(width 0.17145)
		(layer "F.Cu")
		(net "FLT_HDD27")
	)
	(segment
		(start 106.95305 -316.011306)
		(end 106.95305 -326.136)
		(width 0.17145)
		(layer "F.Cu")
		(net "FLT_HDD27")
	)
	(segment
		(start 98.767646 -307.825902)
		(end 98.767646 -305.115468)
		(width 0.17145)
		(layer "F.Cu")
		(net "FLT_HDD27")
	)
	(segment
		(start 112.178338 -325.824088)
		(end 111.949738 -325.595488)
		(width 0.17145)
		(layer "F.Cu")
		(net "FLT_HDD27")
	)
	(segment
		(start 106.95305 -326.136)
		(end 107.81665 -326.9996)
		(width 0.17145)
		(layer "F.Cu")
		(net "FLT_HDD27")
	)
	(segment
		(start 99.524058 -308.582314)
		(end 98.767646 -307.825902)
		(width 0.17145)
		(layer "F.Cu")
		(net "FLT_HDD27")
	)
	(segment
		(start 112.178338 -326.295512)
		(end 112.178338 -325.824088)
		(width 0.17145)
		(layer "F.Cu")
		(net "FLT_HDD27")
	)
	(segment
		(start 99.524058 -308.582314)
		(end 106.95305 -316.011306)
		(width 0.17145)
		(layer "F.Cu")
		(net "FLT_HDD27")
	)
	(segment
		(start 111.47425 -326.9996)
		(end 112.178338 -326.295512)
		(width 0.17145)
		(layer "F.Cu")
		(net "FLT_HDD27")
	)
	(segment
		(start 107.81665 -326.9996)
		(end 111.47425 -326.9996)
		(width 0.17145)
		(layer "F.Cu")
		(net "FLT_HDD27")
	)
	(via
		(at 99.524058 -308.582314)
		(size 0.6604)
		(drill 0.3302)
		(layers "F.Cu" "B.Cu")
		(net "FLT_HDD27")
	)
	(segment
		(start 79.924148 -326.9996)
		(end 79.263748 -326.9996)
		(width 0.17145)
		(layer "F.Cu")
		(net "FLT_HDD26")
	)
	(segment
		(start 79.263748 -326.9996)
		(end 75.402948 -323.1388)
		(width 0.17145)
		(layer "F.Cu")
		(net "FLT_HDD26")
	)
	(segment
		(start 80.628236 -325.865236)
		(end 80.628236 -326.295512)
		(width 0.17145)
		(layer "F.Cu")
		(net "FLT_HDD26")
	)
	(segment
		(start 67.206876 -313.185556)
		(end 71.345552 -317.324232)
		(width 0.17145)
		(layer "F.Cu")
		(net "FLT_HDD26")
	)
	(segment
		(start 67.206876 -305.147472)
		(end 67.206876 -313.185556)
		(width 0.17145)
		(layer "F.Cu")
		(net "FLT_HDD26")
	)
	(segment
		(start 80.399636 -325.636636)
		(end 80.628236 -325.865236)
		(width 0.17145)
		(layer "F.Cu")
		(net "FLT_HDD26")
	)
	(segment
		(start 80.399636 -325.13016)
		(end 80.399636 -325.636636)
		(width 0.17145)
		(layer "F.Cu")
		(net "FLT_HDD26")
	)
	(segment
		(start 75.402948 -321.381628)
		(end 71.345552 -317.324232)
		(width 0.17145)
		(layer "F.Cu")
		(net "FLT_HDD26")
	)
	(segment
		(start 80.628236 -326.295512)
		(end 79.924148 -326.9996)
		(width 0.17145)
		(layer "F.Cu")
		(net "FLT_HDD26")
	)
	(segment
		(start 75.402948 -323.1388)
		(end 75.402948 -321.381628)
		(width 0.17145)
		(layer "F.Cu")
		(net "FLT_HDD26")
	)
	(via
		(at 71.345552 -317.324232)
		(size 0.6604)
		(drill 0.3302)
		(layers "F.Cu" "B.Cu")
		(net "FLT_HDD26")
	)
	(segment
		(start 48.849534 -325.595488)
		(end 48.849534 -325.13016)
		(width 0.17145)
		(layer "F.Cu")
		(net "FLT_HDD25")
	)
	(segment
		(start 37.474652 -308.334918)
		(end 43.852846 -314.713112)
		(width 0.17145)
		(layer "F.Cu")
		(net "FLT_HDD25")
	)
	(segment
		(start 43.852846 -314.713112)
		(end 43.852846 -326.136)
		(width 0.17145)
		(layer "F.Cu")
		(net "FLT_HDD25")
	)
	(segment
		(start 43.852846 -326.136)
		(end 44.716446 -326.9996)
		(width 0.17145)
		(layer "F.Cu")
		(net "FLT_HDD25")
	)
	(segment
		(start 44.716446 -326.9996)
		(end 48.374046 -326.9996)
		(width 0.17145)
		(layer "F.Cu")
		(net "FLT_HDD25")
	)
	(segment
		(start 49.078134 -325.824088)
		(end 48.849534 -325.595488)
		(width 0.17145)
		(layer "F.Cu")
		(net "FLT_HDD25")
	)
	(segment
		(start 49.078134 -326.295512)
		(end 49.078134 -325.824088)
		(width 0.17145)
		(layer "F.Cu")
		(net "FLT_HDD25")
	)
	(segment
		(start 48.374046 -326.9996)
		(end 49.078134 -326.295512)
		(width 0.17145)
		(layer "F.Cu")
		(net "FLT_HDD25")
	)
	(segment
		(start 35.667188 -305.190398)
		(end 35.667188 -306.527454)
		(width 0.17145)
		(layer "F.Cu")
		(net "FLT_HDD25")
	)
	(segment
		(start 35.667188 -306.527454)
		(end 37.474652 -308.334918)
		(width 0.17145)
		(layer "F.Cu")
		(net "FLT_HDD25")
	)
	(via
		(at 37.474652 -308.334918)
		(size 0.6604)
		(drill 0.3302)
		(layers "F.Cu" "B.Cu")
		(net "FLT_HDD25")
	)
	(segment
		(start 7.62 -306.7558)
		(end 7.62 -306.3494)
		(width 0.17145)
		(layer "F.Cu")
		(net "FLT_HDD24")
	)
	(segment
		(start 17.299686 -325.595488)
		(end 17.528286 -325.824088)
		(width 0.17145)
		(layer "F.Cu")
		(net "FLT_HDD24")
	)
	(segment
		(start 11.693398 -325.5264)
		(end 11.693398 -310.829198)
		(width 0.17145)
		(layer "F.Cu")
		(net "FLT_HDD24")
	)
	(segment
		(start 13.166598 -326.9996)
		(end 11.693398 -325.5264)
		(width 0.17145)
		(layer "F.Cu")
		(net "FLT_HDD24")
	)
	(segment
		(start 11.693398 -310.829198)
		(end 7.62 -306.7558)
		(width 0.17145)
		(layer "F.Cu")
		(net "FLT_HDD24")
	)
	(segment
		(start 17.528286 -326.295512)
		(end 16.824198 -326.9996)
		(width 0.17145)
		(layer "F.Cu")
		(net "FLT_HDD24")
	)
	(segment
		(start 7.62 -305.054)
		(end 7.62 -306.3494)
		(width 0.17145)
		(layer "F.Cu")
		(net "FLT_HDD24")
	)
	(segment
		(start 17.528286 -325.824088)
		(end 17.528286 -326.295512)
		(width 0.17145)
		(layer "F.Cu")
		(net "FLT_HDD24")
	)
	(segment
		(start 16.824198 -326.9996)
		(end 13.166598 -326.9996)
		(width 0.17145)
		(layer "F.Cu")
		(net "FLT_HDD24")
	)
	(segment
		(start 17.299686 -325.13016)
		(end 17.299686 -325.595488)
		(width 0.17145)
		(layer "F.Cu")
		(net "FLT_HDD24")
	)
	(via
		(at 7.62 -306.3494)
		(size 0.6604)
		(drill 0.3302)
		(layers "F.Cu" "B.Cu")
		(net "FLT_HDD24")
	)
	(segment
		(start 472.244928 -126.492)
		(end 472.399614 -126.337314)
		(width 0.17145)
		(layer "F.Cu")
		(net "FLT_HDD23")
	)
	(segment
		(start 472.399614 -95.130366)
		(end 472.399614 -114.808)
		(width 0.17145)
		(layer "F.Cu")
		(net "FLT_HDD23")
	)
	(segment
		(start 472.399614 -126.337314)
		(end 472.399614 -114.808)
		(width 0.17145)
		(layer "F.Cu")
		(net "FLT_HDD23")
	)
	(via
		(at 472.399614 -114.808)
		(size 0.6604)
		(drill 0.3302)
		(layers "F.Cu" "B.Cu")
		(net "FLT_HDD23")
	)
	(segment
		(start 440.849512 -126.337314)
		(end 440.849512 -121.06402)
		(width 0.17145)
		(layer "F.Cu")
		(net "FLT_HDD22")
	)
	(segment
		(start 440.849512 -95.130366)
		(end 440.849512 -121.06402)
		(width 0.17145)
		(layer "F.Cu")
		(net "FLT_HDD22")
	)
	(segment
		(start 440.694826 -126.492)
		(end 440.849512 -126.337314)
		(width 0.17145)
		(layer "F.Cu")
		(net "FLT_HDD22")
	)
	(via
		(at 440.849512 -121.06402)
		(size 0.6604)
		(drill 0.3302)
		(layers "F.Cu" "B.Cu")
		(net "FLT_HDD22")
	)
	(segment
		(start 409.144978 -126.492)
		(end 409.299664 -126.337314)
		(width 0.17145)
		(layer "F.Cu")
		(net "FLT_HDD21")
	)
	(segment
		(start 409.299664 -95.130366)
		(end 409.299664 -118.1608)
		(width 0.17145)
		(layer "F.Cu")
		(net "FLT_HDD21")
	)
	(segment
		(start 409.299664 -126.337314)
		(end 409.299664 -118.1608)
		(width 0.17145)
		(layer "F.Cu")
		(net "FLT_HDD21")
	)
	(via
		(at 409.299664 -118.1608)
		(size 0.6604)
		(drill 0.3302)
		(layers "F.Cu" "B.Cu")
		(net "FLT_HDD21")
	)
	(segment
		(start 377.749562 -126.337314)
		(end 377.749562 -113.8682)
		(width 0.17145)
		(layer "F.Cu")
		(net "FLT_HDD20")
	)
	(segment
		(start 377.749562 -95.130366)
		(end 377.749562 -113.8682)
		(width 0.17145)
		(layer "F.Cu")
		(net "FLT_HDD20")
	)
	(segment
		(start 377.594876 -126.492)
		(end 377.749562 -126.337314)
		(width 0.17145)
		(layer "F.Cu")
		(net "FLT_HDD20")
	)
	(via
		(at 377.749562 -113.8682)
		(size 0.6604)
		(drill 0.3302)
		(layers "F.Cu" "B.Cu")
		(net "FLT_HDD20")
	)
	(segment
		(start 80.399636 -210.130136)
		(end 80.399636 -211.386166)
		(width 0.17145)
		(layer "F.Cu")
		(net "FLT_HDD2")
	)
	(segment
		(start 80.1624 -237.1344)
		(end 80.1624 -237.664752)
		(width 0.17145)
		(layer "F.Cu")
		(net "FLT_HDD2")
	)
	(segment
		(start 80.24495 -241.49177)
		(end 80.24495 -239.64773)
		(width 0.17145)
		(layer "F.Cu")
		(net "FLT_HDD2")
	)
	(segment
		(start 80.1624 -237.664752)
		(end 80.6196 -238.121952)
		(width 0.17145)
		(layer "F.Cu")
		(net "FLT_HDD2")
	)
	(segment
		(start 80.6196 -238.121952)
		(end 80.6196 -239.27308)
		(width 0.17145)
		(layer "F.Cu")
		(net "FLT_HDD2")
	)
	(segment
		(start 80.6196 -239.27308)
		(end 80.24495 -239.64773)
		(width 0.17145)
		(layer "F.Cu")
		(net "FLT_HDD2")
	)
	(via
		(at 80.1624 -237.1344)
		(size 0.5588)
		(drill 0.3048)
		(layers "F.Cu" "B.Cu")
		(net "FLT_HDD2")
	)
	(via
		(at 80.399636 -211.386166)
		(size 0.5588)
		(drill 0.3048)
		(layers "F.Cu" "B.Cu")
		(net "FLT_HDD2")
	)
	(via
		(at 80.24495 -239.64773)
		(size 0.6604)
		(drill 0.3302)
		(layers "F.Cu" "B.Cu")
		(net "FLT_HDD2")
	)
	(segment
		(start 80.7212 -211.70773)
		(end 80.7212 -236.5756)
		(width 0.13335)
		(layer "In9.Cu")
		(net "FLT_HDD2")
	)
	(segment
		(start 80.399636 -211.386166)
		(end 80.7212 -211.70773)
		(width 0.13335)
		(layer "In9.Cu")
		(net "FLT_HDD2")
	)
	(segment
		(start 80.7212 -236.5756)
		(end 80.1624 -237.1344)
		(width 0.13335)
		(layer "In9.Cu")
		(net "FLT_HDD2")
	)
	(segment
		(start 345.410028 -124.741686)
		(end 346.199714 -123.952)
		(width 0.17145)
		(layer "F.Cu")
		(net "FLT_HDD19")
	)
	(segment
		(start 346.199714 -123.952)
		(end 346.199714 -109.1946)
		(width 0.17145)
		(layer "F.Cu")
		(net "FLT_HDD19")
	)
	(segment
		(start 346.199714 -95.130366)
		(end 346.199714 -109.1946)
		(width 0.17145)
		(layer "F.Cu")
		(net "FLT_HDD19")
	)
	(segment
		(start 345.410028 -126.492)
		(end 345.410028 -124.741686)
		(width 0.17145)
		(layer "F.Cu")
		(net "FLT_HDD19")
	)
	(via
		(at 346.199714 -109.1946)
		(size 0.6604)
		(drill 0.3302)
		(layers "F.Cu" "B.Cu")
		(net "FLT_HDD19")
	)
	(segment
		(start 321.279012 -120.288812)
		(end 319.151 -118.1608)
		(width 0.17145)
		(layer "F.Cu")
		(net "FLT_HDD18")
	)
	(segment
		(start 314.649612 -113.659412)
		(end 314.649612 -95.130366)
		(width 0.17145)
		(layer "F.Cu")
		(net "FLT_HDD18")
	)
	(segment
		(start 321.279012 -126.598934)
		(end 321.279012 -120.288812)
		(width 0.17145)
		(layer "F.Cu")
		(net "FLT_HDD18")
	)
	(segment
		(start 319.151 -118.1608)
		(end 314.649612 -113.659412)
		(width 0.17145)
		(layer "F.Cu")
		(net "FLT_HDD18")
	)
	(via
		(at 319.151 -118.1608)
		(size 0.6604)
		(drill 0.3302)
		(layers "F.Cu" "B.Cu")
		(net "FLT_HDD18")
	)
	(segment
		(start 164.506402 -127.6096)
		(end 164.506402 -128.524)
		(width 0.17145)
		(layer "F.Cu")
		(net "FLT_HDD17")
	)
	(segment
		(start 175.049688 -98.037904)
		(end 175.049688 -96.590104)
		(width 0.17145)
		(layer "F.Cu")
		(net "FLT_HDD17")
	)
	(segment
		(start 175.049688 -96.590104)
		(end 175.049688 -95.130366)
		(width 0.17145)
		(layer "F.Cu")
		(net "FLT_HDD17")
	)
	(via
		(at 175.049688 -98.037904)
		(size 0.5588)
		(drill 0.3048)
		(layers "F.Cu" "B.Cu")
		(net "FLT_HDD17")
	)
	(via
		(at 175.049688 -96.590104)
		(size 0.6604)
		(drill 0.3302)
		(layers "F.Cu" "B.Cu")
		(net "FLT_HDD17")
	)
	(via
		(at 164.506402 -127.6096)
		(size 0.5588)
		(drill 0.3048)
		(layers "F.Cu" "B.Cu")
		(net "FLT_HDD17")
	)
	(segment
		(start 164.506402 -121.357644)
		(end 174.780448 -111.083598)
		(width 0.13335)
		(layer "In9.Cu")
		(net "FLT_HDD17")
	)
	(segment
		(start 174.780448 -98.307144)
		(end 175.049688 -98.037904)
		(width 0.13335)
		(layer "In9.Cu")
		(net "FLT_HDD17")
	)
	(segment
		(start 174.780448 -111.083598)
		(end 174.780448 -98.307144)
		(width 0.13335)
		(layer "In9.Cu")
		(net "FLT_HDD17")
	)
	(segment
		(start 164.506402 -127.6096)
		(end 164.506402 -121.357644)
		(width 0.13335)
		(layer "In9.Cu")
		(net "FLT_HDD17")
	)
	(segment
		(start 143.499586 -96.386396)
		(end 143.499586 -95.130366)
		(width 0.17145)
		(layer "F.Cu")
		(net "FLT_HDD16")
	)
	(segment
		(start 135.7249 -124.95276)
		(end 135.7249 -126.492)
		(width 0.17145)
		(layer "F.Cu")
		(net "FLT_HDD16")
	)
	(segment
		(start 135.7249 -123.865386)
		(end 135.7249 -124.95276)
		(width 0.17145)
		(layer "F.Cu")
		(net "FLT_HDD16")
	)
	(via
		(at 135.7249 -123.865386)
		(size 0.5588)
		(drill 0.3048)
		(layers "F.Cu" "B.Cu")
		(net "FLT_HDD16")
	)
	(via
		(at 143.499586 -96.386396)
		(size 0.5588)
		(drill 0.3048)
		(layers "F.Cu" "B.Cu")
		(net "FLT_HDD16")
	)
	(via
		(at 135.7249 -124.95276)
		(size 0.6604)
		(drill 0.3302)
		(layers "F.Cu" "B.Cu")
		(net "FLT_HDD16")
	)
	(segment
		(start 143.230346 -104.563672)
		(end 143.230346 -96.655636)
		(width 0.13335)
		(layer "In9.Cu")
		(net "FLT_HDD16")
	)
	(segment
		(start 143.230346 -96.655636)
		(end 143.499586 -96.386396)
		(width 0.13335)
		(layer "In9.Cu")
		(net "FLT_HDD16")
	)
	(segment
		(start 135.7249 -112.069118)
		(end 143.230346 -104.563672)
		(width 0.13335)
		(layer "In9.Cu")
		(net "FLT_HDD16")
	)
	(segment
		(start 135.7249 -123.865386)
		(end 135.7249 -112.069118)
		(width 0.13335)
		(layer "In9.Cu")
		(net "FLT_HDD16")
	)
	(segment
		(start 111.795052 -123.886722)
		(end 111.795052 -125.011942)
		(width 0.17145)
		(layer "F.Cu")
		(net "FLT_HDD15")
	)
	(segment
		(start 111.949738 -96.386396)
		(end 111.949738 -95.130366)
		(width 0.17145)
		(layer "F.Cu")
		(net "FLT_HDD15")
	)
	(segment
		(start 111.795052 -125.011942)
		(end 111.795052 -126.492)
		(width 0.17145)
		(layer "F.Cu")
		(net "FLT_HDD15")
	)
	(via
		(at 111.949738 -96.386396)
		(size 0.5588)
		(drill 0.3048)
		(layers "F.Cu" "B.Cu")
		(net "FLT_HDD15")
	)
	(via
		(at 111.795052 -123.886722)
		(size 0.5588)
		(drill 0.3048)
		(layers "F.Cu" "B.Cu")
		(net "FLT_HDD15")
	)
	(via
		(at 111.795052 -125.011942)
		(size 0.6604)
		(drill 0.3302)
		(layers "F.Cu" "B.Cu")
		(net "FLT_HDD15")
	)
	(segment
		(start 111.795052 -96.541082)
		(end 111.949738 -96.386396)
		(width 0.13335)
		(layer "In9.Cu")
		(net "FLT_HDD15")
	)
	(segment
		(start 111.795052 -123.886722)
		(end 111.795052 -96.541082)
		(width 0.13335)
		(layer "In9.Cu")
		(net "FLT_HDD15")
	)
	(segment
		(start 80.24495 -123.28779)
		(end 80.24495 -124.860812)
		(width 0.17145)
		(layer "F.Cu")
		(net "FLT_HDD14")
	)
	(segment
		(start 80.399636 -95.130366)
		(end 80.399636 -96.386396)
		(width 0.17145)
		(layer "F.Cu")
		(net "FLT_HDD14")
	)
	(segment
		(start 80.24495 -124.860812)
		(end 80.24495 -126.492)
		(width 0.17145)
		(layer "F.Cu")
		(net "FLT_HDD14")
	)
	(via
		(at 80.399636 -96.386396)
		(size 0.5588)
		(drill 0.3048)
		(layers "F.Cu" "B.Cu")
		(net "FLT_HDD14")
	)
	(via
		(at 80.24495 -124.860812)
		(size 0.6604)
		(drill 0.3302)
		(layers "F.Cu" "B.Cu")
		(net "FLT_HDD14")
	)
	(via
		(at 80.24495 -123.28779)
		(size 0.5588)
		(drill 0.3048)
		(layers "F.Cu" "B.Cu")
		(net "FLT_HDD14")
	)
	(segment
		(start 80.24495 -123.28779)
		(end 80.24495 -96.541082)
		(width 0.13335)
		(layer "In9.Cu")
		(net "FLT_HDD14")
	)
	(segment
		(start 80.24495 -96.541082)
		(end 80.399636 -96.386396)
		(width 0.13335)
		(layer "In9.Cu")
		(net "FLT_HDD14")
	)
	(segment
		(start 48.849534 -95.130366)
		(end 48.849534 -103.124)
		(width 0.17145)
		(layer "F.Cu")
		(net "FLT_HDD13")
	)
	(segment
		(start 48.849534 -103.124)
		(end 48.849534 -126.337314)
		(width 0.17145)
		(layer "F.Cu")
		(net "FLT_HDD13")
	)
	(segment
		(start 48.849534 -126.337314)
		(end 48.694848 -126.492)
		(width 0.17145)
		(layer "F.Cu")
		(net "FLT_HDD13")
	)
	(via
		(at 48.849534 -103.124)
		(size 0.6604)
		(drill 0.3302)
		(layers "F.Cu" "B.Cu")
		(net "FLT_HDD13")
	)
	(segment
		(start 17.145 -126.492)
		(end 17.299686 -126.337314)
		(width 0.17145)
		(layer "F.Cu")
		(net "FLT_HDD12")
	)
	(segment
		(start 17.299686 -126.337314)
		(end 17.299686 -115.1382)
		(width 0.17145)
		(layer "F.Cu")
		(net "FLT_HDD12")
	)
	(segment
		(start 17.299686 -115.1382)
		(end 17.299686 -95.130366)
		(width 0.17145)
		(layer "F.Cu")
		(net "FLT_HDD12")
	)
	(via
		(at 17.299686 -115.1382)
		(size 0.6604)
		(drill 0.3302)
		(layers "F.Cu" "B.Cu")
		(net "FLT_HDD12")
	)
	(segment
		(start 472.399614 -210.130136)
		(end 472.399614 -210.79968)
		(width 0.17145)
		(layer "F.Cu")
		(net "FLT_HDD11")
	)
	(segment
		(start 471.73134 -211.467954)
		(end 471.73134 -212.981032)
		(width 0.17145)
		(layer "F.Cu")
		(net "FLT_HDD11")
	)
	(segment
		(start 451.527164 -233.185208)
		(end 451.527164 -236.917992)
		(width 0.17145)
		(layer "F.Cu")
		(net "FLT_HDD11")
	)
	(segment
		(start 472.399614 -210.79968)
		(end 471.73134 -211.467954)
		(width 0.17145)
		(layer "F.Cu")
		(net "FLT_HDD11")
	)
	(segment
		(start 471.73134 -212.981032)
		(end 451.527164 -233.185208)
		(width 0.17145)
		(layer "F.Cu")
		(net "FLT_HDD11")
	)
	(segment
		(start 451.527164 -241.488976)
		(end 451.527164 -236.917992)
		(width 0.17145)
		(layer "F.Cu")
		(net "FLT_HDD11")
	)
	(via
		(at 451.527164 -236.917992)
		(size 0.6604)
		(drill 0.3302)
		(layers "F.Cu" "B.Cu")
		(net "FLT_HDD11")
	)
	(segment
		(start 440.694826 -241.49177)
		(end 440.849512 -241.337084)
		(width 0.17145)
		(layer "F.Cu")
		(net "FLT_HDD10")
	)
	(segment
		(start 440.849512 -210.130136)
		(end 440.849512 -224.4852)
		(width 0.17145)
		(layer "F.Cu")
		(net "FLT_HDD10")
	)
	(segment
		(start 440.849512 -241.337084)
		(end 440.849512 -224.4852)
		(width 0.17145)
		(layer "F.Cu")
		(net "FLT_HDD10")
	)
	(via
		(at 440.849512 -224.4852)
		(size 0.6604)
		(drill 0.3302)
		(layers "F.Cu" "B.Cu")
		(net "FLT_HDD10")
	)
	(segment
		(start 50.473102 -215.115902)
		(end 50.473102 -233.099102)
		(width 0.17145)
		(layer "F.Cu")
		(net "FLT_HDD1")
	)
	(segment
		(start 55.26024 -241.225578)
		(end 55.044848 -241.44097)
		(width 0.17145)
		(layer "F.Cu")
		(net "FLT_HDD1")
	)
	(segment
		(start 48.849534 -210.130136)
		(end 48.849534 -213.492334)
		(width 0.17145)
		(layer "F.Cu")
		(net "FLT_HDD1")
	)
	(segment
		(start 48.849534 -213.492334)
		(end 50.473102 -215.115902)
		(width 0.17145)
		(layer "F.Cu")
		(net "FLT_HDD1")
	)
	(segment
		(start 55.26024 -237.88624)
		(end 55.26024 -241.225578)
		(width 0.17145)
		(layer "F.Cu")
		(net "FLT_HDD1")
	)
	(segment
		(start 50.473102 -233.099102)
		(end 52.3748 -235.0008)
		(width 0.17145)
		(layer "F.Cu")
		(net "FLT_HDD1")
	)
	(segment
		(start 52.3748 -235.0008)
		(end 55.26024 -237.88624)
		(width 0.17145)
		(layer "F.Cu")
		(net "FLT_HDD1")
	)
	(via
		(at 52.3748 -235.0008)
		(size 0.6604)
		(drill 0.3302)
		(layers "F.Cu" "B.Cu")
		(net "FLT_HDD1")
	)
	(segment
		(start 255.143 -298.323)
		(end 255.143 -299.81398)
		(width 0.17145)
		(layer "F.Cu")
		(net "EEPROM_WP")
	)
	(segment
		(start 255.143 -299.81398)
		(end 255.143 -300.7995)
		(width 0.17145)
		(layer "F.Cu")
		(net "EEPROM_WP")
	)
	(via
		(at 255.143 -299.81398)
		(size 0.6604)
		(drill 0.3302)
		(layers "F.Cu" "B.Cu")
		(net "EEPROM_WP")
	)
	(segment
		(start 257.683 -299.824902)
		(end 257.683 -300.7995)
		(width 0.17145)
		(layer "F.Cu")
		(net "EEPROM_SDA")
	)
	(segment
		(start 257.683 -298.323)
		(end 257.683 -299.824902)
		(width 0.17145)
		(layer "F.Cu")
		(net "EEPROM_SDA")
	)
	(via
		(at 257.683 -299.824902)
		(size 0.6604)
		(drill 0.3302)
		(layers "F.Cu" "B.Cu")
		(net "EEPROM_SDA")
	)
	(segment
		(start 256.413 -298.323)
		(end 256.413 -299.815758)
		(width 0.17145)
		(layer "F.Cu")
		(net "EEPROM_SCL")
	)
	(segment
		(start 256.413 -299.815758)
		(end 256.413 -300.7995)
		(width 0.17145)
		(layer "F.Cu")
		(net "EEPROM_SCL")
	)
	(via
		(at 256.413 -299.815758)
		(size 0.6604)
		(drill 0.3302)
		(layers "F.Cu" "B.Cu")
		(net "EEPROM_SCL")
	)
	(segment
		(start 257.4036 -290.6395)
		(end 257.4036 -291.1856)
		(width 0.17145)
		(layer "F.Cu")
		(net "EEPROM_A2")
	)
	(segment
		(start 256.413 -292.1762)
		(end 256.920238 -291.668962)
		(width 0.17145)
		(layer "F.Cu")
		(net "EEPROM_A2")
	)
	(segment
		(start 258.5212 -290.6395)
		(end 257.4036 -290.6395)
		(width 0.17145)
		(layer "F.Cu")
		(net "EEPROM_A2")
	)
	(segment
		(start 257.4036 -291.1856)
		(end 256.920238 -291.668962)
		(width 0.17145)
		(layer "F.Cu")
		(net "EEPROM_A2")
	)
	(segment
		(start 256.413 -293.243)
		(end 256.413 -292.1762)
		(width 0.17145)
		(layer "F.Cu")
		(net "EEPROM_A2")
	)
	(via
		(at 256.920238 -291.668962)
		(size 0.6604)
		(drill 0.3302)
		(layers "F.Cu" "B.Cu")
		(net "EEPROM_A2")
	)
	(segment
		(start 255.143 -290.6903)
		(end 255.0922 -290.6395)
		(width 0.17145)
		(layer "F.Cu")
		(net "EEPROM_A1")
	)
	(segment
		(start 255.0922 -290.6395)
		(end 256.2098 -290.6395)
		(width 0.17145)
		(layer "F.Cu")
		(net "EEPROM_A1")
	)
	(segment
		(start 255.143 -291.6682)
		(end 255.143 -293.243)
		(width 0.17145)
		(layer "F.Cu")
		(net "EEPROM_A1")
	)
	(segment
		(start 255.143 -291.6682)
		(end 255.143 -290.6903)
		(width 0.17145)
		(layer "F.Cu")
		(net "EEPROM_A1")
	)
	(via
		(at 255.143 -291.6682)
		(size 0.6604)
		(drill 0.3302)
		(layers "F.Cu" "B.Cu")
		(net "EEPROM_A1")
	)
	(segment
		(start 253.9238 -290.6395)
		(end 252.73 -290.6395)
		(width 0.17145)
		(layer "F.Cu")
		(net "EEPROM_A0")
	)
	(segment
		(start 252.73 -290.93668)
		(end 253.544832 -291.751512)
		(width 0.17145)
		(layer "F.Cu")
		(net "EEPROM_A0")
	)
	(segment
		(start 253.873 -293.243)
		(end 253.873 -292.07968)
		(width 0.17145)
		(layer "F.Cu")
		(net "EEPROM_A0")
	)
	(segment
		(start 253.873 -292.07968)
		(end 253.544832 -291.751512)
		(width 0.17145)
		(layer "F.Cu")
		(net "EEPROM_A0")
	)
	(segment
		(start 252.73 -290.6395)
		(end 252.73 -290.93668)
		(width 0.17145)
		(layer "F.Cu")
		(net "EEPROM_A0")
	)
	(via
		(at 253.544832 -291.751512)
		(size 0.6604)
		(drill 0.3302)
		(layers "F.Cu" "B.Cu")
		(net "EEPROM_A0")
	)
	(segment
		(start 410.300424 -210.130136)
		(end 410.300424 -224.827846)
		(width 0.17145)
		(layer "F.Cu")
		(net "DRV_ACT_9")
	)
	(segment
		(start 410.300424 -241.377216)
		(end 410.414978 -241.49177)
		(width 0.17145)
		(layer "F.Cu")
		(net "DRV_ACT_9")
	)
	(segment
		(start 410.300424 -224.827846)
		(end 410.300424 -241.377216)
		(width 0.17145)
		(layer "F.Cu")
		(net "DRV_ACT_9")
	)
	(via
		(at 410.300424 -224.827846)
		(size 0.6604)
		(drill 0.3302)
		(layers "F.Cu" "B.Cu")
		(net "DRV_ACT_9")
	)
	(segment
		(start 378.750322 -241.377216)
		(end 378.864876 -241.49177)
		(width 0.17145)
		(layer "F.Cu")
		(net "DRV_ACT_8")
	)
	(segment
		(start 378.750322 -219.3544)
		(end 378.750322 -241.377216)
		(width 0.17145)
		(layer "F.Cu")
		(net "DRV_ACT_8")
	)
	(segment
		(start 378.750322 -210.130136)
		(end 378.750322 -219.3544)
		(width 0.17145)
		(layer "F.Cu")
		(net "DRV_ACT_8")
	)
	(via
		(at 378.750322 -219.3544)
		(size 0.6604)
		(drill 0.3302)
		(layers "F.Cu" "B.Cu")
		(net "DRV_ACT_8")
	)
	(segment
		(start 347.200474 -233.9848)
		(end 347.200474 -241.377216)
		(width 0.17145)
		(layer "F.Cu")
		(net "DRV_ACT_7")
	)
	(segment
		(start 347.200474 -210.130136)
		(end 347.200474 -233.9848)
		(width 0.17145)
		(layer "F.Cu")
		(net "DRV_ACT_7")
	)
	(segment
		(start 347.200474 -241.377216)
		(end 347.315028 -241.49177)
		(width 0.17145)
		(layer "F.Cu")
		(net "DRV_ACT_7")
	)
	(via
		(at 347.200474 -233.9848)
		(size 0.6604)
		(drill 0.3302)
		(layers "F.Cu" "B.Cu")
		(net "DRV_ACT_7")
	)
	(segment
		(start 322.260468 -241.448844)
		(end 322.260468 -234.238292)
		(width 0.17145)
		(layer "F.Cu")
		(net "DRV_ACT_6")
	)
	(segment
		(start 322.260468 -234.238292)
		(end 322.260468 -230.820468)
		(width 0.17145)
		(layer "F.Cu")
		(net "DRV_ACT_6")
	)
	(segment
		(start 322.260468 -230.820468)
		(end 315.650372 -224.210372)
		(width 0.17145)
		(layer "F.Cu")
		(net "DRV_ACT_6")
	)
	(segment
		(start 315.650372 -224.210372)
		(end 315.650372 -210.130136)
		(width 0.17145)
		(layer "F.Cu")
		(net "DRV_ACT_6")
	)
	(via
		(at 322.260468 -234.238292)
		(size 0.6604)
		(drill 0.3302)
		(layers "F.Cu" "B.Cu")
		(net "DRV_ACT_6")
	)
	(segment
		(start 176.165002 -241.49177)
		(end 176.050448 -241.377216)
		(width 0.17145)
		(layer "F.Cu")
		(net "DRV_ACT_5")
	)
	(segment
		(start 176.050448 -241.377216)
		(end 176.050448 -238.7854)
		(width 0.17145)
		(layer "F.Cu")
		(net "DRV_ACT_5")
	)
	(segment
		(start 176.050448 -210.130136)
		(end 176.050448 -238.7854)
		(width 0.17145)
		(layer "F.Cu")
		(net "DRV_ACT_5")
	)
	(via
		(at 176.050448 -238.7854)
		(size 0.6604)
		(drill 0.3302)
		(layers "F.Cu" "B.Cu")
		(net "DRV_ACT_5")
	)
	(segment
		(start 144.6149 -241.49177)
		(end 144.6149 -240.229136)
		(width 0.17145)
		(layer "F.Cu")
		(net "DRV_ACT_4")
	)
	(segment
		(start 144.6149 -240.229136)
		(end 144.6149 -239.17656)
		(width 0.17145)
		(layer "F.Cu")
		(net "DRV_ACT_4")
	)
	(segment
		(start 144.500346 -210.130136)
		(end 144.500346 -211.386166)
		(width 0.17145)
		(layer "F.Cu")
		(net "DRV_ACT_4")
	)
	(via
		(at 144.6149 -240.229136)
		(size 0.6604)
		(drill 0.3302)
		(layers "F.Cu" "B.Cu")
		(net "DRV_ACT_4")
	)
	(via
		(at 144.6149 -239.17656)
		(size 0.5588)
		(drill 0.3048)
		(layers "F.Cu" "B.Cu")
		(net "DRV_ACT_4")
	)
	(via
		(at 144.500346 -211.386166)
		(size 0.5588)
		(drill 0.3048)
		(layers "F.Cu" "B.Cu")
		(net "DRV_ACT_4")
	)
	(segment
		(start 144.6149 -239.17656)
		(end 144.500346 -239.062006)
		(width 0.13335)
		(layer "In9.Cu")
		(net "DRV_ACT_4")
	)
	(segment
		(start 144.500346 -239.062006)
		(end 144.500346 -211.386166)
		(width 0.13335)
		(layer "In9.Cu")
		(net "DRV_ACT_4")
	)
	(segment
		(start 466.4456 -295.0718)
		(end 466.685376 -295.311576)
		(width 0.17145)
		(layer "F.Cu")
		(net "DRV_ACT_35")
	)
	(segment
		(start 469.9 -326.977248)
		(end 469.9 -316.639448)
		(width 0.17145)
		(layer "F.Cu")
		(net "DRV_ACT_35")
	)
	(segment
		(start 473.400374 -325.658226)
		(end 473.1512 -325.9074)
		(width 0.17145)
		(layer "F.Cu")
		(net "DRV_ACT_35")
	)
	(segment
		(start 473.1512 -327.053448)
		(end 472.366848 -327.8378)
		(width 0.17145)
		(layer "F.Cu")
		(net "DRV_ACT_35")
	)
	(segment
		(start 466.685376 -295.311576)
		(end 466.685376 -313.424824)
		(width 0.17145)
		(layer "F.Cu")
		(net "DRV_ACT_35")
	)
	(segment
		(start 466.685376 -313.424824)
		(end 468.411052 -315.1505)
		(width 0.17145)
		(layer "F.Cu")
		(net "DRV_ACT_35")
	)
	(segment
		(start 473.1512 -325.9074)
		(end 473.1512 -327.053448)
		(width 0.17145)
		(layer "F.Cu")
		(net "DRV_ACT_35")
	)
	(segment
		(start 473.400374 -325.13016)
		(end 473.400374 -325.658226)
		(width 0.17145)
		(layer "F.Cu")
		(net "DRV_ACT_35")
	)
	(segment
		(start 472.366848 -327.8378)
		(end 470.760552 -327.8378)
		(width 0.17145)
		(layer "F.Cu")
		(net "DRV_ACT_35")
	)
	(segment
		(start 470.760552 -327.8378)
		(end 469.9 -326.977248)
		(width 0.17145)
		(layer "F.Cu")
		(net "DRV_ACT_35")
	)
	(segment
		(start 469.9 -316.639448)
		(end 468.411052 -315.1505)
		(width 0.17145)
		(layer "F.Cu")
		(net "DRV_ACT_35")
	)
	(via
		(at 468.411052 -315.1505)
		(size 0.6604)
		(drill 0.3302)
		(layers "F.Cu" "B.Cu")
		(net "DRV_ACT_35")
	)
	(segment
		(start 436.401718 -295.186862)
		(end 436.401718 -323.80428)
		(width 0.17145)
		(layer "F.Cu")
		(net "DRV_ACT_34")
	)
	(segment
		(start 437.66994 -328.422)
		(end 436.401718 -327.153778)
		(width 0.17145)
		(layer "F.Cu")
		(net "DRV_ACT_34")
	)
	(segment
		(start 440.743848 -328.422)
		(end 437.66994 -328.422)
		(width 0.17145)
		(layer "F.Cu")
		(net "DRV_ACT_34")
	)
	(segment
		(start 441.850272 -325.79056)
		(end 441.6044 -326.036432)
		(width 0.17145)
		(layer "F.Cu")
		(net "DRV_ACT_34")
	)
	(segment
		(start 441.850272 -325.13016)
		(end 441.850272 -325.79056)
		(width 0.17145)
		(layer "F.Cu")
		(net "DRV_ACT_34")
	)
	(segment
		(start 441.6044 -327.561448)
		(end 440.743848 -328.422)
		(width 0.17145)
		(layer "F.Cu")
		(net "DRV_ACT_34")
	)
	(segment
		(start 436.401718 -327.153778)
		(end 436.401718 -323.80428)
		(width 0.17145)
		(layer "F.Cu")
		(net "DRV_ACT_34")
	)
	(segment
		(start 441.6044 -326.036432)
		(end 441.6044 -327.561448)
		(width 0.17145)
		(layer "F.Cu")
		(net "DRV_ACT_34")
	)
	(via
		(at 436.401718 -323.80428)
		(size 0.6604)
		(drill 0.3302)
		(layers "F.Cu" "B.Cu")
		(net "DRV_ACT_34")
	)
	(segment
		(start 410.054552 -327.561448)
		(end 409.194 -328.422)
		(width 0.17145)
		(layer "F.Cu")
		(net "DRV_ACT_33")
	)
	(segment
		(start 407.638504 -328.422)
		(end 406.828752 -327.612248)
		(width 0.17145)
		(layer "F.Cu")
		(net "DRV_ACT_33")
	)
	(segment
		(start 406.828752 -327.612248)
		(end 406.828752 -310.213248)
		(width 0.17145)
		(layer "F.Cu")
		(net "DRV_ACT_33")
	)
	(segment
		(start 409.1686 -307.8734)
		(end 407.691082 -309.350918)
		(width 0.17145)
		(layer "F.Cu")
		(net "DRV_ACT_33")
	)
	(segment
		(start 410.300424 -325.79056)
		(end 410.054552 -326.036432)
		(width 0.17145)
		(layer "F.Cu")
		(net "DRV_ACT_33")
	)
	(segment
		(start 410.350208 -297.33367)
		(end 409.1686 -298.515278)
		(width 0.17145)
		(layer "F.Cu")
		(net "DRV_ACT_33")
	)
	(segment
		(start 410.054552 -326.036432)
		(end 410.054552 -327.561448)
		(width 0.17145)
		(layer "F.Cu")
		(net "DRV_ACT_33")
	)
	(segment
		(start 410.300424 -325.13016)
		(end 410.300424 -325.79056)
		(width 0.17145)
		(layer "F.Cu")
		(net "DRV_ACT_33")
	)
	(segment
		(start 410.350208 -295.200324)
		(end 410.350208 -297.33367)
		(width 0.17145)
		(layer "F.Cu")
		(net "DRV_ACT_33")
	)
	(segment
		(start 406.828752 -310.213248)
		(end 407.691082 -309.350918)
		(width 0.17145)
		(layer "F.Cu")
		(net "DRV_ACT_33")
	)
	(segment
		(start 409.1686 -298.515278)
		(end 409.1686 -307.8734)
		(width 0.17145)
		(layer "F.Cu")
		(net "DRV_ACT_33")
	)
	(segment
		(start 409.194 -328.422)
		(end 407.638504 -328.422)
		(width 0.17145)
		(layer "F.Cu")
		(net "DRV_ACT_33")
	)
	(via
		(at 407.691082 -309.350918)
		(size 0.6604)
		(drill 0.3302)
		(layers "F.Cu" "B.Cu")
		(net "DRV_ACT_33")
	)
	(segment
		(start 378.50445 -326.036432)
		(end 378.50445 -327.561448)
		(width 0.17145)
		(layer "F.Cu")
		(net "DRV_ACT_32")
	)
	(segment
		(start 374.94845 -313.688222)
		(end 374.94845 -321.4624)
		(width 0.17145)
		(layer "F.Cu")
		(net "DRV_ACT_32")
	)
	(segment
		(start 373.622062 -295.154858)
		(end 373.622062 -312.361834)
		(width 0.17145)
		(layer "F.Cu")
		(net "DRV_ACT_32")
	)
	(segment
		(start 378.50445 -327.561448)
		(end 377.643898 -328.422)
		(width 0.17145)
		(layer "F.Cu")
		(net "DRV_ACT_32")
	)
	(segment
		(start 378.750322 -325.79056)
		(end 378.50445 -326.036432)
		(width 0.17145)
		(layer "F.Cu")
		(net "DRV_ACT_32")
	)
	(segment
		(start 373.622062 -312.361834)
		(end 374.94845 -313.688222)
		(width 0.17145)
		(layer "F.Cu")
		(net "DRV_ACT_32")
	)
	(segment
		(start 377.643898 -328.422)
		(end 376.088402 -328.422)
		(width 0.17145)
		(layer "F.Cu")
		(net "DRV_ACT_32")
	)
	(segment
		(start 378.750322 -325.13016)
		(end 378.750322 -325.79056)
		(width 0.17145)
		(layer "F.Cu")
		(net "DRV_ACT_32")
	)
	(segment
		(start 376.088402 -328.422)
		(end 374.94845 -327.282048)
		(width 0.17145)
		(layer "F.Cu")
		(net "DRV_ACT_32")
	)
	(segment
		(start 374.94845 -327.282048)
		(end 374.94845 -321.4624)
		(width 0.17145)
		(layer "F.Cu")
		(net "DRV_ACT_32")
	)
	(via
		(at 374.94845 -321.4624)
		(size 0.6604)
		(drill 0.3302)
		(layers "F.Cu" "B.Cu")
		(net "DRV_ACT_32")
	)
	(segment
		(start 346.09405 -328.422)
		(end 346.954602 -327.561448)
		(width 0.17145)
		(layer "F.Cu")
		(net "DRV_ACT_31")
	)
	(segment
		(start 344.157554 -328.422)
		(end 346.09405 -328.422)
		(width 0.17145)
		(layer "F.Cu")
		(net "DRV_ACT_31")
	)
	(segment
		(start 346.954602 -327.561448)
		(end 346.954602 -326.036432)
		(width 0.17145)
		(layer "F.Cu")
		(net "DRV_ACT_31")
	)
	(segment
		(start 346.954602 -326.036432)
		(end 347.200474 -325.79056)
		(width 0.17145)
		(layer "F.Cu")
		(net "DRV_ACT_31")
	)
	(segment
		(start 347.200474 -325.79056)
		(end 347.200474 -325.13016)
		(width 0.17145)
		(layer "F.Cu")
		(net "DRV_ACT_31")
	)
	(segment
		(start 341.965534 -300.4058)
		(end 341.965534 -295.186862)
		(width 0.17145)
		(layer "F.Cu")
		(net "DRV_ACT_31")
	)
	(segment
		(start 341.965534 -300.4058)
		(end 341.965534 -326.22998)
		(width 0.17145)
		(layer "F.Cu")
		(net "DRV_ACT_31")
	)
	(segment
		(start 341.965534 -326.22998)
		(end 344.157554 -328.422)
		(width 0.17145)
		(layer "F.Cu")
		(net "DRV_ACT_31")
	)
	(via
		(at 341.965534 -300.4058)
		(size 0.6604)
		(drill 0.3302)
		(layers "F.Cu" "B.Cu")
		(net "DRV_ACT_31")
	)
	(segment
		(start 315.650372 -325.79056)
		(end 315.4045 -326.036432)
		(width 0.17145)
		(layer "F.Cu")
		(net "DRV_ACT_30")
	)
	(segment
		(start 309.272178 -328.422)
		(end 307.64607 -326.795892)
		(width 0.17145)
		(layer "F.Cu")
		(net "DRV_ACT_30")
	)
	(segment
		(start 314.543948 -328.422)
		(end 309.272178 -328.422)
		(width 0.17145)
		(layer "F.Cu")
		(net "DRV_ACT_30")
	)
	(segment
		(start 315.4045 -326.036432)
		(end 315.4045 -327.561448)
		(width 0.17145)
		(layer "F.Cu")
		(net "DRV_ACT_30")
	)
	(segment
		(start 307.64607 -295.197276)
		(end 307.64607 -298.37507)
		(width 0.17145)
		(layer "F.Cu")
		(net "DRV_ACT_30")
	)
	(segment
		(start 315.4045 -327.561448)
		(end 314.543948 -328.422)
		(width 0.17145)
		(layer "F.Cu")
		(net "DRV_ACT_30")
	)
	(segment
		(start 315.650372 -325.13016)
		(end 315.650372 -325.79056)
		(width 0.17145)
		(layer "F.Cu")
		(net "DRV_ACT_30")
	)
	(segment
		(start 307.64607 -326.795892)
		(end 307.64607 -298.37507)
		(width 0.17145)
		(layer "F.Cu")
		(net "DRV_ACT_30")
	)
	(via
		(at 307.64607 -298.37507)
		(size 0.6604)
		(drill 0.3302)
		(layers "F.Cu" "B.Cu")
		(net "DRV_ACT_30")
	)
	(segment
		(start 113.065052 -239.594136)
		(end 113.065052 -238.28756)
		(width 0.17145)
		(layer "F.Cu")
		(net "DRV_ACT_3")
	)
	(segment
		(start 112.950498 -210.130136)
		(end 112.950498 -211.386166)
		(width 0.17145)
		(layer "F.Cu")
		(net "DRV_ACT_3")
	)
	(segment
		(start 113.065052 -241.49177)
		(end 113.065052 -239.594136)
		(width 0.17145)
		(layer "F.Cu")
		(net "DRV_ACT_3")
	)
	(via
		(at 113.065052 -239.594136)
		(size 0.6604)
		(drill 0.3302)
		(layers "F.Cu" "B.Cu")
		(net "DRV_ACT_3")
	)
	(via
		(at 112.950498 -211.386166)
		(size 0.5588)
		(drill 0.3048)
		(layers "F.Cu" "B.Cu")
		(net "DRV_ACT_3")
	)
	(via
		(at 113.065052 -238.28756)
		(size 0.5588)
		(drill 0.3048)
		(layers "F.Cu" "B.Cu")
		(net "DRV_ACT_3")
	)
	(segment
		(start 113.065052 -238.28756)
		(end 113.6904 -237.662212)
		(width 0.13335)
		(layer "In9.Cu")
		(net "DRV_ACT_3")
	)
	(segment
		(start 113.6904 -212.126068)
		(end 112.950498 -211.386166)
		(width 0.13335)
		(layer "In9.Cu")
		(net "DRV_ACT_3")
	)
	(segment
		(start 113.6904 -237.662212)
		(end 113.6904 -212.126068)
		(width 0.13335)
		(layer "In9.Cu")
		(net "DRV_ACT_3")
	)
	(segment
		(start 162.249104 -308.415436)
		(end 169.53865 -315.704982)
		(width 0.17145)
		(layer "F.Cu")
		(net "DRV_ACT_29")
	)
	(segment
		(start 160.608264 -305.072796)
		(end 160.608264 -306.774596)
		(width 0.17145)
		(layer "F.Cu")
		(net "DRV_ACT_29")
	)
	(segment
		(start 169.53865 -315.704982)
		(end 169.53865 -326.349106)
		(width 0.17145)
		(layer "F.Cu")
		(net "DRV_ACT_29")
	)
	(segment
		(start 160.608264 -306.774596)
		(end 162.249104 -308.415436)
		(width 0.17145)
		(layer "F.Cu")
		(net "DRV_ACT_29")
	)
	(segment
		(start 169.53865 -326.349106)
		(end 170.652948 -327.463404)
		(width 0.17145)
		(layer "F.Cu")
		(net "DRV_ACT_29")
	)
	(segment
		(start 171.078652 -327.463404)
		(end 171.078906 -327.46315)
		(width 0.17145)
		(layer "F.Cu")
		(net "DRV_ACT_29")
	)
	(segment
		(start 175.82515 -326.476106)
		(end 175.82515 -325.82485)
		(width 0.17145)
		(layer "F.Cu")
		(net "DRV_ACT_29")
	)
	(segment
		(start 176.050448 -325.599552)
		(end 176.050448 -325.13016)
		(width 0.17145)
		(layer "F.Cu")
		(net "DRV_ACT_29")
	)
	(segment
		(start 170.652948 -327.463404)
		(end 171.078652 -327.463404)
		(width 0.17145)
		(layer "F.Cu")
		(net "DRV_ACT_29")
	)
	(segment
		(start 171.078906 -327.46315)
		(end 174.838106 -327.46315)
		(width 0.17145)
		(layer "F.Cu")
		(net "DRV_ACT_29")
	)
	(segment
		(start 174.838106 -327.46315)
		(end 175.82515 -326.476106)
		(width 0.17145)
		(layer "F.Cu")
		(net "DRV_ACT_29")
	)
	(segment
		(start 175.82515 -325.82485)
		(end 176.050448 -325.599552)
		(width 0.17145)
		(layer "F.Cu")
		(net "DRV_ACT_29")
	)
	(via
		(at 162.249104 -308.415436)
		(size 0.6604)
		(drill 0.3302)
		(layers "F.Cu" "B.Cu")
		(net "DRV_ACT_29")
	)
	(segment
		(start 138.299444 -321.687444)
		(end 129.058162 -312.446162)
		(width 0.17145)
		(layer "F.Cu")
		(net "DRV_ACT_28")
	)
	(segment
		(start 143.776446 -327.0377)
		(end 142.630652 -327.0377)
		(width 0.17145)
		(layer "F.Cu")
		(net "DRV_ACT_28")
	)
	(segment
		(start 129.058162 -312.446162)
		(end 129.058162 -305.093878)
		(width 0.17145)
		(layer "F.Cu")
		(net "DRV_ACT_28")
	)
	(segment
		(start 144.286986 -326.52716)
		(end 143.776446 -327.0377)
		(width 0.17145)
		(layer "F.Cu")
		(net "DRV_ACT_28")
	)
	(segment
		(start 144.500346 -325.628254)
		(end 144.286986 -325.841614)
		(width 0.17145)
		(layer "F.Cu")
		(net "DRV_ACT_28")
	)
	(segment
		(start 144.286986 -325.841614)
		(end 144.286986 -326.52716)
		(width 0.17145)
		(layer "F.Cu")
		(net "DRV_ACT_28")
	)
	(segment
		(start 140.422122 -324.82917)
		(end 140.422122 -323.810122)
		(width 0.17145)
		(layer "F.Cu")
		(net "DRV_ACT_28")
	)
	(segment
		(start 140.422122 -323.810122)
		(end 138.299444 -321.687444)
		(width 0.17145)
		(layer "F.Cu")
		(net "DRV_ACT_28")
	)
	(segment
		(start 144.500346 -325.13016)
		(end 144.500346 -325.628254)
		(width 0.17145)
		(layer "F.Cu")
		(net "DRV_ACT_28")
	)
	(segment
		(start 142.630652 -327.0377)
		(end 140.422122 -324.82917)
		(width 0.17145)
		(layer "F.Cu")
		(net "DRV_ACT_28")
	)
	(via
		(at 138.299444 -321.687444)
		(size 0.6604)
		(drill 0.3302)
		(layers "F.Cu" "B.Cu")
		(net "DRV_ACT_28")
	)
	(segment
		(start 106.39425 -316.538102)
		(end 106.39425 -326.367648)
		(width 0.17145)
		(layer "F.Cu")
		(net "DRV_ACT_27")
	)
	(segment
		(start 99.871022 -310.014874)
		(end 106.39425 -316.538102)
		(width 0.17145)
		(layer "F.Cu")
		(net "DRV_ACT_27")
	)
	(segment
		(start 107.585002 -327.5584)
		(end 111.705898 -327.5584)
		(width 0.17145)
		(layer "F.Cu")
		(net "DRV_ACT_27")
	)
	(segment
		(start 97.497646 -307.641498)
		(end 97.497646 -305.115468)
		(width 0.17145)
		(layer "F.Cu")
		(net "DRV_ACT_27")
	)
	(segment
		(start 112.950498 -325.574152)
		(end 112.950498 -325.13016)
		(width 0.17145)
		(layer "F.Cu")
		(net "DRV_ACT_27")
	)
	(segment
		(start 111.705898 -327.5584)
		(end 112.737138 -326.52716)
		(width 0.17145)
		(layer "F.Cu")
		(net "DRV_ACT_27")
	)
	(segment
		(start 112.737138 -326.52716)
		(end 112.737138 -325.787512)
		(width 0.17145)
		(layer "F.Cu")
		(net "DRV_ACT_27")
	)
	(segment
		(start 99.871022 -310.014874)
		(end 97.497646 -307.641498)
		(width 0.17145)
		(layer "F.Cu")
		(net "DRV_ACT_27")
	)
	(segment
		(start 112.737138 -325.787512)
		(end 112.950498 -325.574152)
		(width 0.17145)
		(layer "F.Cu")
		(net "DRV_ACT_27")
	)
	(segment
		(start 106.39425 -326.367648)
		(end 107.585002 -327.5584)
		(width 0.17145)
		(layer "F.Cu")
		(net "DRV_ACT_27")
	)
	(via
		(at 99.871022 -310.014874)
		(size 0.6604)
		(drill 0.3302)
		(layers "F.Cu" "B.Cu")
		(net "DRV_ACT_27")
	)
	(segment
		(start 65.936876 -305.147472)
		(end 65.936876 -312.85053)
		(width 0.17145)
		(layer "F.Cu")
		(net "DRV_ACT_26")
	)
	(segment
		(start 81.400396 -325.609204)
		(end 81.187036 -325.822564)
		(width 0.17145)
		(layer "F.Cu")
		(net "DRV_ACT_26")
	)
	(segment
		(start 74.844148 -323.370448)
		(end 74.844148 -321.757802)
		(width 0.17145)
		(layer "F.Cu")
		(net "DRV_ACT_26")
	)
	(segment
		(start 65.936876 -312.85053)
		(end 72.378316 -319.29197)
		(width 0.17145)
		(layer "F.Cu")
		(net "DRV_ACT_26")
	)
	(segment
		(start 74.844148 -321.757802)
		(end 72.378316 -319.29197)
		(width 0.17145)
		(layer "F.Cu")
		(net "DRV_ACT_26")
	)
	(segment
		(start 81.187036 -325.822564)
		(end 81.187036 -326.52716)
		(width 0.17145)
		(layer "F.Cu")
		(net "DRV_ACT_26")
	)
	(segment
		(start 81.187036 -326.52716)
		(end 80.155796 -327.5584)
		(width 0.17145)
		(layer "F.Cu")
		(net "DRV_ACT_26")
	)
	(segment
		(start 81.400396 -325.13016)
		(end 81.400396 -325.609204)
		(width 0.17145)
		(layer "F.Cu")
		(net "DRV_ACT_26")
	)
	(segment
		(start 79.0321 -327.5584)
		(end 74.844148 -323.370448)
		(width 0.17145)
		(layer "F.Cu")
		(net "DRV_ACT_26")
	)
	(segment
		(start 80.155796 -327.5584)
		(end 79.0321 -327.5584)
		(width 0.17145)
		(layer "F.Cu")
		(net "DRV_ACT_26")
	)
	(via
		(at 72.378316 -319.29197)
		(size 0.6604)
		(drill 0.3302)
		(layers "F.Cu" "B.Cu")
		(net "DRV_ACT_26")
	)
	(segment
		(start 43.294046 -316.28207)
		(end 43.294046 -326.367648)
		(width 0.17145)
		(layer "F.Cu")
		(net "DRV_ACT_25")
	)
	(segment
		(start 44.484798 -327.5584)
		(end 48.605694 -327.5584)
		(width 0.17145)
		(layer "F.Cu")
		(net "DRV_ACT_25")
	)
	(segment
		(start 34.397188 -307.385212)
		(end 34.397188 -305.190398)
		(width 0.17145)
		(layer "F.Cu")
		(net "DRV_ACT_25")
	)
	(segment
		(start 43.294046 -326.367648)
		(end 44.484798 -327.5584)
		(width 0.17145)
		(layer "F.Cu")
		(net "DRV_ACT_25")
	)
	(segment
		(start 48.605694 -327.5584)
		(end 49.636934 -326.52716)
		(width 0.17145)
		(layer "F.Cu")
		(net "DRV_ACT_25")
	)
	(segment
		(start 49.636934 -326.52716)
		(end 49.636934 -325.787512)
		(width 0.17145)
		(layer "F.Cu")
		(net "DRV_ACT_25")
	)
	(segment
		(start 35.602164 -308.590188)
		(end 43.294046 -316.28207)
		(width 0.17145)
		(layer "F.Cu")
		(net "DRV_ACT_25")
	)
	(segment
		(start 49.636934 -325.787512)
		(end 49.850294 -325.574152)
		(width 0.17145)
		(layer "F.Cu")
		(net "DRV_ACT_25")
	)
	(segment
		(start 49.850294 -325.574152)
		(end 49.850294 -325.13016)
		(width 0.17145)
		(layer "F.Cu")
		(net "DRV_ACT_25")
	)
	(segment
		(start 35.602164 -308.590188)
		(end 34.397188 -307.385212)
		(width 0.17145)
		(layer "F.Cu")
		(net "DRV_ACT_25")
	)
	(via
		(at 35.602164 -308.590188)
		(size 0.6604)
		(drill 0.3302)
		(layers "F.Cu" "B.Cu")
		(net "DRV_ACT_25")
	)
	(segment
		(start 11.134598 -325.758048)
		(end 12.93495 -327.5584)
		(width 0.17145)
		(layer "F.Cu")
		(net "DRV_ACT_24")
	)
	(segment
		(start 11.134598 -311.286398)
		(end 11.134598 -325.758048)
		(width 0.17145)
		(layer "F.Cu")
		(net "DRV_ACT_24")
	)
	(segment
		(start 6.985 -307.7464)
		(end 7.5946 -307.7464)
		(width 0.17145)
		(layer "F.Cu")
		(net "DRV_ACT_24")
	)
	(segment
		(start 18.087086 -326.52716)
		(end 18.087086 -325.787512)
		(width 0.17145)
		(layer "F.Cu")
		(net "DRV_ACT_24")
	)
	(segment
		(start 18.300446 -325.574152)
		(end 18.300446 -325.13016)
		(width 0.17145)
		(layer "F.Cu")
		(net "DRV_ACT_24")
	)
	(segment
		(start 6.35 -307.1114)
		(end 6.985 -307.7464)
		(width 0.17145)
		(layer "F.Cu")
		(net "DRV_ACT_24")
	)
	(segment
		(start 12.93495 -327.5584)
		(end 17.055846 -327.5584)
		(width 0.17145)
		(layer "F.Cu")
		(net "DRV_ACT_24")
	)
	(segment
		(start 18.087086 -325.787512)
		(end 18.300446 -325.574152)
		(width 0.17145)
		(layer "F.Cu")
		(net "DRV_ACT_24")
	)
	(segment
		(start 17.055846 -327.5584)
		(end 18.087086 -326.52716)
		(width 0.17145)
		(layer "F.Cu")
		(net "DRV_ACT_24")
	)
	(segment
		(start 6.35 -305.054)
		(end 6.35 -307.1114)
		(width 0.17145)
		(layer "F.Cu")
		(net "DRV_ACT_24")
	)
	(segment
		(start 7.5946 -307.7464)
		(end 11.134598 -311.286398)
		(width 0.17145)
		(layer "F.Cu")
		(net "DRV_ACT_24")
	)
	(via
		(at 6.35 -307.1114)
		(size 0.6604)
		(drill 0.3302)
		(layers "F.Cu" "B.Cu")
		(net "DRV_ACT_24")
	)
	(segment
		(start 473.514928 -126.492)
		(end 473.400374 -126.377446)
		(width 0.17145)
		(layer "F.Cu")
		(net "DRV_ACT_23")
	)
	(segment
		(start 473.400374 -126.377446)
		(end 473.400374 -109.0168)
		(width 0.17145)
		(layer "F.Cu")
		(net "DRV_ACT_23")
	)
	(segment
		(start 473.400374 -95.130366)
		(end 473.400374 -109.0168)
		(width 0.17145)
		(layer "F.Cu")
		(net "DRV_ACT_23")
	)
	(via
		(at 473.400374 -109.0168)
		(size 0.6604)
		(drill 0.3302)
		(layers "F.Cu" "B.Cu")
		(net "DRV_ACT_23")
	)
	(segment
		(start 441.964826 -126.492)
		(end 441.850272 -126.377446)
		(width 0.17145)
		(layer "F.Cu")
		(net "DRV_ACT_22")
	)
	(segment
		(start 441.850272 -95.130366)
		(end 441.850272 -115.189)
		(width 0.17145)
		(layer "F.Cu")
		(net "DRV_ACT_22")
	)
	(segment
		(start 441.850272 -126.377446)
		(end 441.850272 -115.189)
		(width 0.17145)
		(layer "F.Cu")
		(net "DRV_ACT_22")
	)
	(via
		(at 441.850272 -115.189)
		(size 0.6604)
		(drill 0.3302)
		(layers "F.Cu" "B.Cu")
		(net "DRV_ACT_22")
	)
	(segment
		(start 410.300424 -126.377446)
		(end 410.300424 -123.9012)
		(width 0.17145)
		(layer "F.Cu")
		(net "DRV_ACT_21")
	)
	(segment
		(start 410.414978 -126.492)
		(end 410.300424 -126.377446)
		(width 0.17145)
		(layer "F.Cu")
		(net "DRV_ACT_21")
	)
	(segment
		(start 410.300424 -95.130366)
		(end 410.300424 -123.9012)
		(width 0.17145)
		(layer "F.Cu")
		(net "DRV_ACT_21")
	)
	(via
		(at 410.300424 -123.9012)
		(size 0.6604)
		(drill 0.3302)
		(layers "F.Cu" "B.Cu")
		(net "DRV_ACT_21")
	)
	(segment
		(start 378.750322 -126.377446)
		(end 378.750322 -106.7054)
		(width 0.17145)
		(layer "F.Cu")
		(net "DRV_ACT_20")
	)
	(segment
		(start 378.864876 -126.492)
		(end 378.750322 -126.377446)
		(width 0.17145)
		(layer "F.Cu")
		(net "DRV_ACT_20")
	)
	(segment
		(start 378.750322 -95.130366)
		(end 378.750322 -106.7054)
		(width 0.17145)
		(layer "F.Cu")
		(net "DRV_ACT_20")
	)
	(via
		(at 378.750322 -106.7054)
		(size 0.6604)
		(drill 0.3302)
		(layers "F.Cu" "B.Cu")
		(net "DRV_ACT_20")
	)
	(segment
		(start 81.51495 -241.49177)
		(end 81.51495 -239.594136)
		(width 0.17145)
		(layer "F.Cu")
		(net "DRV_ACT_2")
	)
	(segment
		(start 81.51495 -239.594136)
		(end 81.51495 -238.28756)
		(width 0.17145)
		(layer "F.Cu")
		(net "DRV_ACT_2")
	)
	(segment
		(start 81.400396 -210.130136)
		(end 81.400396 -211.386166)
		(width 0.17145)
		(layer "F.Cu")
		(net "DRV_ACT_2")
	)
	(via
		(at 81.400396 -211.386166)
		(size 0.5588)
		(drill 0.3048)
		(layers "F.Cu" "B.Cu")
		(net "DRV_ACT_2")
	)
	(via
		(at 81.51495 -239.594136)
		(size 0.6604)
		(drill 0.3302)
		(layers "F.Cu" "B.Cu")
		(net "DRV_ACT_2")
	)
	(via
		(at 81.51495 -238.28756)
		(size 0.5588)
		(drill 0.3048)
		(layers "F.Cu" "B.Cu")
		(net "DRV_ACT_2")
	)
	(segment
		(start 81.51495 -238.28756)
		(end 81.400396 -238.173006)
		(width 0.13335)
		(layer "In9.Cu")
		(net "DRV_ACT_2")
	)
	(segment
		(start 81.400396 -238.173006)
		(end 81.400396 -211.386166)
		(width 0.13335)
		(layer "In9.Cu")
		(net "DRV_ACT_2")
	)
	(segment
		(start 347.200474 -95.130366)
		(end 347.200474 -102.3366)
		(width 0.17145)
		(layer "F.Cu")
		(net "DRV_ACT_19")
	)
	(segment
		(start 347.200474 -124.333)
		(end 346.680028 -124.853446)
		(width 0.17145)
		(layer "F.Cu")
		(net "DRV_ACT_19")
	)
	(segment
		(start 346.680028 -124.853446)
		(end 346.680028 -126.492)
		(width 0.17145)
		(layer "F.Cu")
		(net "DRV_ACT_19")
	)
	(segment
		(start 347.200474 -102.3366)
		(end 347.200474 -124.333)
		(width 0.17145)
		(layer "F.Cu")
		(net "DRV_ACT_19")
	)
	(via
		(at 347.200474 -102.3366)
		(size 0.6604)
		(drill 0.3302)
		(layers "F.Cu" "B.Cu")
		(net "DRV_ACT_19")
	)
	(segment
		(start 315.650372 -109.910372)
		(end 315.650372 -95.130366)
		(width 0.17145)
		(layer "F.Cu")
		(net "DRV_ACT_18")
	)
	(segment
		(start 320.421 -114.681)
		(end 315.650372 -109.910372)
		(width 0.17145)
		(layer "F.Cu")
		(net "DRV_ACT_18")
	)
	(segment
		(start 322.549012 -126.598934)
		(end 322.549012 -116.809012)
		(width 0.17145)
		(layer "F.Cu")
		(net "DRV_ACT_18")
	)
	(segment
		(start 322.549012 -116.809012)
		(end 320.421 -114.681)
		(width 0.17145)
		(layer "F.Cu")
		(net "DRV_ACT_18")
	)
	(via
		(at 320.421 -114.681)
		(size 0.6604)
		(drill 0.3302)
		(layers "F.Cu" "B.Cu")
		(net "DRV_ACT_18")
	)
	(segment
		(start 165.776402 -127.6096)
		(end 165.776402 -128.524)
		(width 0.17145)
		(layer "F.Cu")
		(net "DRV_ACT_17")
	)
	(segment
		(start 176.050448 -97.0534)
		(end 176.050448 -95.130366)
		(width 0.17145)
		(layer "F.Cu")
		(net "DRV_ACT_17")
	)
	(segment
		(start 176.050448 -98.037904)
		(end 176.050448 -97.0534)
		(width 0.17145)
		(layer "F.Cu")
		(net "DRV_ACT_17")
	)
	(via
		(at 176.050448 -97.0534)
		(size 0.6604)
		(drill 0.3302)
		(layers "F.Cu" "B.Cu")
		(net "DRV_ACT_17")
	)
	(via
		(at 165.776402 -127.6096)
		(size 0.5588)
		(drill 0.3048)
		(layers "F.Cu" "B.Cu")
		(net "DRV_ACT_17")
	)
	(via
		(at 176.050448 -98.037904)
		(size 0.5588)
		(drill 0.3048)
		(layers "F.Cu" "B.Cu")
		(net "DRV_ACT_17")
	)
	(segment
		(start 176.050448 -111.083598)
		(end 176.050448 -98.037904)
		(width 0.13335)
		(layer "In9.Cu")
		(net "DRV_ACT_17")
	)
	(segment
		(start 165.776402 -121.357644)
		(end 176.050448 -111.083598)
		(width 0.13335)
		(layer "In9.Cu")
		(net "DRV_ACT_17")
	)
	(segment
		(start 165.776402 -127.6096)
		(end 165.776402 -121.357644)
		(width 0.13335)
		(layer "In9.Cu")
		(net "DRV_ACT_17")
	)
	(segment
		(start 144.500346 -96.386396)
		(end 144.500346 -95.130366)
		(width 0.17145)
		(layer "F.Cu")
		(net "DRV_ACT_16")
	)
	(segment
		(start 136.9949 -123.865386)
		(end 136.9949 -124.899166)
		(width 0.17145)
		(layer "F.Cu")
		(net "DRV_ACT_16")
	)
	(segment
		(start 136.9949 -124.899166)
		(end 136.9949 -126.492)
		(width 0.17145)
		(layer "F.Cu")
		(net "DRV_ACT_16")
	)
	(via
		(at 136.9949 -124.899166)
		(size 0.6604)
		(drill 0.3302)
		(layers "F.Cu" "B.Cu")
		(net "DRV_ACT_16")
	)
	(via
		(at 144.500346 -96.386396)
		(size 0.5588)
		(drill 0.3048)
		(layers "F.Cu" "B.Cu")
		(net "DRV_ACT_16")
	)
	(via
		(at 136.9949 -123.865386)
		(size 0.5588)
		(drill 0.3048)
		(layers "F.Cu" "B.Cu")
		(net "DRV_ACT_16")
	)
	(segment
		(start 136.9949 -112.069118)
		(end 144.500346 -104.563672)
		(width 0.13335)
		(layer "In9.Cu")
		(net "DRV_ACT_16")
	)
	(segment
		(start 144.500346 -104.563672)
		(end 144.500346 -96.386396)
		(width 0.13335)
		(layer "In9.Cu")
		(net "DRV_ACT_16")
	)
	(segment
		(start 136.9949 -123.865386)
		(end 136.9949 -112.069118)
		(width 0.13335)
		(layer "In9.Cu")
		(net "DRV_ACT_16")
	)
	(segment
		(start 113.065052 -123.886722)
		(end 113.065052 -125.043946)
		(width 0.17145)
		(layer "F.Cu")
		(net "DRV_ACT_15")
	)
	(segment
		(start 113.065052 -125.043946)
		(end 113.065052 -126.492)
		(width 0.17145)
		(layer "F.Cu")
		(net "DRV_ACT_15")
	)
	(segment
		(start 112.950498 -96.386396)
		(end 112.950498 -95.130366)
		(width 0.17145)
		(layer "F.Cu")
		(net "DRV_ACT_15")
	)
	(via
		(at 112.950498 -96.386396)
		(size 0.5588)
		(drill 0.3048)
		(layers "F.Cu" "B.Cu")
		(net "DRV_ACT_15")
	)
	(via
		(at 113.065052 -125.043946)
		(size 0.6604)
		(drill 0.3302)
		(layers "F.Cu" "B.Cu")
		(net "DRV_ACT_15")
	)
	(via
		(at 113.065052 -123.886722)
		(size 0.5588)
		(drill 0.3048)
		(layers "F.Cu" "B.Cu")
		(net "DRV_ACT_15")
	)
	(segment
		(start 113.065052 -123.886722)
		(end 113.065052 -96.50095)
		(width 0.13335)
		(layer "In9.Cu")
		(net "DRV_ACT_15")
	)
	(segment
		(start 113.065052 -96.50095)
		(end 112.950498 -96.386396)
		(width 0.13335)
		(layer "In9.Cu")
		(net "DRV_ACT_15")
	)
	(segment
		(start 81.51495 -124.807218)
		(end 81.51495 -126.492)
		(width 0.17145)
		(layer "F.Cu")
		(net "DRV_ACT_14")
	)
	(segment
		(start 81.400396 -95.130366)
		(end 81.400396 -96.386396)
		(width 0.17145)
		(layer "F.Cu")
		(net "DRV_ACT_14")
	)
	(segment
		(start 81.51495 -123.28779)
		(end 81.51495 -124.807218)
		(width 0.17145)
		(layer "F.Cu")
		(net "DRV_ACT_14")
	)
	(via
		(at 81.51495 -124.807218)
		(size 0.6604)
		(drill 0.3302)
		(layers "F.Cu" "B.Cu")
		(net "DRV_ACT_14")
	)
	(via
		(at 81.51495 -123.28779)
		(size 0.5588)
		(drill 0.3048)
		(layers "F.Cu" "B.Cu")
		(net "DRV_ACT_14")
	)
	(via
		(at 81.400396 -96.386396)
		(size 0.5588)
		(drill 0.3048)
		(layers "F.Cu" "B.Cu")
		(net "DRV_ACT_14")
	)
	(segment
		(start 81.51495 -123.28779)
		(end 81.51495 -96.50095)
		(width 0.13335)
		(layer "In9.Cu")
		(net "DRV_ACT_14")
	)
	(segment
		(start 81.51495 -96.50095)
		(end 81.400396 -96.386396)
		(width 0.13335)
		(layer "In9.Cu")
		(net "DRV_ACT_14")
	)
	(segment
		(start 49.850294 -100.965)
		(end 49.850294 -126.377446)
		(width 0.17145)
		(layer "F.Cu")
		(net "DRV_ACT_13")
	)
	(segment
		(start 49.850294 -126.377446)
		(end 49.964848 -126.492)
		(width 0.17145)
		(layer "F.Cu")
		(net "DRV_ACT_13")
	)
	(segment
		(start 49.850294 -95.130366)
		(end 49.850294 -100.965)
		(width 0.17145)
		(layer "F.Cu")
		(net "DRV_ACT_13")
	)
	(via
		(at 49.850294 -100.965)
		(size 0.6604)
		(drill 0.3302)
		(layers "F.Cu" "B.Cu")
		(net "DRV_ACT_13")
	)
	(segment
		(start 18.415 -126.492)
		(end 18.300446 -126.377446)
		(width 0.17145)
		(layer "F.Cu")
		(net "DRV_ACT_12")
	)
	(segment
		(start 18.300446 -126.377446)
		(end 18.300446 -107.7468)
		(width 0.17145)
		(layer "F.Cu")
		(net "DRV_ACT_12")
	)
	(segment
		(start 18.300446 -107.7468)
		(end 18.300446 -95.130366)
		(width 0.17145)
		(layer "F.Cu")
		(net "DRV_ACT_12")
	)
	(via
		(at 18.300446 -107.7468)
		(size 0.6604)
		(drill 0.3302)
		(layers "F.Cu" "B.Cu")
		(net "DRV_ACT_12")
	)
	(segment
		(start 473.400374 -210.130136)
		(end 473.400374 -210.621372)
		(width 0.17145)
		(layer "F.Cu")
		(net "DRV_ACT_11")
	)
	(segment
		(start 473.400374 -210.621372)
		(end 472.301824 -211.719922)
		(width 0.17145)
		(layer "F.Cu")
		(net "DRV_ACT_11")
	)
	(segment
		(start 452.797164 -232.698544)
		(end 452.797164 -238.616744)
		(width 0.17145)
		(layer "F.Cu")
		(net "DRV_ACT_11")
	)
	(segment
		(start 452.797164 -241.488976)
		(end 452.797164 -238.616744)
		(width 0.17145)
		(layer "F.Cu")
		(net "DRV_ACT_11")
	)
	(segment
		(start 472.301824 -211.719922)
		(end 472.301824 -213.193884)
		(width 0.17145)
		(layer "F.Cu")
		(net "DRV_ACT_11")
	)
	(segment
		(start 472.301824 -213.193884)
		(end 452.797164 -232.698544)
		(width 0.17145)
		(layer "F.Cu")
		(net "DRV_ACT_11")
	)
	(via
		(at 452.797164 -238.616744)
		(size 0.6604)
		(drill 0.3302)
		(layers "F.Cu" "B.Cu")
		(net "DRV_ACT_11")
	)
	(segment
		(start 441.850272 -210.130136)
		(end 441.850272 -216.6366)
		(width 0.17145)
		(layer "F.Cu")
		(net "DRV_ACT_10")
	)
	(segment
		(start 441.964826 -241.49177)
		(end 441.850272 -241.377216)
		(width 0.17145)
		(layer "F.Cu")
		(net "DRV_ACT_10")
	)
	(segment
		(start 441.850272 -241.377216)
		(end 441.850272 -216.6366)
		(width 0.17145)
		(layer "F.Cu")
		(net "DRV_ACT_10")
	)
	(via
		(at 441.850272 -216.6366)
		(size 0.6604)
		(drill 0.3302)
		(layers "F.Cu" "B.Cu")
		(net "DRV_ACT_10")
	)
	(segment
		(start 51.443636 -213.495636)
		(end 49.850294 -211.902294)
		(width 0.17145)
		(layer "F.Cu")
		(net "DRV_ACT_1")
	)
	(segment
		(start 55.9816 -237.633764)
		(end 51.443636 -233.0958)
		(width 0.17145)
		(layer "F.Cu")
		(net "DRV_ACT_1")
	)
	(segment
		(start 56.314848 -241.44097)
		(end 55.9816 -241.107722)
		(width 0.17145)
		(layer "F.Cu")
		(net "DRV_ACT_1")
	)
	(segment
		(start 55.9816 -241.107722)
		(end 55.9816 -237.633764)
		(width 0.17145)
		(layer "F.Cu")
		(net "DRV_ACT_1")
	)
	(segment
		(start 51.443636 -233.0958)
		(end 51.443636 -213.495636)
		(width 0.17145)
		(layer "F.Cu")
		(net "DRV_ACT_1")
	)
	(segment
		(start 49.850294 -211.902294)
		(end 49.850294 -210.130136)
		(width 0.17145)
		(layer "F.Cu")
		(net "DRV_ACT_1")
	)
	(via
		(at 51.443636 -233.0958)
		(size 0.6604)
		(drill 0.3302)
		(layers "F.Cu" "B.Cu")
		(net "DRV_ACT_1")
	)
	(segment
		(start 224.763076 -350.624648)
		(end 224.944432 -350.443292)
		(width 0.17145)
		(layer "F.Cu")
		(net "VOL_SEN_SDA")
	)
	(segment
		(start 223.865948 -350.624648)
		(end 224.763076 -350.624648)
		(width 0.17145)
		(layer "F.Cu")
		(net "VOL_SEN_SDA")
	)
	(segment
		(start 227.501704 -348.534482)
		(end 226.853242 -348.534482)
		(width 0.17145)
		(layer "F.Cu")
		(net "VOL_SEN_SDA")
	)
	(segment
		(start 226.853242 -348.534482)
		(end 224.944432 -350.443292)
		(width 0.17145)
		(layer "F.Cu")
		(net "VOL_SEN_SDA")
	)
	(via
		(at 224.944432 -350.443292)
		(size 0.6604)
		(drill 0.3302)
		(layers "F.Cu" "B.Cu")
		(net "VOL_SEN_SDA")
	)
	(segment
		(start 223.865694 -349.439484)
		(end 224.919032 -349.439484)
		(width 0.17145)
		(layer "F.Cu")
		(net "VOL_SEN_SCL")
	)
	(segment
		(start 224.919032 -349.439484)
		(end 224.981516 -349.377)
		(width 0.17145)
		(layer "F.Cu")
		(net "VOL_SEN_SCL")
	)
	(segment
		(start 226.474274 -347.884242)
		(end 224.981516 -349.377)
		(width 0.17145)
		(layer "F.Cu")
		(net "VOL_SEN_SCL")
	)
	(segment
		(start 227.501704 -347.884242)
		(end 226.474274 -347.884242)
		(width 0.17145)
		(layer "F.Cu")
		(net "VOL_SEN_SCL")
	)
	(via
		(at 224.981516 -349.377)
		(size 0.6604)
		(drill 0.3302)
		(layers "F.Cu" "B.Cu")
		(net "VOL_SEN_SCL")
	)
	(segment
		(start 426.628052 -275.252942)
		(end 425.815252 -275.252942)
		(width 0.17145)
		(layer "F.Cu")
		(net "SW_PWR_R_HDD9")
	)
	(segment
		(start 426.755052 -275.125942)
		(end 426.628052 -275.252942)
		(width 0.17145)
		(layer "F.Cu")
		(net "SW_PWR_R_HDD9")
	)
	(segment
		(start 427.898052 -273.030442)
		(end 426.755052 -273.030442)
		(width 0.17145)
		(layer "F.Cu")
		(net "SW_PWR_R_HDD9")
	)
	(segment
		(start 426.755052 -273.030442)
		(end 426.755052 -275.125942)
		(width 0.17145)
		(layer "F.Cu")
		(net "SW_PWR_R_HDD9")
	)
	(segment
		(start 430.438052 -273.030442)
		(end 429.168052 -273.030442)
		(width 0.17145)
		(layer "F.Cu")
		(net "SW_PWR_R_HDD9")
	)
	(segment
		(start 429.168052 -273.030442)
		(end 427.898052 -273.030442)
		(width 0.17145)
		(layer "F.Cu")
		(net "SW_PWR_R_HDD9")
	)
	(via
		(at 429.168052 -273.030442)
		(size 0.6604)
		(drill 0.3302)
		(layers "F.Cu" "B.Cu")
		(net "SW_PWR_R_HDD9")
	)
	(segment
		(start 395.07795 -275.252942)
		(end 394.26515 -275.252942)
		(width 0.17145)
		(layer "F.Cu")
		(net "SW_PWR_R_HDD8")
	)
	(segment
		(start 396.34795 -273.030442)
		(end 395.20495 -273.030442)
		(width 0.17145)
		(layer "F.Cu")
		(net "SW_PWR_R_HDD8")
	)
	(segment
		(start 397.61795 -273.030442)
		(end 396.34795 -273.030442)
		(width 0.17145)
		(layer "F.Cu")
		(net "SW_PWR_R_HDD8")
	)
	(segment
		(start 398.88795 -273.030442)
		(end 397.61795 -273.030442)
		(width 0.17145)
		(layer "F.Cu")
		(net "SW_PWR_R_HDD8")
	)
	(segment
		(start 395.20495 -273.030442)
		(end 395.20495 -275.125942)
		(width 0.17145)
		(layer "F.Cu")
		(net "SW_PWR_R_HDD8")
	)
	(segment
		(start 395.20495 -275.125942)
		(end 395.07795 -275.252942)
		(width 0.17145)
		(layer "F.Cu")
		(net "SW_PWR_R_HDD8")
	)
	(via
		(at 397.61795 -273.030442)
		(size 0.6604)
		(drill 0.3302)
		(layers "F.Cu" "B.Cu")
		(net "SW_PWR_R_HDD8")
	)
	(segment
		(start 363.655102 -273.030442)
		(end 363.655102 -275.125942)
		(width 0.17145)
		(layer "F.Cu")
		(net "SW_PWR_R_HDD7")
	)
	(segment
		(start 366.068102 -273.030442)
		(end 364.798102 -273.030442)
		(width 0.17145)
		(layer "F.Cu")
		(net "SW_PWR_R_HDD7")
	)
	(segment
		(start 363.655102 -275.125942)
		(end 363.528102 -275.252942)
		(width 0.17145)
		(layer "F.Cu")
		(net "SW_PWR_R_HDD7")
	)
	(segment
		(start 363.528102 -275.252942)
		(end 362.715302 -275.252942)
		(width 0.17145)
		(layer "F.Cu")
		(net "SW_PWR_R_HDD7")
	)
	(segment
		(start 364.798102 -273.030442)
		(end 363.655102 -273.030442)
		(width 0.17145)
		(layer "F.Cu")
		(net "SW_PWR_R_HDD7")
	)
	(segment
		(start 367.338102 -273.030442)
		(end 366.068102 -273.030442)
		(width 0.17145)
		(layer "F.Cu")
		(net "SW_PWR_R_HDD7")
	)
	(via
		(at 366.068102 -273.030442)
		(size 0.6604)
		(drill 0.3302)
		(layers "F.Cu" "B.Cu")
		(net "SW_PWR_R_HDD7")
	)
	(segment
		(start 332.0034 -275.055838)
		(end 331.806296 -275.252942)
		(width 0.17145)
		(layer "F.Cu")
		(net "SW_PWR_R_HDD6")
	)
	(segment
		(start 331.4954 -273.030442)
		(end 331.4954 -273.557746)
		(width 0.17145)
		(layer "F.Cu")
		(net "SW_PWR_R_HDD6")
	)
	(segment
		(start 331.806296 -275.252942)
		(end 331.1652 -275.252942)
		(width 0.17145)
		(layer "F.Cu")
		(net "SW_PWR_R_HDD6")
	)
	(segment
		(start 332.6384 -273.030442)
		(end 331.4954 -273.030442)
		(width 0.17145)
		(layer "F.Cu")
		(net "SW_PWR_R_HDD6")
	)
	(segment
		(start 333.6036 -273.030442)
		(end 334.612742 -273.030442)
		(width 0.17145)
		(layer "F.Cu")
		(net "SW_PWR_R_HDD6")
	)
	(segment
		(start 332.0034 -274.065746)
		(end 332.0034 -275.055838)
		(width 0.17145)
		(layer "F.Cu")
		(net "SW_PWR_R_HDD6")
	)
	(segment
		(start 334.612742 -273.030442)
		(end 334.6196 -273.0373)
		(width 0.17145)
		(layer "F.Cu")
		(net "SW_PWR_R_HDD6")
	)
	(segment
		(start 333.6036 -273.030442)
		(end 332.6384 -273.030442)
		(width 0.17145)
		(layer "F.Cu")
		(net "SW_PWR_R_HDD6")
	)
	(segment
		(start 331.4954 -273.557746)
		(end 332.0034 -274.065746)
		(width 0.17145)
		(layer "F.Cu")
		(net "SW_PWR_R_HDD6")
	)
	(via
		(at 333.6036 -273.030442)
		(size 0.6604)
		(drill 0.3302)
		(layers "F.Cu" "B.Cu")
		(net "SW_PWR_R_HDD6")
	)
	(segment
		(start 180.3019 -278.554942)
		(end 178.289458 -278.554942)
		(width 0.17145)
		(layer "F.Cu")
		(net "SW_PWR_R_HDD5")
	)
	(segment
		(start 178.289458 -278.554942)
		(end 178.181 -278.6634)
		(width 0.17145)
		(layer "F.Cu")
		(net "SW_PWR_R_HDD5")
	)
	(segment
		(start 180.3019 -276.014942)
		(end 180.3019 -274.821142)
		(width 0.17145)
		(layer "F.Cu")
		(net "SW_PWR_R_HDD5")
	)
	(segment
		(start 180.3019 -277.284942)
		(end 180.3019 -276.014942)
		(width 0.17145)
		(layer "F.Cu")
		(net "SW_PWR_R_HDD5")
	)
	(segment
		(start 178.181 -278.6634)
		(end 178.181 -279.494742)
		(width 0.17145)
		(layer "F.Cu")
		(net "SW_PWR_R_HDD5")
	)
	(segment
		(start 180.3019 -277.284942)
		(end 180.3019 -278.554942)
		(width 0.17145)
		(layer "F.Cu")
		(net "SW_PWR_R_HDD5")
	)
	(via
		(at 180.3019 -277.284942)
		(size 0.6604)
		(drill 0.3302)
		(layers "F.Cu" "B.Cu")
		(net "SW_PWR_R_HDD5")
	)
	(segment
		(start 148.751798 -278.554942)
		(end 146.895058 -278.554942)
		(width 0.17145)
		(layer "F.Cu")
		(net "SW_PWR_R_HDD4")
	)
	(segment
		(start 148.751798 -277.284942)
		(end 148.751798 -276.065742)
		(width 0.17145)
		(layer "F.Cu")
		(net "SW_PWR_R_HDD4")
	)
	(segment
		(start 146.895058 -278.554942)
		(end 146.630898 -278.819102)
		(width 0.17145)
		(layer "F.Cu")
		(net "SW_PWR_R_HDD4")
	)
	(segment
		(start 148.751798 -277.284942)
		(end 148.751798 -278.554942)
		(width 0.17145)
		(layer "F.Cu")
		(net "SW_PWR_R_HDD4")
	)
	(segment
		(start 146.630898 -278.819102)
		(end 146.630898 -279.494742)
		(width 0.17145)
		(layer "F.Cu")
		(net "SW_PWR_R_HDD4")
	)
	(segment
		(start 148.751798 -276.065742)
		(end 148.751798 -274.871942)
		(width 0.17145)
		(layer "F.Cu")
		(net "SW_PWR_R_HDD4")
	)
	(via
		(at 148.751798 -277.284942)
		(size 0.6604)
		(drill 0.3302)
		(layers "F.Cu" "B.Cu")
		(net "SW_PWR_R_HDD4")
	)
	(segment
		(start 470.031318 -41.96715)
		(end 471.301318 -41.96715)
		(width 0.17145)
		(layer "F.Cu")
		(net "SW_PWR_R_HDD35")
	)
	(segment
		(start 471.301318 -41.96715)
		(end 471.301318 -43.73245)
		(width 0.17145)
		(layer "F.Cu")
		(net "SW_PWR_R_HDD35")
	)
	(segment
		(start 471.656918 -44.08805)
		(end 472.215718 -44.08805)
		(width 0.17145)
		(layer "F.Cu")
		(net "SW_PWR_R_HDD35")
	)
	(segment
		(start 468.761318 -41.96715)
		(end 470.031318 -41.96715)
		(width 0.17145)
		(layer "F.Cu")
		(net "SW_PWR_R_HDD35")
	)
	(segment
		(start 471.301318 -43.73245)
		(end 471.656918 -44.08805)
		(width 0.17145)
		(layer "F.Cu")
		(net "SW_PWR_R_HDD35")
	)
	(segment
		(start 467.618318 -41.96715)
		(end 468.761318 -41.96715)
		(width 0.17145)
		(layer "F.Cu")
		(net "SW_PWR_R_HDD35")
	)
	(via
		(at 470.031318 -41.96715)
		(size 0.6604)
		(drill 0.3302)
		(layers "F.Cu" "B.Cu")
		(net "SW_PWR_R_HDD35")
	)
	(segment
		(start 459.4479 -43.030394)
		(end 458.3049 -43.030394)
		(width 0.17145)
		(layer "F.Cu")
		(net "SW_PWR_R_HDD34")
	)
	(segment
		(start 460.7179 -43.030394)
		(end 459.4479 -43.030394)
		(width 0.17145)
		(layer "F.Cu")
		(net "SW_PWR_R_HDD34")
	)
	(segment
		(start 458.3049 -43.030394)
		(end 458.3049 -45.125894)
		(width 0.17145)
		(layer "F.Cu")
		(net "SW_PWR_R_HDD34")
	)
	(segment
		(start 461.9879 -43.030394)
		(end 460.7179 -43.030394)
		(width 0.17145)
		(layer "F.Cu")
		(net "SW_PWR_R_HDD34")
	)
	(segment
		(start 458.3049 -45.125894)
		(end 458.1779 -45.252894)
		(width 0.17145)
		(layer "F.Cu")
		(net "SW_PWR_R_HDD34")
	)
	(segment
		(start 458.1779 -45.252894)
		(end 457.3651 -45.252894)
		(width 0.17145)
		(layer "F.Cu")
		(net "SW_PWR_R_HDD34")
	)
	(via
		(at 460.7179 -43.030394)
		(size 0.6604)
		(drill 0.3302)
		(layers "F.Cu" "B.Cu")
		(net "SW_PWR_R_HDD34")
	)
	(segment
		(start 426.755052 -43.030394)
		(end 426.755052 -45.125894)
		(width 0.17145)
		(layer "F.Cu")
		(net "SW_PWR_R_HDD33")
	)
	(segment
		(start 430.438052 -43.030394)
		(end 429.168052 -43.030394)
		(width 0.17145)
		(layer "F.Cu")
		(net "SW_PWR_R_HDD33")
	)
	(segment
		(start 426.755052 -45.125894)
		(end 426.628052 -45.252894)
		(width 0.17145)
		(layer "F.Cu")
		(net "SW_PWR_R_HDD33")
	)
	(segment
		(start 427.898052 -43.030394)
		(end 426.755052 -43.030394)
		(width 0.17145)
		(layer "F.Cu")
		(net "SW_PWR_R_HDD33")
	)
	(segment
		(start 426.628052 -45.252894)
		(end 425.815252 -45.252894)
		(width 0.17145)
		(layer "F.Cu")
		(net "SW_PWR_R_HDD33")
	)
	(segment
		(start 429.168052 -43.030394)
		(end 427.898052 -43.030394)
		(width 0.17145)
		(layer "F.Cu")
		(net "SW_PWR_R_HDD33")
	)
	(via
		(at 429.168052 -43.030394)
		(size 0.6604)
		(drill 0.3302)
		(layers "F.Cu" "B.Cu")
		(net "SW_PWR_R_HDD33")
	)
	(segment
		(start 396.34795 -43.030394)
		(end 395.20495 -43.030394)
		(width 0.17145)
		(layer "F.Cu")
		(net "SW_PWR_R_HDD32")
	)
	(segment
		(start 398.88795 -43.030394)
		(end 397.61795 -43.030394)
		(width 0.17145)
		(layer "F.Cu")
		(net "SW_PWR_R_HDD32")
	)
	(segment
		(start 395.20495 -43.030394)
		(end 395.20495 -45.125894)
		(width 0.17145)
		(layer "F.Cu")
		(net "SW_PWR_R_HDD32")
	)
	(segment
		(start 395.07795 -45.252894)
		(end 394.26515 -45.252894)
		(width 0.17145)
		(layer "F.Cu")
		(net "SW_PWR_R_HDD32")
	)
	(segment
		(start 397.61795 -43.030394)
		(end 396.34795 -43.030394)
		(width 0.17145)
		(layer "F.Cu")
		(net "SW_PWR_R_HDD32")
	)
	(segment
		(start 395.20495 -45.125894)
		(end 395.07795 -45.252894)
		(width 0.17145)
		(layer "F.Cu")
		(net "SW_PWR_R_HDD32")
	)
	(via
		(at 397.61795 -43.030394)
		(size 0.6604)
		(drill 0.3302)
		(layers "F.Cu" "B.Cu")
		(net "SW_PWR_R_HDD32")
	)
	(segment
		(start 366.068102 -43.030394)
		(end 364.798102 -43.030394)
		(width 0.17145)
		(layer "F.Cu")
		(net "SW_PWR_R_HDD31")
	)
	(segment
		(start 363.655102 -45.125894)
		(end 363.528102 -45.252894)
		(width 0.17145)
		(layer "F.Cu")
		(net "SW_PWR_R_HDD31")
	)
	(segment
		(start 367.338102 -43.030394)
		(end 366.068102 -43.030394)
		(width 0.17145)
		(layer "F.Cu")
		(net "SW_PWR_R_HDD31")
	)
	(segment
		(start 363.528102 -45.252894)
		(end 362.715302 -45.252894)
		(width 0.17145)
		(layer "F.Cu")
		(net "SW_PWR_R_HDD31")
	)
	(segment
		(start 364.798102 -43.030394)
		(end 363.655102 -43.030394)
		(width 0.17145)
		(layer "F.Cu")
		(net "SW_PWR_R_HDD31")
	)
	(segment
		(start 363.655102 -43.030394)
		(end 363.655102 -45.125894)
		(width 0.17145)
		(layer "F.Cu")
		(net "SW_PWR_R_HDD31")
	)
	(via
		(at 366.068102 -43.030394)
		(size 0.6604)
		(drill 0.3302)
		(layers "F.Cu" "B.Cu")
		(net "SW_PWR_R_HDD31")
	)
	(segment
		(start 331.978 -45.252894)
		(end 331.1652 -45.252894)
		(width 0.17145)
		(layer "F.Cu")
		(net "SW_PWR_R_HDD30")
	)
	(segment
		(start 333.248 -43.030394)
		(end 332.105 -43.030394)
		(width 0.17145)
		(layer "F.Cu")
		(net "SW_PWR_R_HDD30")
	)
	(segment
		(start 334.518 -43.030394)
		(end 333.248 -43.030394)
		(width 0.17145)
		(layer "F.Cu")
		(net "SW_PWR_R_HDD30")
	)
	(segment
		(start 332.105 -43.030394)
		(end 332.105 -45.125894)
		(width 0.17145)
		(layer "F.Cu")
		(net "SW_PWR_R_HDD30")
	)
	(segment
		(start 332.105 -45.125894)
		(end 331.978 -45.252894)
		(width 0.17145)
		(layer "F.Cu")
		(net "SW_PWR_R_HDD30")
	)
	(segment
		(start 335.788 -43.030394)
		(end 334.518 -43.030394)
		(width 0.17145)
		(layer "F.Cu")
		(net "SW_PWR_R_HDD30")
	)
	(via
		(at 334.518 -43.030394)
		(size 0.6604)
		(drill 0.3302)
		(layers "F.Cu" "B.Cu")
		(net "SW_PWR_R_HDD30")
	)
	(segment
		(start 116.528342 -275.291804)
		(end 117.061742 -275.291804)
		(width 0.17145)
		(layer "F.Cu")
		(net "SW_PWR_R_HDD3")
	)
	(segment
		(start 116.121942 -273.170904)
		(end 116.121942 -274.885404)
		(width 0.17145)
		(layer "F.Cu")
		(net "SW_PWR_R_HDD3")
	)
	(segment
		(start 116.121942 -274.885404)
		(end 116.528342 -275.291804)
		(width 0.17145)
		(layer "F.Cu")
		(net "SW_PWR_R_HDD3")
	)
	(segment
		(start 113.581942 -273.170904)
		(end 114.851942 -273.170904)
		(width 0.17145)
		(layer "F.Cu")
		(net "SW_PWR_R_HDD3")
	)
	(segment
		(start 112.388142 -273.170904)
		(end 113.581942 -273.170904)
		(width 0.17145)
		(layer "F.Cu")
		(net "SW_PWR_R_HDD3")
	)
	(segment
		(start 114.851942 -273.170904)
		(end 116.121942 -273.170904)
		(width 0.17145)
		(layer "F.Cu")
		(net "SW_PWR_R_HDD3")
	)
	(via
		(at 114.851942 -273.170904)
		(size 0.6604)
		(drill 0.3302)
		(layers "F.Cu" "B.Cu")
		(net "SW_PWR_R_HDD3")
	)
	(segment
		(start 180.3019 -44.821094)
		(end 180.3019 -46.014894)
		(width 0.17145)
		(layer "F.Cu")
		(net "SW_PWR_R_HDD29")
	)
	(segment
		(start 178.181 -48.7172)
		(end 178.181 -49.494694)
		(width 0.17145)
		(layer "F.Cu")
		(net "SW_PWR_R_HDD29")
	)
	(segment
		(start 178.343306 -48.554894)
		(end 178.181 -48.7172)
		(width 0.17145)
		(layer "F.Cu")
		(net "SW_PWR_R_HDD29")
	)
	(segment
		(start 180.3019 -46.014894)
		(end 180.3019 -47.284894)
		(width 0.17145)
		(layer "F.Cu")
		(net "SW_PWR_R_HDD29")
	)
	(segment
		(start 180.3019 -47.284894)
		(end 180.3019 -48.554894)
		(width 0.17145)
		(layer "F.Cu")
		(net "SW_PWR_R_HDD29")
	)
	(segment
		(start 180.3019 -48.554894)
		(end 178.343306 -48.554894)
		(width 0.17145)
		(layer "F.Cu")
		(net "SW_PWR_R_HDD29")
	)
	(via
		(at 180.3019 -47.284894)
		(size 0.6604)
		(drill 0.3302)
		(layers "F.Cu" "B.Cu")
		(net "SW_PWR_R_HDD29")
	)
	(segment
		(start 148.751798 -47.284894)
		(end 148.751798 -48.554894)
		(width 0.17145)
		(layer "F.Cu")
		(net "SW_PWR_R_HDD28")
	)
	(segment
		(start 148.751798 -46.065694)
		(end 148.751798 -47.284894)
		(width 0.17145)
		(layer "F.Cu")
		(net "SW_PWR_R_HDD28")
	)
	(segment
		(start 148.751798 -48.554894)
		(end 146.847306 -48.554894)
		(width 0.17145)
		(layer "F.Cu")
		(net "SW_PWR_R_HDD28")
	)
	(segment
		(start 148.751798 -44.871894)
		(end 148.751798 -46.065694)
		(width 0.17145)
		(layer "F.Cu")
		(net "SW_PWR_R_HDD28")
	)
	(segment
		(start 146.630898 -48.771302)
		(end 146.630898 -49.494694)
		(width 0.17145)
		(layer "F.Cu")
		(net "SW_PWR_R_HDD28")
	)
	(segment
		(start 146.847306 -48.554894)
		(end 146.630898 -48.771302)
		(width 0.17145)
		(layer "F.Cu")
		(net "SW_PWR_R_HDD28")
	)
	(via
		(at 148.751798 -47.284894)
		(size 0.6604)
		(drill 0.3302)
		(layers "F.Cu" "B.Cu")
		(net "SW_PWR_R_HDD28")
	)
	(segment
		(start 117.201696 -46.014894)
		(end 117.201696 -47.284894)
		(width 0.17145)
		(layer "F.Cu")
		(net "SW_PWR_R_HDD27")
	)
	(segment
		(start 117.201696 -48.554894)
		(end 115.461796 -48.554894)
		(width 0.17145)
		(layer "F.Cu")
		(net "SW_PWR_R_HDD27")
	)
	(segment
		(start 117.201696 -47.284894)
		(end 117.201696 -48.554894)
		(width 0.17145)
		(layer "F.Cu")
		(net "SW_PWR_R_HDD27")
	)
	(segment
		(start 115.080796 -48.935894)
		(end 115.080796 -49.494694)
		(width 0.17145)
		(layer "F.Cu")
		(net "SW_PWR_R_HDD27")
	)
	(segment
		(start 117.201696 -44.821094)
		(end 117.201696 -46.014894)
		(width 0.17145)
		(layer "F.Cu")
		(net "SW_PWR_R_HDD27")
	)
	(segment
		(start 115.461796 -48.554894)
		(end 115.080796 -48.935894)
		(width 0.17145)
		(layer "F.Cu")
		(net "SW_PWR_R_HDD27")
	)
	(via
		(at 117.201696 -47.284894)
		(size 0.6604)
		(drill 0.3302)
		(layers "F.Cu" "B.Cu")
		(net "SW_PWR_R_HDD27")
	)
	(segment
		(start 85.651848 -47.284894)
		(end 85.651848 -46.014894)
		(width 0.17145)
		(layer "F.Cu")
		(net "SW_PWR_R_HDD26")
	)
	(segment
		(start 85.651848 -44.846494)
		(end 85.677248 -44.821094)
		(width 0.17145)
		(layer "F.Cu")
		(net "SW_PWR_R_HDD26")
	)
	(segment
		(start 83.530948 -48.935894)
		(end 83.530948 -49.494694)
		(width 0.17145)
		(layer "F.Cu")
		(net "SW_PWR_R_HDD26")
	)
	(segment
		(start 83.911948 -48.554894)
		(end 83.530948 -48.935894)
		(width 0.17145)
		(layer "F.Cu")
		(net "SW_PWR_R_HDD26")
	)
	(segment
		(start 85.651848 -48.554894)
		(end 83.911948 -48.554894)
		(width 0.17145)
		(layer "F.Cu")
		(net "SW_PWR_R_HDD26")
	)
	(segment
		(start 85.651848 -46.014894)
		(end 85.651848 -44.846494)
		(width 0.17145)
		(layer "F.Cu")
		(net "SW_PWR_R_HDD26")
	)
	(segment
		(start 85.651848 -48.554894)
		(end 85.651848 -47.284894)
		(width 0.17145)
		(layer "F.Cu")
		(net "SW_PWR_R_HDD26")
	)
	(via
		(at 85.651848 -47.284894)
		(size 0.6604)
		(drill 0.3302)
		(layers "F.Cu" "B.Cu")
		(net "SW_PWR_R_HDD26")
	)
	(segment
		(start 51.980846 -48.704754)
		(end 51.980846 -49.494694)
		(width 0.17145)
		(layer "F.Cu")
		(net "SW_PWR_R_HDD25")
	)
	(segment
		(start 54.101746 -46.065694)
		(end 54.101746 -44.871894)
		(width 0.17145)
		(layer "F.Cu")
		(net "SW_PWR_R_HDD25")
	)
	(segment
		(start 54.101746 -48.554894)
		(end 52.130706 -48.554894)
		(width 0.17145)
		(layer "F.Cu")
		(net "SW_PWR_R_HDD25")
	)
	(segment
		(start 54.101746 -47.284894)
		(end 54.101746 -48.554894)
		(width 0.17145)
		(layer "F.Cu")
		(net "SW_PWR_R_HDD25")
	)
	(segment
		(start 52.130706 -48.554894)
		(end 51.980846 -48.704754)
		(width 0.17145)
		(layer "F.Cu")
		(net "SW_PWR_R_HDD25")
	)
	(segment
		(start 54.101746 -46.065694)
		(end 54.101746 -47.284894)
		(width 0.17145)
		(layer "F.Cu")
		(net "SW_PWR_R_HDD25")
	)
	(via
		(at 54.101746 -47.284894)
		(size 0.6604)
		(drill 0.3302)
		(layers "F.Cu" "B.Cu")
		(net "SW_PWR_R_HDD25")
	)
	(segment
		(start 20.430998 -48.885602)
		(end 20.761706 -48.554894)
		(width 0.17145)
		(layer "F.Cu")
		(net "SW_PWR_R_HDD24")
	)
	(segment
		(start 22.4282 -46.713394)
		(end 22.4282 -47.3202)
		(width 0.17145)
		(layer "F.Cu")
		(net "SW_PWR_R_HDD24")
	)
	(segment
		(start 20.761706 -48.554894)
		(end 22.551898 -48.554894)
		(width 0.17145)
		(layer "F.Cu")
		(net "SW_PWR_R_HDD24")
	)
	(segment
		(start 22.526498 -46.014894)
		(end 22.526498 -46.615096)
		(width 0.17145)
		(layer "F.Cu")
		(net "SW_PWR_R_HDD24")
	)
	(segment
		(start 22.526498 -46.615096)
		(end 22.4282 -46.713394)
		(width 0.17145)
		(layer "F.Cu")
		(net "SW_PWR_R_HDD24")
	)
	(segment
		(start 20.430998 -49.494694)
		(end 20.430998 -48.885602)
		(width 0.17145)
		(layer "F.Cu")
		(net "SW_PWR_R_HDD24")
	)
	(segment
		(start 22.526498 -46.014894)
		(end 22.526498 -44.871894)
		(width 0.17145)
		(layer "F.Cu")
		(net "SW_PWR_R_HDD24")
	)
	(segment
		(start 22.551898 -48.028098)
		(end 22.551898 -48.554894)
		(width 0.17145)
		(layer "F.Cu")
		(net "SW_PWR_R_HDD24")
	)
	(segment
		(start 22.4282 -47.3202)
		(end 22.4282 -47.9044)
		(width 0.17145)
		(layer "F.Cu")
		(net "SW_PWR_R_HDD24")
	)
	(segment
		(start 22.4282 -47.9044)
		(end 22.551898 -48.028098)
		(width 0.17145)
		(layer "F.Cu")
		(net "SW_PWR_R_HDD24")
	)
	(via
		(at 22.4282 -47.3202)
		(size 0.6604)
		(drill 0.3302)
		(layers "F.Cu" "B.Cu")
		(net "SW_PWR_R_HDD24")
	)
	(segment
		(start 470.005918 -156.967174)
		(end 468.735918 -156.967174)
		(width 0.17145)
		(layer "F.Cu")
		(net "SW_PWR_R_HDD23")
	)
	(segment
		(start 471.275918 -156.967174)
		(end 471.275918 -158.707074)
		(width 0.17145)
		(layer "F.Cu")
		(net "SW_PWR_R_HDD23")
	)
	(segment
		(start 470.005918 -156.967174)
		(end 471.275918 -156.967174)
		(width 0.17145)
		(layer "F.Cu")
		(net "SW_PWR_R_HDD23")
	)
	(segment
		(start 471.275918 -158.707074)
		(end 471.656918 -159.088074)
		(width 0.17145)
		(layer "F.Cu")
		(net "SW_PWR_R_HDD23")
	)
	(segment
		(start 471.656918 -159.088074)
		(end 472.215718 -159.088074)
		(width 0.17145)
		(layer "F.Cu")
		(net "SW_PWR_R_HDD23")
	)
	(segment
		(start 468.735918 -156.967174)
		(end 467.592918 -156.967174)
		(width 0.17145)
		(layer "F.Cu")
		(net "SW_PWR_R_HDD23")
	)
	(via
		(at 470.005918 -156.967174)
		(size 0.6604)
		(drill 0.3302)
		(layers "F.Cu" "B.Cu")
		(net "SW_PWR_R_HDD23")
	)
	(segment
		(start 458.1779 -160.252918)
		(end 457.3651 -160.252918)
		(width 0.17145)
		(layer "F.Cu")
		(net "SW_PWR_R_HDD22")
	)
	(segment
		(start 459.4479 -158.030418)
		(end 458.3049 -158.030418)
		(width 0.17145)
		(layer "F.Cu")
		(net "SW_PWR_R_HDD22")
	)
	(segment
		(start 460.7179 -158.030418)
		(end 459.4479 -158.030418)
		(width 0.17145)
		(layer "F.Cu")
		(net "SW_PWR_R_HDD22")
	)
	(segment
		(start 458.3049 -160.125918)
		(end 458.1779 -160.252918)
		(width 0.17145)
		(layer "F.Cu")
		(net "SW_PWR_R_HDD22")
	)
	(segment
		(start 461.9879 -158.030418)
		(end 460.7179 -158.030418)
		(width 0.17145)
		(layer "F.Cu")
		(net "SW_PWR_R_HDD22")
	)
	(segment
		(start 458.3049 -158.030418)
		(end 458.3049 -160.125918)
		(width 0.17145)
		(layer "F.Cu")
		(net "SW_PWR_R_HDD22")
	)
	(via
		(at 460.7179 -158.030418)
		(size 0.6604)
		(drill 0.3302)
		(layers "F.Cu" "B.Cu")
		(net "SW_PWR_R_HDD22")
	)
	(segment
		(start 426.628052 -160.252918)
		(end 425.815252 -160.252918)
		(width 0.17145)
		(layer "F.Cu")
		(net "SW_PWR_R_HDD21")
	)
	(segment
		(start 426.755052 -160.125918)
		(end 426.628052 -160.252918)
		(width 0.17145)
		(layer "F.Cu")
		(net "SW_PWR_R_HDD21")
	)
	(segment
		(start 427.898052 -158.030418)
		(end 426.755052 -158.030418)
		(width 0.17145)
		(layer "F.Cu")
		(net "SW_PWR_R_HDD21")
	)
	(segment
		(start 429.168052 -158.030418)
		(end 427.898052 -158.030418)
		(width 0.17145)
		(layer "F.Cu")
		(net "SW_PWR_R_HDD21")
	)
	(segment
		(start 430.438052 -158.030418)
		(end 429.168052 -158.030418)
		(width 0.17145)
		(layer "F.Cu")
		(net "SW_PWR_R_HDD21")
	)
	(segment
		(start 426.755052 -158.030418)
		(end 426.755052 -160.125918)
		(width 0.17145)
		(layer "F.Cu")
		(net "SW_PWR_R_HDD21")
	)
	(via
		(at 429.168052 -158.030418)
		(size 0.6604)
		(drill 0.3302)
		(layers "F.Cu" "B.Cu")
		(net "SW_PWR_R_HDD21")
	)
	(segment
		(start 395.20495 -158.030418)
		(end 395.20495 -160.125918)
		(width 0.17145)
		(layer "F.Cu")
		(net "SW_PWR_R_HDD20")
	)
	(segment
		(start 397.61795 -158.030418)
		(end 396.34795 -158.030418)
		(width 0.17145)
		(layer "F.Cu")
		(net "SW_PWR_R_HDD20")
	)
	(segment
		(start 395.20495 -160.125918)
		(end 395.07795 -160.252918)
		(width 0.17145)
		(layer "F.Cu")
		(net "SW_PWR_R_HDD20")
	)
	(segment
		(start 398.88795 -158.030418)
		(end 397.61795 -158.030418)
		(width 0.17145)
		(layer "F.Cu")
		(net "SW_PWR_R_HDD20")
	)
	(segment
		(start 395.07795 -160.252918)
		(end 394.26515 -160.252918)
		(width 0.17145)
		(layer "F.Cu")
		(net "SW_PWR_R_HDD20")
	)
	(segment
		(start 396.34795 -158.030418)
		(end 395.20495 -158.030418)
		(width 0.17145)
		(layer "F.Cu")
		(net "SW_PWR_R_HDD20")
	)
	(via
		(at 397.61795 -158.030418)
		(size 0.6604)
		(drill 0.3302)
		(layers "F.Cu" "B.Cu")
		(net "SW_PWR_R_HDD20")
	)
	(segment
		(start 85.677248 -278.580342)
		(end 83.886548 -278.580342)
		(width 0.17145)
		(layer "F.Cu")
		(net "SW_PWR_R_HDD2")
	)
	(segment
		(start 83.530948 -278.935942)
		(end 83.530948 -279.494742)
		(width 0.17145)
		(layer "F.Cu")
		(net "SW_PWR_R_HDD2")
	)
	(segment
		(start 85.677248 -274.846542)
		(end 85.677248 -276.040342)
		(width 0.17145)
		(layer "F.Cu")
		(net "SW_PWR_R_HDD2")
	)
	(segment
		(start 85.677248 -276.040342)
		(end 85.677248 -277.310342)
		(width 0.17145)
		(layer "F.Cu")
		(net "SW_PWR_R_HDD2")
	)
	(segment
		(start 83.886548 -278.580342)
		(end 83.530948 -278.935942)
		(width 0.17145)
		(layer "F.Cu")
		(net "SW_PWR_R_HDD2")
	)
	(segment
		(start 85.677248 -277.310342)
		(end 85.677248 -278.580342)
		(width 0.17145)
		(layer "F.Cu")
		(net "SW_PWR_R_HDD2")
	)
	(via
		(at 85.677248 -277.310342)
		(size 0.6604)
		(drill 0.3302)
		(layers "F.Cu" "B.Cu")
		(net "SW_PWR_R_HDD2")
	)
	(segment
		(start 364.798102 -158.030418)
		(end 363.655102 -158.030418)
		(width 0.17145)
		(layer "F.Cu")
		(net "SW_PWR_R_HDD19")
	)
	(segment
		(start 366.068102 -158.030418)
		(end 364.798102 -158.030418)
		(width 0.17145)
		(layer "F.Cu")
		(net "SW_PWR_R_HDD19")
	)
	(segment
		(start 363.528102 -160.252918)
		(end 362.715302 -160.252918)
		(width 0.17145)
		(layer "F.Cu")
		(net "SW_PWR_R_HDD19")
	)
	(segment
		(start 367.338102 -158.030418)
		(end 366.068102 -158.030418)
		(width 0.17145)
		(layer "F.Cu")
		(net "SW_PWR_R_HDD19")
	)
	(segment
		(start 363.655102 -158.030418)
		(end 363.655102 -160.125918)
		(width 0.17145)
		(layer "F.Cu")
		(net "SW_PWR_R_HDD19")
	)
	(segment
		(start 363.655102 -160.125918)
		(end 363.528102 -160.252918)
		(width 0.17145)
		(layer "F.Cu")
		(net "SW_PWR_R_HDD19")
	)
	(via
		(at 366.068102 -158.030418)
		(size 0.6604)
		(drill 0.3302)
		(layers "F.Cu" "B.Cu")
		(net "SW_PWR_R_HDD19")
	)
	(segment
		(start 331.978 -160.252918)
		(end 331.1652 -160.252918)
		(width 0.17145)
		(layer "F.Cu")
		(net "SW_PWR_R_HDD18")
	)
	(segment
		(start 332.105 -158.030418)
		(end 332.105 -160.125918)
		(width 0.17145)
		(layer "F.Cu")
		(net "SW_PWR_R_HDD18")
	)
	(segment
		(start 335.788 -158.030418)
		(end 334.518 -158.030418)
		(width 0.17145)
		(layer "F.Cu")
		(net "SW_PWR_R_HDD18")
	)
	(segment
		(start 332.105 -160.125918)
		(end 331.978 -160.252918)
		(width 0.17145)
		(layer "F.Cu")
		(net "SW_PWR_R_HDD18")
	)
	(segment
		(start 334.518 -158.030418)
		(end 333.248 -158.030418)
		(width 0.17145)
		(layer "F.Cu")
		(net "SW_PWR_R_HDD18")
	)
	(segment
		(start 333.248 -158.030418)
		(end 332.105 -158.030418)
		(width 0.17145)
		(layer "F.Cu")
		(net "SW_PWR_R_HDD18")
	)
	(via
		(at 334.518 -158.030418)
		(size 0.6604)
		(drill 0.3302)
		(layers "F.Cu" "B.Cu")
		(net "SW_PWR_R_HDD18")
	)
	(segment
		(start 178.453034 -163.925504)
		(end 179.329842 -163.925504)
		(width 0.17145)
		(layer "F.Cu")
		(net "SW_PWR_R_HDD17")
	)
	(segment
		(start 178.2318 -164.875718)
		(end 178.2318 -164.146738)
		(width 0.17145)
		(layer "F.Cu")
		(net "SW_PWR_R_HDD17")
	)
	(segment
		(start 178.2318 -164.146738)
		(end 178.453034 -163.925504)
		(width 0.17145)
		(layer "F.Cu")
		(net "SW_PWR_R_HDD17")
	)
	(segment
		(start 180.3019 -162.284918)
		(end 180.3019 -163.554918)
		(width 0.17145)
		(layer "F.Cu")
		(net "SW_PWR_R_HDD17")
	)
	(segment
		(start 179.329842 -163.925504)
		(end 179.700428 -163.554918)
		(width 0.17145)
		(layer "F.Cu")
		(net "SW_PWR_R_HDD17")
	)
	(segment
		(start 180.3019 -161.014918)
		(end 180.3019 -162.284918)
		(width 0.17145)
		(layer "F.Cu")
		(net "SW_PWR_R_HDD17")
	)
	(segment
		(start 180.3019 -159.871918)
		(end 180.3019 -161.014918)
		(width 0.17145)
		(layer "F.Cu")
		(net "SW_PWR_R_HDD17")
	)
	(segment
		(start 179.700428 -163.554918)
		(end 180.3019 -163.554918)
		(width 0.17145)
		(layer "F.Cu")
		(net "SW_PWR_R_HDD17")
	)
	(via
		(at 180.3019 -162.284918)
		(size 0.6604)
		(drill 0.3302)
		(layers "F.Cu" "B.Cu")
		(net "SW_PWR_R_HDD17")
	)
	(segment
		(start 148.751798 -161.040318)
		(end 148.751798 -162.284918)
		(width 0.17145)
		(layer "F.Cu")
		(net "SW_PWR_R_HDD16")
	)
	(segment
		(start 147.011898 -163.554918)
		(end 146.630898 -163.935918)
		(width 0.17145)
		(layer "F.Cu")
		(net "SW_PWR_R_HDD16")
	)
	(segment
		(start 148.751798 -162.284918)
		(end 148.751798 -163.554918)
		(width 0.17145)
		(layer "F.Cu")
		(net "SW_PWR_R_HDD16")
	)
	(segment
		(start 148.751798 -159.871918)
		(end 148.751798 -161.040318)
		(width 0.17145)
		(layer "F.Cu")
		(net "SW_PWR_R_HDD16")
	)
	(segment
		(start 146.630898 -163.935918)
		(end 146.630898 -164.494718)
		(width 0.17145)
		(layer "F.Cu")
		(net "SW_PWR_R_HDD16")
	)
	(segment
		(start 148.751798 -163.554918)
		(end 147.011898 -163.554918)
		(width 0.17145)
		(layer "F.Cu")
		(net "SW_PWR_R_HDD16")
	)
	(via
		(at 148.751798 -162.284918)
		(size 0.6604)
		(drill 0.3302)
		(layers "F.Cu" "B.Cu")
		(net "SW_PWR_R_HDD16")
	)
	(segment
		(start 117.183662 -159.939228)
		(end 117.201696 -159.957262)
		(width 0.17145)
		(layer "F.Cu")
		(net "SW_PWR_R_HDD15")
	)
	(segment
		(start 117.201696 -163.554918)
		(end 117.201696 -163.18865)
		(width 0.17145)
		(layer "F.Cu")
		(net "SW_PWR_R_HDD15")
	)
	(segment
		(start 115.080796 -164.494718)
		(end 115.080796 -163.935918)
		(width 0.17145)
		(layer "F.Cu")
		(net "SW_PWR_R_HDD15")
	)
	(segment
		(start 117.201696 -161.377884)
		(end 116.972334 -161.607246)
		(width 0.17145)
		(layer "F.Cu")
		(net "SW_PWR_R_HDD15")
	)
	(segment
		(start 117.201696 -161.014918)
		(end 117.201696 -161.377884)
		(width 0.17145)
		(layer "F.Cu")
		(net "SW_PWR_R_HDD15")
	)
	(segment
		(start 115.461796 -163.554918)
		(end 117.201696 -163.554918)
		(width 0.17145)
		(layer "F.Cu")
		(net "SW_PWR_R_HDD15")
	)
	(segment
		(start 116.972334 -162.959288)
		(end 116.972334 -162.280854)
		(width 0.17145)
		(layer "F.Cu")
		(net "SW_PWR_R_HDD15")
	)
	(segment
		(start 116.972334 -161.607246)
		(end 116.972334 -162.280854)
		(width 0.17145)
		(layer "F.Cu")
		(net "SW_PWR_R_HDD15")
	)
	(segment
		(start 117.201696 -159.957262)
		(end 117.201696 -161.014918)
		(width 0.17145)
		(layer "F.Cu")
		(net "SW_PWR_R_HDD15")
	)
	(segment
		(start 115.080796 -163.935918)
		(end 115.461796 -163.554918)
		(width 0.17145)
		(layer "F.Cu")
		(net "SW_PWR_R_HDD15")
	)
	(segment
		(start 117.201696 -163.18865)
		(end 116.972334 -162.959288)
		(width 0.17145)
		(layer "F.Cu")
		(net "SW_PWR_R_HDD15")
	)
	(via
		(at 116.972334 -162.280854)
		(size 0.6604)
		(drill 0.3302)
		(layers "F.Cu" "B.Cu")
		(net "SW_PWR_R_HDD15")
	)
	(segment
		(start 85.651848 -161.040318)
		(end 85.644228 -161.032698)
		(width 0.17145)
		(layer "F.Cu")
		(net "SW_PWR_R_HDD14")
	)
	(segment
		(start 85.447886 -162.686238)
		(end 85.651848 -162.8902)
		(width 0.17145)
		(layer "F.Cu")
		(net "SW_PWR_R_HDD14")
	)
	(segment
		(start 85.447886 -162.318446)
		(end 85.447886 -162.686238)
		(width 0.17145)
		(layer "F.Cu")
		(net "SW_PWR_R_HDD14")
	)
	(segment
		(start 83.530948 -163.935918)
		(end 83.530948 -164.494718)
		(width 0.17145)
		(layer "F.Cu")
		(net "SW_PWR_R_HDD14")
	)
	(segment
		(start 85.447886 -161.719514)
		(end 85.651848 -161.515552)
		(width 0.17145)
		(layer "F.Cu")
		(net "SW_PWR_R_HDD14")
	)
	(segment
		(start 85.651848 -162.8902)
		(end 85.651848 -163.580318)
		(width 0.17145)
		(layer "F.Cu")
		(net "SW_PWR_R_HDD14")
	)
	(segment
		(start 85.447886 -162.318446)
		(end 85.447886 -161.719514)
		(width 0.17145)
		(layer "F.Cu")
		(net "SW_PWR_R_HDD14")
	)
	(segment
		(start 85.651848 -163.580318)
		(end 83.886548 -163.580318)
		(width 0.17145)
		(layer "F.Cu")
		(net "SW_PWR_R_HDD14")
	)
	(segment
		(start 83.886548 -163.580318)
		(end 83.530948 -163.935918)
		(width 0.17145)
		(layer "F.Cu")
		(net "SW_PWR_R_HDD14")
	)
	(segment
		(start 85.651848 -161.515552)
		(end 85.651848 -161.040318)
		(width 0.17145)
		(layer "F.Cu")
		(net "SW_PWR_R_HDD14")
	)
	(segment
		(start 85.644228 -161.032698)
		(end 85.644228 -159.874966)
		(width 0.17145)
		(layer "F.Cu")
		(net "SW_PWR_R_HDD14")
	)
	(via
		(at 85.447886 -162.318446)
		(size 0.6604)
		(drill 0.3302)
		(layers "F.Cu" "B.Cu")
		(net "SW_PWR_R_HDD14")
	)
	(segment
		(start 54.101746 -159.617918)
		(end 54.101746 -160.887918)
		(width 0.17145)
		(layer "F.Cu")
		(net "SW_PWR_R_HDD13")
	)
	(segment
		(start 52.25288 -161.258504)
		(end 53.129688 -161.258504)
		(width 0.17145)
		(layer "F.Cu")
		(net "SW_PWR_R_HDD13")
	)
	(segment
		(start 52.031646 -162.208718)
		(end 52.031646 -161.479738)
		(width 0.17145)
		(layer "F.Cu")
		(net "SW_PWR_R_HDD13")
	)
	(segment
		(start 52.031646 -161.479738)
		(end 52.25288 -161.258504)
		(width 0.17145)
		(layer "F.Cu")
		(net "SW_PWR_R_HDD13")
	)
	(segment
		(start 53.129688 -161.258504)
		(end 53.500274 -160.887918)
		(width 0.17145)
		(layer "F.Cu")
		(net "SW_PWR_R_HDD13")
	)
	(segment
		(start 54.101746 -158.347918)
		(end 54.101746 -157.204918)
		(width 0.17145)
		(layer "F.Cu")
		(net "SW_PWR_R_HDD13")
	)
	(segment
		(start 54.101746 -159.617918)
		(end 54.101746 -158.347918)
		(width 0.17145)
		(layer "F.Cu")
		(net "SW_PWR_R_HDD13")
	)
	(segment
		(start 53.500274 -160.887918)
		(end 54.101746 -160.887918)
		(width 0.17145)
		(layer "F.Cu")
		(net "SW_PWR_R_HDD13")
	)
	(via
		(at 54.101746 -159.617918)
		(size 0.6604)
		(drill 0.3302)
		(layers "F.Cu" "B.Cu")
		(net "SW_PWR_R_HDD13")
	)
	(segment
		(start 22.306026 -162.720782)
		(end 22.306026 -162.2933)
		(width 0.17145)
		(layer "F.Cu")
		(net "SW_PWR_R_HDD12")
	)
	(segment
		(start 22.526498 -161.439606)
		(end 22.526498 -161.014918)
		(width 0.17145)
		(layer "F.Cu")
		(net "SW_PWR_R_HDD12")
	)
	(segment
		(start 22.526498 -161.014918)
		(end 22.526498 -159.936688)
		(width 0.17145)
		(layer "F.Cu")
		(net "SW_PWR_R_HDD12")
	)
	(segment
		(start 20.430998 -163.795202)
		(end 20.671282 -163.554918)
		(width 0.17145)
		(layer "F.Cu")
		(net "SW_PWR_R_HDD12")
	)
	(segment
		(start 22.551898 -163.554918)
		(end 22.551898 -162.966654)
		(width 0.17145)
		(layer "F.Cu")
		(net "SW_PWR_R_HDD12")
	)
	(segment
		(start 22.306026 -161.660078)
		(end 22.526498 -161.439606)
		(width 0.17145)
		(layer "F.Cu")
		(net "SW_PWR_R_HDD12")
	)
	(segment
		(start 20.671282 -163.554918)
		(end 22.551898 -163.554918)
		(width 0.17145)
		(layer "F.Cu")
		(net "SW_PWR_R_HDD12")
	)
	(segment
		(start 22.306026 -162.2933)
		(end 22.306026 -161.660078)
		(width 0.17145)
		(layer "F.Cu")
		(net "SW_PWR_R_HDD12")
	)
	(segment
		(start 22.551898 -162.966654)
		(end 22.306026 -162.720782)
		(width 0.17145)
		(layer "F.Cu")
		(net "SW_PWR_R_HDD12")
	)
	(segment
		(start 20.430998 -164.494718)
		(end 20.430998 -163.795202)
		(width 0.17145)
		(layer "F.Cu")
		(net "SW_PWR_R_HDD12")
	)
	(segment
		(start 22.526498 -159.936688)
		(end 22.516084 -159.926274)
		(width 0.17145)
		(layer "F.Cu")
		(net "SW_PWR_R_HDD12")
	)
	(via
		(at 22.306026 -162.2933)
		(size 0.6604)
		(drill 0.3302)
		(layers "F.Cu" "B.Cu")
		(net "SW_PWR_R_HDD12")
	)
	(segment
		(start 475.733618 -271.021556)
		(end 476.4532 -271.021556)
		(width 0.17145)
		(layer "F.Cu")
		(net "SW_PWR_R_HDD11")
	)
	(segment
		(start 475.529148 -270.817086)
		(end 475.733618 -271.021556)
		(width 0.17145)
		(layer "F.Cu")
		(net "SW_PWR_R_HDD11")
	)
	(segment
		(start 476.4532 -271.021556)
		(end 476.672148 -270.802608)
		(width 0.17145)
		(layer "F.Cu")
		(net "SW_PWR_R_HDD11")
	)
	(segment
		(start 474.669104 -274.193)
		(end 475.24162 -274.193)
		(width 0.17145)
		(layer "F.Cu")
		(net "SW_PWR_R_HDD11")
	)
	(segment
		(start 474.26626 -273.790156)
		(end 474.669104 -274.193)
		(width 0.17145)
		(layer "F.Cu")
		(net "SW_PWR_R_HDD11")
	)
	(segment
		(start 474.4974 -269.8115)
		(end 474.26626 -270.04264)
		(width 0.17145)
		(layer "F.Cu")
		(net "SW_PWR_R_HDD11")
	)
	(segment
		(start 474.4974 -269.8115)
		(end 475.510352 -269.8115)
		(width 0.17145)
		(layer "F.Cu")
		(net "SW_PWR_R_HDD11")
	)
	(segment
		(start 475.510352 -269.8115)
		(end 475.529148 -269.792704)
		(width 0.17145)
		(layer "F.Cu")
		(net "SW_PWR_R_HDD11")
	)
	(segment
		(start 474.26626 -270.04264)
		(end 474.26626 -273.790156)
		(width 0.17145)
		(layer "F.Cu")
		(net "SW_PWR_R_HDD11")
	)
	(segment
		(start 476.672148 -270.802608)
		(end 476.672148 -269.792704)
		(width 0.17145)
		(layer "F.Cu")
		(net "SW_PWR_R_HDD11")
	)
	(segment
		(start 475.529148 -269.792704)
		(end 475.529148 -270.817086)
		(width 0.17145)
		(layer "F.Cu")
		(net "SW_PWR_R_HDD11")
	)
	(via
		(at 475.733618 -271.021556)
		(size 0.6604)
		(drill 0.3302)
		(layers "F.Cu" "B.Cu")
		(net "SW_PWR_R_HDD11")
	)
	(segment
		(start 458.172058 -275.252942)
		(end 457.3651 -275.252942)
		(width 0.17145)
		(layer "F.Cu")
		(net "SW_PWR_R_HDD10")
	)
	(segment
		(start 458.3176 -274.193254)
		(end 458.3176 -275.1074)
		(width 0.17145)
		(layer "F.Cu")
		(net "SW_PWR_R_HDD10")
	)
	(segment
		(start 461.0735 -272.979642)
		(end 459.8035 -272.979642)
		(width 0.17145)
		(layer "F.Cu")
		(net "SW_PWR_R_HDD10")
	)
	(segment
		(start 458.5335 -272.979642)
		(end 457.3905 -272.979642)
		(width 0.17145)
		(layer "F.Cu")
		(net "SW_PWR_R_HDD10")
	)
	(segment
		(start 458.3176 -275.1074)
		(end 458.172058 -275.252942)
		(width 0.17145)
		(layer "F.Cu")
		(net "SW_PWR_R_HDD10")
	)
	(segment
		(start 459.8035 -272.979642)
		(end 458.5335 -272.979642)
		(width 0.17145)
		(layer "F.Cu")
		(net "SW_PWR_R_HDD10")
	)
	(segment
		(start 457.3905 -273.266154)
		(end 458.3176 -274.193254)
		(width 0.17145)
		(layer "F.Cu")
		(net "SW_PWR_R_HDD10")
	)
	(segment
		(start 457.3905 -272.979642)
		(end 457.3905 -273.266154)
		(width 0.17145)
		(layer "F.Cu")
		(net "SW_PWR_R_HDD10")
	)
	(via
		(at 459.8035 -272.979642)
		(size 0.6604)
		(drill 0.3302)
		(layers "F.Cu" "B.Cu")
		(net "SW_PWR_R_HDD10")
	)
	(segment
		(start 51.980846 -278.803354)
		(end 51.980846 -279.494742)
		(width 0.17145)
		(layer "F.Cu")
		(net "SW_PWR_R_HDD1")
	)
	(segment
		(start 54.101746 -276.065742)
		(end 54.101746 -277.284942)
		(width 0.17145)
		(layer "F.Cu")
		(net "SW_PWR_R_HDD1")
	)
	(segment
		(start 52.229258 -278.554942)
		(end 51.980846 -278.803354)
		(width 0.17145)
		(layer "F.Cu")
		(net "SW_PWR_R_HDD1")
	)
	(segment
		(start 54.101746 -278.554942)
		(end 52.229258 -278.554942)
		(width 0.17145)
		(layer "F.Cu")
		(net "SW_PWR_R_HDD1")
	)
	(segment
		(start 54.101746 -274.871942)
		(end 54.101746 -276.065742)
		(width 0.17145)
		(layer "F.Cu")
		(net "SW_PWR_R_HDD1")
	)
	(segment
		(start 54.101746 -277.284942)
		(end 54.101746 -278.554942)
		(width 0.17145)
		(layer "F.Cu")
		(net "SW_PWR_R_HDD1")
	)
	(via
		(at 54.101746 -277.284942)
		(size 0.6604)
		(drill 0.3302)
		(layers "F.Cu" "B.Cu")
		(net "SW_PWR_R_HDD1")
	)
	(segment
		(start 431.581052 -276.180042)
		(end 431.581052 -276.570948)
		(width 0.17145)
		(layer "F.Cu")
		(net "SW_HDD_R9")
	)
	(segment
		(start 430.387252 -276.180042)
		(end 431.581052 -276.180042)
		(width 0.17145)
		(layer "F.Cu")
		(net "SW_HDD_R9")
	)
	(segment
		(start 432.279552 -279.443942)
		(end 431.073052 -279.443942)
		(width 0.17145)
		(layer "F.Cu")
		(net "SW_HDD_R9")
	)
	(segment
		(start 431.073052 -279.443942)
		(end 430.819052 -279.189942)
		(width 0.17145)
		(layer "F.Cu")
		(net "SW_HDD_R9")
	)
	(segment
		(start 431.581052 -276.570948)
		(end 430.819052 -277.332948)
		(width 0.17145)
		(layer "F.Cu")
		(net "SW_HDD_R9")
	)
	(segment
		(start 428.825152 -276.180042)
		(end 430.387252 -276.180042)
		(width 0.17145)
		(layer "F.Cu")
		(net "SW_HDD_R9")
	)
	(segment
		(start 430.819052 -277.332948)
		(end 430.819052 -277.792942)
		(width 0.17145)
		(layer "F.Cu")
		(net "SW_HDD_R9")
	)
	(segment
		(start 430.819052 -279.189942)
		(end 430.819052 -277.792942)
		(width 0.17145)
		(layer "F.Cu")
		(net "SW_HDD_R9")
	)
	(segment
		(start 428.548292 -275.903182)
		(end 428.825152 -276.180042)
		(width 0.17145)
		(layer "F.Cu")
		(net "SW_HDD_R9")
	)
	(segment
		(start 427.694852 -275.903182)
		(end 428.548292 -275.903182)
		(width 0.17145)
		(layer "F.Cu")
		(net "SW_HDD_R9")
	)
	(via
		(at 431.073052 -279.443942)
		(size 0.6604)
		(drill 0.3302)
		(layers "F.Cu" "B.Cu")
		(net "SW_HDD_R9")
	)
	(segment
		(start 396.99819 -275.903182)
		(end 397.30045 -276.205442)
		(width 0.17145)
		(layer "F.Cu")
		(net "SW_HDD_R8")
	)
	(segment
		(start 397.30045 -276.205442)
		(end 398.88795 -276.205442)
		(width 0.17145)
		(layer "F.Cu")
		(net "SW_HDD_R8")
	)
	(segment
		(start 401.83435 -277.843742)
		(end 401.58035 -277.589742)
		(width 0.17145)
		(layer "F.Cu")
		(net "SW_HDD_R8")
	)
	(segment
		(start 401.58035 -277.589742)
		(end 401.58035 -276.192742)
		(width 0.17145)
		(layer "F.Cu")
		(net "SW_HDD_R8")
	)
	(segment
		(start 400.03095 -276.205442)
		(end 401.56765 -276.205442)
		(width 0.17145)
		(layer "F.Cu")
		(net "SW_HDD_R8")
	)
	(segment
		(start 396.14475 -275.903182)
		(end 396.99819 -275.903182)
		(width 0.17145)
		(layer "F.Cu")
		(net "SW_HDD_R8")
	)
	(segment
		(start 401.56765 -276.205442)
		(end 401.58035 -276.192742)
		(width 0.17145)
		(layer "F.Cu")
		(net "SW_HDD_R8")
	)
	(segment
		(start 403.04085 -277.843742)
		(end 401.83435 -277.843742)
		(width 0.17145)
		(layer "F.Cu")
		(net "SW_HDD_R8")
	)
	(segment
		(start 398.88795 -276.205442)
		(end 400.03095 -276.205442)
		(width 0.17145)
		(layer "F.Cu")
		(net "SW_HDD_R8")
	)
	(via
		(at 401.83435 -277.843742)
		(size 0.6604)
		(drill 0.3302)
		(layers "F.Cu" "B.Cu")
		(net "SW_HDD_R8")
	)
	(segment
		(start 365.448342 -275.903182)
		(end 365.725202 -276.180042)
		(width 0.17145)
		(layer "F.Cu")
		(net "SW_HDD_R7")
	)
	(segment
		(start 368.481102 -276.180042)
		(end 368.481102 -276.704298)
		(width 0.17145)
		(layer "F.Cu")
		(net "SW_HDD_R7")
	)
	(segment
		(start 367.719102 -277.466298)
		(end 367.719102 -277.792942)
		(width 0.17145)
		(layer "F.Cu")
		(net "SW_HDD_R7")
	)
	(segment
		(start 369.179602 -279.443942)
		(end 367.973102 -279.443942)
		(width 0.17145)
		(layer "F.Cu")
		(net "SW_HDD_R7")
	)
	(segment
		(start 365.725202 -276.180042)
		(end 367.287302 -276.180042)
		(width 0.17145)
		(layer "F.Cu")
		(net "SW_HDD_R7")
	)
	(segment
		(start 367.719102 -277.792942)
		(end 367.719102 -279.189942)
		(width 0.17145)
		(layer "F.Cu")
		(net "SW_HDD_R7")
	)
	(segment
		(start 364.594902 -275.903182)
		(end 365.448342 -275.903182)
		(width 0.17145)
		(layer "F.Cu")
		(net "SW_HDD_R7")
	)
	(segment
		(start 367.287302 -276.180042)
		(end 368.481102 -276.180042)
		(width 0.17145)
		(layer "F.Cu")
		(net "SW_HDD_R7")
	)
	(segment
		(start 367.719102 -279.189942)
		(end 367.973102 -279.443942)
		(width 0.17145)
		(layer "F.Cu")
		(net "SW_HDD_R7")
	)
	(segment
		(start 368.481102 -276.704298)
		(end 367.719102 -277.466298)
		(width 0.17145)
		(layer "F.Cu")
		(net "SW_HDD_R7")
	)
	(via
		(at 367.973102 -279.443942)
		(size 0.6604)
		(drill 0.3302)
		(layers "F.Cu" "B.Cu")
		(net "SW_HDD_R7")
	)
	(segment
		(start 336.169 -279.189942)
		(end 336.169 -277.792942)
		(width 0.17145)
		(layer "F.Cu")
		(net "SW_HDD_R6")
	)
	(segment
		(start 333.0448 -275.903182)
		(end 333.89824 -275.903182)
		(width 0.17145)
		(layer "F.Cu")
		(net "SW_HDD_R6")
	)
	(segment
		(start 336.169 -277.4696)
		(end 336.169 -277.792942)
		(width 0.17145)
		(layer "F.Cu")
		(net "SW_HDD_R6")
	)
	(segment
		(start 333.89824 -275.903182)
		(end 334.1751 -276.180042)
		(width 0.17145)
		(layer "F.Cu")
		(net "SW_HDD_R6")
	)
	(segment
		(start 335.788 -276.180042)
		(end 336.931 -276.180042)
		(width 0.17145)
		(layer "F.Cu")
		(net "SW_HDD_R6")
	)
	(segment
		(start 336.931 -276.180042)
		(end 336.931 -276.7076)
		(width 0.17145)
		(layer "F.Cu")
		(net "SW_HDD_R6")
	)
	(segment
		(start 336.423 -279.443942)
		(end 336.169 -279.189942)
		(width 0.17145)
		(layer "F.Cu")
		(net "SW_HDD_R6")
	)
	(segment
		(start 334.1751 -276.180042)
		(end 335.788 -276.180042)
		(width 0.17145)
		(layer "F.Cu")
		(net "SW_HDD_R6")
	)
	(segment
		(start 337.6295 -279.443942)
		(end 336.423 -279.443942)
		(width 0.17145)
		(layer "F.Cu")
		(net "SW_HDD_R6")
	)
	(segment
		(start 336.931 -276.7076)
		(end 336.169 -277.4696)
		(width 0.17145)
		(layer "F.Cu")
		(net "SW_HDD_R6")
	)
	(via
		(at 336.423 -279.443942)
		(size 0.6604)
		(drill 0.3302)
		(layers "F.Cu" "B.Cu")
		(net "SW_HDD_R6")
	)
	(segment
		(start 175.5775 -275.189442)
		(end 175.26 -275.506942)
		(width 0.17145)
		(layer "F.Cu")
		(net "SW_HDD_R5")
	)
	(segment
		(start 174.625 -275.506942)
		(end 174.022512 -275.506942)
		(width 0.17145)
		(layer "F.Cu")
		(net "SW_HDD_R5")
	)
	(segment
		(start 172.843952 -278.747982)
		(end 172.843952 -277.688548)
		(width 0.17145)
		(layer "F.Cu")
		(net "SW_HDD_R5")
	)
	(segment
		(start 176.2506 -275.189442)
		(end 175.5775 -275.189442)
		(width 0.17145)
		(layer "F.Cu")
		(net "SW_HDD_R5")
	)
	(segment
		(start 178.435 -275.189442)
		(end 176.2506 -275.189442)
		(width 0.17145)
		(layer "F.Cu")
		(net "SW_HDD_R5")
	)
	(segment
		(start 172.8216 -278.770334)
		(end 172.843952 -278.747982)
		(width 0.17145)
		(layer "F.Cu")
		(net "SW_HDD_R5")
	)
	(segment
		(start 175.26 -275.506942)
		(end 174.625 -275.506942)
		(width 0.17145)
		(layer "F.Cu")
		(net "SW_HDD_R5")
	)
	(segment
		(start 174.022512 -275.506942)
		(end 172.8851 -276.644354)
		(width 0.17145)
		(layer "F.Cu")
		(net "SW_HDD_R5")
	)
	(segment
		(start 172.8851 -276.644354)
		(end 172.8851 -277.6474)
		(width 0.17145)
		(layer "F.Cu")
		(net "SW_HDD_R5")
	)
	(segment
		(start 178.83124 -277.615142)
		(end 178.83124 -275.585682)
		(width 0.17145)
		(layer "F.Cu")
		(net "SW_HDD_R5")
	)
	(segment
		(start 172.8216 -278.7777)
		(end 172.8216 -278.770334)
		(width 0.17145)
		(layer "F.Cu")
		(net "SW_HDD_R5")
	)
	(segment
		(start 178.83124 -275.585682)
		(end 178.435 -275.189442)
		(width 0.17145)
		(layer "F.Cu")
		(net "SW_HDD_R5")
	)
	(segment
		(start 172.843952 -277.688548)
		(end 172.8851 -277.6474)
		(width 0.17145)
		(layer "F.Cu")
		(net "SW_HDD_R5")
	)
	(via
		(at 178.435 -275.189442)
		(size 0.6604)
		(drill 0.3302)
		(layers "F.Cu" "B.Cu")
		(net "SW_HDD_R5")
	)
	(segment
		(start 147.281138 -277.615142)
		(end 147.281138 -275.585682)
		(width 0.17145)
		(layer "F.Cu")
		(net "SW_HDD_R4")
	)
	(segment
		(start 147.281138 -275.585682)
		(end 146.884898 -275.189442)
		(width 0.17145)
		(layer "F.Cu")
		(net "SW_HDD_R4")
	)
	(segment
		(start 143.074898 -275.506942)
		(end 141.588998 -275.506942)
		(width 0.17145)
		(layer "F.Cu")
		(net "SW_HDD_R4")
	)
	(segment
		(start 141.461998 -275.633942)
		(end 141.423898 -275.672042)
		(width 0.17145)
		(layer "F.Cu")
		(net "SW_HDD_R4")
	)
	(segment
		(start 144.027398 -275.189442)
		(end 143.709898 -275.506942)
		(width 0.17145)
		(layer "F.Cu")
		(net "SW_HDD_R4")
	)
	(segment
		(start 141.423898 -275.672042)
		(end 141.423898 -276.738842)
		(width 0.17145)
		(layer "F.Cu")
		(net "SW_HDD_R4")
	)
	(segment
		(start 143.709898 -275.506942)
		(end 143.074898 -275.506942)
		(width 0.17145)
		(layer "F.Cu")
		(net "SW_HDD_R4")
	)
	(segment
		(start 141.588998 -275.506942)
		(end 141.461998 -275.633942)
		(width 0.17145)
		(layer "F.Cu")
		(net "SW_HDD_R4")
	)
	(segment
		(start 144.700498 -275.189442)
		(end 144.027398 -275.189442)
		(width 0.17145)
		(layer "F.Cu")
		(net "SW_HDD_R4")
	)
	(segment
		(start 146.884898 -275.189442)
		(end 144.700498 -275.189442)
		(width 0.17145)
		(layer "F.Cu")
		(net "SW_HDD_R4")
	)
	(via
		(at 146.884898 -275.189442)
		(size 0.6604)
		(drill 0.3302)
		(layers "F.Cu" "B.Cu")
		(net "SW_HDD_R4")
	)
	(segment
		(start 468.227918 -49.12995)
		(end 468.354918 -49.25695)
		(width 0.17145)
		(layer "F.Cu")
		(net "SW_HDD_R35")
	)
	(segment
		(start 467.885018 -43.85945)
		(end 467.910418 -43.83405)
		(width 0.17145)
		(layer "F.Cu")
		(net "SW_HDD_R35")
	)
	(segment
		(start 470.336118 -43.43781)
		(end 468.306658 -43.43781)
		(width 0.17145)
		(layer "F.Cu")
		(net "SW_HDD_R35")
	)
	(segment
		(start 468.227918 -46.841918)
		(end 467.885018 -46.499018)
		(width 0.17145)
		(layer "F.Cu")
		(net "SW_HDD_R35")
	)
	(segment
		(start 468.306658 -43.43781)
		(end 467.910418 -43.83405)
		(width 0.17145)
		(layer "F.Cu")
		(net "SW_HDD_R35")
	)
	(segment
		(start 468.227918 -47.64405)
		(end 468.227918 -46.841918)
		(width 0.17145)
		(layer "F.Cu")
		(net "SW_HDD_R35")
	)
	(segment
		(start 468.354918 -49.25695)
		(end 468.393018 -49.29505)
		(width 0.17145)
		(layer "F.Cu")
		(net "SW_HDD_R35")
	)
	(segment
		(start 467.885018 -46.499018)
		(end 467.885018 -46.01845)
		(width 0.17145)
		(layer "F.Cu")
		(net "SW_HDD_R35")
	)
	(segment
		(start 468.227918 -47.64405)
		(end 468.227918 -49.12995)
		(width 0.17145)
		(layer "F.Cu")
		(net "SW_HDD_R35")
	)
	(segment
		(start 467.885018 -46.01845)
		(end 467.885018 -43.85945)
		(width 0.17145)
		(layer "F.Cu")
		(net "SW_HDD_R35")
	)
	(segment
		(start 468.393018 -49.29505)
		(end 469.459818 -49.29505)
		(width 0.17145)
		(layer "F.Cu")
		(net "SW_HDD_R35")
	)
	(via
		(at 467.910418 -43.83405)
		(size 0.6604)
		(drill 0.3302)
		(layers "F.Cu" "B.Cu")
		(net "SW_HDD_R35")
	)
	(segment
		(start 459.2447 -45.903134)
		(end 460.09814 -45.903134)
		(width 0.17145)
		(layer "F.Cu")
		(net "SW_HDD_R34")
	)
	(segment
		(start 460.09814 -45.903134)
		(end 460.375 -46.179994)
		(width 0.17145)
		(layer "F.Cu")
		(net "SW_HDD_R34")
	)
	(segment
		(start 461.9371 -46.179994)
		(end 463.1309 -46.179994)
		(width 0.17145)
		(layer "F.Cu")
		(net "SW_HDD_R34")
	)
	(segment
		(start 463.1309 -46.179994)
		(end 463.1309 -47.030894)
		(width 0.17145)
		(layer "F.Cu")
		(net "SW_HDD_R34")
	)
	(segment
		(start 460.375 -46.179994)
		(end 461.9371 -46.179994)
		(width 0.17145)
		(layer "F.Cu")
		(net "SW_HDD_R34")
	)
	(segment
		(start 462.6229 -49.443894)
		(end 462.3689 -49.189894)
		(width 0.17145)
		(layer "F.Cu")
		(net "SW_HDD_R34")
	)
	(segment
		(start 463.1309 -47.030894)
		(end 462.3689 -47.792894)
		(width 0.17145)
		(layer "F.Cu")
		(net "SW_HDD_R34")
	)
	(segment
		(start 463.8294 -49.443894)
		(end 462.6229 -49.443894)
		(width 0.17145)
		(layer "F.Cu")
		(net "SW_HDD_R34")
	)
	(segment
		(start 462.3689 -49.189894)
		(end 462.3689 -47.792894)
		(width 0.17145)
		(layer "F.Cu")
		(net "SW_HDD_R34")
	)
	(via
		(at 462.6229 -49.443894)
		(size 0.6604)
		(drill 0.3302)
		(layers "F.Cu" "B.Cu")
		(net "SW_HDD_R34")
	)
	(segment
		(start 431.581052 -46.179994)
		(end 431.581052 -46.599348)
		(width 0.17145)
		(layer "F.Cu")
		(net "SW_HDD_R33")
	)
	(segment
		(start 428.548292 -45.903134)
		(end 428.825152 -46.179994)
		(width 0.17145)
		(layer "F.Cu")
		(net "SW_HDD_R33")
	)
	(segment
		(start 430.819052 -49.189894)
		(end 430.819052 -47.792894)
		(width 0.17145)
		(layer "F.Cu")
		(net "SW_HDD_R33")
	)
	(segment
		(start 431.073052 -49.443894)
		(end 430.819052 -49.189894)
		(width 0.17145)
		(layer "F.Cu")
		(net "SW_HDD_R33")
	)
	(segment
		(start 427.694852 -45.903134)
		(end 428.548292 -45.903134)
		(width 0.17145)
		(layer "F.Cu")
		(net "SW_HDD_R33")
	)
	(segment
		(start 428.825152 -46.179994)
		(end 430.387252 -46.179994)
		(width 0.17145)
		(layer "F.Cu")
		(net "SW_HDD_R33")
	)
	(segment
		(start 430.819052 -47.361348)
		(end 430.819052 -47.792894)
		(width 0.17145)
		(layer "F.Cu")
		(net "SW_HDD_R33")
	)
	(segment
		(start 432.279552 -49.443894)
		(end 431.073052 -49.443894)
		(width 0.17145)
		(layer "F.Cu")
		(net "SW_HDD_R33")
	)
	(segment
		(start 431.581052 -46.599348)
		(end 430.819052 -47.361348)
		(width 0.17145)
		(layer "F.Cu")
		(net "SW_HDD_R33")
	)
	(segment
		(start 430.387252 -46.179994)
		(end 431.581052 -46.179994)
		(width 0.17145)
		(layer "F.Cu")
		(net "SW_HDD_R33")
	)
	(via
		(at 431.073052 -49.443894)
		(size 0.6604)
		(drill 0.3302)
		(layers "F.Cu" "B.Cu")
		(net "SW_HDD_R33")
	)
	(segment
		(start 400.03095 -46.70425)
		(end 399.26895 -47.46625)
		(width 0.17145)
		(layer "F.Cu")
		(net "SW_HDD_R32")
	)
	(segment
		(start 398.81175 -46.179994)
		(end 400.03095 -46.179994)
		(width 0.17145)
		(layer "F.Cu")
		(net "SW_HDD_R32")
	)
	(segment
		(start 396.99819 -45.903134)
		(end 397.27505 -46.179994)
		(width 0.17145)
		(layer "F.Cu")
		(net "SW_HDD_R32")
	)
	(segment
		(start 399.26895 -47.46625)
		(end 399.26895 -47.792894)
		(width 0.17145)
		(layer "F.Cu")
		(net "SW_HDD_R32")
	)
	(segment
		(start 399.26895 -49.189894)
		(end 399.26895 -47.792894)
		(width 0.17145)
		(layer "F.Cu")
		(net "SW_HDD_R32")
	)
	(segment
		(start 400.72945 -49.443894)
		(end 399.52295 -49.443894)
		(width 0.17145)
		(layer "F.Cu")
		(net "SW_HDD_R32")
	)
	(segment
		(start 399.52295 -49.443894)
		(end 399.26895 -49.189894)
		(width 0.17145)
		(layer "F.Cu")
		(net "SW_HDD_R32")
	)
	(segment
		(start 400.03095 -46.179994)
		(end 400.03095 -46.70425)
		(width 0.17145)
		(layer "F.Cu")
		(net "SW_HDD_R32")
	)
	(segment
		(start 397.27505 -46.179994)
		(end 398.81175 -46.179994)
		(width 0.17145)
		(layer "F.Cu")
		(net "SW_HDD_R32")
	)
	(segment
		(start 396.14475 -45.903134)
		(end 396.99819 -45.903134)
		(width 0.17145)
		(layer "F.Cu")
		(net "SW_HDD_R32")
	)
	(via
		(at 399.52295 -49.443894)
		(size 0.6604)
		(drill 0.3302)
		(layers "F.Cu" "B.Cu")
		(net "SW_HDD_R32")
	)
	(segment
		(start 367.719102 -47.494698)
		(end 367.719102 -47.792894)
		(width 0.17145)
		(layer "F.Cu")
		(net "SW_HDD_R31")
	)
	(segment
		(start 368.481102 -46.732698)
		(end 367.719102 -47.494698)
		(width 0.17145)
		(layer "F.Cu")
		(net "SW_HDD_R31")
	)
	(segment
		(start 367.287302 -46.179994)
		(end 368.481102 -46.179994)
		(width 0.17145)
		(layer "F.Cu")
		(net "SW_HDD_R31")
	)
	(segment
		(start 369.179602 -49.443894)
		(end 367.973102 -49.443894)
		(width 0.17145)
		(layer "F.Cu")
		(net "SW_HDD_R31")
	)
	(segment
		(start 365.448342 -45.903134)
		(end 365.725202 -46.179994)
		(width 0.17145)
		(layer "F.Cu")
		(net "SW_HDD_R31")
	)
	(segment
		(start 367.719102 -49.189894)
		(end 367.719102 -47.792894)
		(width 0.17145)
		(layer "F.Cu")
		(net "SW_HDD_R31")
	)
	(segment
		(start 364.594902 -45.903134)
		(end 365.448342 -45.903134)
		(width 0.17145)
		(layer "F.Cu")
		(net "SW_HDD_R31")
	)
	(segment
		(start 367.973102 -49.443894)
		(end 367.719102 -49.189894)
		(width 0.17145)
		(layer "F.Cu")
		(net "SW_HDD_R31")
	)
	(segment
		(start 365.725202 -46.179994)
		(end 367.287302 -46.179994)
		(width 0.17145)
		(layer "F.Cu")
		(net "SW_HDD_R31")
	)
	(segment
		(start 368.481102 -46.179994)
		(end 368.481102 -46.732698)
		(width 0.17145)
		(layer "F.Cu")
		(net "SW_HDD_R31")
	)
	(via
		(at 367.973102 -49.443894)
		(size 0.6604)
		(drill 0.3302)
		(layers "F.Cu" "B.Cu")
		(net "SW_HDD_R31")
	)
	(segment
		(start 337.6295 -49.443894)
		(end 336.423 -49.443894)
		(width 0.17145)
		(layer "F.Cu")
		(net "SW_HDD_R30")
	)
	(segment
		(start 335.7626 -46.179994)
		(end 336.9056 -46.179994)
		(width 0.17145)
		(layer "F.Cu")
		(net "SW_HDD_R30")
	)
	(segment
		(start 336.9056 -46.7106)
		(end 336.169 -47.4472)
		(width 0.17145)
		(layer "F.Cu")
		(net "SW_HDD_R30")
	)
	(segment
		(start 333.0448 -45.903134)
		(end 333.89824 -45.903134)
		(width 0.17145)
		(layer "F.Cu")
		(net "SW_HDD_R30")
	)
	(segment
		(start 333.89824 -45.903134)
		(end 334.1751 -46.179994)
		(width 0.17145)
		(layer "F.Cu")
		(net "SW_HDD_R30")
	)
	(segment
		(start 334.1751 -46.179994)
		(end 335.7626 -46.179994)
		(width 0.17145)
		(layer "F.Cu")
		(net "SW_HDD_R30")
	)
	(segment
		(start 336.169 -49.189894)
		(end 336.169 -47.792894)
		(width 0.17145)
		(layer "F.Cu")
		(net "SW_HDD_R30")
	)
	(segment
		(start 336.9056 -46.179994)
		(end 336.9056 -46.7106)
		(width 0.17145)
		(layer "F.Cu")
		(net "SW_HDD_R30")
	)
	(segment
		(start 336.169 -47.4472)
		(end 336.169 -47.792894)
		(width 0.17145)
		(layer "F.Cu")
		(net "SW_HDD_R30")
	)
	(segment
		(start 336.423 -49.443894)
		(end 336.169 -49.189894)
		(width 0.17145)
		(layer "F.Cu")
		(net "SW_HDD_R30")
	)
	(via
		(at 336.423 -49.443894)
		(size 0.6604)
		(drill 0.3302)
		(layers "F.Cu" "B.Cu")
		(net "SW_HDD_R30")
	)
	(segment
		(start 113.073942 -280.333704)
		(end 113.073942 -278.822404)
		(width 0.17145)
		(layer "F.Cu")
		(net "SW_HDD_R3")
	)
	(segment
		(start 113.175542 -280.435304)
		(end 113.073942 -280.333704)
		(width 0.17145)
		(layer "F.Cu")
		(net "SW_HDD_R3")
	)
	(segment
		(start 112.756442 -275.012404)
		(end 112.756442 -277.196804)
		(width 0.17145)
		(layer "F.Cu")
		(net "SW_HDD_R3")
	)
	(segment
		(start 114.280442 -280.498804)
		(end 113.7412 -280.498804)
		(width 0.17145)
		(layer "F.Cu")
		(net "SW_HDD_R3")
	)
	(segment
		(start 113.7412 -280.498804)
		(end 113.6777 -280.435304)
		(width 0.17145)
		(layer "F.Cu")
		(net "SW_HDD_R3")
	)
	(segment
		(start 112.756442 -277.196804)
		(end 112.756442 -277.869904)
		(width 0.17145)
		(layer "F.Cu")
		(net "SW_HDD_R3")
	)
	(segment
		(start 112.756442 -277.869904)
		(end 113.073942 -278.187404)
		(width 0.17145)
		(layer "F.Cu")
		(net "SW_HDD_R3")
	)
	(segment
		(start 115.182142 -274.641564)
		(end 113.127282 -274.641564)
		(width 0.17145)
		(layer "F.Cu")
		(net "SW_HDD_R3")
	)
	(segment
		(start 113.6777 -280.435304)
		(end 113.175542 -280.435304)
		(width 0.17145)
		(layer "F.Cu")
		(net "SW_HDD_R3")
	)
	(segment
		(start 113.127282 -274.641564)
		(end 112.756442 -275.012404)
		(width 0.17145)
		(layer "F.Cu")
		(net "SW_HDD_R3")
	)
	(segment
		(start 113.073942 -278.187404)
		(end 113.073942 -278.822404)
		(width 0.17145)
		(layer "F.Cu")
		(net "SW_HDD_R3")
	)
	(via
		(at 112.756442 -275.012404)
		(size 0.6604)
		(drill 0.3302)
		(layers "F.Cu" "B.Cu")
		(net "SW_HDD_R3")
	)
	(segment
		(start 175.5775 -45.189394)
		(end 175.26 -45.506894)
		(width 0.17145)
		(layer "F.Cu")
		(net "SW_HDD_R29")
	)
	(segment
		(start 178.83124 -47.615094)
		(end 178.83124 -45.585634)
		(width 0.17145)
		(layer "F.Cu")
		(net "SW_HDD_R29")
	)
	(segment
		(start 178.435 -45.189394)
		(end 176.2506 -45.189394)
		(width 0.17145)
		(layer "F.Cu")
		(net "SW_HDD_R29")
	)
	(segment
		(start 172.9867 -45.608494)
		(end 172.974 -45.621194)
		(width 0.17145)
		(layer "F.Cu")
		(net "SW_HDD_R29")
	)
	(segment
		(start 174.625 -45.506894)
		(end 173.0883 -45.506894)
		(width 0.17145)
		(layer "F.Cu")
		(net "SW_HDD_R29")
	)
	(segment
		(start 176.2506 -45.189394)
		(end 175.5775 -45.189394)
		(width 0.17145)
		(layer "F.Cu")
		(net "SW_HDD_R29")
	)
	(segment
		(start 172.974 -45.621194)
		(end 172.974 -46.713394)
		(width 0.17145)
		(layer "F.Cu")
		(net "SW_HDD_R29")
	)
	(segment
		(start 175.26 -45.506894)
		(end 174.625 -45.506894)
		(width 0.17145)
		(layer "F.Cu")
		(net "SW_HDD_R29")
	)
	(segment
		(start 173.0883 -45.506894)
		(end 172.9867 -45.608494)
		(width 0.17145)
		(layer "F.Cu")
		(net "SW_HDD_R29")
	)
	(segment
		(start 178.83124 -45.585634)
		(end 178.435 -45.189394)
		(width 0.17145)
		(layer "F.Cu")
		(net "SW_HDD_R29")
	)
	(via
		(at 178.435 -45.189394)
		(size 0.6604)
		(drill 0.3302)
		(layers "F.Cu" "B.Cu")
		(net "SW_HDD_R29")
	)
	(segment
		(start 143.709898 -45.506894)
		(end 143.074898 -45.506894)
		(width 0.17145)
		(layer "F.Cu")
		(net "SW_HDD_R28")
	)
	(segment
		(start 141.538198 -45.506894)
		(end 143.074898 -45.506894)
		(width 0.17145)
		(layer "F.Cu")
		(net "SW_HDD_R28")
	)
	(segment
		(start 147.281138 -47.615094)
		(end 147.281138 -45.585634)
		(width 0.17145)
		(layer "F.Cu")
		(net "SW_HDD_R28")
	)
	(segment
		(start 144.027398 -45.189394)
		(end 143.709898 -45.506894)
		(width 0.17145)
		(layer "F.Cu")
		(net "SW_HDD_R28")
	)
	(segment
		(start 141.436598 -46.700694)
		(end 141.436598 -45.608494)
		(width 0.17145)
		(layer "F.Cu")
		(net "SW_HDD_R28")
	)
	(segment
		(start 141.423898 -46.713394)
		(end 141.436598 -46.700694)
		(width 0.17145)
		(layer "F.Cu")
		(net "SW_HDD_R28")
	)
	(segment
		(start 141.436598 -45.608494)
		(end 141.538198 -45.506894)
		(width 0.17145)
		(layer "F.Cu")
		(net "SW_HDD_R28")
	)
	(segment
		(start 144.700498 -45.189394)
		(end 144.027398 -45.189394)
		(width 0.17145)
		(layer "F.Cu")
		(net "SW_HDD_R28")
	)
	(segment
		(start 147.281138 -45.585634)
		(end 146.884898 -45.189394)
		(width 0.17145)
		(layer "F.Cu")
		(net "SW_HDD_R28")
	)
	(segment
		(start 146.884898 -45.189394)
		(end 144.700498 -45.189394)
		(width 0.17145)
		(layer "F.Cu")
		(net "SW_HDD_R28")
	)
	(via
		(at 146.884898 -45.189394)
		(size 0.6604)
		(drill 0.3302)
		(layers "F.Cu" "B.Cu")
		(net "SW_HDD_R28")
	)
	(segment
		(start 113.150396 -45.189394)
		(end 112.477296 -45.189394)
		(width 0.17145)
		(layer "F.Cu")
		(net "SW_HDD_R27")
	)
	(segment
		(start 115.334796 -45.189394)
		(end 113.150396 -45.189394)
		(width 0.17145)
		(layer "F.Cu")
		(net "SW_HDD_R27")
	)
	(segment
		(start 111.524796 -45.506894)
		(end 110.038896 -45.506894)
		(width 0.17145)
		(layer "F.Cu")
		(net "SW_HDD_R27")
	)
	(segment
		(start 115.731036 -45.585634)
		(end 115.334796 -45.189394)
		(width 0.17145)
		(layer "F.Cu")
		(net "SW_HDD_R27")
	)
	(segment
		(start 112.159796 -45.506894)
		(end 111.524796 -45.506894)
		(width 0.17145)
		(layer "F.Cu")
		(net "SW_HDD_R27")
	)
	(segment
		(start 109.911896 -45.633894)
		(end 109.873796 -45.671994)
		(width 0.17145)
		(layer "F.Cu")
		(net "SW_HDD_R27")
	)
	(segment
		(start 109.873796 -45.671994)
		(end 109.873796 -46.738794)
		(width 0.17145)
		(layer "F.Cu")
		(net "SW_HDD_R27")
	)
	(segment
		(start 112.477296 -45.189394)
		(end 112.159796 -45.506894)
		(width 0.17145)
		(layer "F.Cu")
		(net "SW_HDD_R27")
	)
	(segment
		(start 115.731036 -47.615094)
		(end 115.731036 -45.585634)
		(width 0.17145)
		(layer "F.Cu")
		(net "SW_HDD_R27")
	)
	(segment
		(start 110.038896 -45.506894)
		(end 109.911896 -45.633894)
		(width 0.17145)
		(layer "F.Cu")
		(net "SW_HDD_R27")
	)
	(via
		(at 115.334796 -45.189394)
		(size 0.6604)
		(drill 0.3302)
		(layers "F.Cu" "B.Cu")
		(net "SW_HDD_R27")
	)
	(segment
		(start 78.336648 -45.633894)
		(end 78.463648 -45.506894)
		(width 0.17145)
		(layer "F.Cu")
		(net "SW_HDD_R26")
	)
	(segment
		(start 78.323948 -46.738794)
		(end 78.323948 -45.646594)
		(width 0.17145)
		(layer "F.Cu")
		(net "SW_HDD_R26")
	)
	(segment
		(start 81.625948 -45.189394)
		(end 80.927448 -45.189394)
		(width 0.17145)
		(layer "F.Cu")
		(net "SW_HDD_R26")
	)
	(segment
		(start 78.323948 -45.646594)
		(end 78.336648 -45.633894)
		(width 0.17145)
		(layer "F.Cu")
		(net "SW_HDD_R26")
	)
	(segment
		(start 80.927448 -45.189394)
		(end 80.609948 -45.506894)
		(width 0.17145)
		(layer "F.Cu")
		(net "SW_HDD_R26")
	)
	(segment
		(start 81.625948 -45.189394)
		(end 83.784948 -45.189394)
		(width 0.17145)
		(layer "F.Cu")
		(net "SW_HDD_R26")
	)
	(segment
		(start 84.181188 -45.585634)
		(end 84.181188 -47.615094)
		(width 0.17145)
		(layer "F.Cu")
		(net "SW_HDD_R26")
	)
	(segment
		(start 83.784948 -45.189394)
		(end 84.181188 -45.585634)
		(width 0.17145)
		(layer "F.Cu")
		(net "SW_HDD_R26")
	)
	(segment
		(start 80.609948 -45.506894)
		(end 79.974948 -45.506894)
		(width 0.17145)
		(layer "F.Cu")
		(net "SW_HDD_R26")
	)
	(segment
		(start 78.463648 -45.506894)
		(end 79.974948 -45.506894)
		(width 0.17145)
		(layer "F.Cu")
		(net "SW_HDD_R26")
	)
	(via
		(at 83.784948 -45.189394)
		(size 0.6604)
		(drill 0.3302)
		(layers "F.Cu" "B.Cu")
		(net "SW_HDD_R26")
	)
	(segment
		(start 46.786546 -45.633894)
		(end 46.913546 -45.506894)
		(width 0.17145)
		(layer "F.Cu")
		(net "SW_HDD_R25")
	)
	(segment
		(start 49.377346 -45.189394)
		(end 49.059846 -45.506894)
		(width 0.17145)
		(layer "F.Cu")
		(net "SW_HDD_R25")
	)
	(segment
		(start 52.631086 -45.585634)
		(end 52.631086 -47.615094)
		(width 0.17145)
		(layer "F.Cu")
		(net "SW_HDD_R25")
	)
	(segment
		(start 46.773846 -46.738794)
		(end 46.773846 -45.646594)
		(width 0.17145)
		(layer "F.Cu")
		(net "SW_HDD_R25")
	)
	(segment
		(start 50.050446 -45.189394)
		(end 49.377346 -45.189394)
		(width 0.17145)
		(layer "F.Cu")
		(net "SW_HDD_R25")
	)
	(segment
		(start 46.773846 -45.646594)
		(end 46.786546 -45.633894)
		(width 0.17145)
		(layer "F.Cu")
		(net "SW_HDD_R25")
	)
	(segment
		(start 52.234846 -45.189394)
		(end 52.631086 -45.585634)
		(width 0.17145)
		(layer "F.Cu")
		(net "SW_HDD_R25")
	)
	(segment
		(start 46.913546 -45.506894)
		(end 48.424846 -45.506894)
		(width 0.17145)
		(layer "F.Cu")
		(net "SW_HDD_R25")
	)
	(segment
		(start 50.050446 -45.189394)
		(end 52.234846 -45.189394)
		(width 0.17145)
		(layer "F.Cu")
		(net "SW_HDD_R25")
	)
	(segment
		(start 49.059846 -45.506894)
		(end 48.424846 -45.506894)
		(width 0.17145)
		(layer "F.Cu")
		(net "SW_HDD_R25")
	)
	(via
		(at 52.234846 -45.189394)
		(size 0.6604)
		(drill 0.3302)
		(layers "F.Cu" "B.Cu")
		(net "SW_HDD_R25")
	)
	(segment
		(start 18.500598 -45.189394)
		(end 20.684998 -45.189394)
		(width 0.17145)
		(layer "F.Cu")
		(net "SW_HDD_R24")
	)
	(segment
		(start 15.223998 -45.646594)
		(end 15.223998 -46.713394)
		(width 0.17145)
		(layer "F.Cu")
		(net "SW_HDD_R24")
	)
	(segment
		(start 15.363698 -45.506894)
		(end 15.262098 -45.608494)
		(width 0.17145)
		(layer "F.Cu")
		(net "SW_HDD_R24")
	)
	(segment
		(start 17.827498 -45.189394)
		(end 17.509998 -45.506894)
		(width 0.17145)
		(layer "F.Cu")
		(net "SW_HDD_R24")
	)
	(segment
		(start 21.081238 -45.585634)
		(end 21.081238 -47.615094)
		(width 0.17145)
		(layer "F.Cu")
		(net "SW_HDD_R24")
	)
	(segment
		(start 15.262098 -45.608494)
		(end 15.223998 -45.646594)
		(width 0.17145)
		(layer "F.Cu")
		(net "SW_HDD_R24")
	)
	(segment
		(start 17.509998 -45.506894)
		(end 16.874998 -45.506894)
		(width 0.17145)
		(layer "F.Cu")
		(net "SW_HDD_R24")
	)
	(segment
		(start 20.684998 -45.189394)
		(end 21.081238 -45.585634)
		(width 0.17145)
		(layer "F.Cu")
		(net "SW_HDD_R24")
	)
	(segment
		(start 18.500598 -45.189394)
		(end 17.827498 -45.189394)
		(width 0.17145)
		(layer "F.Cu")
		(net "SW_HDD_R24")
	)
	(segment
		(start 16.874998 -45.506894)
		(end 15.363698 -45.506894)
		(width 0.17145)
		(layer "F.Cu")
		(net "SW_HDD_R24")
	)
	(via
		(at 20.684998 -45.189394)
		(size 0.6604)
		(drill 0.3302)
		(layers "F.Cu" "B.Cu")
		(net "SW_HDD_R24")
	)
	(segment
		(start 468.393018 -164.295074)
		(end 469.459818 -164.295074)
		(width 0.17145)
		(layer "F.Cu")
		(net "SW_HDD_R23")
	)
	(segment
		(start 470.336118 -158.437834)
		(end 468.306658 -158.437834)
		(width 0.17145)
		(layer "F.Cu")
		(net "SW_HDD_R23")
	)
	(segment
		(start 468.227918 -162.009074)
		(end 468.227918 -162.644074)
		(width 0.17145)
		(layer "F.Cu")
		(net "SW_HDD_R23")
	)
	(segment
		(start 467.910418 -161.018474)
		(end 467.910418 -161.691574)
		(width 0.17145)
		(layer "F.Cu")
		(net "SW_HDD_R23")
	)
	(segment
		(start 468.306658 -158.437834)
		(end 467.910418 -158.834074)
		(width 0.17145)
		(layer "F.Cu")
		(net "SW_HDD_R23")
	)
	(segment
		(start 467.910418 -158.834074)
		(end 467.910418 -161.018474)
		(width 0.17145)
		(layer "F.Cu")
		(net "SW_HDD_R23")
	)
	(segment
		(start 468.354918 -164.256974)
		(end 468.393018 -164.295074)
		(width 0.17145)
		(layer "F.Cu")
		(net "SW_HDD_R23")
	)
	(segment
		(start 468.227918 -164.129974)
		(end 468.354918 -164.256974)
		(width 0.17145)
		(layer "F.Cu")
		(net "SW_HDD_R23")
	)
	(segment
		(start 467.910418 -161.691574)
		(end 468.227918 -162.009074)
		(width 0.17145)
		(layer "F.Cu")
		(net "SW_HDD_R23")
	)
	(segment
		(start 468.227918 -162.644074)
		(end 468.227918 -164.129974)
		(width 0.17145)
		(layer "F.Cu")
		(net "SW_HDD_R23")
	)
	(via
		(at 467.910418 -158.834074)
		(size 0.6604)
		(drill 0.3302)
		(layers "F.Cu" "B.Cu")
		(net "SW_HDD_R23")
	)
	(segment
		(start 460.09814 -160.903158)
		(end 460.375 -161.180018)
		(width 0.17145)
		(layer "F.Cu")
		(net "SW_HDD_R22")
	)
	(segment
		(start 460.375 -161.180018)
		(end 461.9371 -161.180018)
		(width 0.17145)
		(layer "F.Cu")
		(net "SW_HDD_R22")
	)
	(segment
		(start 463.1309 -161.6075)
		(end 462.3689 -162.3695)
		(width 0.17145)
		(layer "F.Cu")
		(net "SW_HDD_R22")
	)
	(segment
		(start 463.8294 -164.443918)
		(end 462.6229 -164.443918)
		(width 0.17145)
		(layer "F.Cu")
		(net "SW_HDD_R22")
	)
	(segment
		(start 462.6229 -164.443918)
		(end 462.3689 -164.189918)
		(width 0.17145)
		(layer "F.Cu")
		(net "SW_HDD_R22")
	)
	(segment
		(start 459.2447 -160.903158)
		(end 460.09814 -160.903158)
		(width 0.17145)
		(layer "F.Cu")
		(net "SW_HDD_R22")
	)
	(segment
		(start 462.3689 -162.3695)
		(end 462.3689 -162.792918)
		(width 0.17145)
		(layer "F.Cu")
		(net "SW_HDD_R22")
	)
	(segment
		(start 461.9371 -161.180018)
		(end 463.1309 -161.180018)
		(width 0.17145)
		(layer "F.Cu")
		(net "SW_HDD_R22")
	)
	(segment
		(start 462.3689 -164.189918)
		(end 462.3689 -162.792918)
		(width 0.17145)
		(layer "F.Cu")
		(net "SW_HDD_R22")
	)
	(segment
		(start 463.1309 -161.180018)
		(end 463.1309 -161.6075)
		(width 0.17145)
		(layer "F.Cu")
		(net "SW_HDD_R22")
	)
	(via
		(at 462.6229 -164.443918)
		(size 0.6604)
		(drill 0.3302)
		(layers "F.Cu" "B.Cu")
		(net "SW_HDD_R22")
	)
	(segment
		(start 432.279552 -164.443918)
		(end 431.073052 -164.443918)
		(width 0.17145)
		(layer "F.Cu")
		(net "SW_HDD_R21")
	)
	(segment
		(start 431.073052 -164.443918)
		(end 430.819052 -164.189918)
		(width 0.17145)
		(layer "F.Cu")
		(net "SW_HDD_R21")
	)
	(segment
		(start 431.581052 -161.180018)
		(end 431.581052 -162.030918)
		(width 0.17145)
		(layer "F.Cu")
		(net "SW_HDD_R21")
	)
	(segment
		(start 428.548292 -160.903158)
		(end 428.825152 -161.180018)
		(width 0.17145)
		(layer "F.Cu")
		(net "SW_HDD_R21")
	)
	(segment
		(start 427.694852 -160.903158)
		(end 428.548292 -160.903158)
		(width 0.17145)
		(layer "F.Cu")
		(net "SW_HDD_R21")
	)
	(segment
		(start 431.581052 -162.030918)
		(end 430.819052 -162.792918)
		(width 0.17145)
		(layer "F.Cu")
		(net "SW_HDD_R21")
	)
	(segment
		(start 430.387252 -161.180018)
		(end 431.581052 -161.180018)
		(width 0.17145)
		(layer "F.Cu")
		(net "SW_HDD_R21")
	)
	(segment
		(start 428.825152 -161.180018)
		(end 430.387252 -161.180018)
		(width 0.17145)
		(layer "F.Cu")
		(net "SW_HDD_R21")
	)
	(segment
		(start 430.819052 -164.189918)
		(end 430.819052 -162.792918)
		(width 0.17145)
		(layer "F.Cu")
		(net "SW_HDD_R21")
	)
	(via
		(at 431.073052 -164.443918)
		(size 0.6604)
		(drill 0.3302)
		(layers "F.Cu" "B.Cu")
		(net "SW_HDD_R21")
	)
	(segment
		(start 400.03095 -161.61385)
		(end 400.03095 -161.180018)
		(width 0.17145)
		(layer "F.Cu")
		(net "SW_HDD_R20")
	)
	(segment
		(start 396.14475 -160.903158)
		(end 396.99819 -160.903158)
		(width 0.17145)
		(layer "F.Cu")
		(net "SW_HDD_R20")
	)
	(segment
		(start 397.99895 -164.697918)
		(end 397.99895 -163.300918)
		(width 0.17145)
		(layer "F.Cu")
		(net "SW_HDD_R20")
	)
	(segment
		(start 399.26895 -162.792918)
		(end 399.26895 -162.37585)
		(width 0.17145)
		(layer "F.Cu")
		(net "SW_HDD_R20")
	)
	(segment
		(start 397.27505 -161.180018)
		(end 398.83715 -161.180018)
		(width 0.17145)
		(layer "F.Cu")
		(net "SW_HDD_R20")
	)
	(segment
		(start 396.99819 -160.903158)
		(end 397.27505 -161.180018)
		(width 0.17145)
		(layer "F.Cu")
		(net "SW_HDD_R20")
	)
	(segment
		(start 398.25295 -164.951918)
		(end 397.99895 -164.697918)
		(width 0.17145)
		(layer "F.Cu")
		(net "SW_HDD_R20")
	)
	(segment
		(start 398.76095 -163.300918)
		(end 399.26895 -162.792918)
		(width 0.17145)
		(layer "F.Cu")
		(net "SW_HDD_R20")
	)
	(segment
		(start 397.99895 -163.300918)
		(end 398.76095 -163.300918)
		(width 0.17145)
		(layer "F.Cu")
		(net "SW_HDD_R20")
	)
	(segment
		(start 399.45945 -164.951918)
		(end 398.25295 -164.951918)
		(width 0.17145)
		(layer "F.Cu")
		(net "SW_HDD_R20")
	)
	(segment
		(start 399.26895 -162.37585)
		(end 400.03095 -161.61385)
		(width 0.17145)
		(layer "F.Cu")
		(net "SW_HDD_R20")
	)
	(segment
		(start 398.83715 -161.180018)
		(end 400.03095 -161.180018)
		(width 0.17145)
		(layer "F.Cu")
		(net "SW_HDD_R20")
	)
	(via
		(at 398.25295 -164.951918)
		(size 0.6604)
		(drill 0.3302)
		(layers "F.Cu" "B.Cu")
		(net "SW_HDD_R20")
	)
	(segment
		(start 78.463648 -275.506942)
		(end 79.974948 -275.506942)
		(width 0.17145)
		(layer "F.Cu")
		(net "SW_HDD_R2")
	)
	(segment
		(start 81.600548 -275.189442)
		(end 80.927448 -275.189442)
		(width 0.17145)
		(layer "F.Cu")
		(net "SW_HDD_R2")
	)
	(segment
		(start 78.298548 -275.672042)
		(end 78.336648 -275.633942)
		(width 0.17145)
		(layer "F.Cu")
		(net "SW_HDD_R2")
	)
	(segment
		(start 78.298548 -276.738842)
		(end 78.298548 -275.672042)
		(width 0.17145)
		(layer "F.Cu")
		(net "SW_HDD_R2")
	)
	(segment
		(start 80.609948 -275.506942)
		(end 79.974948 -275.506942)
		(width 0.17145)
		(layer "F.Cu")
		(net "SW_HDD_R2")
	)
	(segment
		(start 83.784948 -275.189442)
		(end 81.600548 -275.189442)
		(width 0.17145)
		(layer "F.Cu")
		(net "SW_HDD_R2")
	)
	(segment
		(start 84.181188 -277.615142)
		(end 84.181188 -275.585682)
		(width 0.17145)
		(layer "F.Cu")
		(net "SW_HDD_R2")
	)
	(segment
		(start 80.927448 -275.189442)
		(end 80.609948 -275.506942)
		(width 0.17145)
		(layer "F.Cu")
		(net "SW_HDD_R2")
	)
	(segment
		(start 84.181188 -275.585682)
		(end 83.784948 -275.189442)
		(width 0.17145)
		(layer "F.Cu")
		(net "SW_HDD_R2")
	)
	(segment
		(start 78.336648 -275.633942)
		(end 78.463648 -275.506942)
		(width 0.17145)
		(layer "F.Cu")
		(net "SW_HDD_R2")
	)
	(via
		(at 83.784948 -275.189442)
		(size 0.6604)
		(drill 0.3302)
		(layers "F.Cu" "B.Cu")
		(net "SW_HDD_R2")
	)
	(segment
		(start 368.481102 -161.540698)
		(end 367.719102 -162.302698)
		(width 0.17145)
		(layer "F.Cu")
		(net "SW_HDD_R19")
	)
	(segment
		(start 365.448342 -160.903158)
		(end 365.725202 -161.180018)
		(width 0.17145)
		(layer "F.Cu")
		(net "SW_HDD_R19")
	)
	(segment
		(start 369.179602 -164.443918)
		(end 367.973102 -164.443918)
		(width 0.17145)
		(layer "F.Cu")
		(net "SW_HDD_R19")
	)
	(segment
		(start 367.719102 -164.189918)
		(end 367.719102 -162.792918)
		(width 0.17145)
		(layer "F.Cu")
		(net "SW_HDD_R19")
	)
	(segment
		(start 368.481102 -161.180018)
		(end 368.481102 -161.540698)
		(width 0.17145)
		(layer "F.Cu")
		(net "SW_HDD_R19")
	)
	(segment
		(start 367.287302 -161.180018)
		(end 368.481102 -161.180018)
		(width 0.17145)
		(layer "F.Cu")
		(net "SW_HDD_R19")
	)
	(segment
		(start 365.725202 -161.180018)
		(end 367.287302 -161.180018)
		(width 0.17145)
		(layer "F.Cu")
		(net "SW_HDD_R19")
	)
	(segment
		(start 367.973102 -164.443918)
		(end 367.719102 -164.189918)
		(width 0.17145)
		(layer "F.Cu")
		(net "SW_HDD_R19")
	)
	(segment
		(start 367.719102 -162.302698)
		(end 367.719102 -162.792918)
		(width 0.17145)
		(layer "F.Cu")
		(net "SW_HDD_R19")
	)
	(segment
		(start 364.594902 -160.903158)
		(end 365.448342 -160.903158)
		(width 0.17145)
		(layer "F.Cu")
		(net "SW_HDD_R19")
	)
	(via
		(at 367.973102 -164.443918)
		(size 0.6604)
		(drill 0.3302)
		(layers "F.Cu" "B.Cu")
		(net "SW_HDD_R19")
	)
	(segment
		(start 333.89824 -160.903158)
		(end 334.1751 -161.180018)
		(width 0.17145)
		(layer "F.Cu")
		(net "SW_HDD_R18")
	)
	(segment
		(start 337.6295 -164.443918)
		(end 336.423 -164.443918)
		(width 0.17145)
		(layer "F.Cu")
		(net "SW_HDD_R18")
	)
	(segment
		(start 336.931 -161.7472)
		(end 336.169 -162.5092)
		(width 0.17145)
		(layer "F.Cu")
		(net "SW_HDD_R18")
	)
	(segment
		(start 336.423 -164.443918)
		(end 336.169 -164.189918)
		(width 0.17145)
		(layer "F.Cu")
		(net "SW_HDD_R18")
	)
	(segment
		(start 334.1751 -161.180018)
		(end 335.788 -161.180018)
		(width 0.17145)
		(layer "F.Cu")
		(net "SW_HDD_R18")
	)
	(segment
		(start 336.169 -164.189918)
		(end 336.169 -162.792918)
		(width 0.17145)
		(layer "F.Cu")
		(net "SW_HDD_R18")
	)
	(segment
		(start 336.931 -161.180018)
		(end 336.931 -161.7472)
		(width 0.17145)
		(layer "F.Cu")
		(net "SW_HDD_R18")
	)
	(segment
		(start 336.169 -162.5092)
		(end 336.169 -162.792918)
		(width 0.17145)
		(layer "F.Cu")
		(net "SW_HDD_R18")
	)
	(segment
		(start 333.0448 -160.903158)
		(end 333.89824 -160.903158)
		(width 0.17145)
		(layer "F.Cu")
		(net "SW_HDD_R18")
	)
	(segment
		(start 335.788 -161.180018)
		(end 336.931 -161.180018)
		(width 0.17145)
		(layer "F.Cu")
		(net "SW_HDD_R18")
	)
	(via
		(at 336.423 -164.443918)
		(size 0.6604)
		(drill 0.3302)
		(layers "F.Cu" "B.Cu")
		(net "SW_HDD_R18")
	)
	(segment
		(start 177.57775 -159.694372)
		(end 178.156362 -160.272984)
		(width 0.17145)
		(layer "F.Cu")
		(net "SW_HDD_R17")
	)
	(segment
		(start 178.88204 -161.533078)
		(end 178.88204 -162.996118)
		(width 0.17145)
		(layer "F.Cu")
		(net "SW_HDD_R17")
	)
	(segment
		(start 176.004474 -160.506918)
		(end 176.81702 -159.694372)
		(width 0.17145)
		(layer "F.Cu")
		(net "SW_HDD_R17")
	)
	(segment
		(start 176.81702 -159.694372)
		(end 177.57775 -159.694372)
		(width 0.17145)
		(layer "F.Cu")
		(net "SW_HDD_R17")
	)
	(segment
		(start 178.156362 -160.272984)
		(end 178.88204 -160.998662)
		(width 0.17145)
		(layer "F.Cu")
		(net "SW_HDD_R17")
	)
	(segment
		(start 175.6664 -160.506918)
		(end 176.004474 -160.506918)
		(width 0.17145)
		(layer "F.Cu")
		(net "SW_HDD_R17")
	)
	(segment
		(start 175.6664 -160.506918)
		(end 174.117 -160.506918)
		(width 0.17145)
		(layer "F.Cu")
		(net "SW_HDD_R17")
	)
	(segment
		(start 178.88204 -160.998662)
		(end 178.88204 -161.533078)
		(width 0.17145)
		(layer "F.Cu")
		(net "SW_HDD_R17")
	)
	(segment
		(start 174.117 -161.713418)
		(end 174.117 -160.506918)
		(width 0.17145)
		(layer "F.Cu")
		(net "SW_HDD_R17")
	)
	(via
		(at 178.88204 -161.533078)
		(size 0.6604)
		(drill 0.3302)
		(layers "F.Cu" "B.Cu")
		(net "SW_HDD_R17")
	)
	(segment
		(start 141.461998 -160.608518)
		(end 141.563598 -160.506918)
		(width 0.17145)
		(layer "F.Cu")
		(net "SW_HDD_R16")
	)
	(segment
		(start 141.423898 -161.713418)
		(end 141.461998 -161.675318)
		(width 0.17145)
		(layer "F.Cu")
		(net "SW_HDD_R16")
	)
	(segment
		(start 146.884898 -160.189418)
		(end 144.700498 -160.189418)
		(width 0.17145)
		(layer "F.Cu")
		(net "SW_HDD_R16")
	)
	(segment
		(start 143.709898 -160.506918)
		(end 143.074898 -160.506918)
		(width 0.17145)
		(layer "F.Cu")
		(net "SW_HDD_R16")
	)
	(segment
		(start 147.281138 -160.585658)
		(end 146.884898 -160.189418)
		(width 0.17145)
		(layer "F.Cu")
		(net "SW_HDD_R16")
	)
	(segment
		(start 141.461998 -161.675318)
		(end 141.461998 -160.608518)
		(width 0.17145)
		(layer "F.Cu")
		(net "SW_HDD_R16")
	)
	(segment
		(start 141.563598 -160.506918)
		(end 143.074898 -160.506918)
		(width 0.17145)
		(layer "F.Cu")
		(net "SW_HDD_R16")
	)
	(segment
		(start 144.700498 -160.189418)
		(end 144.027398 -160.189418)
		(width 0.17145)
		(layer "F.Cu")
		(net "SW_HDD_R16")
	)
	(segment
		(start 144.027398 -160.189418)
		(end 143.709898 -160.506918)
		(width 0.17145)
		(layer "F.Cu")
		(net "SW_HDD_R16")
	)
	(segment
		(start 147.281138 -162.615118)
		(end 147.281138 -160.585658)
		(width 0.17145)
		(layer "F.Cu")
		(net "SW_HDD_R16")
	)
	(via
		(at 146.884898 -160.189418)
		(size 0.6604)
		(drill 0.3302)
		(layers "F.Cu" "B.Cu")
		(net "SW_HDD_R16")
	)
	(segment
		(start 110.744 -160.506918)
		(end 111.524796 -160.506918)
		(width 0.17145)
		(layer "F.Cu")
		(net "SW_HDD_R15")
	)
	(segment
		(start 109.911896 -161.675318)
		(end 109.911896 -160.608518)
		(width 0.17145)
		(layer "F.Cu")
		(net "SW_HDD_R15")
	)
	(segment
		(start 112.477296 -160.189418)
		(end 112.159796 -160.506918)
		(width 0.17145)
		(layer "F.Cu")
		(net "SW_HDD_R15")
	)
	(segment
		(start 110.6424 -160.608518)
		(end 110.744 -160.506918)
		(width 0.17145)
		(layer "F.Cu")
		(net "SW_HDD_R15")
	)
	(segment
		(start 115.731036 -162.615118)
		(end 115.731036 -160.585658)
		(width 0.17145)
		(layer "F.Cu")
		(net "SW_HDD_R15")
	)
	(segment
		(start 109.911896 -160.608518)
		(end 110.6424 -160.608518)
		(width 0.17145)
		(layer "F.Cu")
		(net "SW_HDD_R15")
	)
	(segment
		(start 112.159796 -160.506918)
		(end 111.524796 -160.506918)
		(width 0.17145)
		(layer "F.Cu")
		(net "SW_HDD_R15")
	)
	(segment
		(start 115.334796 -160.189418)
		(end 113.150396 -160.189418)
		(width 0.17145)
		(layer "F.Cu")
		(net "SW_HDD_R15")
	)
	(segment
		(start 113.150396 -160.189418)
		(end 112.477296 -160.189418)
		(width 0.17145)
		(layer "F.Cu")
		(net "SW_HDD_R15")
	)
	(segment
		(start 115.731036 -160.585658)
		(end 115.334796 -160.189418)
		(width 0.17145)
		(layer "F.Cu")
		(net "SW_HDD_R15")
	)
	(segment
		(start 109.873796 -161.713418)
		(end 109.911896 -161.675318)
		(width 0.17145)
		(layer "F.Cu")
		(net "SW_HDD_R15")
	)
	(via
		(at 115.334796 -160.189418)
		(size 0.6604)
		(drill 0.3302)
		(layers "F.Cu" "B.Cu")
		(net "SW_HDD_R15")
	)
	(segment
		(start 84.181188 -160.585658)
		(end 83.784948 -160.189418)
		(width 0.17145)
		(layer "F.Cu")
		(net "SW_HDD_R14")
	)
	(segment
		(start 78.489048 -160.506918)
		(end 78.362048 -160.633918)
		(width 0.17145)
		(layer "F.Cu")
		(net "SW_HDD_R14")
	)
	(segment
		(start 80.609948 -160.506918)
		(end 79.974948 -160.506918)
		(width 0.17145)
		(layer "F.Cu")
		(net "SW_HDD_R14")
	)
	(segment
		(start 80.927448 -160.189418)
		(end 80.609948 -160.506918)
		(width 0.17145)
		(layer "F.Cu")
		(net "SW_HDD_R14")
	)
	(segment
		(start 78.362048 -160.633918)
		(end 78.298548 -160.697418)
		(width 0.17145)
		(layer "F.Cu")
		(net "SW_HDD_R14")
	)
	(segment
		(start 79.974948 -160.506918)
		(end 78.489048 -160.506918)
		(width 0.17145)
		(layer "F.Cu")
		(net "SW_HDD_R14")
	)
	(segment
		(start 81.600548 -160.189418)
		(end 80.927448 -160.189418)
		(width 0.17145)
		(layer "F.Cu")
		(net "SW_HDD_R14")
	)
	(segment
		(start 83.784948 -160.189418)
		(end 81.600548 -160.189418)
		(width 0.17145)
		(layer "F.Cu")
		(net "SW_HDD_R14")
	)
	(segment
		(start 78.298548 -160.697418)
		(end 78.298548 -161.738818)
		(width 0.17145)
		(layer "F.Cu")
		(net "SW_HDD_R14")
	)
	(segment
		(start 84.181188 -162.615118)
		(end 84.181188 -160.585658)
		(width 0.17145)
		(layer "F.Cu")
		(net "SW_HDD_R14")
	)
	(via
		(at 83.784948 -160.189418)
		(size 0.6604)
		(drill 0.3302)
		(layers "F.Cu" "B.Cu")
		(net "SW_HDD_R14")
	)
	(segment
		(start 51.956208 -157.605984)
		(end 52.681886 -158.331662)
		(width 0.17145)
		(layer "F.Cu")
		(net "SW_HDD_R13")
	)
	(segment
		(start 47.916846 -157.839918)
		(end 47.916846 -159.046418)
		(width 0.17145)
		(layer "F.Cu")
		(net "SW_HDD_R13")
	)
	(segment
		(start 52.681886 -158.331662)
		(end 52.681886 -158.886906)
		(width 0.17145)
		(layer "F.Cu")
		(net "SW_HDD_R13")
	)
	(segment
		(start 49.80432 -157.839918)
		(end 49.466246 -157.839918)
		(width 0.17145)
		(layer "F.Cu")
		(net "SW_HDD_R13")
	)
	(segment
		(start 49.466246 -157.839918)
		(end 47.916846 -157.839918)
		(width 0.17145)
		(layer "F.Cu")
		(net "SW_HDD_R13")
	)
	(segment
		(start 51.956208 -157.605984)
		(end 51.377596 -157.027372)
		(width 0.17145)
		(layer "F.Cu")
		(net "SW_HDD_R13")
	)
	(segment
		(start 52.681886 -158.886906)
		(end 52.681886 -160.329118)
		(width 0.17145)
		(layer "F.Cu")
		(net "SW_HDD_R13")
	)
	(segment
		(start 50.616866 -157.027372)
		(end 49.80432 -157.839918)
		(width 0.17145)
		(layer "F.Cu")
		(net "SW_HDD_R13")
	)
	(segment
		(start 51.377596 -157.027372)
		(end 50.616866 -157.027372)
		(width 0.17145)
		(layer "F.Cu")
		(net "SW_HDD_R13")
	)
	(via
		(at 52.681886 -158.886906)
		(size 0.6604)
		(drill 0.3302)
		(layers "F.Cu" "B.Cu")
		(net "SW_HDD_R13")
	)
	(segment
		(start 15.363698 -160.506918)
		(end 15.262098 -160.608518)
		(width 0.17145)
		(layer "F.Cu")
		(net "SW_HDD_R12")
	)
	(segment
		(start 15.262098 -160.608518)
		(end 15.223998 -160.646618)
		(width 0.17145)
		(layer "F.Cu")
		(net "SW_HDD_R12")
	)
	(segment
		(start 17.509998 -160.506918)
		(end 16.874998 -160.506918)
		(width 0.17145)
		(layer "F.Cu")
		(net "SW_HDD_R12")
	)
	(segment
		(start 20.684998 -160.189418)
		(end 18.500598 -160.189418)
		(width 0.17145)
		(layer "F.Cu")
		(net "SW_HDD_R12")
	)
	(segment
		(start 16.874998 -160.506918)
		(end 15.363698 -160.506918)
		(width 0.17145)
		(layer "F.Cu")
		(net "SW_HDD_R12")
	)
	(segment
		(start 17.827498 -160.189418)
		(end 17.509998 -160.506918)
		(width 0.17145)
		(layer "F.Cu")
		(net "SW_HDD_R12")
	)
	(segment
		(start 21.081238 -162.615118)
		(end 21.081238 -160.585658)
		(width 0.17145)
		(layer "F.Cu")
		(net "SW_HDD_R12")
	)
	(segment
		(start 15.223998 -160.646618)
		(end 15.223998 -161.713418)
		(width 0.17145)
		(layer "F.Cu")
		(net "SW_HDD_R12")
	)
	(segment
		(start 21.081238 -160.585658)
		(end 20.684998 -160.189418)
		(width 0.17145)
		(layer "F.Cu")
		(net "SW_HDD_R12")
	)
	(segment
		(start 18.500598 -160.189418)
		(end 17.827498 -160.189418)
		(width 0.17145)
		(layer "F.Cu")
		(net "SW_HDD_R12")
	)
	(via
		(at 20.684998 -160.189418)
		(size 0.6604)
		(drill 0.3302)
		(layers "F.Cu" "B.Cu")
		(net "SW_HDD_R12")
	)
	(segment
		(start 468.349584 -278.171402)
		(end 468.349584 -277.472902)
		(width 0.17145)
		(layer "F.Cu")
		(net "SW_HDD_R11")
	)
	(segment
		(start 468.485728 -279.372314)
		(end 467.469982 -279.372314)
		(width 0.17145)
		(layer "F.Cu")
		(net "SW_HDD_R11")
	)
	(segment
		(start 469.180672 -279.372314)
		(end 468.485728 -279.372314)
		(width 0.17145)
		(layer "F.Cu")
		(net "SW_HDD_R11")
	)
	(segment
		(start 473.36202 -273.54276)
		(end 472.018106 -273.54276)
		(width 0.17145)
		(layer "F.Cu")
		(net "SW_HDD_R11")
	)
	(segment
		(start 466.011514 -276.084284)
		(end 466.011514 -277.20671)
		(width 0.17145)
		(layer "F.Cu")
		(net "SW_HDD_R11")
	)
	(segment
		(start 472.018106 -273.54276)
		(end 469.808306 -275.75256)
		(width 0.17145)
		(layer "F.Cu")
		(net "SW_HDD_R11")
	)
	(segment
		(start 466.878924 -277.472902)
		(end 466.870796 -277.48103)
		(width 0.17145)
		(layer "F.Cu")
		(net "SW_HDD_R11")
	)
	(segment
		(start 466.285834 -277.48103)
		(end 466.870796 -277.48103)
		(width 0.17145)
		(layer "F.Cu")
		(net "SW_HDD_R11")
	)
	(segment
		(start 469.808306 -275.75256)
		(end 466.343238 -275.75256)
		(width 0.17145)
		(layer "F.Cu")
		(net "SW_HDD_R11")
	)
	(segment
		(start 466.343238 -275.75256)
		(end 466.011514 -276.084284)
		(width 0.17145)
		(layer "F.Cu")
		(net "SW_HDD_R11")
	)
	(segment
		(start 469.454484 -279.098502)
		(end 469.180672 -279.372314)
		(width 0.17145)
		(layer "F.Cu")
		(net "SW_HDD_R11")
	)
	(segment
		(start 466.011514 -277.20671)
		(end 466.285834 -277.48103)
		(width 0.17145)
		(layer "F.Cu")
		(net "SW_HDD_R11")
	)
	(segment
		(start 468.349584 -277.472902)
		(end 466.878924 -277.472902)
		(width 0.17145)
		(layer "F.Cu")
		(net "SW_HDD_R11")
	)
	(segment
		(start 467.469982 -279.051004)
		(end 468.349584 -278.171402)
		(width 0.17145)
		(layer "F.Cu")
		(net "SW_HDD_R11")
	)
	(segment
		(start 467.469982 -279.372314)
		(end 467.469982 -279.051004)
		(width 0.17145)
		(layer "F.Cu")
		(net "SW_HDD_R11")
	)
	(via
		(at 468.485728 -279.372314)
		(size 0.6604)
		(drill 0.3302)
		(layers "F.Cu" "B.Cu")
		(net "SW_HDD_R11")
	)
	(segment
		(start 459.2447 -275.903182)
		(end 460.09814 -275.903182)
		(width 0.17145)
		(layer "F.Cu")
		(net "SW_HDD_R10")
	)
	(segment
		(start 463.1309 -276.180042)
		(end 463.1309 -277.030942)
		(width 0.17145)
		(layer "F.Cu")
		(net "SW_HDD_R10")
	)
	(segment
		(start 463.1309 -277.030942)
		(end 462.3689 -277.792942)
		(width 0.17145)
		(layer "F.Cu")
		(net "SW_HDD_R10")
	)
	(segment
		(start 460.375 -276.180042)
		(end 461.9371 -276.180042)
		(width 0.17145)
		(layer "F.Cu")
		(net "SW_HDD_R10")
	)
	(segment
		(start 463.8294 -279.443942)
		(end 462.6229 -279.443942)
		(width 0.17145)
		(layer "F.Cu")
		(net "SW_HDD_R10")
	)
	(segment
		(start 462.3689 -279.189942)
		(end 462.3689 -277.792942)
		(width 0.17145)
		(layer "F.Cu")
		(net "SW_HDD_R10")
	)
	(segment
		(start 462.6229 -279.443942)
		(end 462.3689 -279.189942)
		(width 0.17145)
		(layer "F.Cu")
		(net "SW_HDD_R10")
	)
	(segment
		(start 460.09814 -275.903182)
		(end 460.375 -276.180042)
		(width 0.17145)
		(layer "F.Cu")
		(net "SW_HDD_R10")
	)
	(segment
		(start 461.9371 -276.180042)
		(end 463.1309 -276.180042)
		(width 0.17145)
		(layer "F.Cu")
		(net "SW_HDD_R10")
	)
	(via
		(at 462.6229 -279.443942)
		(size 0.6604)
		(drill 0.3302)
		(layers "F.Cu" "B.Cu")
		(net "SW_HDD_R10")
	)
	(segment
		(start 48.425354 -275.85289)
		(end 48.919638 -275.85289)
		(width 0.17145)
		(layer "F.Cu")
		(net "SW_HDD_R1")
	)
	(segment
		(start 52.631086 -275.585682)
		(end 52.234846 -275.189442)
		(width 0.17145)
		(layer "F.Cu")
		(net "SW_HDD_R1")
	)
	(segment
		(start 52.631086 -277.615142)
		(end 52.631086 -275.585682)
		(width 0.17145)
		(layer "F.Cu")
		(net "SW_HDD_R1")
	)
	(segment
		(start 45.971206 -278.975058)
		(end 46.857158 -278.089106)
		(width 0.17145)
		(layer "F.Cu")
		(net "SW_HDD_R1")
	)
	(segment
		(start 52.234846 -275.189442)
		(end 50.152046 -275.189442)
		(width 0.17145)
		(layer "F.Cu")
		(net "SW_HDD_R1")
	)
	(segment
		(start 48.919638 -275.85289)
		(end 49.583086 -275.189442)
		(width 0.17145)
		(layer "F.Cu")
		(net "SW_HDD_R1")
	)
	(segment
		(start 49.583086 -275.189442)
		(end 50.152046 -275.189442)
		(width 0.17145)
		(layer "F.Cu")
		(net "SW_HDD_R1")
	)
	(segment
		(start 45.971206 -279.156922)
		(end 45.971206 -278.975058)
		(width 0.17145)
		(layer "F.Cu")
		(net "SW_HDD_R1")
	)
	(segment
		(start 47.701454 -275.85289)
		(end 46.857158 -276.697186)
		(width 0.17145)
		(layer "F.Cu")
		(net "SW_HDD_R1")
	)
	(segment
		(start 46.857158 -276.697186)
		(end 46.857158 -278.089106)
		(width 0.17145)
		(layer "F.Cu")
		(net "SW_HDD_R1")
	)
	(segment
		(start 48.425354 -275.85289)
		(end 47.701454 -275.85289)
		(width 0.17145)
		(layer "F.Cu")
		(net "SW_HDD_R1")
	)
	(via
		(at 52.234846 -275.189442)
		(size 0.6604)
		(drill 0.3302)
		(layers "F.Cu" "B.Cu")
		(net "SW_HDD_R1")
	)
	(segment
		(start 424.596052 -275.110702)
		(end 424.596052 -277.284942)
		(width 0.17145)
		(layer "F.Cu")
		(net "SW_HDD_P9")
	)
	(segment
		(start 425.815252 -274.602702)
		(end 425.104052 -274.602702)
		(width 0.17145)
		(layer "F.Cu")
		(net "SW_HDD_P9")
	)
	(segment
		(start 424.596052 -277.284942)
		(end 425.485052 -278.173942)
		(width 0.17145)
		(layer "F.Cu")
		(net "SW_HDD_P9")
	)
	(segment
		(start 425.866052 -278.554942)
		(end 425.485052 -278.173942)
		(width 0.17145)
		(layer "F.Cu")
		(net "SW_HDD_P9")
	)
	(segment
		(start 426.945552 -279.596342)
		(end 426.945552 -278.554942)
		(width 0.17145)
		(layer "F.Cu")
		(net "SW_HDD_P9")
	)
	(segment
		(start 426.945552 -280.904442)
		(end 426.945552 -279.596342)
		(width 0.17145)
		(layer "F.Cu")
		(net "SW_HDD_P9")
	)
	(segment
		(start 427.009052 -280.967942)
		(end 426.945552 -280.904442)
		(width 0.17145)
		(layer "F.Cu")
		(net "SW_HDD_P9")
	)
	(segment
		(start 426.945552 -278.554942)
		(end 425.866052 -278.554942)
		(width 0.17145)
		(layer "F.Cu")
		(net "SW_HDD_P9")
	)
	(segment
		(start 425.104052 -274.602702)
		(end 424.596052 -275.110702)
		(width 0.17145)
		(layer "F.Cu")
		(net "SW_HDD_P9")
	)
	(via
		(at 425.485052 -278.173942)
		(size 0.6604)
		(drill 0.3302)
		(layers "F.Cu" "B.Cu")
		(net "SW_HDD_P9")
	)
	(segment
		(start 393.46505 -287.597342)
		(end 393.46505 -285.794958)
		(width 0.17145)
		(layer "F.Cu")
		(net "SW_HDD_P8")
	)
	(segment
		(start 394.26515 -274.602702)
		(end 393.55395 -274.602702)
		(width 0.17145)
		(layer "F.Cu")
		(net "SW_HDD_P8")
	)
	(segment
		(start 392.4554 -278.713692)
		(end 392.4554 -288.4424)
		(width 0.17145)
		(layer "F.Cu")
		(net "SW_HDD_P8")
	)
	(segment
		(start 392.4554 -288.4424)
		(end 392.651742 -288.638742)
		(width 0.17145)
		(layer "F.Cu")
		(net "SW_HDD_P8")
	)
	(segment
		(start 393.04595 -277.107142)
		(end 393.55395 -277.615142)
		(width 0.17145)
		(layer "F.Cu")
		(net "SW_HDD_P8")
	)
	(segment
		(start 393.55395 -274.602702)
		(end 393.04595 -275.110702)
		(width 0.17145)
		(layer "F.Cu")
		(net "SW_HDD_P8")
	)
	(segment
		(start 393.04595 -275.110702)
		(end 393.04595 -277.107142)
		(width 0.17145)
		(layer "F.Cu")
		(net "SW_HDD_P8")
	)
	(segment
		(start 393.46505 -288.638742)
		(end 393.46505 -287.597342)
		(width 0.17145)
		(layer "F.Cu")
		(net "SW_HDD_P8")
	)
	(segment
		(start 393.55395 -277.615142)
		(end 392.4554 -278.713692)
		(width 0.17145)
		(layer "F.Cu")
		(net "SW_HDD_P8")
	)
	(segment
		(start 392.651742 -288.638742)
		(end 393.46505 -288.638742)
		(width 0.17145)
		(layer "F.Cu")
		(net "SW_HDD_P8")
	)
	(segment
		(start 393.46505 -285.794958)
		(end 393.464542 -285.79445)
		(width 0.17145)
		(layer "F.Cu")
		(net "SW_HDD_P8")
	)
	(via
		(at 393.55395 -277.615142)
		(size 0.6604)
		(drill 0.3302)
		(layers "F.Cu" "B.Cu")
		(net "SW_HDD_P8")
	)
	(segment
		(start 363.909102 -280.967942)
		(end 363.845602 -280.904442)
		(width 0.17145)
		(layer "F.Cu")
		(net "SW_HDD_P7")
	)
	(segment
		(start 363.845602 -279.596342)
		(end 363.845602 -278.554942)
		(width 0.17145)
		(layer "F.Cu")
		(net "SW_HDD_P7")
	)
	(segment
		(start 362.766102 -278.554942)
		(end 362.385102 -278.173942)
		(width 0.17145)
		(layer "F.Cu")
		(net "SW_HDD_P7")
	)
	(segment
		(start 362.004102 -274.602702)
		(end 361.496102 -275.110702)
		(width 0.17145)
		(layer "F.Cu")
		(net "SW_HDD_P7")
	)
	(segment
		(start 363.845602 -278.554942)
		(end 362.766102 -278.554942)
		(width 0.17145)
		(layer "F.Cu")
		(net "SW_HDD_P7")
	)
	(segment
		(start 361.496102 -277.284942)
		(end 362.385102 -278.173942)
		(width 0.17145)
		(layer "F.Cu")
		(net "SW_HDD_P7")
	)
	(segment
		(start 361.496102 -275.110702)
		(end 361.496102 -277.284942)
		(width 0.17145)
		(layer "F.Cu")
		(net "SW_HDD_P7")
	)
	(segment
		(start 363.845602 -280.904442)
		(end 363.845602 -279.596342)
		(width 0.17145)
		(layer "F.Cu")
		(net "SW_HDD_P7")
	)
	(segment
		(start 362.715302 -274.602702)
		(end 362.004102 -274.602702)
		(width 0.17145)
		(layer "F.Cu")
		(net "SW_HDD_P7")
	)
	(via
		(at 362.385102 -278.173942)
		(size 0.6604)
		(drill 0.3302)
		(layers "F.Cu" "B.Cu")
		(net "SW_HDD_P7")
	)
	(segment
		(start 332.359 -280.967942)
		(end 332.2955 -280.904442)
		(width 0.17145)
		(layer "F.Cu")
		(net "SW_HDD_P6")
	)
	(segment
		(start 332.2955 -279.596342)
		(end 332.2955 -278.554942)
		(width 0.17145)
		(layer "F.Cu")
		(net "SW_HDD_P6")
	)
	(segment
		(start 329.946 -275.110702)
		(end 329.946 -277.284942)
		(width 0.17145)
		(layer "F.Cu")
		(net "SW_HDD_P6")
	)
	(segment
		(start 332.2955 -280.904442)
		(end 332.2955 -279.596342)
		(width 0.17145)
		(layer "F.Cu")
		(net "SW_HDD_P6")
	)
	(segment
		(start 329.946 -277.284942)
		(end 330.835 -278.173942)
		(width 0.17145)
		(layer "F.Cu")
		(net "SW_HDD_P6")
	)
	(segment
		(start 331.216 -278.554942)
		(end 330.835 -278.173942)
		(width 0.17145)
		(layer "F.Cu")
		(net "SW_HDD_P6")
	)
	(segment
		(start 332.2955 -278.554942)
		(end 331.216 -278.554942)
		(width 0.17145)
		(layer "F.Cu")
		(net "SW_HDD_P6")
	)
	(segment
		(start 330.454 -274.602702)
		(end 329.946 -275.110702)
		(width 0.17145)
		(layer "F.Cu")
		(net "SW_HDD_P6")
	)
	(segment
		(start 331.1652 -274.602702)
		(end 330.454 -274.602702)
		(width 0.17145)
		(layer "F.Cu")
		(net "SW_HDD_P6")
	)
	(via
		(at 330.835 -278.173942)
		(size 0.6604)
		(drill 0.3302)
		(layers "F.Cu" "B.Cu")
		(net "SW_HDD_P6")
	)
	(segment
		(start 175.6156 -279.8826)
		(end 174.9425 -280.5557)
		(width 0.17145)
		(layer "F.Cu")
		(net "SW_HDD_P5")
	)
	(segment
		(start 176.003458 -279.494742)
		(end 175.6156 -279.8826)
		(width 0.17145)
		(layer "F.Cu")
		(net "SW_HDD_P5")
	)
	(segment
		(start 174.9425 -283.0449)
		(end 176.53 -284.6324)
		(width 0.17145)
		(layer "F.Cu")
		(net "SW_HDD_P5")
	)
	(segment
		(start 174.9425 -280.5557)
		(end 174.9425 -280.993342)
		(width 0.17145)
		(layer "F.Cu")
		(net "SW_HDD_P5")
	)
	(segment
		(start 174.9425 -280.993342)
		(end 174.9425 -282.034742)
		(width 0.17145)
		(layer "F.Cu")
		(net "SW_HDD_P5")
	)
	(segment
		(start 174.9425 -282.034742)
		(end 174.9425 -283.0449)
		(width 0.17145)
		(layer "F.Cu")
		(net "SW_HDD_P5")
	)
	(segment
		(start 176.53 -284.6324)
		(end 176.53 -287.825942)
		(width 0.17145)
		(layer "F.Cu")
		(net "SW_HDD_P5")
	)
	(segment
		(start 177.53076 -279.494742)
		(end 176.003458 -279.494742)
		(width 0.17145)
		(layer "F.Cu")
		(net "SW_HDD_P5")
	)
	(via
		(at 175.6156 -279.8826)
		(size 0.6604)
		(drill 0.3302)
		(layers "F.Cu" "B.Cu")
		(net "SW_HDD_P5")
	)
	(segment
		(start 144.484598 -279.494742)
		(end 143.468598 -280.510742)
		(width 0.17145)
		(layer "F.Cu")
		(net "SW_HDD_P4")
	)
	(segment
		(start 143.468598 -280.6192)
		(end 143.468598 -282.060142)
		(width 0.17145)
		(layer "F.Cu")
		(net "SW_HDD_P4")
	)
	(segment
		(start 144.979898 -286.301942)
		(end 144.979898 -287.825942)
		(width 0.17145)
		(layer "F.Cu")
		(net "SW_HDD_P4")
	)
	(segment
		(start 145.980658 -279.494742)
		(end 144.484598 -279.494742)
		(width 0.17145)
		(layer "F.Cu")
		(net "SW_HDD_P4")
	)
	(segment
		(start 143.468598 -283.126942)
		(end 143.468598 -284.790642)
		(width 0.17145)
		(layer "F.Cu")
		(net "SW_HDD_P4")
	)
	(segment
		(start 143.468598 -284.790642)
		(end 144.979898 -286.301942)
		(width 0.17145)
		(layer "F.Cu")
		(net "SW_HDD_P4")
	)
	(segment
		(start 143.468598 -282.060142)
		(end 143.468598 -283.126942)
		(width 0.17145)
		(layer "F.Cu")
		(net "SW_HDD_P4")
	)
	(segment
		(start 143.468598 -280.510742)
		(end 143.468598 -280.6192)
		(width 0.17145)
		(layer "F.Cu")
		(net "SW_HDD_P4")
	)
	(via
		(at 143.468598 -280.6192)
		(size 0.6604)
		(drill 0.3302)
		(layers "F.Cu" "B.Cu")
		(net "SW_HDD_P4")
	)
	(segment
		(start 472.368626 -50.703226)
		(end 472.368626 -52.060094)
		(width 0.17145)
		(layer "F.Cu")
		(net "SW_HDD_P35")
	)
	(segment
		(start 472.368626 -53.126894)
		(end 472.368626 -54.790594)
		(width 0.17145)
		(layer "F.Cu")
		(net "SW_HDD_P35")
	)
	(segment
		(start 472.368626 -54.790594)
		(end 473.879926 -56.301894)
		(width 0.17145)
		(layer "F.Cu")
		(net "SW_HDD_P35")
	)
	(segment
		(start 472.215718 -44.73829)
		(end 472.215718 -49.210976)
		(width 0.17145)
		(layer "F.Cu")
		(net "SW_HDD_P35")
	)
	(segment
		(start 473.879926 -56.301894)
		(end 473.879926 -57.825894)
		(width 0.17145)
		(layer "F.Cu")
		(net "SW_HDD_P35")
	)
	(segment
		(start 472.215718 -50.550318)
		(end 472.368626 -50.703226)
		(width 0.17145)
		(layer "F.Cu")
		(net "SW_HDD_P35")
	)
	(segment
		(start 472.368626 -52.060094)
		(end 472.368626 -53.126894)
		(width 0.17145)
		(layer "F.Cu")
		(net "SW_HDD_P35")
	)
	(segment
		(start 472.215718 -49.210976)
		(end 472.215718 -50.550318)
		(width 0.17145)
		(layer "F.Cu")
		(net "SW_HDD_P35")
	)
	(via
		(at 472.215718 -49.210976)
		(size 0.6604)
		(drill 0.3302)
		(layers "F.Cu" "B.Cu")
		(net "SW_HDD_P35")
	)
	(segment
		(start 456.1459 -45.110654)
		(end 456.1459 -46.736)
		(width 0.17145)
		(layer "F.Cu")
		(net "SW_HDD_P34")
	)
	(segment
		(start 458.4954 -50.904394)
		(end 458.5589 -50.967894)
		(width 0.17145)
		(layer "F.Cu")
		(net "SW_HDD_P34")
	)
	(segment
		(start 458.4954 -49.596294)
		(end 458.4954 -50.904394)
		(width 0.17145)
		(layer "F.Cu")
		(net "SW_HDD_P34")
	)
	(segment
		(start 456.9206 -47.5107)
		(end 458.443838 -47.5107)
		(width 0.17145)
		(layer "F.Cu")
		(net "SW_HDD_P34")
	)
	(segment
		(start 457.3651 -44.602654)
		(end 456.6539 -44.602654)
		(width 0.17145)
		(layer "F.Cu")
		(net "SW_HDD_P34")
	)
	(segment
		(start 456.6539 -44.602654)
		(end 456.1459 -45.110654)
		(width 0.17145)
		(layer "F.Cu")
		(net "SW_HDD_P34")
	)
	(segment
		(start 458.4954 -48.554894)
		(end 458.4954 -49.596294)
		(width 0.17145)
		(layer "F.Cu")
		(net "SW_HDD_P34")
	)
	(segment
		(start 458.4954 -47.562262)
		(end 458.4954 -48.554894)
		(width 0.17145)
		(layer "F.Cu")
		(net "SW_HDD_P34")
	)
	(segment
		(start 458.443838 -47.5107)
		(end 458.4954 -47.562262)
		(width 0.17145)
		(layer "F.Cu")
		(net "SW_HDD_P34")
	)
	(segment
		(start 456.1459 -46.736)
		(end 456.9206 -47.5107)
		(width 0.17145)
		(layer "F.Cu")
		(net "SW_HDD_P34")
	)
	(via
		(at 458.443838 -47.5107)
		(size 0.6604)
		(drill 0.3302)
		(layers "F.Cu" "B.Cu")
		(net "SW_HDD_P34")
	)
	(segment
		(start 426.945552 -49.596294)
		(end 426.945552 -50.904394)
		(width 0.17145)
		(layer "F.Cu")
		(net "SW_HDD_P33")
	)
	(segment
		(start 425.104052 -44.602654)
		(end 424.596052 -45.110654)
		(width 0.17145)
		(layer "F.Cu")
		(net "SW_HDD_P33")
	)
	(segment
		(start 426.945552 -47.3202)
		(end 426.945552 -48.554894)
		(width 0.17145)
		(layer "F.Cu")
		(net "SW_HDD_P33")
	)
	(segment
		(start 424.596052 -46.9392)
		(end 424.977052 -47.3202)
		(width 0.17145)
		(layer "F.Cu")
		(net "SW_HDD_P33")
	)
	(segment
		(start 425.815252 -44.602654)
		(end 425.104052 -44.602654)
		(width 0.17145)
		(layer "F.Cu")
		(net "SW_HDD_P33")
	)
	(segment
		(start 426.945552 -48.554894)
		(end 426.945552 -49.596294)
		(width 0.17145)
		(layer "F.Cu")
		(net "SW_HDD_P33")
	)
	(segment
		(start 424.596052 -45.110654)
		(end 424.596052 -46.9392)
		(width 0.17145)
		(layer "F.Cu")
		(net "SW_HDD_P33")
	)
	(segment
		(start 426.945552 -50.904394)
		(end 427.009052 -50.967894)
		(width 0.17145)
		(layer "F.Cu")
		(net "SW_HDD_P33")
	)
	(segment
		(start 424.977052 -47.3202)
		(end 426.945552 -47.3202)
		(width 0.17145)
		(layer "F.Cu")
		(net "SW_HDD_P33")
	)
	(via
		(at 426.945552 -47.3202)
		(size 0.6604)
		(drill 0.3302)
		(layers "F.Cu" "B.Cu")
		(net "SW_HDD_P33")
	)
	(segment
		(start 393.04595 -46.609)
		(end 393.68095 -47.244)
		(width 0.17145)
		(layer "F.Cu")
		(net "SW_HDD_P32")
	)
	(segment
		(start 393.55395 -44.602654)
		(end 393.04595 -45.110654)
		(width 0.17145)
		(layer "F.Cu")
		(net "SW_HDD_P32")
	)
	(segment
		(start 393.04595 -45.110654)
		(end 393.04595 -46.609)
		(width 0.17145)
		(layer "F.Cu")
		(net "SW_HDD_P32")
	)
	(segment
		(start 393.68095 -47.244)
		(end 395.39545 -47.244)
		(width 0.17145)
		(layer "F.Cu")
		(net "SW_HDD_P32")
	)
	(segment
		(start 395.39545 -50.904394)
		(end 395.45895 -50.967894)
		(width 0.17145)
		(layer "F.Cu")
		(net "SW_HDD_P32")
	)
	(segment
		(start 394.26515 -44.602654)
		(end 393.55395 -44.602654)
		(width 0.17145)
		(layer "F.Cu")
		(net "SW_HDD_P32")
	)
	(segment
		(start 395.39545 -49.596294)
		(end 395.39545 -50.904394)
		(width 0.17145)
		(layer "F.Cu")
		(net "SW_HDD_P32")
	)
	(segment
		(start 395.39545 -47.244)
		(end 395.39545 -48.554894)
		(width 0.17145)
		(layer "F.Cu")
		(net "SW_HDD_P32")
	)
	(segment
		(start 395.39545 -48.554894)
		(end 395.39545 -49.596294)
		(width 0.17145)
		(layer "F.Cu")
		(net "SW_HDD_P32")
	)
	(via
		(at 395.39545 -47.244)
		(size 0.6604)
		(drill 0.3302)
		(layers "F.Cu" "B.Cu")
		(net "SW_HDD_P32")
	)
	(segment
		(start 363.41939 -47.828454)
		(end 363.845602 -47.402242)
		(width 0.17145)
		(layer "F.Cu")
		(net "SW_HDD_P31")
	)
	(segment
		(start 363.845602 -47.402242)
		(end 363.845602 -48.554894)
		(width 0.17145)
		(layer "F.Cu")
		(net "SW_HDD_P31")
	)
	(segment
		(start 361.496102 -47.172372)
		(end 362.152184 -47.828454)
		(width 0.17145)
		(layer "F.Cu")
		(net "SW_HDD_P31")
	)
	(segment
		(start 363.845602 -48.554894)
		(end 363.845602 -49.596294)
		(width 0.17145)
		(layer "F.Cu")
		(net "SW_HDD_P31")
	)
	(segment
		(start 363.845602 -50.904394)
		(end 363.909102 -50.967894)
		(width 0.17145)
		(layer "F.Cu")
		(net "SW_HDD_P31")
	)
	(segment
		(start 362.004102 -44.602654)
		(end 361.496102 -45.110654)
		(width 0.17145)
		(layer "F.Cu")
		(net "SW_HDD_P31")
	)
	(segment
		(start 362.715302 -44.602654)
		(end 362.004102 -44.602654)
		(width 0.17145)
		(layer "F.Cu")
		(net "SW_HDD_P31")
	)
	(segment
		(start 362.152184 -47.828454)
		(end 363.41939 -47.828454)
		(width 0.17145)
		(layer "F.Cu")
		(net "SW_HDD_P31")
	)
	(segment
		(start 361.496102 -45.110654)
		(end 361.496102 -47.172372)
		(width 0.17145)
		(layer "F.Cu")
		(net "SW_HDD_P31")
	)
	(segment
		(start 363.845602 -49.596294)
		(end 363.845602 -50.904394)
		(width 0.17145)
		(layer "F.Cu")
		(net "SW_HDD_P31")
	)
	(via
		(at 363.845602 -47.402242)
		(size 0.6604)
		(drill 0.3302)
		(layers "F.Cu" "B.Cu")
		(net "SW_HDD_P31")
	)
	(segment
		(start 330.454 -44.602654)
		(end 329.946 -45.110654)
		(width 0.17145)
		(layer "F.Cu")
		(net "SW_HDD_P30")
	)
	(segment
		(start 329.946 -46.7106)
		(end 330.5302 -47.2948)
		(width 0.17145)
		(layer "F.Cu")
		(net "SW_HDD_P30")
	)
	(segment
		(start 332.2955 -49.596294)
		(end 332.2955 -50.904394)
		(width 0.17145)
		(layer "F.Cu")
		(net "SW_HDD_P30")
	)
	(segment
		(start 332.2955 -48.554894)
		(end 332.2955 -49.596294)
		(width 0.17145)
		(layer "F.Cu")
		(net "SW_HDD_P30")
	)
	(segment
		(start 330.5302 -47.2948)
		(end 332.2955 -47.2948)
		(width 0.17145)
		(layer "F.Cu")
		(net "SW_HDD_P30")
	)
	(segment
		(start 332.2955 -47.2948)
		(end 332.2955 -48.554894)
		(width 0.17145)
		(layer "F.Cu")
		(net "SW_HDD_P30")
	)
	(segment
		(start 331.1652 -44.602654)
		(end 330.454 -44.602654)
		(width 0.17145)
		(layer "F.Cu")
		(net "SW_HDD_P30")
	)
	(segment
		(start 332.2955 -50.904394)
		(end 332.359 -50.967894)
		(width 0.17145)
		(layer "F.Cu")
		(net "SW_HDD_P30")
	)
	(segment
		(start 329.946 -45.110654)
		(end 329.946 -46.7106)
		(width 0.17145)
		(layer "F.Cu")
		(net "SW_HDD_P30")
	)
	(via
		(at 332.2955 -47.2948)
		(size 0.6604)
		(drill 0.3302)
		(layers "F.Cu" "B.Cu")
		(net "SW_HDD_P30")
	)
	(segment
		(start 122.9614 -280.5938)
		(end 121.5644 -279.1968)
		(width 0.17145)
		(layer "F.Cu")
		(net "SW_HDD_P3")
	)
	(segment
		(start 129.088896 -283.101542)
		(end 129.088896 -282.085542)
		(width 0.17145)
		(layer "F.Cu")
		(net "SW_HDD_P3")
	)
	(segment
		(start 121.5644 -279.1968)
		(end 121.5644 -276.86)
		(width 0.17145)
		(layer "F.Cu")
		(net "SW_HDD_P3")
	)
	(segment
		(start 128.8288 -280.5938)
		(end 122.9614 -280.5938)
		(width 0.17145)
		(layer "F.Cu")
		(net "SW_HDD_P3")
	)
	(segment
		(start 120.646444 -275.942044)
		(end 117.061742 -275.942044)
		(width 0.17145)
		(layer "F.Cu")
		(net "SW_HDD_P3")
	)
	(segment
		(start 130.676396 -287.800542)
		(end 130.676396 -286.175196)
		(width 0.17145)
		(layer "F.Cu")
		(net "SW_HDD_P3")
	)
	(segment
		(start 121.5644 -276.86)
		(end 120.646444 -275.942044)
		(width 0.17145)
		(layer "F.Cu")
		(net "SW_HDD_P3")
	)
	(segment
		(start 130.676396 -286.175196)
		(end 129.3622 -284.861)
		(width 0.17145)
		(layer "F.Cu")
		(net "SW_HDD_P3")
	)
	(segment
		(start 129.088896 -280.853896)
		(end 128.8288 -280.5938)
		(width 0.17145)
		(layer "F.Cu")
		(net "SW_HDD_P3")
	)
	(segment
		(start 129.088896 -282.085542)
		(end 129.088896 -280.853896)
		(width 0.17145)
		(layer "F.Cu")
		(net "SW_HDD_P3")
	)
	(segment
		(start 129.3622 -284.861)
		(end 129.088896 -284.587696)
		(width 0.17145)
		(layer "F.Cu")
		(net "SW_HDD_P3")
	)
	(segment
		(start 129.088896 -284.587696)
		(end 129.088896 -283.101542)
		(width 0.17145)
		(layer "F.Cu")
		(net "SW_HDD_P3")
	)
	(via
		(at 129.3622 -284.861)
		(size 0.6604)
		(drill 0.3302)
		(layers "F.Cu" "B.Cu")
		(net "SW_HDD_P3")
	)
	(segment
		(start 175.0187 -50.58664)
		(end 175.302164 -50.303176)
		(width 0.17145)
		(layer "F.Cu")
		(net "SW_HDD_P29")
	)
	(segment
		(start 175.0187 -52.110894)
		(end 175.0187 -53.152294)
		(width 0.17145)
		(layer "F.Cu")
		(net "SW_HDD_P29")
	)
	(segment
		(start 175.0187 -53.152294)
		(end 175.0187 -53.63083)
		(width 0.17145)
		(layer "F.Cu")
		(net "SW_HDD_P29")
	)
	(segment
		(start 175.0187 -53.63083)
		(end 176.53 -55.14213)
		(width 0.17145)
		(layer "F.Cu")
		(net "SW_HDD_P29")
	)
	(segment
		(start 176.110646 -49.494694)
		(end 177.53076 -49.494694)
		(width 0.17145)
		(layer "F.Cu")
		(net "SW_HDD_P29")
	)
	(segment
		(start 176.53 -55.14213)
		(end 176.53 -57.825894)
		(width 0.17145)
		(layer "F.Cu")
		(net "SW_HDD_P29")
	)
	(segment
		(start 175.0187 -52.110894)
		(end 175.0187 -50.58664)
		(width 0.17145)
		(layer "F.Cu")
		(net "SW_HDD_P29")
	)
	(segment
		(start 175.302164 -50.303176)
		(end 176.110646 -49.494694)
		(width 0.17145)
		(layer "F.Cu")
		(net "SW_HDD_P29")
	)
	(via
		(at 175.302164 -50.303176)
		(size 0.6604)
		(drill 0.3302)
		(layers "F.Cu" "B.Cu")
		(net "SW_HDD_P29")
	)
	(segment
		(start 144.979898 -54.962298)
		(end 143.493998 -53.476398)
		(width 0.17145)
		(layer "F.Cu")
		(net "SW_HDD_P28")
	)
	(segment
		(start 144.979898 -57.825894)
		(end 144.979898 -54.962298)
		(width 0.17145)
		(layer "F.Cu")
		(net "SW_HDD_P28")
	)
	(segment
		(start 143.493998 -53.126894)
		(end 143.493998 -52.034694)
		(width 0.17145)
		(layer "F.Cu")
		(net "SW_HDD_P28")
	)
	(segment
		(start 143.493998 -50.495708)
		(end 143.80464 -50.185066)
		(width 0.17145)
		(layer "F.Cu")
		(net "SW_HDD_P28")
	)
	(segment
		(start 143.80464 -50.185066)
		(end 144.495012 -49.494694)
		(width 0.17145)
		(layer "F.Cu")
		(net "SW_HDD_P28")
	)
	(segment
		(start 143.493998 -52.034694)
		(end 143.493998 -50.495708)
		(width 0.17145)
		(layer "F.Cu")
		(net "SW_HDD_P28")
	)
	(segment
		(start 143.493998 -53.476398)
		(end 143.493998 -53.126894)
		(width 0.17145)
		(layer "F.Cu")
		(net "SW_HDD_P28")
	)
	(segment
		(start 144.495012 -49.494694)
		(end 145.980658 -49.494694)
		(width 0.17145)
		(layer "F.Cu")
		(net "SW_HDD_P28")
	)
	(via
		(at 143.80464 -50.185066)
		(size 0.6604)
		(drill 0.3302)
		(layers "F.Cu" "B.Cu")
		(net "SW_HDD_P28")
	)
	(segment
		(start 111.918496 -50.510694)
		(end 111.918496 -50.5714)
		(width 0.17145)
		(layer "F.Cu")
		(net "SW_HDD_P27")
	)
	(segment
		(start 112.934496 -49.494694)
		(end 111.918496 -50.510694)
		(width 0.17145)
		(layer "F.Cu")
		(net "SW_HDD_P27")
	)
	(segment
		(start 113.429796 -56.301894)
		(end 113.429796 -57.825894)
		(width 0.17145)
		(layer "F.Cu")
		(net "SW_HDD_P27")
	)
	(segment
		(start 111.918496 -54.790594)
		(end 113.429796 -56.301894)
		(width 0.17145)
		(layer "F.Cu")
		(net "SW_HDD_P27")
	)
	(segment
		(start 111.918496 -53.126894)
		(end 111.918496 -54.790594)
		(width 0.17145)
		(layer "F.Cu")
		(net "SW_HDD_P27")
	)
	(segment
		(start 114.430556 -49.494694)
		(end 112.934496 -49.494694)
		(width 0.17145)
		(layer "F.Cu")
		(net "SW_HDD_P27")
	)
	(segment
		(start 111.918496 -50.5714)
		(end 111.918496 -52.085494)
		(width 0.17145)
		(layer "F.Cu")
		(net "SW_HDD_P27")
	)
	(segment
		(start 111.918496 -52.085494)
		(end 111.918496 -53.126894)
		(width 0.17145)
		(layer "F.Cu")
		(net "SW_HDD_P27")
	)
	(via
		(at 111.918496 -50.5714)
		(size 0.6604)
		(drill 0.3302)
		(layers "F.Cu" "B.Cu")
		(net "SW_HDD_P27")
	)
	(segment
		(start 80.368648 -52.085494)
		(end 80.368648 -53.126894)
		(width 0.17145)
		(layer "F.Cu")
		(net "SW_HDD_P26")
	)
	(segment
		(start 80.368648 -53.126894)
		(end 81.879948 -54.638194)
		(width 0.17145)
		(layer "F.Cu")
		(net "SW_HDD_P26")
	)
	(segment
		(start 81.879948 -54.638194)
		(end 81.879948 -57.825894)
		(width 0.17145)
		(layer "F.Cu")
		(net "SW_HDD_P26")
	)
	(segment
		(start 81.460848 -49.494694)
		(end 80.368648 -50.586894)
		(width 0.17145)
		(layer "F.Cu")
		(net "SW_HDD_P26")
	)
	(segment
		(start 82.880708 -49.494694)
		(end 81.460848 -49.494694)
		(width 0.17145)
		(layer "F.Cu")
		(net "SW_HDD_P26")
	)
	(segment
		(start 80.368648 -50.586894)
		(end 80.368648 -52.085494)
		(width 0.17145)
		(layer "F.Cu")
		(net "SW_HDD_P26")
	)
	(via
		(at 80.368648 -50.586894)
		(size 0.6604)
		(drill 0.3302)
		(layers "F.Cu" "B.Cu")
		(net "SW_HDD_P26")
	)
	(segment
		(start 48.818546 -52.060094)
		(end 48.818546 -53.101494)
		(width 0.17145)
		(layer "F.Cu")
		(net "SW_HDD_P25")
	)
	(segment
		(start 48.818546 -50.561494)
		(end 48.818546 -52.060094)
		(width 0.17145)
		(layer "F.Cu")
		(net "SW_HDD_P25")
	)
	(segment
		(start 49.885346 -49.494694)
		(end 48.818546 -50.561494)
		(width 0.17145)
		(layer "F.Cu")
		(net "SW_HDD_P25")
	)
	(segment
		(start 51.330606 -49.494694)
		(end 49.885346 -49.494694)
		(width 0.17145)
		(layer "F.Cu")
		(net "SW_HDD_P25")
	)
	(segment
		(start 50.329846 -56.301894)
		(end 50.329846 -57.825894)
		(width 0.17145)
		(layer "F.Cu")
		(net "SW_HDD_P25")
	)
	(segment
		(start 48.818546 -53.101494)
		(end 48.818546 -54.790594)
		(width 0.17145)
		(layer "F.Cu")
		(net "SW_HDD_P25")
	)
	(segment
		(start 48.818546 -54.790594)
		(end 50.329846 -56.301894)
		(width 0.17145)
		(layer "F.Cu")
		(net "SW_HDD_P25")
	)
	(via
		(at 48.818546 -50.561494)
		(size 0.6604)
		(drill 0.3302)
		(layers "F.Cu" "B.Cu")
		(net "SW_HDD_P25")
	)
	(segment
		(start 17.268698 -54.790594)
		(end 18.779998 -56.301894)
		(width 0.17145)
		(layer "F.Cu")
		(net "SW_HDD_P24")
	)
	(segment
		(start 18.386298 -49.494694)
		(end 19.780758 -49.494694)
		(width 0.17145)
		(layer "F.Cu")
		(net "SW_HDD_P24")
	)
	(segment
		(start 17.268698 -50.612294)
		(end 18.386298 -49.494694)
		(width 0.17145)
		(layer "F.Cu")
		(net "SW_HDD_P24")
	)
	(segment
		(start 17.268698 -52.136294)
		(end 17.268698 -53.177694)
		(width 0.17145)
		(layer "F.Cu")
		(net "SW_HDD_P24")
	)
	(segment
		(start 17.268698 -53.177694)
		(end 17.268698 -54.790594)
		(width 0.17145)
		(layer "F.Cu")
		(net "SW_HDD_P24")
	)
	(segment
		(start 17.268698 -52.136294)
		(end 17.268698 -50.612294)
		(width 0.17145)
		(layer "F.Cu")
		(net "SW_HDD_P24")
	)
	(segment
		(start 18.779998 -56.301894)
		(end 18.779998 -57.825894)
		(width 0.17145)
		(layer "F.Cu")
		(net "SW_HDD_P24")
	)
	(via
		(at 17.268698 -50.612294)
		(size 0.6604)
		(drill 0.3302)
		(layers "F.Cu" "B.Cu")
		(net "SW_HDD_P24")
	)
	(segment
		(start 472.368626 -167.085518)
		(end 472.368626 -168.126918)
		(width 0.17145)
		(layer "F.Cu")
		(net "SW_HDD_P23")
	)
	(segment
		(start 472.215718 -165.180518)
		(end 472.368626 -165.333426)
		(width 0.17145)
		(layer "F.Cu")
		(net "SW_HDD_P23")
	)
	(segment
		(start 472.215718 -164.211)
		(end 472.215718 -165.180518)
		(width 0.17145)
		(layer "F.Cu")
		(net "SW_HDD_P23")
	)
	(segment
		(start 472.368626 -169.790618)
		(end 473.879926 -171.301918)
		(width 0.17145)
		(layer "F.Cu")
		(net "SW_HDD_P23")
	)
	(segment
		(start 472.215718 -159.738314)
		(end 472.215718 -164.211)
		(width 0.17145)
		(layer "F.Cu")
		(net "SW_HDD_P23")
	)
	(segment
		(start 473.879926 -171.301918)
		(end 473.879926 -172.825918)
		(width 0.17145)
		(layer "F.Cu")
		(net "SW_HDD_P23")
	)
	(segment
		(start 472.368626 -165.333426)
		(end 472.368626 -167.085518)
		(width 0.17145)
		(layer "F.Cu")
		(net "SW_HDD_P23")
	)
	(segment
		(start 472.368626 -168.126918)
		(end 472.368626 -169.790618)
		(width 0.17145)
		(layer "F.Cu")
		(net "SW_HDD_P23")
	)
	(via
		(at 472.215718 -164.211)
		(size 0.6604)
		(drill 0.3302)
		(layers "F.Cu" "B.Cu")
		(net "SW_HDD_P23")
	)
	(segment
		(start 456.1459 -162.284918)
		(end 457.0349 -163.173918)
		(width 0.17145)
		(layer "F.Cu")
		(net "SW_HDD_P22")
	)
	(segment
		(start 458.5589 -165.967918)
		(end 458.4954 -165.904418)
		(width 0.17145)
		(layer "F.Cu")
		(net "SW_HDD_P22")
	)
	(segment
		(start 458.4954 -163.554918)
		(end 457.4159 -163.554918)
		(width 0.17145)
		(layer "F.Cu")
		(net "SW_HDD_P22")
	)
	(segment
		(start 458.4954 -164.596318)
		(end 458.4954 -163.554918)
		(width 0.17145)
		(layer "F.Cu")
		(net "SW_HDD_P22")
	)
	(segment
		(start 456.6539 -159.602678)
		(end 456.1459 -160.110678)
		(width 0.17145)
		(layer "F.Cu")
		(net "SW_HDD_P22")
	)
	(segment
		(start 457.4159 -163.554918)
		(end 457.0349 -163.173918)
		(width 0.17145)
		(layer "F.Cu")
		(net "SW_HDD_P22")
	)
	(segment
		(start 457.3651 -159.602678)
		(end 456.6539 -159.602678)
		(width 0.17145)
		(layer "F.Cu")
		(net "SW_HDD_P22")
	)
	(segment
		(start 458.4954 -165.904418)
		(end 458.4954 -164.596318)
		(width 0.17145)
		(layer "F.Cu")
		(net "SW_HDD_P22")
	)
	(segment
		(start 456.1459 -160.110678)
		(end 456.1459 -162.284918)
		(width 0.17145)
		(layer "F.Cu")
		(net "SW_HDD_P22")
	)
	(via
		(at 457.0349 -163.173918)
		(size 0.6604)
		(drill 0.3302)
		(layers "F.Cu" "B.Cu")
		(net "SW_HDD_P22")
	)
	(segment
		(start 425.815252 -159.602678)
		(end 425.104052 -159.602678)
		(width 0.17145)
		(layer "F.Cu")
		(net "SW_HDD_P21")
	)
	(segment
		(start 425.866052 -163.554918)
		(end 425.485052 -163.173918)
		(width 0.17145)
		(layer "F.Cu")
		(net "SW_HDD_P21")
	)
	(segment
		(start 426.945552 -164.596318)
		(end 426.945552 -163.554918)
		(width 0.17145)
		(layer "F.Cu")
		(net "SW_HDD_P21")
	)
	(segment
		(start 426.945552 -165.904418)
		(end 426.945552 -164.596318)
		(width 0.17145)
		(layer "F.Cu")
		(net "SW_HDD_P21")
	)
	(segment
		(start 425.104052 -159.602678)
		(end 424.596052 -160.110678)
		(width 0.17145)
		(layer "F.Cu")
		(net "SW_HDD_P21")
	)
	(segment
		(start 426.945552 -163.554918)
		(end 425.866052 -163.554918)
		(width 0.17145)
		(layer "F.Cu")
		(net "SW_HDD_P21")
	)
	(segment
		(start 424.596052 -160.110678)
		(end 424.596052 -162.284918)
		(width 0.17145)
		(layer "F.Cu")
		(net "SW_HDD_P21")
	)
	(segment
		(start 424.596052 -162.284918)
		(end 425.485052 -163.173918)
		(width 0.17145)
		(layer "F.Cu")
		(net "SW_HDD_P21")
	)
	(segment
		(start 427.009052 -165.967918)
		(end 426.945552 -165.904418)
		(width 0.17145)
		(layer "F.Cu")
		(net "SW_HDD_P21")
	)
	(via
		(at 425.485052 -163.173918)
		(size 0.6604)
		(drill 0.3302)
		(layers "F.Cu" "B.Cu")
		(net "SW_HDD_P21")
	)
	(segment
		(start 394.12545 -166.412418)
		(end 394.12545 -165.104318)
		(width 0.17145)
		(layer "F.Cu")
		(net "SW_HDD_P20")
	)
	(segment
		(start 394.12545 -162.667696)
		(end 394.12545 -164.062918)
		(width 0.17145)
		(layer "F.Cu")
		(net "SW_HDD_P20")
	)
	(segment
		(start 394.12545 -162.667696)
		(end 394.12545 -162.2552)
		(width 0.17145)
		(layer "F.Cu")
		(net "SW_HDD_P20")
	)
	(segment
		(start 394.12545 -162.2552)
		(end 393.04595 -161.1757)
		(width 0.17145)
		(layer "F.Cu")
		(net "SW_HDD_P20")
	)
	(segment
		(start 393.55395 -159.602678)
		(end 394.26515 -159.602678)
		(width 0.17145)
		(layer "F.Cu")
		(net "SW_HDD_P20")
	)
	(segment
		(start 394.18895 -166.475918)
		(end 394.12545 -166.412418)
		(width 0.17145)
		(layer "F.Cu")
		(net "SW_HDD_P20")
	)
	(segment
		(start 394.12545 -165.104318)
		(end 394.12545 -164.062918)
		(width 0.17145)
		(layer "F.Cu")
		(net "SW_HDD_P20")
	)
	(segment
		(start 393.04595 -161.1757)
		(end 393.04595 -160.110678)
		(width 0.17145)
		(layer "F.Cu")
		(net "SW_HDD_P20")
	)
	(segment
		(start 393.04595 -160.110678)
		(end 393.55395 -159.602678)
		(width 0.17145)
		(layer "F.Cu")
		(net "SW_HDD_P20")
	)
	(via
		(at 394.12545 -162.667696)
		(size 0.6604)
		(drill 0.3302)
		(layers "F.Cu" "B.Cu")
		(net "SW_HDD_P20")
	)
	(segment
		(start 81.879948 -287.825942)
		(end 81.879948 -286.301942)
		(width 0.17145)
		(layer "F.Cu")
		(net "SW_HDD_P2")
	)
	(segment
		(start 80.368648 -284.790642)
		(end 80.368648 -283.152342)
		(width 0.17145)
		(layer "F.Cu")
		(net "SW_HDD_P2")
	)
	(segment
		(start 81.879948 -286.301942)
		(end 80.368648 -284.790642)
		(width 0.17145)
		(layer "F.Cu")
		(net "SW_HDD_P2")
	)
	(segment
		(start 80.368648 -280.501344)
		(end 80.723994 -280.145998)
		(width 0.17145)
		(layer "F.Cu")
		(net "SW_HDD_P2")
	)
	(segment
		(start 82.880708 -279.494742)
		(end 81.37525 -279.494742)
		(width 0.17145)
		(layer "F.Cu")
		(net "SW_HDD_P2")
	)
	(segment
		(start 80.368648 -282.085542)
		(end 80.368648 -280.501344)
		(width 0.17145)
		(layer "F.Cu")
		(net "SW_HDD_P2")
	)
	(segment
		(start 81.37525 -279.494742)
		(end 80.723994 -280.145998)
		(width 0.17145)
		(layer "F.Cu")
		(net "SW_HDD_P2")
	)
	(segment
		(start 80.368648 -283.152342)
		(end 80.368648 -282.085542)
		(width 0.17145)
		(layer "F.Cu")
		(net "SW_HDD_P2")
	)
	(via
		(at 80.723994 -280.145998)
		(size 0.6604)
		(drill 0.3302)
		(layers "F.Cu" "B.Cu")
		(net "SW_HDD_P2")
	)
	(segment
		(start 363.845602 -164.596318)
		(end 363.845602 -163.554918)
		(width 0.17145)
		(layer "F.Cu")
		(net "SW_HDD_P19")
	)
	(segment
		(start 362.004102 -159.602678)
		(end 361.496102 -160.110678)
		(width 0.17145)
		(layer "F.Cu")
		(net "SW_HDD_P19")
	)
	(segment
		(start 363.845602 -163.554918)
		(end 362.766102 -163.554918)
		(width 0.17145)
		(layer "F.Cu")
		(net "SW_HDD_P19")
	)
	(segment
		(start 363.909102 -165.967918)
		(end 363.845602 -165.904418)
		(width 0.17145)
		(layer "F.Cu")
		(net "SW_HDD_P19")
	)
	(segment
		(start 362.766102 -163.554918)
		(end 362.385102 -163.173918)
		(width 0.17145)
		(layer "F.Cu")
		(net "SW_HDD_P19")
	)
	(segment
		(start 361.496102 -160.110678)
		(end 361.496102 -162.284918)
		(width 0.17145)
		(layer "F.Cu")
		(net "SW_HDD_P19")
	)
	(segment
		(start 361.496102 -162.284918)
		(end 362.385102 -163.173918)
		(width 0.17145)
		(layer "F.Cu")
		(net "SW_HDD_P19")
	)
	(segment
		(start 363.845602 -165.904418)
		(end 363.845602 -164.596318)
		(width 0.17145)
		(layer "F.Cu")
		(net "SW_HDD_P19")
	)
	(segment
		(start 362.715302 -159.602678)
		(end 362.004102 -159.602678)
		(width 0.17145)
		(layer "F.Cu")
		(net "SW_HDD_P19")
	)
	(via
		(at 362.385102 -163.173918)
		(size 0.6604)
		(drill 0.3302)
		(layers "F.Cu" "B.Cu")
		(net "SW_HDD_P19")
	)
	(segment
		(start 329.946 -162.284918)
		(end 330.835 -163.173918)
		(width 0.17145)
		(layer "F.Cu")
		(net "SW_HDD_P18")
	)
	(segment
		(start 331.1652 -159.602678)
		(end 330.454 -159.602678)
		(width 0.17145)
		(layer "F.Cu")
		(net "SW_HDD_P18")
	)
	(segment
		(start 330.454 -159.602678)
		(end 329.946 -160.110678)
		(width 0.17145)
		(layer "F.Cu")
		(net "SW_HDD_P18")
	)
	(segment
		(start 331.216 -163.554918)
		(end 330.835 -163.173918)
		(width 0.17145)
		(layer "F.Cu")
		(net "SW_HDD_P18")
	)
	(segment
		(start 332.2955 -165.904418)
		(end 332.2955 -164.596318)
		(width 0.17145)
		(layer "F.Cu")
		(net "SW_HDD_P18")
	)
	(segment
		(start 332.2955 -163.554918)
		(end 331.216 -163.554918)
		(width 0.17145)
		(layer "F.Cu")
		(net "SW_HDD_P18")
	)
	(segment
		(start 332.359 -165.967918)
		(end 332.2955 -165.904418)
		(width 0.17145)
		(layer "F.Cu")
		(net "SW_HDD_P18")
	)
	(segment
		(start 329.946 -160.110678)
		(end 329.946 -162.284918)
		(width 0.17145)
		(layer "F.Cu")
		(net "SW_HDD_P18")
	)
	(segment
		(start 332.2955 -164.596318)
		(end 332.2955 -163.554918)
		(width 0.17145)
		(layer "F.Cu")
		(net "SW_HDD_P18")
	)
	(via
		(at 330.835 -163.173918)
		(size 0.6604)
		(drill 0.3302)
		(layers "F.Cu" "B.Cu")
		(net "SW_HDD_P18")
	)
	(segment
		(start 177.58156 -164.875718)
		(end 176.507902 -164.875718)
		(width 0.17145)
		(layer "F.Cu")
		(net "SW_HDD_P17")
	)
	(segment
		(start 175.0187 -168.152318)
		(end 175.0187 -169.963084)
		(width 0.17145)
		(layer "F.Cu")
		(net "SW_HDD_P17")
	)
	(segment
		(start 176.507902 -164.875718)
		(end 175.0187 -166.36492)
		(width 0.17145)
		(layer "F.Cu")
		(net "SW_HDD_P17")
	)
	(segment
		(start 175.0187 -170.379898)
		(end 176.53 -171.891198)
		(width 0.17145)
		(layer "F.Cu")
		(net "SW_HDD_P17")
	)
	(segment
		(start 175.0187 -167.110918)
		(end 175.0187 -168.152318)
		(width 0.17145)
		(layer "F.Cu")
		(net "SW_HDD_P17")
	)
	(segment
		(start 176.53 -171.891198)
		(end 176.53 -172.825918)
		(width 0.17145)
		(layer "F.Cu")
		(net "SW_HDD_P17")
	)
	(segment
		(start 175.0187 -169.963084)
		(end 175.0187 -170.379898)
		(width 0.17145)
		(layer "F.Cu")
		(net "SW_HDD_P17")
	)
	(segment
		(start 175.0187 -166.36492)
		(end 175.0187 -167.110918)
		(width 0.17145)
		(layer "F.Cu")
		(net "SW_HDD_P17")
	)
	(via
		(at 175.0187 -169.963084)
		(size 0.6604)
		(drill 0.3302)
		(layers "F.Cu" "B.Cu")
		(net "SW_HDD_P17")
	)
	(segment
		(start 143.493998 -168.126918)
		(end 143.493998 -169.816018)
		(width 0.17145)
		(layer "F.Cu")
		(net "SW_HDD_P16")
	)
	(segment
		(start 143.493998 -169.816018)
		(end 144.979898 -171.301918)
		(width 0.17145)
		(layer "F.Cu")
		(net "SW_HDD_P16")
	)
	(segment
		(start 145.980658 -164.494718)
		(end 144.586198 -164.494718)
		(width 0.17145)
		(layer "F.Cu")
		(net "SW_HDD_P16")
	)
	(segment
		(start 144.979898 -171.301918)
		(end 144.979898 -172.825918)
		(width 0.17145)
		(layer "F.Cu")
		(net "SW_HDD_P16")
	)
	(segment
		(start 144.586198 -164.494718)
		(end 143.493998 -165.586918)
		(width 0.17145)
		(layer "F.Cu")
		(net "SW_HDD_P16")
	)
	(segment
		(start 143.493998 -167.060118)
		(end 143.493998 -168.126918)
		(width 0.17145)
		(layer "F.Cu")
		(net "SW_HDD_P16")
	)
	(segment
		(start 143.493998 -165.586918)
		(end 143.493998 -167.060118)
		(width 0.17145)
		(layer "F.Cu")
		(net "SW_HDD_P16")
	)
	(via
		(at 143.493998 -165.586918)
		(size 0.6604)
		(drill 0.3302)
		(layers "F.Cu" "B.Cu")
		(net "SW_HDD_P16")
	)
	(segment
		(start 111.943896 -168.126918)
		(end 111.943896 -169.816018)
		(width 0.17145)
		(layer "F.Cu")
		(net "SW_HDD_P15")
	)
	(segment
		(start 112.1664 -165.3032)
		(end 111.943896 -165.525704)
		(width 0.17145)
		(layer "F.Cu")
		(net "SW_HDD_P15")
	)
	(segment
		(start 111.943896 -169.816018)
		(end 113.429796 -171.301918)
		(width 0.17145)
		(layer "F.Cu")
		(net "SW_HDD_P15")
	)
	(segment
		(start 113.429796 -171.301918)
		(end 113.429796 -172.825918)
		(width 0.17145)
		(layer "F.Cu")
		(net "SW_HDD_P15")
	)
	(segment
		(start 111.943896 -165.525704)
		(end 111.943896 -167.085518)
		(width 0.17145)
		(layer "F.Cu")
		(net "SW_HDD_P15")
	)
	(segment
		(start 112.974882 -164.494718)
		(end 112.1664 -165.3032)
		(width 0.17145)
		(layer "F.Cu")
		(net "SW_HDD_P15")
	)
	(segment
		(start 114.430556 -164.494718)
		(end 112.974882 -164.494718)
		(width 0.17145)
		(layer "F.Cu")
		(net "SW_HDD_P15")
	)
	(segment
		(start 111.943896 -167.085518)
		(end 111.943896 -168.126918)
		(width 0.17145)
		(layer "F.Cu")
		(net "SW_HDD_P15")
	)
	(via
		(at 112.1664 -165.3032)
		(size 0.6604)
		(drill 0.3302)
		(layers "F.Cu" "B.Cu")
		(net "SW_HDD_P15")
	)
	(segment
		(start 81.460848 -164.494718)
		(end 80.368648 -165.586918)
		(width 0.17145)
		(layer "F.Cu")
		(net "SW_HDD_P14")
	)
	(segment
		(start 80.368648 -169.790618)
		(end 81.879948 -171.301918)
		(width 0.17145)
		(layer "F.Cu")
		(net "SW_HDD_P14")
	)
	(segment
		(start 80.368648 -165.586918)
		(end 80.368648 -167.060118)
		(width 0.17145)
		(layer "F.Cu")
		(net "SW_HDD_P14")
	)
	(segment
		(start 81.879948 -171.301918)
		(end 81.879948 -172.825918)
		(width 0.17145)
		(layer "F.Cu")
		(net "SW_HDD_P14")
	)
	(segment
		(start 82.880708 -164.494718)
		(end 81.460848 -164.494718)
		(width 0.17145)
		(layer "F.Cu")
		(net "SW_HDD_P14")
	)
	(segment
		(start 80.368648 -167.060118)
		(end 80.368648 -168.126918)
		(width 0.17145)
		(layer "F.Cu")
		(net "SW_HDD_P14")
	)
	(segment
		(start 80.368648 -168.126918)
		(end 80.368648 -169.790618)
		(width 0.17145)
		(layer "F.Cu")
		(net "SW_HDD_P14")
	)
	(via
		(at 80.368648 -165.586918)
		(size 0.6604)
		(drill 0.3302)
		(layers "F.Cu" "B.Cu")
		(net "SW_HDD_P14")
	)
	(segment
		(start 51.4985 -165.1)
		(end 51.4985 -163.576)
		(width 0.17145)
		(layer "F.Cu")
		(net "SW_HDD_P13")
	)
	(segment
		(start 51.4985 -163.108894)
		(end 51.4985 -163.576)
		(width 0.17145)
		(layer "F.Cu")
		(net "SW_HDD_P13")
	)
	(segment
		(start 48.98898 -165.71976)
		(end 48.98898 -168.61282)
		(width 0.17145)
		(layer "F.Cu")
		(net "SW_HDD_P13")
	)
	(segment
		(start 50.329846 -169.953686)
		(end 50.329846 -172.825918)
		(width 0.17145)
		(layer "F.Cu")
		(net "SW_HDD_P13")
	)
	(segment
		(start 50.292 -165.1)
		(end 49.60874 -165.1)
		(width 0.17145)
		(layer "F.Cu")
		(net "SW_HDD_P13")
	)
	(segment
		(start 50.292 -165.1)
		(end 51.4985 -165.1)
		(width 0.17145)
		(layer "F.Cu")
		(net "SW_HDD_P13")
	)
	(segment
		(start 51.381406 -162.9918)
		(end 51.4985 -163.108894)
		(width 0.17145)
		(layer "F.Cu")
		(net "SW_HDD_P13")
	)
	(segment
		(start 49.60874 -165.1)
		(end 48.98898 -165.71976)
		(width 0.17145)
		(layer "F.Cu")
		(net "SW_HDD_P13")
	)
	(segment
		(start 51.381406 -162.208718)
		(end 51.381406 -162.9918)
		(width 0.17145)
		(layer "F.Cu")
		(net "SW_HDD_P13")
	)
	(segment
		(start 48.98898 -168.61282)
		(end 50.329846 -169.953686)
		(width 0.17145)
		(layer "F.Cu")
		(net "SW_HDD_P13")
	)
	(via
		(at 50.292 -165.1)
		(size 0.6604)
		(drill 0.3302)
		(layers "F.Cu" "B.Cu")
		(net "SW_HDD_P13")
	)
	(segment
		(start 17.268698 -167.110918)
		(end 17.268698 -168.152318)
		(width 0.17145)
		(layer "F.Cu")
		(net "SW_HDD_P12")
	)
	(segment
		(start 17.268698 -169.790618)
		(end 18.779998 -171.301918)
		(width 0.17145)
		(layer "F.Cu")
		(net "SW_HDD_P12")
	)
	(segment
		(start 17.268698 -165.510718)
		(end 17.268698 -165.5826)
		(width 0.17145)
		(layer "F.Cu")
		(net "SW_HDD_P12")
	)
	(segment
		(start 19.780758 -164.494718)
		(end 18.284698 -164.494718)
		(width 0.17145)
		(layer "F.Cu")
		(net "SW_HDD_P12")
	)
	(segment
		(start 17.268698 -168.152318)
		(end 17.268698 -169.790618)
		(width 0.17145)
		(layer "F.Cu")
		(net "SW_HDD_P12")
	)
	(segment
		(start 18.284698 -164.494718)
		(end 17.268698 -165.510718)
		(width 0.17145)
		(layer "F.Cu")
		(net "SW_HDD_P12")
	)
	(segment
		(start 17.268698 -165.5826)
		(end 17.268698 -167.110918)
		(width 0.17145)
		(layer "F.Cu")
		(net "SW_HDD_P12")
	)
	(segment
		(start 18.779998 -171.301918)
		(end 18.779998 -172.825918)
		(width 0.17145)
		(layer "F.Cu")
		(net "SW_HDD_P12")
	)
	(via
		(at 17.268698 -165.5826)
		(size 0.6604)
		(drill 0.3302)
		(layers "F.Cu" "B.Cu")
		(net "SW_HDD_P12")
	)
	(segment
		(start 473.907866 -283.172916)
		(end 472.433396 -281.698446)
		(width 0.17145)
		(layer "F.Cu")
		(net "SW_HDD_P11")
	)
	(segment
		(start 475.24162 -275.93798)
		(end 475.24162 -274.84324)
		(width 0.17145)
		(layer "F.Cu")
		(net "SW_HDD_P11")
	)
	(segment
		(start 474.82506 -276.35454)
		(end 475.24162 -275.93798)
		(width 0.17145)
		(layer "F.Cu")
		(net "SW_HDD_P11")
	)
	(segment
		(start 472.425014 -279.117298)
		(end 472.399614 -279.091898)
		(width 0.17145)
		(layer "F.Cu")
		(net "SW_HDD_P11")
	)
	(segment
		(start 472.425014 -281.690064)
		(end 472.425014 -280.158698)
		(width 0.17145)
		(layer "F.Cu")
		(net "SW_HDD_P11")
	)
	(segment
		(start 472.425014 -280.158698)
		(end 472.425014 -279.117298)
		(width 0.17145)
		(layer "F.Cu")
		(net "SW_HDD_P11")
	)
	(segment
		(start 472.433396 -281.698446)
		(end 472.425014 -281.690064)
		(width 0.17145)
		(layer "F.Cu")
		(net "SW_HDD_P11")
	)
	(segment
		(start 472.399614 -279.091898)
		(end 472.739212 -278.7523)
		(width 0.17145)
		(layer "F.Cu")
		(net "SW_HDD_P11")
	)
	(segment
		(start 473.206572 -276.35454)
		(end 474.82506 -276.35454)
		(width 0.17145)
		(layer "F.Cu")
		(net "SW_HDD_P11")
	)
	(segment
		(start 473.907866 -283.911802)
		(end 473.907866 -283.172916)
		(width 0.17145)
		(layer "F.Cu")
		(net "SW_HDD_P11")
	)
	(segment
		(start 472.739212 -276.8219)
		(end 473.206572 -276.35454)
		(width 0.17145)
		(layer "F.Cu")
		(net "SW_HDD_P11")
	)
	(segment
		(start 472.739212 -278.7523)
		(end 472.739212 -276.8219)
		(width 0.17145)
		(layer "F.Cu")
		(net "SW_HDD_P11")
	)
	(via
		(at 472.433396 -281.698446)
		(size 0.6604)
		(drill 0.3302)
		(layers "F.Cu" "B.Cu")
		(net "SW_HDD_P11")
	)
	(segment
		(start 456.1459 -277.284942)
		(end 457.0349 -278.173942)
		(width 0.17145)
		(layer "F.Cu")
		(net "SW_HDD_P10")
	)
	(segment
		(start 456.1459 -275.110702)
		(end 456.1459 -277.284942)
		(width 0.17145)
		(layer "F.Cu")
		(net "SW_HDD_P10")
	)
	(segment
		(start 456.6539 -274.602702)
		(end 456.1459 -275.110702)
		(width 0.17145)
		(layer "F.Cu")
		(net "SW_HDD_P10")
	)
	(segment
		(start 458.4954 -279.862026)
		(end 458.4954 -279.596342)
		(width 0.17145)
		(layer "F.Cu")
		(net "SW_HDD_P10")
	)
	(segment
		(start 457.4159 -278.554942)
		(end 457.0349 -278.173942)
		(width 0.17145)
		(layer "F.Cu")
		(net "SW_HDD_P10")
	)
	(segment
		(start 458.4954 -278.554942)
		(end 457.4159 -278.554942)
		(width 0.17145)
		(layer "F.Cu")
		(net "SW_HDD_P10")
	)
	(segment
		(start 458.4954 -279.596342)
		(end 458.4954 -278.554942)
		(width 0.17145)
		(layer "F.Cu")
		(net "SW_HDD_P10")
	)
	(segment
		(start 458.0509 -280.967942)
		(end 458.0509 -280.306526)
		(width 0.17145)
		(layer "F.Cu")
		(net "SW_HDD_P10")
	)
	(segment
		(start 457.3651 -274.602702)
		(end 456.6539 -274.602702)
		(width 0.17145)
		(layer "F.Cu")
		(net "SW_HDD_P10")
	)
	(segment
		(start 458.0509 -280.306526)
		(end 458.4954 -279.862026)
		(width 0.17145)
		(layer "F.Cu")
		(net "SW_HDD_P10")
	)
	(via
		(at 457.0349 -278.173942)
		(size 0.6604)
		(drill 0.3302)
		(layers "F.Cu" "B.Cu")
		(net "SW_HDD_P10")
	)
	(segment
		(start 50.329846 -284.924246)
		(end 48.742346 -283.336746)
		(width 0.17145)
		(layer "F.Cu")
		(net "SW_HDD_P1")
	)
	(segment
		(start 51.330606 -279.494742)
		(end 49.663858 -279.494742)
		(width 0.17145)
		(layer "F.Cu")
		(net "SW_HDD_P1")
	)
	(segment
		(start 48.742346 -282.060142)
		(end 48.742346 -281.018742)
		(width 0.17145)
		(layer "F.Cu")
		(net "SW_HDD_P1")
	)
	(segment
		(start 50.329846 -287.825942)
		(end 50.329846 -284.924246)
		(width 0.17145)
		(layer "F.Cu")
		(net "SW_HDD_P1")
	)
	(segment
		(start 48.742346 -280.416254)
		(end 49.3014 -279.8572)
		(width 0.17145)
		(layer "F.Cu")
		(net "SW_HDD_P1")
	)
	(segment
		(start 48.742346 -283.336746)
		(end 48.742346 -282.060142)
		(width 0.17145)
		(layer "F.Cu")
		(net "SW_HDD_P1")
	)
	(segment
		(start 49.663858 -279.494742)
		(end 49.3014 -279.8572)
		(width 0.17145)
		(layer "F.Cu")
		(net "SW_HDD_P1")
	)
	(segment
		(start 48.742346 -281.018742)
		(end 48.742346 -280.416254)
		(width 0.17145)
		(layer "F.Cu")
		(net "SW_HDD_P1")
	)
	(via
		(at 49.3014 -279.8572)
		(size 0.6604)
		(drill 0.3302)
		(layers "F.Cu" "B.Cu")
		(net "SW_HDD_P1")
	)
	(segment
		(start 433.168552 -277.856442)
		(end 433.105052 -277.792942)
		(width 0.17145)
		(layer "F.Cu")
		(net "SW_HDD_N9")
	)
	(segment
		(start 433.359052 -289.476942)
		(end 433.359052 -289.032442)
		(width 0.17145)
		(layer "F.Cu")
		(net "SW_HDD_N9")
	)
	(segment
		(start 433.359052 -289.032442)
		(end 433.803552 -288.587942)
		(width 0.17145)
		(layer "F.Cu")
		(net "SW_HDD_N9")
	)
	(segment
		(start 433.803552 -286.809942)
		(end 434.502052 -286.111442)
		(width 0.17145)
		(layer "F.Cu")
		(net "SW_HDD_N9")
	)
	(segment
		(start 433.803552 -287.851342)
		(end 433.803552 -286.809942)
		(width 0.17145)
		(layer "F.Cu")
		(net "SW_HDD_N9")
	)
	(segment
		(start 434.502052 -279.824942)
		(end 434.121052 -279.443942)
		(width 0.17145)
		(layer "F.Cu")
		(net "SW_HDD_N9")
	)
	(segment
		(start 434.502052 -286.111442)
		(end 434.502052 -279.824942)
		(width 0.17145)
		(layer "F.Cu")
		(net "SW_HDD_N9")
	)
	(segment
		(start 434.121052 -279.443942)
		(end 433.168552 -279.443942)
		(width 0.17145)
		(layer "F.Cu")
		(net "SW_HDD_N9")
	)
	(segment
		(start 433.168552 -279.443942)
		(end 433.168552 -277.856442)
		(width 0.17145)
		(layer "F.Cu")
		(net "SW_HDD_N9")
	)
	(segment
		(start 433.803552 -288.587942)
		(end 433.803552 -287.851342)
		(width 0.17145)
		(layer "F.Cu")
		(net "SW_HDD_N9")
	)
	(via
		(at 434.121052 -279.443942)
		(size 0.6604)
		(drill 0.3302)
		(layers "F.Cu" "B.Cu")
		(net "SW_HDD_N9")
	)
	(segment
		(start 405.9936 -283.1465)
		(end 405.9809 -283.1338)
		(width 0.17145)
		(layer "F.Cu")
		(net "SW_HDD_N8")
	)
	(segment
		(start 405.9809 -283.1338)
		(end 404.3934 -283.1338)
		(width 0.17145)
		(layer "F.Cu")
		(net "SW_HDD_N8")
	)
	(segment
		(start 406.9334 -283.1465)
		(end 406.9588 -283.1211)
		(width 0.17145)
		(layer "F.Cu")
		(net "SW_HDD_N8")
	)
	(segment
		(start 404.88235 -277.843742)
		(end 403.92985 -277.843742)
		(width 0.17145)
		(layer "F.Cu")
		(net "SW_HDD_N8")
	)
	(segment
		(start 404.88235 -277.843742)
		(end 406.951942 -277.843742)
		(width 0.17145)
		(layer "F.Cu")
		(net "SW_HDD_N8")
	)
	(segment
		(start 405.9936 -283.1465)
		(end 406.9334 -283.1465)
		(width 0.17145)
		(layer "F.Cu")
		(net "SW_HDD_N8")
	)
	(segment
		(start 406.951942 -277.843742)
		(end 408.3812 -279.273)
		(width 0.17145)
		(layer "F.Cu")
		(net "SW_HDD_N8")
	)
	(segment
		(start 403.92985 -276.256242)
		(end 403.86635 -276.192742)
		(width 0.17145)
		(layer "F.Cu")
		(net "SW_HDD_N8")
	)
	(segment
		(start 408.3812 -279.273)
		(end 408.3812 -282.6512)
		(width 0.17145)
		(layer "F.Cu")
		(net "SW_HDD_N8")
	)
	(segment
		(start 407.9113 -283.1211)
		(end 406.9588 -283.1211)
		(width 0.17145)
		(layer "F.Cu")
		(net "SW_HDD_N8")
	)
	(segment
		(start 403.92985 -277.843742)
		(end 403.92985 -276.256242)
		(width 0.17145)
		(layer "F.Cu")
		(net "SW_HDD_N8")
	)
	(segment
		(start 408.3812 -282.6512)
		(end 407.9113 -283.1211)
		(width 0.17145)
		(layer "F.Cu")
		(net "SW_HDD_N8")
	)
	(via
		(at 404.88235 -277.843742)
		(size 0.6604)
		(drill 0.3302)
		(layers "F.Cu" "B.Cu")
		(net "SW_HDD_N8")
	)
	(segment
		(start 370.703602 -286.809942)
		(end 370.703602 -287.851342)
		(width 0.17145)
		(layer "F.Cu")
		(net "SW_HDD_N7")
	)
	(segment
		(start 370.703602 -287.851342)
		(end 370.703602 -288.587942)
		(width 0.17145)
		(layer "F.Cu")
		(net "SW_HDD_N7")
	)
	(segment
		(start 371.928136 -285.585408)
		(end 370.703602 -286.809942)
		(width 0.17145)
		(layer "F.Cu")
		(net "SW_HDD_N7")
	)
	(segment
		(start 371.021102 -279.443942)
		(end 370.068602 -279.443942)
		(width 0.17145)
		(layer "F.Cu")
		(net "SW_HDD_N7")
	)
	(segment
		(start 370.259102 -289.032442)
		(end 370.259102 -289.476942)
		(width 0.17145)
		(layer "F.Cu")
		(net "SW_HDD_N7")
	)
	(segment
		(start 371.928136 -280.350976)
		(end 371.928136 -285.585408)
		(width 0.17145)
		(layer "F.Cu")
		(net "SW_HDD_N7")
	)
	(segment
		(start 370.068602 -277.856442)
		(end 370.005102 -277.792942)
		(width 0.17145)
		(layer "F.Cu")
		(net "SW_HDD_N7")
	)
	(segment
		(start 370.703602 -288.587942)
		(end 370.259102 -289.032442)
		(width 0.17145)
		(layer "F.Cu")
		(net "SW_HDD_N7")
	)
	(segment
		(start 371.021102 -279.443942)
		(end 371.928136 -280.350976)
		(width 0.17145)
		(layer "F.Cu")
		(net "SW_HDD_N7")
	)
	(segment
		(start 370.068602 -279.443942)
		(end 370.068602 -277.856442)
		(width 0.17145)
		(layer "F.Cu")
		(net "SW_HDD_N7")
	)
	(via
		(at 371.021102 -279.443942)
		(size 0.6604)
		(drill 0.3302)
		(layers "F.Cu" "B.Cu")
		(net "SW_HDD_N7")
	)
	(segment
		(start 338.709 -289.032442)
		(end 339.1535 -288.587942)
		(width 0.17145)
		(layer "F.Cu")
		(net "SW_HDD_N6")
	)
	(segment
		(start 339.1535 -287.851342)
		(end 339.1535 -286.809942)
		(width 0.17145)
		(layer "F.Cu")
		(net "SW_HDD_N6")
	)
	(segment
		(start 343.535 -281.1272)
		(end 341.851742 -279.443942)
		(width 0.17145)
		(layer "F.Cu")
		(net "SW_HDD_N6")
	)
	(segment
		(start 338.5185 -279.443942)
		(end 338.5185 -277.856442)
		(width 0.17145)
		(layer "F.Cu")
		(net "SW_HDD_N6")
	)
	(segment
		(start 341.851742 -279.443942)
		(end 339.471 -279.443942)
		(width 0.17145)
		(layer "F.Cu")
		(net "SW_HDD_N6")
	)
	(segment
		(start 339.1535 -286.809942)
		(end 341.611458 -286.809942)
		(width 0.17145)
		(layer "F.Cu")
		(net "SW_HDD_N6")
	)
	(segment
		(start 339.471 -279.443942)
		(end 338.5185 -279.443942)
		(width 0.17145)
		(layer "F.Cu")
		(net "SW_HDD_N6")
	)
	(segment
		(start 343.535 -284.8864)
		(end 343.535 -281.1272)
		(width 0.17145)
		(layer "F.Cu")
		(net "SW_HDD_N6")
	)
	(segment
		(start 339.1535 -288.587942)
		(end 339.1535 -287.851342)
		(width 0.17145)
		(layer "F.Cu")
		(net "SW_HDD_N6")
	)
	(segment
		(start 341.611458 -286.809942)
		(end 343.535 -284.8864)
		(width 0.17145)
		(layer "F.Cu")
		(net "SW_HDD_N6")
	)
	(segment
		(start 338.5185 -277.856442)
		(end 338.455 -277.792942)
		(width 0.17145)
		(layer "F.Cu")
		(net "SW_HDD_N6")
	)
	(segment
		(start 338.709 -289.476942)
		(end 338.709 -289.032442)
		(width 0.17145)
		(layer "F.Cu")
		(net "SW_HDD_N6")
	)
	(via
		(at 339.471 -279.443942)
		(size 0.6604)
		(drill 0.3302)
		(layers "F.Cu" "B.Cu")
		(net "SW_HDD_N6")
	)
	(segment
		(start 173.0121 -279.4762)
		(end 174.0662 -279.4762)
		(width 0.17145)
		(layer "F.Cu")
		(net "SW_HDD_N5")
	)
	(segment
		(start 172.8216 -280.8732)
		(end 172.8216 -282.4226)
		(width 0.17145)
		(layer "F.Cu")
		(net "SW_HDD_N5")
	)
	(segment
		(start 174.5107 -283.932376)
		(end 174.5107 -284.473142)
		(width 0.17145)
		(layer "F.Cu")
		(net "SW_HDD_N5")
	)
	(segment
		(start 173.968918 -283.390594)
		(end 174.5107 -283.932376)
		(width 0.17145)
		(layer "F.Cu")
		(net "SW_HDD_N5")
	)
	(segment
		(start 174.498 -287.317942)
		(end 174.498 -285.527242)
		(width 0.17145)
		(layer "F.Cu")
		(net "SW_HDD_N5")
	)
	(segment
		(start 173.789594 -283.390594)
		(end 173.968918 -283.390594)
		(width 0.17145)
		(layer "F.Cu")
		(net "SW_HDD_N5")
	)
	(segment
		(start 172.8216 -279.6667)
		(end 173.0121 -279.4762)
		(width 0.17145)
		(layer "F.Cu")
		(net "SW_HDD_N5")
	)
	(segment
		(start 174.5107 -285.514542)
		(end 174.5107 -284.473142)
		(width 0.17145)
		(layer "F.Cu")
		(net "SW_HDD_N5")
	)
	(segment
		(start 172.8216 -282.4226)
		(end 173.789594 -283.390594)
		(width 0.17145)
		(layer "F.Cu")
		(net "SW_HDD_N5")
	)
	(segment
		(start 172.8216 -279.6667)
		(end 172.8216 -280.8732)
		(width 0.17145)
		(layer "F.Cu")
		(net "SW_HDD_N5")
	)
	(segment
		(start 174.0662 -279.4762)
		(end 174.625 -278.9174)
		(width 0.17145)
		(layer "F.Cu")
		(net "SW_HDD_N5")
	)
	(segment
		(start 174.498 -285.527242)
		(end 174.5107 -285.514542)
		(width 0.17145)
		(layer "F.Cu")
		(net "SW_HDD_N5")
	)
	(segment
		(start 174.625 -278.9174)
		(end 174.625 -277.792942)
		(width 0.17145)
		(layer "F.Cu")
		(net "SW_HDD_N5")
	)
	(via
		(at 172.8216 -280.8732)
		(size 0.6604)
		(drill 0.3302)
		(layers "F.Cu" "B.Cu")
		(net "SW_HDD_N5")
	)
	(segment
		(start 141.487398 -284.523942)
		(end 142.947898 -285.984442)
		(width 0.17145)
		(layer "F.Cu")
		(net "SW_HDD_N4")
	)
	(segment
		(start 141.487398 -279.316942)
		(end 141.487398 -283.507942)
		(width 0.17145)
		(layer "F.Cu")
		(net "SW_HDD_N4")
	)
	(segment
		(start 142.947898 -285.984442)
		(end 142.947898 -287.317942)
		(width 0.17145)
		(layer "F.Cu")
		(net "SW_HDD_N4")
	)
	(segment
		(start 141.487398 -283.507942)
		(end 141.487398 -284.523942)
		(width 0.17145)
		(layer "F.Cu")
		(net "SW_HDD_N4")
	)
	(segment
		(start 141.423898 -277.627842)
		(end 142.909798 -277.627842)
		(width 0.17145)
		(layer "F.Cu")
		(net "SW_HDD_N4")
	)
	(segment
		(start 141.423898 -278.5872)
		(end 141.423898 -277.627842)
		(width 0.17145)
		(layer "F.Cu")
		(net "SW_HDD_N4")
	)
	(segment
		(start 141.487398 -279.316942)
		(end 141.487398 -278.6507)
		(width 0.17145)
		(layer "F.Cu")
		(net "SW_HDD_N4")
	)
	(segment
		(start 141.487398 -278.6507)
		(end 141.423898 -278.5872)
		(width 0.17145)
		(layer "F.Cu")
		(net "SW_HDD_N4")
	)
	(segment
		(start 142.909798 -277.627842)
		(end 143.074898 -277.792942)
		(width 0.17145)
		(layer "F.Cu")
		(net "SW_HDD_N4")
	)
	(via
		(at 141.487398 -279.316942)
		(size 0.6604)
		(drill 0.3302)
		(layers "F.Cu" "B.Cu")
		(net "SW_HDD_N4")
	)
	(segment
		(start 470.348818 -49.29505)
		(end 470.348818 -47.80915)
		(width 0.17145)
		(layer "F.Cu")
		(net "SW_HDD_N35")
	)
	(segment
		(start 470.387426 -53.457094)
		(end 470.387426 -54.523894)
		(width 0.17145)
		(layer "F.Cu")
		(net "SW_HDD_N35")
	)
	(segment
		(start 470.348818 -50.670968)
		(end 470.348818 -49.29505)
		(width 0.17145)
		(layer "F.Cu")
		(net "SW_HDD_N35")
	)
	(segment
		(start 470.348818 -47.80915)
		(end 470.513918 -47.64405)
		(width 0.17145)
		(layer "F.Cu")
		(net "SW_HDD_N35")
	)
	(segment
		(start 470.387426 -54.523894)
		(end 471.847926 -55.984394)
		(width 0.17145)
		(layer "F.Cu")
		(net "SW_HDD_N35")
	)
	(segment
		(start 471.847926 -55.984394)
		(end 471.847926 -57.317894)
		(width 0.17145)
		(layer "F.Cu")
		(net "SW_HDD_N35")
	)
	(segment
		(start 470.387426 -50.709576)
		(end 470.348818 -50.670968)
		(width 0.17145)
		(layer "F.Cu")
		(net "SW_HDD_N35")
	)
	(segment
		(start 470.387426 -50.709576)
		(end 470.387426 -53.457094)
		(width 0.17145)
		(layer "F.Cu")
		(net "SW_HDD_N35")
	)
	(via
		(at 470.387426 -50.709576)
		(size 0.6604)
		(drill 0.3302)
		(layers "F.Cu" "B.Cu")
		(net "SW_HDD_N35")
	)
	(segment
		(start 465.3534 -57.851294)
		(end 465.3534 -56.809894)
		(width 0.17145)
		(layer "F.Cu")
		(net "SW_HDD_N34")
	)
	(segment
		(start 464.7184 -49.443894)
		(end 464.7184 -47.856394)
		(width 0.17145)
		(layer "F.Cu")
		(net "SW_HDD_N34")
	)
	(segment
		(start 466.0519 -56.111394)
		(end 466.0519 -49.824894)
		(width 0.17145)
		(layer "F.Cu")
		(net "SW_HDD_N34")
	)
	(segment
		(start 465.3534 -56.809894)
		(end 466.0519 -56.111394)
		(width 0.17145)
		(layer "F.Cu")
		(net "SW_HDD_N34")
	)
	(segment
		(start 464.9089 -59.032394)
		(end 465.3534 -58.587894)
		(width 0.17145)
		(layer "F.Cu")
		(net "SW_HDD_N34")
	)
	(segment
		(start 465.3534 -58.587894)
		(end 465.3534 -57.851294)
		(width 0.17145)
		(layer "F.Cu")
		(net "SW_HDD_N34")
	)
	(segment
		(start 464.7184 -47.856394)
		(end 464.6549 -47.792894)
		(width 0.17145)
		(layer "F.Cu")
		(net "SW_HDD_N34")
	)
	(segment
		(start 465.6709 -49.443894)
		(end 464.7184 -49.443894)
		(width 0.17145)
		(layer "F.Cu")
		(net "SW_HDD_N34")
	)
	(segment
		(start 464.9089 -59.476894)
		(end 464.9089 -59.032394)
		(width 0.17145)
		(layer "F.Cu")
		(net "SW_HDD_N34")
	)
	(segment
		(start 466.0519 -49.824894)
		(end 465.6709 -49.443894)
		(width 0.17145)
		(layer "F.Cu")
		(net "SW_HDD_N34")
	)
	(via
		(at 465.6709 -49.443894)
		(size 0.6604)
		(drill 0.3302)
		(layers "F.Cu" "B.Cu")
		(net "SW_HDD_N34")
	)
	(segment
		(start 433.359052 -59.032394)
		(end 433.803552 -58.587894)
		(width 0.17145)
		(layer "F.Cu")
		(net "SW_HDD_N33")
	)
	(segment
		(start 434.502052 -49.824894)
		(end 434.121052 -49.443894)
		(width 0.17145)
		(layer "F.Cu")
		(net "SW_HDD_N33")
	)
	(segment
		(start 434.121052 -49.443894)
		(end 433.168552 -49.443894)
		(width 0.17145)
		(layer "F.Cu")
		(net "SW_HDD_N33")
	)
	(segment
		(start 433.803552 -58.587894)
		(end 433.803552 -57.851294)
		(width 0.17145)
		(layer "F.Cu")
		(net "SW_HDD_N33")
	)
	(segment
		(start 433.359052 -59.476894)
		(end 433.359052 -59.032394)
		(width 0.17145)
		(layer "F.Cu")
		(net "SW_HDD_N33")
	)
	(segment
		(start 434.502052 -56.111394)
		(end 434.502052 -49.824894)
		(width 0.17145)
		(layer "F.Cu")
		(net "SW_HDD_N33")
	)
	(segment
		(start 433.168552 -47.856394)
		(end 433.105052 -47.792894)
		(width 0.17145)
		(layer "F.Cu")
		(net "SW_HDD_N33")
	)
	(segment
		(start 433.803552 -57.851294)
		(end 433.803552 -56.809894)
		(width 0.17145)
		(layer "F.Cu")
		(net "SW_HDD_N33")
	)
	(segment
		(start 433.168552 -49.443894)
		(end 433.168552 -47.856394)
		(width 0.17145)
		(layer "F.Cu")
		(net "SW_HDD_N33")
	)
	(segment
		(start 433.803552 -56.809894)
		(end 434.502052 -56.111394)
		(width 0.17145)
		(layer "F.Cu")
		(net "SW_HDD_N33")
	)
	(via
		(at 434.121052 -49.443894)
		(size 0.6604)
		(drill 0.3302)
		(layers "F.Cu" "B.Cu")
		(net "SW_HDD_N33")
	)
	(segment
		(start 402.95195 -49.824894)
		(end 402.57095 -49.443894)
		(width 0.17145)
		(layer "F.Cu")
		(net "SW_HDD_N32")
	)
	(segment
		(start 402.25345 -57.851294)
		(end 402.25345 -56.809894)
		(width 0.17145)
		(layer "F.Cu")
		(net "SW_HDD_N32")
	)
	(segment
		(start 402.57095 -49.443894)
		(end 401.61845 -49.443894)
		(width 0.17145)
		(layer "F.Cu")
		(net "SW_HDD_N32")
	)
	(segment
		(start 401.61845 -49.443894)
		(end 401.61845 -47.856394)
		(width 0.17145)
		(layer "F.Cu")
		(net "SW_HDD_N32")
	)
	(segment
		(start 402.25345 -58.587894)
		(end 402.25345 -57.851294)
		(width 0.17145)
		(layer "F.Cu")
		(net "SW_HDD_N32")
	)
	(segment
		(start 401.80895 -59.476894)
		(end 401.80895 -59.032394)
		(width 0.17145)
		(layer "F.Cu")
		(net "SW_HDD_N32")
	)
	(segment
		(start 401.61845 -47.856394)
		(end 401.55495 -47.792894)
		(width 0.17145)
		(layer "F.Cu")
		(net "SW_HDD_N32")
	)
	(segment
		(start 401.80895 -59.032394)
		(end 402.25345 -58.587894)
		(width 0.17145)
		(layer "F.Cu")
		(net "SW_HDD_N32")
	)
	(segment
		(start 402.95195 -56.111394)
		(end 402.95195 -49.824894)
		(width 0.17145)
		(layer "F.Cu")
		(net "SW_HDD_N32")
	)
	(segment
		(start 402.25345 -56.809894)
		(end 402.95195 -56.111394)
		(width 0.17145)
		(layer "F.Cu")
		(net "SW_HDD_N32")
	)
	(via
		(at 402.57095 -49.443894)
		(size 0.6604)
		(drill 0.3302)
		(layers "F.Cu" "B.Cu")
		(net "SW_HDD_N32")
	)
	(segment
		(start 370.259102 -59.032394)
		(end 370.703602 -58.587894)
		(width 0.17145)
		(layer "F.Cu")
		(net "SW_HDD_N31")
	)
	(segment
		(start 370.703602 -56.809894)
		(end 371.402102 -56.111394)
		(width 0.17145)
		(layer "F.Cu")
		(net "SW_HDD_N31")
	)
	(segment
		(start 370.703602 -57.851294)
		(end 370.703602 -56.809894)
		(width 0.17145)
		(layer "F.Cu")
		(net "SW_HDD_N31")
	)
	(segment
		(start 371.402102 -49.824894)
		(end 371.021102 -49.443894)
		(width 0.17145)
		(layer "F.Cu")
		(net "SW_HDD_N31")
	)
	(segment
		(start 370.703602 -58.587894)
		(end 370.703602 -57.851294)
		(width 0.17145)
		(layer "F.Cu")
		(net "SW_HDD_N31")
	)
	(segment
		(start 370.068602 -47.856394)
		(end 370.005102 -47.792894)
		(width 0.17145)
		(layer "F.Cu")
		(net "SW_HDD_N31")
	)
	(segment
		(start 371.021102 -49.443894)
		(end 370.068602 -49.443894)
		(width 0.17145)
		(layer "F.Cu")
		(net "SW_HDD_N31")
	)
	(segment
		(start 370.068602 -49.443894)
		(end 370.068602 -47.856394)
		(width 0.17145)
		(layer "F.Cu")
		(net "SW_HDD_N31")
	)
	(segment
		(start 371.402102 -56.111394)
		(end 371.402102 -49.824894)
		(width 0.17145)
		(layer "F.Cu")
		(net "SW_HDD_N31")
	)
	(segment
		(start 370.259102 -59.476894)
		(end 370.259102 -59.032394)
		(width 0.17145)
		(layer "F.Cu")
		(net "SW_HDD_N31")
	)
	(via
		(at 371.021102 -49.443894)
		(size 0.6604)
		(drill 0.3302)
		(layers "F.Cu" "B.Cu")
		(net "SW_HDD_N31")
	)
	(segment
		(start 338.5185 -49.443894)
		(end 338.5185 -47.856394)
		(width 0.17145)
		(layer "F.Cu")
		(net "SW_HDD_N30")
	)
	(segment
		(start 338.709 -59.476894)
		(end 338.709 -59.032394)
		(width 0.17145)
		(layer "F.Cu")
		(net "SW_HDD_N30")
	)
	(segment
		(start 339.1535 -58.587894)
		(end 339.1535 -57.851294)
		(width 0.17145)
		(layer "F.Cu")
		(net "SW_HDD_N30")
	)
	(segment
		(start 339.852 -49.824894)
		(end 339.471 -49.443894)
		(width 0.17145)
		(layer "F.Cu")
		(net "SW_HDD_N30")
	)
	(segment
		(start 338.5185 -47.856394)
		(end 338.455 -47.792894)
		(width 0.17145)
		(layer "F.Cu")
		(net "SW_HDD_N30")
	)
	(segment
		(start 339.1535 -57.851294)
		(end 339.1535 -56.809894)
		(width 0.17145)
		(layer "F.Cu")
		(net "SW_HDD_N30")
	)
	(segment
		(start 338.709 -59.032394)
		(end 339.1535 -58.587894)
		(width 0.17145)
		(layer "F.Cu")
		(net "SW_HDD_N30")
	)
	(segment
		(start 339.1535 -56.809894)
		(end 339.852 -56.111394)
		(width 0.17145)
		(layer "F.Cu")
		(net "SW_HDD_N30")
	)
	(segment
		(start 339.852 -56.111394)
		(end 339.852 -49.824894)
		(width 0.17145)
		(layer "F.Cu")
		(net "SW_HDD_N30")
	)
	(segment
		(start 339.471 -49.443894)
		(end 338.5185 -49.443894)
		(width 0.17145)
		(layer "F.Cu")
		(net "SW_HDD_N30")
	)
	(via
		(at 339.471 -49.443894)
		(size 0.6604)
		(drill 0.3302)
		(layers "F.Cu" "B.Cu")
		(net "SW_HDD_N30")
	)
	(segment
		(start 117.3734 -284.4546)
		(end 116.655342 -283.736542)
		(width 0.17145)
		(layer "F.Cu")
		(net "SW_HDD_N3")
	)
	(segment
		(start 115.169696 -282.695142)
		(end 115.169696 -283.736542)
		(width 0.17145)
		(layer "F.Cu")
		(net "SW_HDD_N3")
	)
	(segment
		(start 115.169442 -281.5844)
		(end 115.169442 -280.498804)
		(width 0.17145)
		(layer "F.Cu")
		(net "SW_HDD_N3")
	)
	(segment
		(start 115.169442 -280.498804)
		(end 115.169442 -279.012904)
		(width 0.17145)
		(layer "F.Cu")
		(net "SW_HDD_N3")
	)
	(segment
		(start 115.169696 -281.584654)
		(end 115.169442 -281.5844)
		(width 0.17145)
		(layer "F.Cu")
		(net "SW_HDD_N3")
	)
	(segment
		(start 115.169442 -279.012904)
		(end 115.359942 -278.822404)
		(width 0.17145)
		(layer "F.Cu")
		(net "SW_HDD_N3")
	)
	(segment
		(start 115.169696 -282.695142)
		(end 115.169696 -281.584654)
		(width 0.17145)
		(layer "F.Cu")
		(net "SW_HDD_N3")
	)
	(segment
		(start 116.655342 -283.736542)
		(end 115.169696 -283.736542)
		(width 0.17145)
		(layer "F.Cu")
		(net "SW_HDD_N3")
	)
	(segment
		(start 117.3734 -287.0708)
		(end 117.3734 -284.4546)
		(width 0.17145)
		(layer "F.Cu")
		(net "SW_HDD_N3")
	)
	(via
		(at 115.169442 -281.5844)
		(size 0.6604)
		(drill 0.3302)
		(layers "F.Cu" "B.Cu")
		(net "SW_HDD_N3")
	)
	(segment
		(start 173.0375 -47.665894)
		(end 172.974 -47.602394)
		(width 0.17145)
		(layer "F.Cu")
		(net "SW_HDD_N29")
	)
	(segment
		(start 173.0375 -53.482494)
		(end 173.0375 -54.523894)
		(width 0.17145)
		(layer "F.Cu")
		(net "SW_HDD_N29")
	)
	(segment
		(start 172.974 -47.602394)
		(end 174.4345 -47.602394)
		(width 0.17145)
		(layer "F.Cu")
		(net "SW_HDD_N29")
	)
	(segment
		(start 173.0375 -49.316894)
		(end 173.0375 -47.665894)
		(width 0.17145)
		(layer "F.Cu")
		(net "SW_HDD_N29")
	)
	(segment
		(start 173.0375 -54.523894)
		(end 174.498 -55.984394)
		(width 0.17145)
		(layer "F.Cu")
		(net "SW_HDD_N29")
	)
	(segment
		(start 174.4345 -47.602394)
		(end 174.625 -47.792894)
		(width 0.17145)
		(layer "F.Cu")
		(net "SW_HDD_N29")
	)
	(segment
		(start 174.498 -55.984394)
		(end 174.498 -57.317894)
		(width 0.17145)
		(layer "F.Cu")
		(net "SW_HDD_N29")
	)
	(segment
		(start 173.0375 -53.482494)
		(end 173.0375 -49.316894)
		(width 0.17145)
		(layer "F.Cu")
		(net "SW_HDD_N29")
	)
	(via
		(at 173.0375 -49.316894)
		(size 0.6604)
		(drill 0.3302)
		(layers "F.Cu" "B.Cu")
		(net "SW_HDD_N29")
	)
	(segment
		(start 141.487398 -54.523894)
		(end 142.947898 -55.984394)
		(width 0.17145)
		(layer "F.Cu")
		(net "SW_HDD_N28")
	)
	(segment
		(start 142.947898 -55.984394)
		(end 142.947898 -57.317894)
		(width 0.17145)
		(layer "F.Cu")
		(net "SW_HDD_N28")
	)
	(segment
		(start 141.487398 -49.316894)
		(end 141.487398 -53.507894)
		(width 0.17145)
		(layer "F.Cu")
		(net "SW_HDD_N28")
	)
	(segment
		(start 141.423898 -47.602394)
		(end 142.884398 -47.602394)
		(width 0.17145)
		(layer "F.Cu")
		(net "SW_HDD_N28")
	)
	(segment
		(start 141.487398 -47.665894)
		(end 141.487398 -49.316894)
		(width 0.17145)
		(layer "F.Cu")
		(net "SW_HDD_N28")
	)
	(segment
		(start 141.487398 -53.507894)
		(end 141.487398 -54.523894)
		(width 0.17145)
		(layer "F.Cu")
		(net "SW_HDD_N28")
	)
	(segment
		(start 141.423898 -47.602394)
		(end 141.487398 -47.665894)
		(width 0.17145)
		(layer "F.Cu")
		(net "SW_HDD_N28")
	)
	(segment
		(start 142.884398 -47.602394)
		(end 143.074898 -47.792894)
		(width 0.17145)
		(layer "F.Cu")
		(net "SW_HDD_N28")
	)
	(via
		(at 141.487398 -49.316894)
		(size 0.6604)
		(drill 0.3302)
		(layers "F.Cu" "B.Cu")
		(net "SW_HDD_N28")
	)
	(segment
		(start 110.822994 -47.627794)
		(end 109.873796 -47.627794)
		(width 0.17145)
		(layer "F.Cu")
		(net "SW_HDD_N27")
	)
	(segment
		(start 109.873796 -48.0695)
		(end 109.873796 -47.627794)
		(width 0.17145)
		(layer "F.Cu")
		(net "SW_HDD_N27")
	)
	(segment
		(start 109.937296 -54.523894)
		(end 111.397796 -55.984394)
		(width 0.17145)
		(layer "F.Cu")
		(net "SW_HDD_N27")
	)
	(segment
		(start 109.937296 -53.482494)
		(end 109.937296 -54.523894)
		(width 0.17145)
		(layer "F.Cu")
		(net "SW_HDD_N27")
	)
	(segment
		(start 111.397796 -55.984394)
		(end 111.397796 -57.317894)
		(width 0.17145)
		(layer "F.Cu")
		(net "SW_HDD_N27")
	)
	(segment
		(start 109.937296 -49.316894)
		(end 109.937296 -48.133)
		(width 0.17145)
		(layer "F.Cu")
		(net "SW_HDD_N27")
	)
	(segment
		(start 109.937296 -53.482494)
		(end 109.937296 -49.316894)
		(width 0.17145)
		(layer "F.Cu")
		(net "SW_HDD_N27")
	)
	(segment
		(start 111.524796 -47.792894)
		(end 110.988094 -47.792894)
		(width 0.17145)
		(layer "F.Cu")
		(net "SW_HDD_N27")
	)
	(segment
		(start 110.988094 -47.792894)
		(end 110.822994 -47.627794)
		(width 0.17145)
		(layer "F.Cu")
		(net "SW_HDD_N27")
	)
	(segment
		(start 109.937296 -48.133)
		(end 109.873796 -48.0695)
		(width 0.17145)
		(layer "F.Cu")
		(net "SW_HDD_N27")
	)
	(via
		(at 109.937296 -49.316894)
		(size 0.6604)
		(drill 0.3302)
		(layers "F.Cu" "B.Cu")
		(net "SW_HDD_N27")
	)
	(segment
		(start 79.375 -47.792894)
		(end 79.2099 -47.627794)
		(width 0.17145)
		(layer "F.Cu")
		(net "SW_HDD_N26")
	)
	(segment
		(start 79.974948 -47.792894)
		(end 79.375 -47.792894)
		(width 0.17145)
		(layer "F.Cu")
		(net "SW_HDD_N26")
	)
	(segment
		(start 78.387448 -53.482494)
		(end 78.387448 -49.316894)
		(width 0.17145)
		(layer "F.Cu")
		(net "SW_HDD_N26")
	)
	(segment
		(start 78.387448 -54.523894)
		(end 79.847948 -55.984394)
		(width 0.17145)
		(layer "F.Cu")
		(net "SW_HDD_N26")
	)
	(segment
		(start 79.2099 -47.627794)
		(end 78.323948 -47.627794)
		(width 0.17145)
		(layer "F.Cu")
		(net "SW_HDD_N26")
	)
	(segment
		(start 78.387448 -53.482494)
		(end 78.387448 -54.523894)
		(width 0.17145)
		(layer "F.Cu")
		(net "SW_HDD_N26")
	)
	(segment
		(start 78.387448 -49.316894)
		(end 78.387448 -48.5902)
		(width 0.17145)
		(layer "F.Cu")
		(net "SW_HDD_N26")
	)
	(segment
		(start 78.323948 -48.5267)
		(end 78.323948 -47.627794)
		(width 0.17145)
		(layer "F.Cu")
		(net "SW_HDD_N26")
	)
	(segment
		(start 78.387448 -48.5902)
		(end 78.323948 -48.5267)
		(width 0.17145)
		(layer "F.Cu")
		(net "SW_HDD_N26")
	)
	(segment
		(start 79.847948 -55.984394)
		(end 79.847948 -57.317894)
		(width 0.17145)
		(layer "F.Cu")
		(net "SW_HDD_N26")
	)
	(via
		(at 78.387448 -49.316894)
		(size 0.6604)
		(drill 0.3302)
		(layers "F.Cu" "B.Cu")
		(net "SW_HDD_N26")
	)
	(segment
		(start 46.837346 -54.523894)
		(end 48.297846 -55.984394)
		(width 0.17145)
		(layer "F.Cu")
		(net "SW_HDD_N25")
	)
	(segment
		(start 46.837346 -53.482494)
		(end 46.837346 -49.316894)
		(width 0.17145)
		(layer "F.Cu")
		(net "SW_HDD_N25")
	)
	(segment
		(start 48.424846 -47.792894)
		(end 48.259746 -47.627794)
		(width 0.17145)
		(layer "F.Cu")
		(net "SW_HDD_N25")
	)
	(segment
		(start 48.259746 -47.627794)
		(end 46.773846 -47.627794)
		(width 0.17145)
		(layer "F.Cu")
		(net "SW_HDD_N25")
	)
	(segment
		(start 46.837346 -49.316894)
		(end 46.773846 -49.253394)
		(width 0.17145)
		(layer "F.Cu")
		(net "SW_HDD_N25")
	)
	(segment
		(start 46.773846 -49.253394)
		(end 46.773846 -47.627794)
		(width 0.17145)
		(layer "F.Cu")
		(net "SW_HDD_N25")
	)
	(segment
		(start 48.297846 -55.984394)
		(end 48.297846 -57.317894)
		(width 0.17145)
		(layer "F.Cu")
		(net "SW_HDD_N25")
	)
	(segment
		(start 46.837346 -53.482494)
		(end 46.837346 -54.523894)
		(width 0.17145)
		(layer "F.Cu")
		(net "SW_HDD_N25")
	)
	(via
		(at 46.837346 -49.316894)
		(size 0.6604)
		(drill 0.3302)
		(layers "F.Cu" "B.Cu")
		(net "SW_HDD_N25")
	)
	(segment
		(start 15.287498 -53.482494)
		(end 15.287498 -54.523894)
		(width 0.17145)
		(layer "F.Cu")
		(net "SW_HDD_N24")
	)
	(segment
		(start 15.287498 -47.665894)
		(end 15.287498 -49.316894)
		(width 0.17145)
		(layer "F.Cu")
		(net "SW_HDD_N24")
	)
	(segment
		(start 15.287498 -54.523894)
		(end 16.747998 -55.984394)
		(width 0.17145)
		(layer "F.Cu")
		(net "SW_HDD_N24")
	)
	(segment
		(start 15.287498 -49.316894)
		(end 15.287498 -53.482494)
		(width 0.17145)
		(layer "F.Cu")
		(net "SW_HDD_N24")
	)
	(segment
		(start 16.747998 -55.984394)
		(end 16.747998 -57.317894)
		(width 0.17145)
		(layer "F.Cu")
		(net "SW_HDD_N24")
	)
	(segment
		(start 15.223998 -47.602394)
		(end 15.287498 -47.665894)
		(width 0.17145)
		(layer "F.Cu")
		(net "SW_HDD_N24")
	)
	(segment
		(start 16.684498 -47.602394)
		(end 16.874998 -47.792894)
		(width 0.17145)
		(layer "F.Cu")
		(net "SW_HDD_N24")
	)
	(segment
		(start 15.223998 -47.602394)
		(end 16.684498 -47.602394)
		(width 0.17145)
		(layer "F.Cu")
		(net "SW_HDD_N24")
	)
	(via
		(at 15.287498 -49.316894)
		(size 0.6604)
		(drill 0.3302)
		(layers "F.Cu" "B.Cu")
		(net "SW_HDD_N24")
	)
	(segment
		(start 470.387426 -168.482518)
		(end 470.387426 -169.523918)
		(width 0.17145)
		(layer "F.Cu")
		(net "SW_HDD_N23")
	)
	(segment
		(start 470.348818 -163.4871)
		(end 470.348818 -164.295074)
		(width 0.17145)
		(layer "F.Cu")
		(net "SW_HDD_N23")
	)
	(segment
		(start 470.513918 -163.322)
		(end 470.348818 -163.4871)
		(width 0.17145)
		(layer "F.Cu")
		(net "SW_HDD_N23")
	)
	(segment
		(start 470.348818 -165.7096)
		(end 470.323418 -165.735)
		(width 0.17145)
		(layer "F.Cu")
		(net "SW_HDD_N23")
	)
	(segment
		(start 471.847926 -170.984418)
		(end 471.847926 -172.317918)
		(width 0.17145)
		(layer "F.Cu")
		(net "SW_HDD_N23")
	)
	(segment
		(start 470.387426 -165.799008)
		(end 470.387426 -168.482518)
		(width 0.17145)
		(layer "F.Cu")
		(net "SW_HDD_N23")
	)
	(segment
		(start 470.323418 -165.735)
		(end 470.387426 -165.799008)
		(width 0.17145)
		(layer "F.Cu")
		(net "SW_HDD_N23")
	)
	(segment
		(start 470.387426 -169.523918)
		(end 471.847926 -170.984418)
		(width 0.17145)
		(layer "F.Cu")
		(net "SW_HDD_N23")
	)
	(segment
		(start 470.348818 -164.295074)
		(end 470.348818 -165.7096)
		(width 0.17145)
		(layer "F.Cu")
		(net "SW_HDD_N23")
	)
	(segment
		(start 470.513918 -162.644074)
		(end 470.513918 -163.322)
		(width 0.17145)
		(layer "F.Cu")
		(net "SW_HDD_N23")
	)
	(via
		(at 470.323418 -165.735)
		(size 0.6604)
		(drill 0.3302)
		(layers "F.Cu" "B.Cu")
		(net "SW_HDD_N23")
	)
	(segment
		(start 465.3534 -172.851318)
		(end 465.3534 -171.809918)
		(width 0.17145)
		(layer "F.Cu")
		(net "SW_HDD_N22")
	)
	(segment
		(start 465.6709 -164.443918)
		(end 464.7184 -164.443918)
		(width 0.17145)
		(layer "F.Cu")
		(net "SW_HDD_N22")
	)
	(segment
		(start 465.3534 -173.587918)
		(end 465.3534 -172.851318)
		(width 0.17145)
		(layer "F.Cu")
		(net "SW_HDD_N22")
	)
	(segment
		(start 464.9089 -174.476918)
		(end 464.9089 -174.032418)
		(width 0.17145)
		(layer "F.Cu")
		(net "SW_HDD_N22")
	)
	(segment
		(start 464.9089 -174.032418)
		(end 465.3534 -173.587918)
		(width 0.17145)
		(layer "F.Cu")
		(net "SW_HDD_N22")
	)
	(segment
		(start 464.7184 -162.856418)
		(end 464.6549 -162.792918)
		(width 0.17145)
		(layer "F.Cu")
		(net "SW_HDD_N22")
	)
	(segment
		(start 466.28812 -165.061138)
		(end 465.6709 -164.443918)
		(width 0.17145)
		(layer "F.Cu")
		(net "SW_HDD_N22")
	)
	(segment
		(start 464.7184 -164.443918)
		(end 464.7184 -162.856418)
		(width 0.17145)
		(layer "F.Cu")
		(net "SW_HDD_N22")
	)
	(segment
		(start 466.28812 -170.875198)
		(end 466.28812 -165.061138)
		(width 0.17145)
		(layer "F.Cu")
		(net "SW_HDD_N22")
	)
	(segment
		(start 465.3534 -171.809918)
		(end 466.28812 -170.875198)
		(width 0.17145)
		(layer "F.Cu")
		(net "SW_HDD_N22")
	)
	(via
		(at 465.6709 -164.443918)
		(size 0.6604)
		(drill 0.3302)
		(layers "F.Cu" "B.Cu")
		(net "SW_HDD_N22")
	)
	(segment
		(start 434.121052 -164.443918)
		(end 433.168552 -164.443918)
		(width 0.17145)
		(layer "F.Cu")
		(net "SW_HDD_N21")
	)
	(segment
		(start 433.803552 -172.851318)
		(end 433.803552 -171.809918)
		(width 0.17145)
		(layer "F.Cu")
		(net "SW_HDD_N21")
	)
	(segment
		(start 433.803552 -171.809918)
		(end 434.353462 -171.260008)
		(width 0.17145)
		(layer "F.Cu")
		(net "SW_HDD_N21")
	)
	(segment
		(start 433.168552 -164.443918)
		(end 433.168552 -162.856418)
		(width 0.17145)
		(layer "F.Cu")
		(net "SW_HDD_N21")
	)
	(segment
		(start 433.359052 -174.032418)
		(end 433.803552 -173.587918)
		(width 0.17145)
		(layer "F.Cu")
		(net "SW_HDD_N21")
	)
	(segment
		(start 433.168552 -162.856418)
		(end 433.105052 -162.792918)
		(width 0.17145)
		(layer "F.Cu")
		(net "SW_HDD_N21")
	)
	(segment
		(start 433.359052 -174.476918)
		(end 433.359052 -174.032418)
		(width 0.17145)
		(layer "F.Cu")
		(net "SW_HDD_N21")
	)
	(segment
		(start 433.803552 -173.587918)
		(end 433.803552 -172.851318)
		(width 0.17145)
		(layer "F.Cu")
		(net "SW_HDD_N21")
	)
	(segment
		(start 434.353462 -164.676328)
		(end 434.121052 -164.443918)
		(width 0.17145)
		(layer "F.Cu")
		(net "SW_HDD_N21")
	)
	(segment
		(start 434.353462 -171.260008)
		(end 434.353462 -164.676328)
		(width 0.17145)
		(layer "F.Cu")
		(net "SW_HDD_N21")
	)
	(via
		(at 434.121052 -164.443918)
		(size 0.6604)
		(drill 0.3302)
		(layers "F.Cu" "B.Cu")
		(net "SW_HDD_N21")
	)
	(segment
		(start 400.34845 -169.594784)
		(end 400.34845 -164.951918)
		(width 0.17145)
		(layer "F.Cu")
		(net "SW_HDD_N20")
	)
	(segment
		(start 402.25345 -171.499784)
		(end 401.059904 -170.306238)
		(width 0.17145)
		(layer "F.Cu")
		(net "SW_HDD_N20")
	)
	(segment
		(start 400.28495 -163.300918)
		(end 400.28495 -164.888418)
		(width 0.17145)
		(layer "F.Cu")
		(net "SW_HDD_N20")
	)
	(segment
		(start 400.28495 -164.888418)
		(end 400.34845 -164.951918)
		(width 0.17145)
		(layer "F.Cu")
		(net "SW_HDD_N20")
	)
	(segment
		(start 402.25345 -171.809918)
		(end 402.25345 -171.499784)
		(width 0.17145)
		(layer "F.Cu")
		(net "SW_HDD_N20")
	)
	(segment
		(start 401.80895 -174.476918)
		(end 401.80895 -174.032418)
		(width 0.17145)
		(layer "F.Cu")
		(net "SW_HDD_N20")
	)
	(segment
		(start 401.80895 -174.032418)
		(end 402.25345 -173.587918)
		(width 0.17145)
		(layer "F.Cu")
		(net "SW_HDD_N20")
	)
	(segment
		(start 401.059904 -170.306238)
		(end 400.34845 -169.594784)
		(width 0.17145)
		(layer "F.Cu")
		(net "SW_HDD_N20")
	)
	(segment
		(start 402.25345 -173.587918)
		(end 402.25345 -172.851318)
		(width 0.17145)
		(layer "F.Cu")
		(net "SW_HDD_N20")
	)
	(segment
		(start 402.25345 -172.851318)
		(end 402.25345 -171.809918)
		(width 0.17145)
		(layer "F.Cu")
		(net "SW_HDD_N20")
	)
	(via
		(at 401.059904 -170.306238)
		(size 0.6604)
		(drill 0.3302)
		(layers "F.Cu" "B.Cu")
		(net "SW_HDD_N20")
	)
	(segment
		(start 79.847948 -285.984442)
		(end 79.847948 -287.317942)
		(width 0.17145)
		(layer "F.Cu")
		(net "SW_HDD_N2")
	)
	(segment
		(start 79.974948 -277.792942)
		(end 79.809848 -277.627842)
		(width 0.17145)
		(layer "F.Cu")
		(net "SW_HDD_N2")
	)
	(segment
		(start 79.809848 -277.627842)
		(end 78.298548 -277.627842)
		(width 0.17145)
		(layer "F.Cu")
		(net "SW_HDD_N2")
	)
	(segment
		(start 78.387448 -284.523942)
		(end 79.847948 -285.984442)
		(width 0.17145)
		(layer "F.Cu")
		(net "SW_HDD_N2")
	)
	(segment
		(start 78.387448 -279.316942)
		(end 78.387448 -283.482542)
		(width 0.17145)
		(layer "F.Cu")
		(net "SW_HDD_N2")
	)
	(segment
		(start 78.387448 -278.3078)
		(end 78.387448 -279.316942)
		(width 0.17145)
		(layer "F.Cu")
		(net "SW_HDD_N2")
	)
	(segment
		(start 78.298548 -277.627842)
		(end 78.298548 -278.2189)
		(width 0.17145)
		(layer "F.Cu")
		(net "SW_HDD_N2")
	)
	(segment
		(start 78.298548 -278.2189)
		(end 78.387448 -278.3078)
		(width 0.17145)
		(layer "F.Cu")
		(net "SW_HDD_N2")
	)
	(segment
		(start 78.387448 -283.482542)
		(end 78.387448 -284.523942)
		(width 0.17145)
		(layer "F.Cu")
		(net "SW_HDD_N2")
	)
	(via
		(at 78.387448 -279.316942)
		(size 0.6604)
		(drill 0.3302)
		(layers "F.Cu" "B.Cu")
		(net "SW_HDD_N2")
	)
	(segment
		(start 370.259102 -174.032418)
		(end 370.703602 -173.587918)
		(width 0.17145)
		(layer "F.Cu")
		(net "SW_HDD_N19")
	)
	(segment
		(start 370.259102 -174.476918)
		(end 370.259102 -174.032418)
		(width 0.17145)
		(layer "F.Cu")
		(net "SW_HDD_N19")
	)
	(segment
		(start 371.402102 -171.111418)
		(end 371.402102 -164.824918)
		(width 0.17145)
		(layer "F.Cu")
		(net "SW_HDD_N19")
	)
	(segment
		(start 370.703602 -173.587918)
		(end 370.703602 -172.851318)
		(width 0.17145)
		(layer "F.Cu")
		(net "SW_HDD_N19")
	)
	(segment
		(start 370.703602 -172.851318)
		(end 370.703602 -171.809918)
		(width 0.17145)
		(layer "F.Cu")
		(net "SW_HDD_N19")
	)
	(segment
		(start 371.402102 -164.824918)
		(end 371.021102 -164.443918)
		(width 0.17145)
		(layer "F.Cu")
		(net "SW_HDD_N19")
	)
	(segment
		(start 370.068602 -162.856418)
		(end 370.005102 -162.792918)
		(width 0.17145)
		(layer "F.Cu")
		(net "SW_HDD_N19")
	)
	(segment
		(start 370.703602 -171.809918)
		(end 371.402102 -171.111418)
		(width 0.17145)
		(layer "F.Cu")
		(net "SW_HDD_N19")
	)
	(segment
		(start 371.021102 -164.443918)
		(end 370.068602 -164.443918)
		(width 0.17145)
		(layer "F.Cu")
		(net "SW_HDD_N19")
	)
	(segment
		(start 370.068602 -164.443918)
		(end 370.068602 -162.856418)
		(width 0.17145)
		(layer "F.Cu")
		(net "SW_HDD_N19")
	)
	(via
		(at 371.021102 -164.443918)
		(size 0.6604)
		(drill 0.3302)
		(layers "F.Cu" "B.Cu")
		(net "SW_HDD_N19")
	)
	(segment
		(start 339.852 -164.824918)
		(end 339.471 -164.443918)
		(width 0.17145)
		(layer "F.Cu")
		(net "SW_HDD_N18")
	)
	(segment
		(start 339.852 -171.111418)
		(end 339.852 -164.824918)
		(width 0.17145)
		(layer "F.Cu")
		(net "SW_HDD_N18")
	)
	(segment
		(start 338.5185 -164.443918)
		(end 338.5185 -162.856418)
		(width 0.17145)
		(layer "F.Cu")
		(net "SW_HDD_N18")
	)
	(segment
		(start 339.1535 -171.809918)
		(end 339.852 -171.111418)
		(width 0.17145)
		(layer "F.Cu")
		(net "SW_HDD_N18")
	)
	(segment
		(start 339.1535 -173.587918)
		(end 339.1535 -172.851318)
		(width 0.17145)
		(layer "F.Cu")
		(net "SW_HDD_N18")
	)
	(segment
		(start 338.709 -174.032418)
		(end 339.1535 -173.587918)
		(width 0.17145)
		(layer "F.Cu")
		(net "SW_HDD_N18")
	)
	(segment
		(start 338.5185 -162.856418)
		(end 338.455 -162.792918)
		(width 0.17145)
		(layer "F.Cu")
		(net "SW_HDD_N18")
	)
	(segment
		(start 339.471 -164.443918)
		(end 338.5185 -164.443918)
		(width 0.17145)
		(layer "F.Cu")
		(net "SW_HDD_N18")
	)
	(segment
		(start 338.709 -174.476918)
		(end 338.709 -174.032418)
		(width 0.17145)
		(layer "F.Cu")
		(net "SW_HDD_N18")
	)
	(segment
		(start 339.1535 -172.851318)
		(end 339.1535 -171.809918)
		(width 0.17145)
		(layer "F.Cu")
		(net "SW_HDD_N18")
	)
	(via
		(at 339.471 -164.443918)
		(size 0.6604)
		(drill 0.3302)
		(layers "F.Cu" "B.Cu")
		(net "SW_HDD_N18")
	)
	(segment
		(start 175.198532 -164.399976)
		(end 175.198532 -165.04666)
		(width 0.17145)
		(layer "F.Cu")
		(net "SW_HDD_N17")
	)
	(segment
		(start 175.198532 -165.42639)
		(end 175.198532 -165.04666)
		(width 0.17145)
		(layer "F.Cu")
		(net "SW_HDD_N17")
	)
	(segment
		(start 174.117 -162.602418)
		(end 174.117 -163.318444)
		(width 0.17145)
		(layer "F.Cu")
		(net "SW_HDD_N17")
	)
	(segment
		(start 173.1645 -170.158918)
		(end 173.1645 -169.117518)
		(width 0.17145)
		(layer "F.Cu")
		(net "SW_HDD_N17")
	)
	(segment
		(start 174.498 -170.966638)
		(end 173.69028 -170.158918)
		(width 0.17145)
		(layer "F.Cu")
		(net "SW_HDD_N17")
	)
	(segment
		(start 173.1645 -169.117518)
		(end 173.1645 -165.947344)
		(width 0.17145)
		(layer "F.Cu")
		(net "SW_HDD_N17")
	)
	(segment
		(start 173.69028 -170.158918)
		(end 173.1645 -170.158918)
		(width 0.17145)
		(layer "F.Cu")
		(net "SW_HDD_N17")
	)
	(segment
		(start 173.1645 -165.947344)
		(end 173.484286 -165.627558)
		(width 0.17145)
		(layer "F.Cu")
		(net "SW_HDD_N17")
	)
	(segment
		(start 173.484286 -165.627558)
		(end 174.997364 -165.627558)
		(width 0.17145)
		(layer "F.Cu")
		(net "SW_HDD_N17")
	)
	(segment
		(start 174.997364 -165.627558)
		(end 175.198532 -165.42639)
		(width 0.17145)
		(layer "F.Cu")
		(net "SW_HDD_N17")
	)
	(segment
		(start 174.117 -163.318444)
		(end 175.198532 -164.399976)
		(width 0.17145)
		(layer "F.Cu")
		(net "SW_HDD_N17")
	)
	(segment
		(start 174.117 -162.602418)
		(end 175.4759 -162.602418)
		(width 0.17145)
		(layer "F.Cu")
		(net "SW_HDD_N17")
	)
	(segment
		(start 174.498 -172.317918)
		(end 174.498 -170.966638)
		(width 0.17145)
		(layer "F.Cu")
		(net "SW_HDD_N17")
	)
	(segment
		(start 175.4759 -162.602418)
		(end 175.6664 -162.792918)
		(width 0.17145)
		(layer "F.Cu")
		(net "SW_HDD_N17")
	)
	(via
		(at 175.198532 -165.04666)
		(size 0.6604)
		(drill 0.3302)
		(layers "F.Cu" "B.Cu")
		(net "SW_HDD_N17")
	)
	(segment
		(start 141.487398 -168.507918)
		(end 141.487398 -169.523918)
		(width 0.17145)
		(layer "F.Cu")
		(net "SW_HDD_N16")
	)
	(segment
		(start 141.487398 -164.316918)
		(end 141.487398 -168.507918)
		(width 0.17145)
		(layer "F.Cu")
		(net "SW_HDD_N16")
	)
	(segment
		(start 142.947898 -170.984418)
		(end 142.947898 -172.317918)
		(width 0.17145)
		(layer "F.Cu")
		(net "SW_HDD_N16")
	)
	(segment
		(start 141.487398 -164.316918)
		(end 141.487398 -162.665918)
		(width 0.17145)
		(layer "F.Cu")
		(net "SW_HDD_N16")
	)
	(segment
		(start 141.487398 -169.523918)
		(end 142.947898 -170.984418)
		(width 0.17145)
		(layer "F.Cu")
		(net "SW_HDD_N16")
	)
	(segment
		(start 141.423898 -162.602418)
		(end 142.884398 -162.602418)
		(width 0.17145)
		(layer "F.Cu")
		(net "SW_HDD_N16")
	)
	(segment
		(start 142.884398 -162.602418)
		(end 143.074898 -162.792918)
		(width 0.17145)
		(layer "F.Cu")
		(net "SW_HDD_N16")
	)
	(segment
		(start 141.487398 -162.665918)
		(end 141.423898 -162.602418)
		(width 0.17145)
		(layer "F.Cu")
		(net "SW_HDD_N16")
	)
	(via
		(at 141.487398 -164.316918)
		(size 0.6604)
		(drill 0.3302)
		(layers "F.Cu" "B.Cu")
		(net "SW_HDD_N16")
	)
	(segment
		(start 109.937296 -164.316918)
		(end 109.937296 -168.482518)
		(width 0.17145)
		(layer "F.Cu")
		(net "SW_HDD_N15")
	)
	(segment
		(start 109.937296 -164.316918)
		(end 109.937296 -163.1442)
		(width 0.17145)
		(layer "F.Cu")
		(net "SW_HDD_N15")
	)
	(segment
		(start 111.397796 -170.984418)
		(end 111.397796 -172.317918)
		(width 0.17145)
		(layer "F.Cu")
		(net "SW_HDD_N15")
	)
	(segment
		(start 109.937296 -168.482518)
		(end 109.937296 -169.523918)
		(width 0.17145)
		(layer "F.Cu")
		(net "SW_HDD_N15")
	)
	(segment
		(start 109.937296 -163.1442)
		(end 109.873796 -163.0807)
		(width 0.17145)
		(layer "F.Cu")
		(net "SW_HDD_N15")
	)
	(segment
		(start 109.873796 -163.0807)
		(end 109.873796 -162.602418)
		(width 0.17145)
		(layer "F.Cu")
		(net "SW_HDD_N15")
	)
	(segment
		(start 109.873796 -162.602418)
		(end 110.710218 -162.602418)
		(width 0.17145)
		(layer "F.Cu")
		(net "SW_HDD_N15")
	)
	(segment
		(start 110.710218 -162.602418)
		(end 110.900718 -162.792918)
		(width 0.17145)
		(layer "F.Cu")
		(net "SW_HDD_N15")
	)
	(segment
		(start 110.900718 -162.792918)
		(end 111.524796 -162.792918)
		(width 0.17145)
		(layer "F.Cu")
		(net "SW_HDD_N15")
	)
	(segment
		(start 109.937296 -169.523918)
		(end 111.397796 -170.984418)
		(width 0.17145)
		(layer "F.Cu")
		(net "SW_HDD_N15")
	)
	(via
		(at 109.937296 -164.316918)
		(size 0.6604)
		(drill 0.3302)
		(layers "F.Cu" "B.Cu")
		(net "SW_HDD_N15")
	)
	(segment
		(start 79.315818 -162.627818)
		(end 78.298548 -162.627818)
		(width 0.17145)
		(layer "F.Cu")
		(net "SW_HDD_N14")
	)
	(segment
		(start 78.387448 -164.316918)
		(end 78.387448 -168.482518)
		(width 0.17145)
		(layer "F.Cu")
		(net "SW_HDD_N14")
	)
	(segment
		(start 79.974948 -162.792918)
		(end 79.480918 -162.792918)
		(width 0.17145)
		(layer "F.Cu")
		(net "SW_HDD_N14")
	)
	(segment
		(start 78.387448 -163.4236)
		(end 78.387448 -164.316918)
		(width 0.17145)
		(layer "F.Cu")
		(net "SW_HDD_N14")
	)
	(segment
		(start 78.387448 -168.482518)
		(end 78.387448 -169.523918)
		(width 0.17145)
		(layer "F.Cu")
		(net "SW_HDD_N14")
	)
	(segment
		(start 78.298548 -162.627818)
		(end 78.298548 -163.3347)
		(width 0.17145)
		(layer "F.Cu")
		(net "SW_HDD_N14")
	)
	(segment
		(start 79.847948 -170.984418)
		(end 79.847948 -172.317918)
		(width 0.17145)
		(layer "F.Cu")
		(net "SW_HDD_N14")
	)
	(segment
		(start 78.298548 -163.3347)
		(end 78.387448 -163.4236)
		(width 0.17145)
		(layer "F.Cu")
		(net "SW_HDD_N14")
	)
	(segment
		(start 79.480918 -162.792918)
		(end 79.315818 -162.627818)
		(width 0.17145)
		(layer "F.Cu")
		(net "SW_HDD_N14")
	)
	(segment
		(start 78.387448 -169.523918)
		(end 79.847948 -170.984418)
		(width 0.17145)
		(layer "F.Cu")
		(net "SW_HDD_N14")
	)
	(via
		(at 78.387448 -164.316918)
		(size 0.6604)
		(drill 0.3302)
		(layers "F.Cu" "B.Cu")
		(net "SW_HDD_N14")
	)
	(segment
		(start 49.275746 -159.935418)
		(end 47.916846 -159.935418)
		(width 0.17145)
		(layer "F.Cu")
		(net "SW_HDD_N13")
	)
	(segment
		(start 48.297846 -169.567606)
		(end 48.297846 -165.1)
		(width 0.17145)
		(layer "F.Cu")
		(net "SW_HDD_N13")
	)
	(segment
		(start 49.87544 -162.1536)
		(end 47.916846 -160.195006)
		(width 0.17145)
		(layer "F.Cu")
		(net "SW_HDD_N13")
	)
	(segment
		(start 48.297846 -172.317918)
		(end 48.297846 -170.609006)
		(width 0.17145)
		(layer "F.Cu")
		(net "SW_HDD_N13")
	)
	(segment
		(start 47.916846 -160.195006)
		(end 47.916846 -159.935418)
		(width 0.17145)
		(layer "F.Cu")
		(net "SW_HDD_N13")
	)
	(segment
		(start 49.87544 -163.522406)
		(end 49.87544 -162.1536)
		(width 0.17145)
		(layer "F.Cu")
		(net "SW_HDD_N13")
	)
	(segment
		(start 49.466246 -160.125918)
		(end 49.275746 -159.935418)
		(width 0.17145)
		(layer "F.Cu")
		(net "SW_HDD_N13")
	)
	(segment
		(start 48.297846 -170.609006)
		(end 48.297846 -169.567606)
		(width 0.17145)
		(layer "F.Cu")
		(net "SW_HDD_N13")
	)
	(segment
		(start 48.297846 -165.1)
		(end 49.87544 -163.522406)
		(width 0.17145)
		(layer "F.Cu")
		(net "SW_HDD_N13")
	)
	(via
		(at 49.87544 -162.1536)
		(size 0.6604)
		(drill 0.3302)
		(layers "F.Cu" "B.Cu")
		(net "SW_HDD_N13")
	)
	(segment
		(start 15.287498 -169.523918)
		(end 16.747998 -170.984418)
		(width 0.17145)
		(layer "F.Cu")
		(net "SW_HDD_N12")
	)
	(segment
		(start 15.287498 -164.316918)
		(end 15.287498 -162.665918)
		(width 0.17145)
		(layer "F.Cu")
		(net "SW_HDD_N12")
	)
	(segment
		(start 15.287498 -164.316918)
		(end 15.287498 -168.482518)
		(width 0.17145)
		(layer "F.Cu")
		(net "SW_HDD_N12")
	)
	(segment
		(start 15.287498 -162.665918)
		(end 15.223998 -162.602418)
		(width 0.17145)
		(layer "F.Cu")
		(net "SW_HDD_N12")
	)
	(segment
		(start 15.287498 -168.482518)
		(end 15.287498 -169.523918)
		(width 0.17145)
		(layer "F.Cu")
		(net "SW_HDD_N12")
	)
	(segment
		(start 15.223998 -162.602418)
		(end 16.684498 -162.602418)
		(width 0.17145)
		(layer "F.Cu")
		(net "SW_HDD_N12")
	)
	(segment
		(start 16.684498 -162.602418)
		(end 16.874998 -162.792918)
		(width 0.17145)
		(layer "F.Cu")
		(net "SW_HDD_N12")
	)
	(segment
		(start 16.747998 -170.984418)
		(end 16.747998 -172.317918)
		(width 0.17145)
		(layer "F.Cu")
		(net "SW_HDD_N12")
	)
	(via
		(at 15.287498 -164.316918)
		(size 0.6604)
		(drill 0.3302)
		(layers "F.Cu" "B.Cu")
		(net "SW_HDD_N12")
	)
	(segment
		(start 472.002358 -285.817056)
		(end 472.002358 -283.863542)
		(width 0.17145)
		(layer "F.Cu")
		(net "SW_HDD_N11")
	)
	(segment
		(start 470.635584 -277.978616)
		(end 470.635584 -277.472902)
		(width 0.17145)
		(layer "F.Cu")
		(net "SW_HDD_N11")
	)
	(segment
		(start 472.047824 -283.818076)
		(end 472.047824 -282.776676)
		(width 0.17145)
		(layer "F.Cu")
		(net "SW_HDD_N11")
	)
	(segment
		(start 470.343484 -278.270716)
		(end 470.635584 -277.978616)
		(width 0.17145)
		(layer "F.Cu")
		(net "SW_HDD_N11")
	)
	(segment
		(start 470.343484 -279.098502)
		(end 470.343484 -278.270716)
		(width 0.17145)
		(layer "F.Cu")
		(net "SW_HDD_N11")
	)
	(segment
		(start 470.403174 -281.132026)
		(end 470.403174 -280.317702)
		(width 0.17145)
		(layer "F.Cu")
		(net "SW_HDD_N11")
	)
	(segment
		(start 470.403174 -280.317702)
		(end 470.403174 -279.158192)
		(width 0.17145)
		(layer "F.Cu")
		(net "SW_HDD_N11")
	)
	(segment
		(start 472.002358 -283.863542)
		(end 472.047824 -283.818076)
		(width 0.17145)
		(layer "F.Cu")
		(net "SW_HDD_N11")
	)
	(segment
		(start 472.047824 -282.776676)
		(end 470.403174 -281.132026)
		(width 0.17145)
		(layer "F.Cu")
		(net "SW_HDD_N11")
	)
	(segment
		(start 470.403174 -279.158192)
		(end 470.343484 -279.098502)
		(width 0.17145)
		(layer "F.Cu")
		(net "SW_HDD_N11")
	)
	(via
		(at 470.403174 -280.317702)
		(size 0.6604)
		(drill 0.3302)
		(layers "F.Cu" "B.Cu")
		(net "SW_HDD_N11")
	)
	(segment
		(start 465.6709 -279.443942)
		(end 464.7184 -279.443942)
		(width 0.17145)
		(layer "F.Cu")
		(net "SW_HDD_N10")
	)
	(segment
		(start 465.2518 -286.759142)
		(end 465.2518 -287.825942)
		(width 0.17145)
		(layer "F.Cu")
		(net "SW_HDD_N10")
	)
	(segment
		(start 465.6709 -279.443942)
		(end 466.0519 -279.824942)
		(width 0.17145)
		(layer "F.Cu")
		(net "SW_HDD_N10")
	)
	(segment
		(start 465.59343 -286.417512)
		(end 465.2518 -286.759142)
		(width 0.17145)
		(layer "F.Cu")
		(net "SW_HDD_N10")
	)
	(segment
		(start 464.7184 -277.856442)
		(end 464.6549 -277.792942)
		(width 0.17145)
		(layer "F.Cu")
		(net "SW_HDD_N10")
	)
	(segment
		(start 466.0519 -281.3685)
		(end 465.59343 -281.82697)
		(width 0.17145)
		(layer "F.Cu")
		(net "SW_HDD_N10")
	)
	(segment
		(start 465.2518 -287.825942)
		(end 465.2518 -288.6202)
		(width 0.17145)
		(layer "F.Cu")
		(net "SW_HDD_N10")
	)
	(segment
		(start 465.59343 -281.82697)
		(end 465.59343 -286.417512)
		(width 0.17145)
		(layer "F.Cu")
		(net "SW_HDD_N10")
	)
	(segment
		(start 464.9089 -288.9631)
		(end 464.9089 -289.476942)
		(width 0.17145)
		(layer "F.Cu")
		(net "SW_HDD_N10")
	)
	(segment
		(start 465.2518 -288.6202)
		(end 464.9089 -288.9631)
		(width 0.17145)
		(layer "F.Cu")
		(net "SW_HDD_N10")
	)
	(segment
		(start 466.0519 -279.824942)
		(end 466.0519 -281.3685)
		(width 0.17145)
		(layer "F.Cu")
		(net "SW_HDD_N10")
	)
	(segment
		(start 464.7184 -279.443942)
		(end 464.7184 -277.856442)
		(width 0.17145)
		(layer "F.Cu")
		(net "SW_HDD_N10")
	)
	(via
		(at 465.6709 -279.443942)
		(size 0.6604)
		(drill 0.3302)
		(layers "F.Cu" "B.Cu")
		(net "SW_HDD_N10")
	)
	(segment
		(start 48.36414 -278.077676)
		(end 47.939452 -278.077676)
		(width 0.17145)
		(layer "F.Cu")
		(net "SW_HDD_N1")
	)
	(segment
		(start 48.297846 -287.317942)
		(end 48.310546 -287.305242)
		(width 0.17145)
		(layer "F.Cu")
		(net "SW_HDD_N1")
	)
	(segment
		(start 48.425354 -278.13889)
		(end 48.36414 -278.077676)
		(width 0.17145)
		(layer "F.Cu")
		(net "SW_HDD_N1")
	)
	(segment
		(start 47.939452 -278.077676)
		(end 46.860206 -279.156922)
		(width 0.17145)
		(layer "F.Cu")
		(net "SW_HDD_N1")
	)
	(segment
		(start 48.310546 -284.371542)
		(end 48.310546 -283.819346)
		(width 0.17145)
		(layer "F.Cu")
		(net "SW_HDD_N1")
	)
	(segment
		(start 46.683422 -280.460958)
		(end 46.683422 -279.333706)
		(width 0.17145)
		(layer "F.Cu")
		(net "SW_HDD_N1")
	)
	(segment
		(start 47.625 -283.6164)
		(end 46.683422 -282.674822)
		(width 0.17145)
		(layer "F.Cu")
		(net "SW_HDD_N1")
	)
	(segment
		(start 46.683422 -282.674822)
		(end 46.683422 -280.460958)
		(width 0.17145)
		(layer "F.Cu")
		(net "SW_HDD_N1")
	)
	(segment
		(start 48.310546 -283.819346)
		(end 48.1076 -283.6164)
		(width 0.17145)
		(layer "F.Cu")
		(net "SW_HDD_N1")
	)
	(segment
		(start 48.310546 -285.412942)
		(end 48.310546 -284.371542)
		(width 0.17145)
		(layer "F.Cu")
		(net "SW_HDD_N1")
	)
	(segment
		(start 46.683422 -279.333706)
		(end 46.860206 -279.156922)
		(width 0.17145)
		(layer "F.Cu")
		(net "SW_HDD_N1")
	)
	(segment
		(start 48.310546 -287.305242)
		(end 48.310546 -285.412942)
		(width 0.17145)
		(layer "F.Cu")
		(net "SW_HDD_N1")
	)
	(segment
		(start 48.1076 -283.6164)
		(end 47.625 -283.6164)
		(width 0.17145)
		(layer "F.Cu")
		(net "SW_HDD_N1")
	)
	(via
		(at 46.683422 -280.460958)
		(size 0.6604)
		(drill 0.3302)
		(layers "F.Cu" "B.Cu")
		(net "SW_HDD_N1")
	)
	(segment
		(start 427.694852 -275.252942)
		(end 429.168052 -275.252942)
		(width 0.17145)
		(layer "F.Cu")
		(net "SW_HDD_G9")
	)
	(segment
		(start 430.349152 -275.252942)
		(end 429.168052 -275.252942)
		(width 0.17145)
		(layer "F.Cu")
		(net "SW_HDD_G9")
	)
	(segment
		(start 430.387252 -275.291042)
		(end 430.349152 -275.252942)
		(width 0.17145)
		(layer "F.Cu")
		(net "SW_HDD_G9")
	)
	(via
		(at 429.168052 -275.252942)
		(size 0.6604)
		(drill 0.3302)
		(layers "F.Cu" "B.Cu")
		(net "SW_HDD_G9")
	)
	(segment
		(start 396.14475 -275.252942)
		(end 397.61795 -275.252942)
		(width 0.17145)
		(layer "F.Cu")
		(net "SW_HDD_G8")
	)
	(segment
		(start 398.82445 -275.252942)
		(end 397.61795 -275.252942)
		(width 0.17145)
		(layer "F.Cu")
		(net "SW_HDD_G8")
	)
	(segment
		(start 398.88795 -275.316442)
		(end 398.82445 -275.252942)
		(width 0.17145)
		(layer "F.Cu")
		(net "SW_HDD_G8")
	)
	(via
		(at 397.61795 -275.252942)
		(size 0.6604)
		(drill 0.3302)
		(layers "F.Cu" "B.Cu")
		(net "SW_HDD_G8")
	)
	(segment
		(start 367.287302 -275.291042)
		(end 367.249202 -275.252942)
		(width 0.17145)
		(layer "F.Cu")
		(net "SW_HDD_G7")
	)
	(segment
		(start 364.594902 -275.252942)
		(end 366.068102 -275.252942)
		(width 0.17145)
		(layer "F.Cu")
		(net "SW_HDD_G7")
	)
	(segment
		(start 367.249202 -275.252942)
		(end 366.068102 -275.252942)
		(width 0.17145)
		(layer "F.Cu")
		(net "SW_HDD_G7")
	)
	(via
		(at 366.068102 -275.252942)
		(size 0.6604)
		(drill 0.3302)
		(layers "F.Cu" "B.Cu")
		(net "SW_HDD_G7")
	)
	(segment
		(start 335.788 -275.291042)
		(end 335.7499 -275.252942)
		(width 0.17145)
		(layer "F.Cu")
		(net "SW_HDD_G6")
	)
	(segment
		(start 333.0448 -275.252942)
		(end 334.518 -275.252942)
		(width 0.17145)
		(layer "F.Cu")
		(net "SW_HDD_G6")
	)
	(segment
		(start 335.7499 -275.252942)
		(end 334.518 -275.252942)
		(width 0.17145)
		(layer "F.Cu")
		(net "SW_HDD_G6")
	)
	(via
		(at 334.518 -275.252942)
		(size 0.6604)
		(drill 0.3302)
		(layers "F.Cu" "B.Cu")
		(net "SW_HDD_G6")
	)
	(segment
		(start 178.181 -276.891242)
		(end 177.3682 -276.078442)
		(width 0.17145)
		(layer "F.Cu")
		(net "SW_HDD_G5")
	)
	(segment
		(start 176.2506 -276.078442)
		(end 177.3682 -276.078442)
		(width 0.17145)
		(layer "F.Cu")
		(net "SW_HDD_G5")
	)
	(segment
		(start 178.181 -277.615142)
		(end 178.181 -276.891242)
		(width 0.17145)
		(layer "F.Cu")
		(net "SW_HDD_G5")
	)
	(via
		(at 177.3682 -276.078442)
		(size 0.6604)
		(drill 0.3302)
		(layers "F.Cu" "B.Cu")
		(net "SW_HDD_G5")
	)
	(segment
		(start 146.630898 -277.615142)
		(end 146.630898 -276.891242)
		(width 0.17145)
		(layer "F.Cu")
		(net "SW_HDD_G4")
	)
	(segment
		(start 146.630898 -276.891242)
		(end 145.818098 -276.078442)
		(width 0.17145)
		(layer "F.Cu")
		(net "SW_HDD_G4")
	)
	(segment
		(start 145.818098 -276.078442)
		(end 144.700498 -276.078442)
		(width 0.17145)
		(layer "F.Cu")
		(net "SW_HDD_G4")
	)
	(via
		(at 145.818098 -276.078442)
		(size 0.6604)
		(drill 0.3302)
		(layers "F.Cu" "B.Cu")
		(net "SW_HDD_G4")
	)
	(segment
		(start 468.774018 -44.92625)
		(end 468.799418 -44.90085)
		(width 0.17145)
		(layer "F.Cu")
		(net "SW_HDD_G35")
	)
	(segment
		(start 470.336118 -44.08805)
		(end 469.612218 -44.08805)
		(width 0.17145)
		(layer "F.Cu")
		(net "SW_HDD_G35")
	)
	(segment
		(start 469.612218 -44.08805)
		(end 468.799418 -44.90085)
		(width 0.17145)
		(layer "F.Cu")
		(net "SW_HDD_G35")
	)
	(segment
		(start 468.774018 -46.01845)
		(end 468.774018 -44.92625)
		(width 0.17145)
		(layer "F.Cu")
		(net "SW_HDD_G35")
	)
	(via
		(at 468.799418 -44.90085)
		(size 0.6604)
		(drill 0.3302)
		(layers "F.Cu" "B.Cu")
		(net "SW_HDD_G35")
	)
	(segment
		(start 461.9371 -45.290994)
		(end 461.899 -45.252894)
		(width 0.17145)
		(layer "F.Cu")
		(net "SW_HDD_G34")
	)
	(segment
		(start 459.2447 -45.252894)
		(end 460.7179 -45.252894)
		(width 0.17145)
		(layer "F.Cu")
		(net "SW_HDD_G34")
	)
	(segment
		(start 461.899 -45.252894)
		(end 460.7179 -45.252894)
		(width 0.17145)
		(layer "F.Cu")
		(net "SW_HDD_G34")
	)
	(via
		(at 460.7179 -45.252894)
		(size 0.6604)
		(drill 0.3302)
		(layers "F.Cu" "B.Cu")
		(net "SW_HDD_G34")
	)
	(segment
		(start 430.387252 -45.290994)
		(end 430.349152 -45.252894)
		(width 0.17145)
		(layer "F.Cu")
		(net "SW_HDD_G33")
	)
	(segment
		(start 430.349152 -45.252894)
		(end 429.168052 -45.252894)
		(width 0.17145)
		(layer "F.Cu")
		(net "SW_HDD_G33")
	)
	(segment
		(start 427.694852 -45.252894)
		(end 429.168052 -45.252894)
		(width 0.17145)
		(layer "F.Cu")
		(net "SW_HDD_G33")
	)
	(via
		(at 429.168052 -45.252894)
		(size 0.6604)
		(drill 0.3302)
		(layers "F.Cu" "B.Cu")
		(net "SW_HDD_G33")
	)
	(segment
		(start 398.81175 -45.290994)
		(end 398.77365 -45.252894)
		(width 0.17145)
		(layer "F.Cu")
		(net "SW_HDD_G32")
	)
	(segment
		(start 398.77365 -45.252894)
		(end 397.61795 -45.252894)
		(width 0.17145)
		(layer "F.Cu")
		(net "SW_HDD_G32")
	)
	(segment
		(start 396.14475 -45.252894)
		(end 397.61795 -45.252894)
		(width 0.17145)
		(layer "F.Cu")
		(net "SW_HDD_G32")
	)
	(via
		(at 397.61795 -45.252894)
		(size 0.6604)
		(drill 0.3302)
		(layers "F.Cu" "B.Cu")
		(net "SW_HDD_G32")
	)
	(segment
		(start 367.287302 -45.290994)
		(end 367.249202 -45.252894)
		(width 0.17145)
		(layer "F.Cu")
		(net "SW_HDD_G31")
	)
	(segment
		(start 367.249202 -45.252894)
		(end 366.068102 -45.252894)
		(width 0.17145)
		(layer "F.Cu")
		(net "SW_HDD_G31")
	)
	(segment
		(start 364.594902 -45.252894)
		(end 366.068102 -45.252894)
		(width 0.17145)
		(layer "F.Cu")
		(net "SW_HDD_G31")
	)
	(via
		(at 366.068102 -45.252894)
		(size 0.6604)
		(drill 0.3302)
		(layers "F.Cu" "B.Cu")
		(net "SW_HDD_G31")
	)
	(segment
		(start 335.7626 -45.290994)
		(end 335.7245 -45.252894)
		(width 0.17145)
		(layer "F.Cu")
		(net "SW_HDD_G30")
	)
	(segment
		(start 333.0448 -45.252894)
		(end 334.518 -45.252894)
		(width 0.17145)
		(layer "F.Cu")
		(net "SW_HDD_G30")
	)
	(segment
		(start 335.7245 -45.252894)
		(end 334.518 -45.252894)
		(width 0.17145)
		(layer "F.Cu")
		(net "SW_HDD_G30")
	)
	(via
		(at 334.518 -45.252894)
		(size 0.6604)
		(drill 0.3302)
		(layers "F.Cu" "B.Cu")
		(net "SW_HDD_G30")
	)
	(segment
		(start 113.645442 -276.079204)
		(end 113.645442 -277.196804)
		(width 0.17145)
		(layer "F.Cu")
		(net "SW_HDD_G3")
	)
	(segment
		(start 115.182142 -275.291804)
		(end 114.432842 -275.291804)
		(width 0.17145)
		(layer "F.Cu")
		(net "SW_HDD_G3")
	)
	(segment
		(start 114.432842 -275.291804)
		(end 113.645442 -276.079204)
		(width 0.17145)
		(layer "F.Cu")
		(net "SW_HDD_G3")
	)
	(via
		(at 113.645442 -276.079204)
		(size 0.6604)
		(drill 0.3302)
		(layers "F.Cu" "B.Cu")
		(net "SW_HDD_G3")
	)
	(segment
		(start 178.181 -46.891194)
		(end 178.181 -47.615094)
		(width 0.17145)
		(layer "F.Cu")
		(net "SW_HDD_G29")
	)
	(segment
		(start 176.2506 -46.078394)
		(end 177.3682 -46.078394)
		(width 0.17145)
		(layer "F.Cu")
		(net "SW_HDD_G29")
	)
	(segment
		(start 177.3682 -46.078394)
		(end 178.181 -46.891194)
		(width 0.17145)
		(layer "F.Cu")
		(net "SW_HDD_G29")
	)
	(via
		(at 177.3682 -46.078394)
		(size 0.6604)
		(drill 0.3302)
		(layers "F.Cu" "B.Cu")
		(net "SW_HDD_G29")
	)
	(segment
		(start 145.818098 -46.078394)
		(end 146.630898 -46.891194)
		(width 0.17145)
		(layer "F.Cu")
		(net "SW_HDD_G28")
	)
	(segment
		(start 146.630898 -46.891194)
		(end 146.630898 -47.615094)
		(width 0.17145)
		(layer "F.Cu")
		(net "SW_HDD_G28")
	)
	(segment
		(start 144.700498 -46.078394)
		(end 145.818098 -46.078394)
		(width 0.17145)
		(layer "F.Cu")
		(net "SW_HDD_G28")
	)
	(via
		(at 145.818098 -46.078394)
		(size 0.6604)
		(drill 0.3302)
		(layers "F.Cu" "B.Cu")
		(net "SW_HDD_G28")
	)
	(segment
		(start 113.150396 -46.078394)
		(end 114.267996 -46.078394)
		(width 0.17145)
		(layer "F.Cu")
		(net "SW_HDD_G27")
	)
	(segment
		(start 114.267996 -46.078394)
		(end 115.080796 -46.891194)
		(width 0.17145)
		(layer "F.Cu")
		(net "SW_HDD_G27")
	)
	(segment
		(start 115.080796 -46.891194)
		(end 115.080796 -47.615094)
		(width 0.17145)
		(layer "F.Cu")
		(net "SW_HDD_G27")
	)
	(via
		(at 114.267996 -46.078394)
		(size 0.6604)
		(drill 0.3302)
		(layers "F.Cu" "B.Cu")
		(net "SW_HDD_G27")
	)
	(segment
		(start 83.530948 -46.891194)
		(end 83.530948 -47.615094)
		(width 0.17145)
		(layer "F.Cu")
		(net "SW_HDD_G26")
	)
	(segment
		(start 82.718148 -46.078394)
		(end 83.530948 -46.891194)
		(width 0.17145)
		(layer "F.Cu")
		(net "SW_HDD_G26")
	)
	(segment
		(start 81.625948 -46.078394)
		(end 82.718148 -46.078394)
		(width 0.17145)
		(layer "F.Cu")
		(net "SW_HDD_G26")
	)
	(via
		(at 82.718148 -46.078394)
		(size 0.6604)
		(drill 0.3302)
		(layers "F.Cu" "B.Cu")
		(net "SW_HDD_G26")
	)
	(segment
		(start 51.980846 -46.891194)
		(end 51.980846 -47.615094)
		(width 0.17145)
		(layer "F.Cu")
		(net "SW_HDD_G25")
	)
	(segment
		(start 51.168046 -46.078394)
		(end 51.980846 -46.891194)
		(width 0.17145)
		(layer "F.Cu")
		(net "SW_HDD_G25")
	)
	(segment
		(start 50.050446 -46.078394)
		(end 51.168046 -46.078394)
		(width 0.17145)
		(layer "F.Cu")
		(net "SW_HDD_G25")
	)
	(via
		(at 51.168046 -46.078394)
		(size 0.6604)
		(drill 0.3302)
		(layers "F.Cu" "B.Cu")
		(net "SW_HDD_G25")
	)
	(segment
		(start 20.430998 -47.615094)
		(end 20.430998 -46.891194)
		(width 0.17145)
		(layer "F.Cu")
		(net "SW_HDD_G24")
	)
	(segment
		(start 20.430998 -46.891194)
		(end 19.618198 -46.078394)
		(width 0.17145)
		(layer "F.Cu")
		(net "SW_HDD_G24")
	)
	(segment
		(start 19.618198 -46.078394)
		(end 18.500598 -46.078394)
		(width 0.17145)
		(layer "F.Cu")
		(net "SW_HDD_G24")
	)
	(via
		(at 19.618198 -46.078394)
		(size 0.6604)
		(drill 0.3302)
		(layers "F.Cu" "B.Cu")
		(net "SW_HDD_G24")
	)
	(segment
		(start 470.336118 -159.088074)
		(end 469.612218 -159.088074)
		(width 0.17145)
		(layer "F.Cu")
		(net "SW_HDD_G23")
	)
	(segment
		(start 469.612218 -159.088074)
		(end 468.799418 -159.900874)
		(width 0.17145)
		(layer "F.Cu")
		(net "SW_HDD_G23")
	)
	(segment
		(start 468.799418 -159.900874)
		(end 468.799418 -161.018474)
		(width 0.17145)
		(layer "F.Cu")
		(net "SW_HDD_G23")
	)
	(via
		(at 468.799418 -159.900874)
		(size 0.6604)
		(drill 0.3302)
		(layers "F.Cu" "B.Cu")
		(net "SW_HDD_G23")
	)
	(segment
		(start 461.899 -160.252918)
		(end 460.7179 -160.252918)
		(width 0.17145)
		(layer "F.Cu")
		(net "SW_HDD_G22")
	)
	(segment
		(start 459.2447 -160.252918)
		(end 460.7179 -160.252918)
		(width 0.17145)
		(layer "F.Cu")
		(net "SW_HDD_G22")
	)
	(segment
		(start 461.9371 -160.291018)
		(end 461.899 -160.252918)
		(width 0.17145)
		(layer "F.Cu")
		(net "SW_HDD_G22")
	)
	(via
		(at 460.7179 -160.252918)
		(size 0.6604)
		(drill 0.3302)
		(layers "F.Cu" "B.Cu")
		(net "SW_HDD_G22")
	)
	(segment
		(start 430.387252 -160.291018)
		(end 430.349152 -160.252918)
		(width 0.17145)
		(layer "F.Cu")
		(net "SW_HDD_G21")
	)
	(segment
		(start 427.694852 -160.252918)
		(end 429.168052 -160.252918)
		(width 0.17145)
		(layer "F.Cu")
		(net "SW_HDD_G21")
	)
	(segment
		(start 430.349152 -160.252918)
		(end 429.168052 -160.252918)
		(width 0.17145)
		(layer "F.Cu")
		(net "SW_HDD_G21")
	)
	(via
		(at 429.168052 -160.252918)
		(size 0.6604)
		(drill 0.3302)
		(layers "F.Cu" "B.Cu")
		(net "SW_HDD_G21")
	)
	(segment
		(start 398.83715 -160.291018)
		(end 398.79905 -160.252918)
		(width 0.17145)
		(layer "F.Cu")
		(net "SW_HDD_G20")
	)
	(segment
		(start 396.14475 -160.252918)
		(end 397.61795 -160.252918)
		(width 0.17145)
		(layer "F.Cu")
		(net "SW_HDD_G20")
	)
	(segment
		(start 398.79905 -160.252918)
		(end 397.61795 -160.252918)
		(width 0.17145)
		(layer "F.Cu")
		(net "SW_HDD_G20")
	)
	(via
		(at 397.61795 -160.252918)
		(size 0.6604)
		(drill 0.3302)
		(layers "F.Cu" "B.Cu")
		(net "SW_HDD_G20")
	)
	(segment
		(start 83.530948 -276.891242)
		(end 82.718148 -276.078442)
		(width 0.17145)
		(layer "F.Cu")
		(net "SW_HDD_G2")
	)
	(segment
		(start 83.530948 -277.615142)
		(end 83.530948 -276.891242)
		(width 0.17145)
		(layer "F.Cu")
		(net "SW_HDD_G2")
	)
	(segment
		(start 82.718148 -276.078442)
		(end 81.600548 -276.078442)
		(width 0.17145)
		(layer "F.Cu")
		(net "SW_HDD_G2")
	)
	(via
		(at 82.718148 -276.078442)
		(size 0.6604)
		(drill 0.3302)
		(layers "F.Cu" "B.Cu")
		(net "SW_HDD_G2")
	)
	(segment
		(start 367.287302 -160.291018)
		(end 367.249202 -160.252918)
		(width 0.17145)
		(layer "F.Cu")
		(net "SW_HDD_G19")
	)
	(segment
		(start 367.249202 -160.252918)
		(end 366.068102 -160.252918)
		(width 0.17145)
		(layer "F.Cu")
		(net "SW_HDD_G19")
	)
	(segment
		(start 364.594902 -160.252918)
		(end 366.068102 -160.252918)
		(width 0.17145)
		(layer "F.Cu")
		(net "SW_HDD_G19")
	)
	(via
		(at 366.068102 -160.252918)
		(size 0.6604)
		(drill 0.3302)
		(layers "F.Cu" "B.Cu")
		(net "SW_HDD_G19")
	)
	(segment
		(start 333.0448 -160.252918)
		(end 334.518 -160.252918)
		(width 0.17145)
		(layer "F.Cu")
		(net "SW_HDD_G18")
	)
	(segment
		(start 335.788 -160.291018)
		(end 335.7499 -160.252918)
		(width 0.17145)
		(layer "F.Cu")
		(net "SW_HDD_G18")
	)
	(segment
		(start 335.7499 -160.252918)
		(end 334.518 -160.252918)
		(width 0.17145)
		(layer "F.Cu")
		(net "SW_HDD_G18")
	)
	(via
		(at 334.518 -160.252918)
		(size 0.6604)
		(drill 0.3302)
		(layers "F.Cu" "B.Cu")
		(net "SW_HDD_G18")
	)
	(segment
		(start 177.267362 -161.264854)
		(end 177.55235 -161.549842)
		(width 0.17145)
		(layer "F.Cu")
		(net "SW_HDD_G17")
	)
	(segment
		(start 177.267362 -160.272984)
		(end 177.267362 -161.264854)
		(width 0.17145)
		(layer "F.Cu")
		(net "SW_HDD_G17")
	)
	(segment
		(start 178.2318 -162.229292)
		(end 177.55235 -161.549842)
		(width 0.17145)
		(layer "F.Cu")
		(net "SW_HDD_G17")
	)
	(segment
		(start 178.2318 -162.996118)
		(end 178.2318 -162.229292)
		(width 0.17145)
		(layer "F.Cu")
		(net "SW_HDD_G17")
	)
	(via
		(at 177.55235 -161.549842)
		(size 0.6604)
		(drill 0.3302)
		(layers "F.Cu" "B.Cu")
		(net "SW_HDD_G17")
	)
	(segment
		(start 146.630898 -162.615118)
		(end 146.630898 -161.891218)
		(width 0.17145)
		(layer "F.Cu")
		(net "SW_HDD_G16")
	)
	(segment
		(start 145.818098 -161.078418)
		(end 144.700498 -161.078418)
		(width 0.17145)
		(layer "F.Cu")
		(net "SW_HDD_G16")
	)
	(segment
		(start 146.630898 -161.891218)
		(end 145.818098 -161.078418)
		(width 0.17145)
		(layer "F.Cu")
		(net "SW_HDD_G16")
	)
	(via
		(at 145.818098 -161.078418)
		(size 0.6604)
		(drill 0.3302)
		(layers "F.Cu" "B.Cu")
		(net "SW_HDD_G16")
	)
	(segment
		(start 114.267996 -161.078418)
		(end 113.150396 -161.078418)
		(width 0.17145)
		(layer "F.Cu")
		(net "SW_HDD_G15")
	)
	(segment
		(start 115.080796 -162.615118)
		(end 115.080796 -161.891218)
		(width 0.17145)
		(layer "F.Cu")
		(net "SW_HDD_G15")
	)
	(segment
		(start 115.080796 -161.891218)
		(end 114.267996 -161.078418)
		(width 0.17145)
		(layer "F.Cu")
		(net "SW_HDD_G15")
	)
	(via
		(at 114.267996 -161.078418)
		(size 0.6604)
		(drill 0.3302)
		(layers "F.Cu" "B.Cu")
		(net "SW_HDD_G15")
	)
	(segment
		(start 83.530948 -161.891218)
		(end 82.718148 -161.078418)
		(width 0.17145)
		(layer "F.Cu")
		(net "SW_HDD_G14")
	)
	(segment
		(start 83.530948 -162.615118)
		(end 83.530948 -161.891218)
		(width 0.17145)
		(layer "F.Cu")
		(net "SW_HDD_G14")
	)
	(segment
		(start 82.718148 -161.078418)
		(end 81.600548 -161.078418)
		(width 0.17145)
		(layer "F.Cu")
		(net "SW_HDD_G14")
	)
	(via
		(at 82.718148 -161.078418)
		(size 0.6604)
		(drill 0.3302)
		(layers "F.Cu" "B.Cu")
		(net "SW_HDD_G14")
	)
	(segment
		(start 51.067208 -158.597854)
		(end 51.352196 -158.882842)
		(width 0.17145)
		(layer "F.Cu")
		(net "SW_HDD_G13")
	)
	(segment
		(start 52.031646 -159.562292)
		(end 51.352196 -158.882842)
		(width 0.17145)
		(layer "F.Cu")
		(net "SW_HDD_G13")
	)
	(segment
		(start 51.067208 -157.605984)
		(end 51.067208 -158.597854)
		(width 0.17145)
		(layer "F.Cu")
		(net "SW_HDD_G13")
	)
	(segment
		(start 52.031646 -160.329118)
		(end 52.031646 -159.562292)
		(width 0.17145)
		(layer "F.Cu")
		(net "SW_HDD_G13")
	)
	(via
		(at 51.352196 -158.882842)
		(size 0.6604)
		(drill 0.3302)
		(layers "F.Cu" "B.Cu")
		(net "SW_HDD_G13")
	)
	(segment
		(start 20.430998 -162.615118)
		(end 20.430998 -161.891218)
		(width 0.17145)
		(layer "F.Cu")
		(net "SW_HDD_G12")
	)
	(segment
		(start 19.618198 -161.078418)
		(end 18.500598 -161.078418)
		(width 0.17145)
		(layer "F.Cu")
		(net "SW_HDD_G12")
	)
	(segment
		(start 20.430998 -161.891218)
		(end 19.618198 -161.078418)
		(width 0.17145)
		(layer "F.Cu")
		(net "SW_HDD_G12")
	)
	(via
		(at 19.618198 -161.078418)
		(size 0.6604)
		(drill 0.3302)
		(layers "F.Cu" "B.Cu")
		(net "SW_HDD_G12")
	)
	(segment
		(start 466.870796 -276.59203)
		(end 471.03157 -276.59203)
		(width 0.17145)
		(layer "F.Cu")
		(net "SW_HDD_G11")
	)
	(segment
		(start 472.467432 -274.193)
		(end 472.076272 -274.58416)
		(width 0.17145)
		(layer "F.Cu")
		(net "SW_HDD_G11")
	)
	(segment
		(start 473.36202 -274.193)
		(end 472.467432 -274.193)
		(width 0.17145)
		(layer "F.Cu")
		(net "SW_HDD_G11")
	)
	(segment
		(start 472.076272 -275.547328)
		(end 471.7034 -275.9202)
		(width 0.17145)
		(layer "F.Cu")
		(net "SW_HDD_G11")
	)
	(segment
		(start 472.076272 -274.58416)
		(end 472.076272 -275.547328)
		(width 0.17145)
		(layer "F.Cu")
		(net "SW_HDD_G11")
	)
	(segment
		(start 471.03157 -276.59203)
		(end 471.7034 -275.9202)
		(width 0.17145)
		(layer "F.Cu")
		(net "SW_HDD_G11")
	)
	(via
		(at 471.7034 -275.9202)
		(size 0.6604)
		(drill 0.3302)
		(layers "F.Cu" "B.Cu")
		(net "SW_HDD_G11")
	)
	(segment
		(start 461.899 -275.252942)
		(end 460.7179 -275.252942)
		(width 0.17145)
		(layer "F.Cu")
		(net "SW_HDD_G10")
	)
	(segment
		(start 459.2447 -275.252942)
		(end 460.7179 -275.252942)
		(width 0.17145)
		(layer "F.Cu")
		(net "SW_HDD_G10")
	)
	(segment
		(start 461.9371 -275.291042)
		(end 461.899 -275.252942)
		(width 0.17145)
		(layer "F.Cu")
		(net "SW_HDD_G10")
	)
	(via
		(at 460.7179 -275.252942)
		(size 0.6604)
		(drill 0.3302)
		(layers "F.Cu" "B.Cu")
		(net "SW_HDD_G10")
	)
	(segment
		(start 51.168046 -276.078442)
		(end 50.152046 -276.078442)
		(width 0.17145)
		(layer "F.Cu")
		(net "SW_HDD_G1")
	)
	(segment
		(start 51.980846 -277.615142)
		(end 51.980846 -276.891242)
		(width 0.17145)
		(layer "F.Cu")
		(net "SW_HDD_G1")
	)
	(segment
		(start 51.980846 -276.891242)
		(end 51.168046 -276.078442)
		(width 0.17145)
		(layer "F.Cu")
		(net "SW_HDD_G1")
	)
	(via
		(at 51.168046 -276.078442)
		(size 0.6604)
		(drill 0.3302)
		(layers "F.Cu" "B.Cu")
		(net "SW_HDD_G1")
	)
	(segment
		(start 420.436548 -273.793966)
		(end 420.563548 -273.666966)
		(width 0.127)
		(layer "F.Cu")
		(net "SAS_HDD_RX_P9")
	)
	(segment
		(start 420.690548 -273.305016)
		(end 422.025064 -273.305016)
		(width 0.127)
		(layer "F.Cu")
		(net "SAS_HDD_RX_P9")
	)
	(segment
		(start 417.12388 -273.660616)
		(end 417.25723 -273.793966)
		(width 0.127)
		(layer "F.Cu")
		(net "SAS_HDD_RX_P9")
	)
	(segment
		(start 420.563548 -273.666966)
		(end 420.563548 -273.432016)
		(width 0.127)
		(layer "F.Cu")
		(net "SAS_HDD_RX_P9")
	)
	(segment
		(start 416.564064 -273.660616)
		(end 417.12388 -273.660616)
		(width 0.127)
		(layer "F.Cu")
		(net "SAS_HDD_RX_P9")
	)
	(segment
		(start 417.25723 -273.793966)
		(end 420.436548 -273.793966)
		(width 0.127)
		(layer "F.Cu")
		(net "SAS_HDD_RX_P9")
	)
	(segment
		(start 420.563548 -273.432016)
		(end 420.690548 -273.305016)
		(width 0.127)
		(layer "F.Cu")
		(net "SAS_HDD_RX_P9")
	)
	(segment
		(start 389.013446 -273.432016)
		(end 389.140446 -273.305016)
		(width 0.127)
		(layer "F.Cu")
		(net "SAS_HDD_RX_P8")
	)
	(segment
		(start 385.497578 -273.660616)
		(end 385.630928 -273.793966)
		(width 0.127)
		(layer "F.Cu")
		(net "SAS_HDD_RX_P8")
	)
	(segment
		(start 385.630928 -273.793966)
		(end 388.886446 -273.793966)
		(width 0.127)
		(layer "F.Cu")
		(net "SAS_HDD_RX_P8")
	)
	(segment
		(start 389.013446 -273.666966)
		(end 389.013446 -273.432016)
		(width 0.127)
		(layer "F.Cu")
		(net "SAS_HDD_RX_P8")
	)
	(segment
		(start 385.013962 -273.660616)
		(end 385.497578 -273.660616)
		(width 0.127)
		(layer "F.Cu")
		(net "SAS_HDD_RX_P8")
	)
	(segment
		(start 388.886446 -273.793966)
		(end 389.013446 -273.666966)
		(width 0.127)
		(layer "F.Cu")
		(net "SAS_HDD_RX_P8")
	)
	(segment
		(start 389.140446 -273.305016)
		(end 390.474962 -273.305016)
		(width 0.127)
		(layer "F.Cu")
		(net "SAS_HDD_RX_P8")
	)
	(segment
		(start 353.464114 -273.660616)
		(end 354.02393 -273.660616)
		(width 0.127)
		(layer "F.Cu")
		(net "SAS_HDD_RX_P7")
	)
	(segment
		(start 354.15728 -273.793966)
		(end 357.336598 -273.793966)
		(width 0.127)
		(layer "F.Cu")
		(net "SAS_HDD_RX_P7")
	)
	(segment
		(start 357.463598 -273.666966)
		(end 357.463598 -273.432016)
		(width 0.127)
		(layer "F.Cu")
		(net "SAS_HDD_RX_P7")
	)
	(segment
		(start 354.02393 -273.660616)
		(end 354.15728 -273.793966)
		(width 0.127)
		(layer "F.Cu")
		(net "SAS_HDD_RX_P7")
	)
	(segment
		(start 357.336598 -273.793966)
		(end 357.463598 -273.666966)
		(width 0.127)
		(layer "F.Cu")
		(net "SAS_HDD_RX_P7")
	)
	(segment
		(start 357.463598 -273.432016)
		(end 357.590598 -273.305016)
		(width 0.127)
		(layer "F.Cu")
		(net "SAS_HDD_RX_P7")
	)
	(segment
		(start 357.590598 -273.305016)
		(end 358.925114 -273.305016)
		(width 0.127)
		(layer "F.Cu")
		(net "SAS_HDD_RX_P7")
	)
	(segment
		(start 322.448428 -273.660616)
		(end 322.581778 -273.793966)
		(width 0.127)
		(layer "F.Cu")
		(net "SAS_HDD_RX_P6")
	)
	(segment
		(start 325.913496 -273.666966)
		(end 325.913496 -273.432016)
		(width 0.127)
		(layer "F.Cu")
		(net "SAS_HDD_RX_P6")
	)
	(segment
		(start 325.786496 -273.793966)
		(end 325.913496 -273.666966)
		(width 0.127)
		(layer "F.Cu")
		(net "SAS_HDD_RX_P6")
	)
	(segment
		(start 326.040496 -273.305016)
		(end 327.375012 -273.305016)
		(width 0.127)
		(layer "F.Cu")
		(net "SAS_HDD_RX_P6")
	)
	(segment
		(start 321.914012 -273.660616)
		(end 322.448428 -273.660616)
		(width 0.127)
		(layer "F.Cu")
		(net "SAS_HDD_RX_P6")
	)
	(segment
		(start 325.913496 -273.432016)
		(end 326.040496 -273.305016)
		(width 0.127)
		(layer "F.Cu")
		(net "SAS_HDD_RX_P6")
	)
	(segment
		(start 322.581778 -273.793966)
		(end 325.786496 -273.793966)
		(width 0.127)
		(layer "F.Cu")
		(net "SAS_HDD_RX_P6")
	)
	(segment
		(start 189.602872 -273.660616)
		(end 189.469522 -273.793966)
		(width 0.127)
		(layer "F.Cu")
		(net "SAS_HDD_RX_P5")
	)
	(segment
		(start 189.236604 -273.666966)
		(end 189.236604 -273.432016)
		(width 0.127)
		(layer "F.Cu")
		(net "SAS_HDD_RX_P5")
	)
	(segment
		(start 189.109604 -273.305016)
		(end 187.775088 -273.305016)
		(width 0.127)
		(layer "F.Cu")
		(net "SAS_HDD_RX_P5")
	)
	(segment
		(start 189.236604 -273.432016)
		(end 189.109604 -273.305016)
		(width 0.127)
		(layer "F.Cu")
		(net "SAS_HDD_RX_P5")
	)
	(segment
		(start 189.934088 -273.660616)
		(end 189.602872 -273.660616)
		(width 0.127)
		(layer "F.Cu")
		(net "SAS_HDD_RX_P5")
	)
	(segment
		(start 189.363604 -273.793966)
		(end 189.236604 -273.666966)
		(width 0.127)
		(layer "F.Cu")
		(net "SAS_HDD_RX_P5")
	)
	(segment
		(start 189.469522 -273.793966)
		(end 189.363604 -273.793966)
		(width 0.127)
		(layer "F.Cu")
		(net "SAS_HDD_RX_P5")
	)
	(segment
		(start 157.91942 -273.793966)
		(end 157.813502 -273.793966)
		(width 0.127)
		(layer "F.Cu")
		(net "SAS_HDD_RX_P4")
	)
	(segment
		(start 157.813502 -273.793966)
		(end 157.686502 -273.666966)
		(width 0.127)
		(layer "F.Cu")
		(net "SAS_HDD_RX_P4")
	)
	(segment
		(start 157.686502 -273.432016)
		(end 157.559502 -273.305016)
		(width 0.127)
		(layer "F.Cu")
		(net "SAS_HDD_RX_P4")
	)
	(segment
		(start 158.05277 -273.660616)
		(end 157.91942 -273.793966)
		(width 0.127)
		(layer "F.Cu")
		(net "SAS_HDD_RX_P4")
	)
	(segment
		(start 158.383986 -273.660616)
		(end 158.05277 -273.660616)
		(width 0.127)
		(layer "F.Cu")
		(net "SAS_HDD_RX_P4")
	)
	(segment
		(start 157.559502 -273.305016)
		(end 156.224986 -273.305016)
		(width 0.127)
		(layer "F.Cu")
		(net "SAS_HDD_RX_P4")
	)
	(segment
		(start 157.686502 -273.666966)
		(end 157.686502 -273.432016)
		(width 0.127)
		(layer "F.Cu")
		(net "SAS_HDD_RX_P4")
	)
	(segment
		(start 480.17303 -43.660568)
		(end 480.30638 -43.793918)
		(width 0.127)
		(layer "F.Cu")
		(net "SAS_HDD_RX_P35")
	)
	(segment
		(start 483.536498 -43.793918)
		(end 483.663498 -43.666918)
		(width 0.127)
		(layer "F.Cu")
		(net "SAS_HDD_RX_P35")
	)
	(segment
		(start 480.30638 -43.793918)
		(end 483.536498 -43.793918)
		(width 0.127)
		(layer "F.Cu")
		(net "SAS_HDD_RX_P35")
	)
	(segment
		(start 483.663498 -43.666918)
		(end 483.663498 -43.431968)
		(width 0.127)
		(layer "F.Cu")
		(net "SAS_HDD_RX_P35")
	)
	(segment
		(start 479.664014 -43.660568)
		(end 480.17303 -43.660568)
		(width 0.127)
		(layer "F.Cu")
		(net "SAS_HDD_RX_P35")
	)
	(segment
		(start 483.663498 -43.431968)
		(end 483.790498 -43.304968)
		(width 0.127)
		(layer "F.Cu")
		(net "SAS_HDD_RX_P35")
	)
	(segment
		(start 483.790498 -43.304968)
		(end 485.125014 -43.304968)
		(width 0.127)
		(layer "F.Cu")
		(net "SAS_HDD_RX_P35")
	)
	(segment
		(start 452.113396 -43.431968)
		(end 452.240396 -43.304968)
		(width 0.127)
		(layer "F.Cu")
		(net "SAS_HDD_RX_P34")
	)
	(segment
		(start 452.240396 -43.304968)
		(end 453.574912 -43.304968)
		(width 0.127)
		(layer "F.Cu")
		(net "SAS_HDD_RX_P34")
	)
	(segment
		(start 448.113912 -43.660568)
		(end 448.622928 -43.660568)
		(width 0.127)
		(layer "F.Cu")
		(net "SAS_HDD_RX_P34")
	)
	(segment
		(start 448.756278 -43.793918)
		(end 451.986396 -43.793918)
		(width 0.127)
		(layer "F.Cu")
		(net "SAS_HDD_RX_P34")
	)
	(segment
		(start 451.986396 -43.793918)
		(end 452.113396 -43.666918)
		(width 0.127)
		(layer "F.Cu")
		(net "SAS_HDD_RX_P34")
	)
	(segment
		(start 452.113396 -43.666918)
		(end 452.113396 -43.431968)
		(width 0.127)
		(layer "F.Cu")
		(net "SAS_HDD_RX_P34")
	)
	(segment
		(start 448.622928 -43.660568)
		(end 448.756278 -43.793918)
		(width 0.127)
		(layer "F.Cu")
		(net "SAS_HDD_RX_P34")
	)
	(segment
		(start 420.690548 -43.304968)
		(end 422.025064 -43.304968)
		(width 0.127)
		(layer "F.Cu")
		(net "SAS_HDD_RX_P33")
	)
	(segment
		(start 416.564064 -43.660568)
		(end 417.07308 -43.660568)
		(width 0.127)
		(layer "F.Cu")
		(net "SAS_HDD_RX_P33")
	)
	(segment
		(start 417.20643 -43.793918)
		(end 420.436548 -43.793918)
		(width 0.127)
		(layer "F.Cu")
		(net "SAS_HDD_RX_P33")
	)
	(segment
		(start 417.07308 -43.660568)
		(end 417.20643 -43.793918)
		(width 0.127)
		(layer "F.Cu")
		(net "SAS_HDD_RX_P33")
	)
	(segment
		(start 420.563548 -43.666918)
		(end 420.563548 -43.431968)
		(width 0.127)
		(layer "F.Cu")
		(net "SAS_HDD_RX_P33")
	)
	(segment
		(start 420.563548 -43.431968)
		(end 420.690548 -43.304968)
		(width 0.127)
		(layer "F.Cu")
		(net "SAS_HDD_RX_P33")
	)
	(segment
		(start 420.436548 -43.793918)
		(end 420.563548 -43.666918)
		(width 0.127)
		(layer "F.Cu")
		(net "SAS_HDD_RX_P33")
	)
	(segment
		(start 389.013446 -43.666918)
		(end 389.013446 -43.431968)
		(width 0.127)
		(layer "F.Cu")
		(net "SAS_HDD_RX_P32")
	)
	(segment
		(start 389.140446 -43.304968)
		(end 390.474962 -43.304968)
		(width 0.127)
		(layer "F.Cu")
		(net "SAS_HDD_RX_P32")
	)
	(segment
		(start 385.472178 -43.660568)
		(end 385.605528 -43.793918)
		(width 0.127)
		(layer "F.Cu")
		(net "SAS_HDD_RX_P32")
	)
	(segment
		(start 385.013962 -43.660568)
		(end 385.472178 -43.660568)
		(width 0.127)
		(layer "F.Cu")
		(net "SAS_HDD_RX_P32")
	)
	(segment
		(start 389.013446 -43.431968)
		(end 389.140446 -43.304968)
		(width 0.127)
		(layer "F.Cu")
		(net "SAS_HDD_RX_P32")
	)
	(segment
		(start 385.605528 -43.793918)
		(end 388.886446 -43.793918)
		(width 0.127)
		(layer "F.Cu")
		(net "SAS_HDD_RX_P32")
	)
	(segment
		(start 388.886446 -43.793918)
		(end 389.013446 -43.666918)
		(width 0.127)
		(layer "F.Cu")
		(net "SAS_HDD_RX_P32")
	)
	(segment
		(start 354.00488 -43.793918)
		(end 357.336598 -43.793918)
		(width 0.127)
		(layer "F.Cu")
		(net "SAS_HDD_RX_P31")
	)
	(segment
		(start 353.87153 -43.660568)
		(end 354.00488 -43.793918)
		(width 0.127)
		(layer "F.Cu")
		(net "SAS_HDD_RX_P31")
	)
	(segment
		(start 357.463598 -43.431968)
		(end 357.590598 -43.304968)
		(width 0.127)
		(layer "F.Cu")
		(net "SAS_HDD_RX_P31")
	)
	(segment
		(start 357.590598 -43.304968)
		(end 358.925114 -43.304968)
		(width 0.127)
		(layer "F.Cu")
		(net "SAS_HDD_RX_P31")
	)
	(segment
		(start 357.463598 -43.666918)
		(end 357.463598 -43.431968)
		(width 0.127)
		(layer "F.Cu")
		(net "SAS_HDD_RX_P31")
	)
	(segment
		(start 357.336598 -43.793918)
		(end 357.463598 -43.666918)
		(width 0.127)
		(layer "F.Cu")
		(net "SAS_HDD_RX_P31")
	)
	(segment
		(start 353.464114 -43.660568)
		(end 353.87153 -43.660568)
		(width 0.127)
		(layer "F.Cu")
		(net "SAS_HDD_RX_P31")
	)
	(segment
		(start 325.913496 -43.431968)
		(end 326.040496 -43.304968)
		(width 0.127)
		(layer "F.Cu")
		(net "SAS_HDD_RX_P30")
	)
	(segment
		(start 325.913496 -43.666918)
		(end 325.913496 -43.431968)
		(width 0.127)
		(layer "F.Cu")
		(net "SAS_HDD_RX_P30")
	)
	(segment
		(start 322.397628 -43.660568)
		(end 322.530978 -43.793918)
		(width 0.127)
		(layer "F.Cu")
		(net "SAS_HDD_RX_P30")
	)
	(segment
		(start 322.530978 -43.793918)
		(end 325.786496 -43.793918)
		(width 0.127)
		(layer "F.Cu")
		(net "SAS_HDD_RX_P30")
	)
	(segment
		(start 321.914012 -43.660568)
		(end 322.397628 -43.660568)
		(width 0.127)
		(layer "F.Cu")
		(net "SAS_HDD_RX_P30")
	)
	(segment
		(start 326.040496 -43.304968)
		(end 327.375012 -43.304968)
		(width 0.127)
		(layer "F.Cu")
		(net "SAS_HDD_RX_P30")
	)
	(segment
		(start 325.786496 -43.793918)
		(end 325.913496 -43.666918)
		(width 0.127)
		(layer "F.Cu")
		(net "SAS_HDD_RX_P30")
	)
	(segment
		(start 126.1364 -273.432016)
		(end 126.0094 -273.305016)
		(width 0.127)
		(layer "F.Cu")
		(net "SAS_HDD_RX_P3")
	)
	(segment
		(start 126.1364 -273.666966)
		(end 126.1364 -273.432016)
		(width 0.127)
		(layer "F.Cu")
		(net "SAS_HDD_RX_P3")
	)
	(segment
		(start 126.502668 -273.660616)
		(end 126.369318 -273.793966)
		(width 0.127)
		(layer "F.Cu")
		(net "SAS_HDD_RX_P3")
	)
	(segment
		(start 126.0094 -273.305016)
		(end 124.674884 -273.305016)
		(width 0.127)
		(layer "F.Cu")
		(net "SAS_HDD_RX_P3")
	)
	(segment
		(start 126.833884 -273.660616)
		(end 126.502668 -273.660616)
		(width 0.127)
		(layer "F.Cu")
		(net "SAS_HDD_RX_P3")
	)
	(segment
		(start 126.369318 -273.793966)
		(end 126.2634 -273.793966)
		(width 0.127)
		(layer "F.Cu")
		(net "SAS_HDD_RX_P3")
	)
	(segment
		(start 126.2634 -273.793966)
		(end 126.1364 -273.666966)
		(width 0.127)
		(layer "F.Cu")
		(net "SAS_HDD_RX_P3")
	)
	(segment
		(start 189.469522 -43.793918)
		(end 189.363604 -43.793918)
		(width 0.127)
		(layer "F.Cu")
		(net "SAS_HDD_RX_P29")
	)
	(segment
		(start 189.236604 -43.431968)
		(end 189.109604 -43.304968)
		(width 0.127)
		(layer "F.Cu")
		(net "SAS_HDD_RX_P29")
	)
	(segment
		(start 189.236604 -43.666918)
		(end 189.236604 -43.431968)
		(width 0.127)
		(layer "F.Cu")
		(net "SAS_HDD_RX_P29")
	)
	(segment
		(start 189.934088 -43.660568)
		(end 189.602872 -43.660568)
		(width 0.127)
		(layer "F.Cu")
		(net "SAS_HDD_RX_P29")
	)
	(segment
		(start 189.602872 -43.660568)
		(end 189.469522 -43.793918)
		(width 0.127)
		(layer "F.Cu")
		(net "SAS_HDD_RX_P29")
	)
	(segment
		(start 189.109604 -43.304968)
		(end 187.775088 -43.304968)
		(width 0.127)
		(layer "F.Cu")
		(net "SAS_HDD_RX_P29")
	)
	(segment
		(start 189.363604 -43.793918)
		(end 189.236604 -43.666918)
		(width 0.127)
		(layer "F.Cu")
		(net "SAS_HDD_RX_P29")
	)
	(segment
		(start 158.383986 -43.660568)
		(end 158.05277 -43.660568)
		(width 0.127)
		(layer "F.Cu")
		(net "SAS_HDD_RX_P28")
	)
	(segment
		(start 157.91942 -43.793918)
		(end 157.813502 -43.793918)
		(width 0.127)
		(layer "F.Cu")
		(net "SAS_HDD_RX_P28")
	)
	(segment
		(start 157.686502 -43.431968)
		(end 157.559502 -43.304968)
		(width 0.127)
		(layer "F.Cu")
		(net "SAS_HDD_RX_P28")
	)
	(segment
		(start 157.559502 -43.304968)
		(end 156.224986 -43.304968)
		(width 0.127)
		(layer "F.Cu")
		(net "SAS_HDD_RX_P28")
	)
	(segment
		(start 157.686502 -43.666918)
		(end 157.686502 -43.431968)
		(width 0.127)
		(layer "F.Cu")
		(net "SAS_HDD_RX_P28")
	)
	(segment
		(start 157.813502 -43.793918)
		(end 157.686502 -43.666918)
		(width 0.127)
		(layer "F.Cu")
		(net "SAS_HDD_RX_P28")
	)
	(segment
		(start 158.05277 -43.660568)
		(end 157.91942 -43.793918)
		(width 0.127)
		(layer "F.Cu")
		(net "SAS_HDD_RX_P28")
	)
	(segment
		(start 126.502668 -43.660568)
		(end 126.369318 -43.793918)
		(width 0.127)
		(layer "F.Cu")
		(net "SAS_HDD_RX_P27")
	)
	(segment
		(start 126.0094 -43.304968)
		(end 124.674884 -43.304968)
		(width 0.127)
		(layer "F.Cu")
		(net "SAS_HDD_RX_P27")
	)
	(segment
		(start 126.833884 -43.660568)
		(end 126.502668 -43.660568)
		(width 0.127)
		(layer "F.Cu")
		(net "SAS_HDD_RX_P27")
	)
	(segment
		(start 126.1364 -43.666918)
		(end 126.1364 -43.431968)
		(width 0.127)
		(layer "F.Cu")
		(net "SAS_HDD_RX_P27")
	)
	(segment
		(start 126.2634 -43.793918)
		(end 126.1364 -43.666918)
		(width 0.127)
		(layer "F.Cu")
		(net "SAS_HDD_RX_P27")
	)
	(segment
		(start 126.1364 -43.431968)
		(end 126.0094 -43.304968)
		(width 0.127)
		(layer "F.Cu")
		(net "SAS_HDD_RX_P27")
	)
	(segment
		(start 126.369318 -43.793918)
		(end 126.2634 -43.793918)
		(width 0.127)
		(layer "F.Cu")
		(net "SAS_HDD_RX_P27")
	)
	(segment
		(start 94.459552 -43.304968)
		(end 93.125036 -43.304968)
		(width 0.127)
		(layer "F.Cu")
		(net "SAS_HDD_RX_P26")
	)
	(segment
		(start 94.713552 -43.793918)
		(end 94.586552 -43.666918)
		(width 0.127)
		(layer "F.Cu")
		(net "SAS_HDD_RX_P26")
	)
	(segment
		(start 94.81947 -43.793918)
		(end 94.713552 -43.793918)
		(width 0.127)
		(layer "F.Cu")
		(net "SAS_HDD_RX_P26")
	)
	(segment
		(start 94.586552 -43.431968)
		(end 94.459552 -43.304968)
		(width 0.127)
		(layer "F.Cu")
		(net "SAS_HDD_RX_P26")
	)
	(segment
		(start 94.586552 -43.666918)
		(end 94.586552 -43.431968)
		(width 0.127)
		(layer "F.Cu")
		(net "SAS_HDD_RX_P26")
	)
	(segment
		(start 94.95282 -43.660568)
		(end 94.81947 -43.793918)
		(width 0.127)
		(layer "F.Cu")
		(net "SAS_HDD_RX_P26")
	)
	(segment
		(start 95.284036 -43.660568)
		(end 94.95282 -43.660568)
		(width 0.127)
		(layer "F.Cu")
		(net "SAS_HDD_RX_P26")
	)
	(segment
		(start 63.733934 -43.660568)
		(end 63.402718 -43.660568)
		(width 0.127)
		(layer "F.Cu")
		(net "SAS_HDD_RX_P25")
	)
	(segment
		(start 62.90945 -43.304968)
		(end 61.574934 -43.304968)
		(width 0.127)
		(layer "F.Cu")
		(net "SAS_HDD_RX_P25")
	)
	(segment
		(start 63.03645 -43.431968)
		(end 62.90945 -43.304968)
		(width 0.127)
		(layer "F.Cu")
		(net "SAS_HDD_RX_P25")
	)
	(segment
		(start 63.16345 -43.793918)
		(end 63.03645 -43.666918)
		(width 0.127)
		(layer "F.Cu")
		(net "SAS_HDD_RX_P25")
	)
	(segment
		(start 63.269368 -43.793918)
		(end 63.16345 -43.793918)
		(width 0.127)
		(layer "F.Cu")
		(net "SAS_HDD_RX_P25")
	)
	(segment
		(start 63.03645 -43.666918)
		(end 63.03645 -43.431968)
		(width 0.127)
		(layer "F.Cu")
		(net "SAS_HDD_RX_P25")
	)
	(segment
		(start 63.402718 -43.660568)
		(end 63.269368 -43.793918)
		(width 0.127)
		(layer "F.Cu")
		(net "SAS_HDD_RX_P25")
	)
	(segment
		(start 31.71952 -43.793918)
		(end 31.613602 -43.793918)
		(width 0.127)
		(layer "F.Cu")
		(net "SAS_HDD_RX_P24")
	)
	(segment
		(start 31.486602 -43.431968)
		(end 31.359602 -43.304968)
		(width 0.127)
		(layer "F.Cu")
		(net "SAS_HDD_RX_P24")
	)
	(segment
		(start 31.613602 -43.793918)
		(end 31.486602 -43.666918)
		(width 0.127)
		(layer "F.Cu")
		(net "SAS_HDD_RX_P24")
	)
	(segment
		(start 31.486602 -43.666918)
		(end 31.486602 -43.431968)
		(width 0.127)
		(layer "F.Cu")
		(net "SAS_HDD_RX_P24")
	)
	(segment
		(start 32.184086 -43.660568)
		(end 31.85287 -43.660568)
		(width 0.127)
		(layer "F.Cu")
		(net "SAS_HDD_RX_P24")
	)
	(segment
		(start 31.359602 -43.304968)
		(end 30.025086 -43.304968)
		(width 0.127)
		(layer "F.Cu")
		(net "SAS_HDD_RX_P24")
	)
	(segment
		(start 31.85287 -43.660568)
		(end 31.71952 -43.793918)
		(width 0.127)
		(layer "F.Cu")
		(net "SAS_HDD_RX_P24")
	)
	(segment
		(start 483.790498 -158.304992)
		(end 485.125014 -158.304992)
		(width 0.127)
		(layer "F.Cu")
		(net "SAS_HDD_RX_P23")
	)
	(segment
		(start 479.664014 -158.660592)
		(end 480.24923 -158.660592)
		(width 0.127)
		(layer "F.Cu")
		(net "SAS_HDD_RX_P23")
	)
	(segment
		(start 483.663498 -158.431992)
		(end 483.790498 -158.304992)
		(width 0.127)
		(layer "F.Cu")
		(net "SAS_HDD_RX_P23")
	)
	(segment
		(start 480.38258 -158.793942)
		(end 483.536498 -158.793942)
		(width 0.127)
		(layer "F.Cu")
		(net "SAS_HDD_RX_P23")
	)
	(segment
		(start 480.24923 -158.660592)
		(end 480.38258 -158.793942)
		(width 0.127)
		(layer "F.Cu")
		(net "SAS_HDD_RX_P23")
	)
	(segment
		(start 483.536498 -158.793942)
		(end 483.663498 -158.666942)
		(width 0.127)
		(layer "F.Cu")
		(net "SAS_HDD_RX_P23")
	)
	(segment
		(start 483.663498 -158.666942)
		(end 483.663498 -158.431992)
		(width 0.127)
		(layer "F.Cu")
		(net "SAS_HDD_RX_P23")
	)
	(segment
		(start 452.113396 -158.431992)
		(end 452.113396 -158.666942)
		(width 0.127)
		(layer "F.Cu")
		(net "SAS_HDD_RX_P22")
	)
	(segment
		(start 442.222128 -158.660592)
		(end 441.763912 -158.660592)
		(width 0.127)
		(layer "F.Cu")
		(net "SAS_HDD_RX_P22")
	)
	(segment
		(start 452.240396 -158.304992)
		(end 452.113396 -158.431992)
		(width 0.127)
		(layer "F.Cu")
		(net "SAS_HDD_RX_P22")
	)
	(segment
		(start 451.986396 -158.793942)
		(end 442.355478 -158.793942)
		(width 0.127)
		(layer "F.Cu")
		(net "SAS_HDD_RX_P22")
	)
	(segment
		(start 452.113396 -158.666942)
		(end 451.986396 -158.793942)
		(width 0.127)
		(layer "F.Cu")
		(net "SAS_HDD_RX_P22")
	)
	(segment
		(start 453.574912 -158.304992)
		(end 452.240396 -158.304992)
		(width 0.127)
		(layer "F.Cu")
		(net "SAS_HDD_RX_P22")
	)
	(segment
		(start 442.355478 -158.793942)
		(end 442.222128 -158.660592)
		(width 0.127)
		(layer "F.Cu")
		(net "SAS_HDD_RX_P22")
	)
	(segment
		(start 420.436548 -158.793942)
		(end 420.563548 -158.666942)
		(width 0.127)
		(layer "F.Cu")
		(net "SAS_HDD_RX_P21")
	)
	(segment
		(start 416.564064 -158.660592)
		(end 416.99688 -158.660592)
		(width 0.127)
		(layer "F.Cu")
		(net "SAS_HDD_RX_P21")
	)
	(segment
		(start 416.99688 -158.660592)
		(end 417.13023 -158.793942)
		(width 0.127)
		(layer "F.Cu")
		(net "SAS_HDD_RX_P21")
	)
	(segment
		(start 417.13023 -158.793942)
		(end 420.436548 -158.793942)
		(width 0.127)
		(layer "F.Cu")
		(net "SAS_HDD_RX_P21")
	)
	(segment
		(start 420.563548 -158.666942)
		(end 420.563548 -158.431992)
		(width 0.127)
		(layer "F.Cu")
		(net "SAS_HDD_RX_P21")
	)
	(segment
		(start 420.690548 -158.304992)
		(end 422.025064 -158.304992)
		(width 0.127)
		(layer "F.Cu")
		(net "SAS_HDD_RX_P21")
	)
	(segment
		(start 420.563548 -158.431992)
		(end 420.690548 -158.304992)
		(width 0.127)
		(layer "F.Cu")
		(net "SAS_HDD_RX_P21")
	)
	(segment
		(start 389.140446 -158.304992)
		(end 390.474962 -158.304992)
		(width 0.127)
		(layer "F.Cu")
		(net "SAS_HDD_RX_P20")
	)
	(segment
		(start 385.421378 -158.660592)
		(end 385.554728 -158.793942)
		(width 0.127)
		(layer "F.Cu")
		(net "SAS_HDD_RX_P20")
	)
	(segment
		(start 385.554728 -158.793942)
		(end 388.886446 -158.793942)
		(width 0.127)
		(layer "F.Cu")
		(net "SAS_HDD_RX_P20")
	)
	(segment
		(start 385.013962 -158.660592)
		(end 385.421378 -158.660592)
		(width 0.127)
		(layer "F.Cu")
		(net "SAS_HDD_RX_P20")
	)
	(segment
		(start 388.886446 -158.793942)
		(end 389.013446 -158.666942)
		(width 0.127)
		(layer "F.Cu")
		(net "SAS_HDD_RX_P20")
	)
	(segment
		(start 389.013446 -158.666942)
		(end 389.013446 -158.431992)
		(width 0.127)
		(layer "F.Cu")
		(net "SAS_HDD_RX_P20")
	)
	(segment
		(start 389.013446 -158.431992)
		(end 389.140446 -158.304992)
		(width 0.127)
		(layer "F.Cu")
		(net "SAS_HDD_RX_P20")
	)
	(segment
		(start 94.586552 -273.432016)
		(end 94.459552 -273.305016)
		(width 0.127)
		(layer "F.Cu")
		(net "SAS_HDD_RX_P2")
	)
	(segment
		(start 94.95282 -273.660616)
		(end 94.81947 -273.793966)
		(width 0.127)
		(layer "F.Cu")
		(net "SAS_HDD_RX_P2")
	)
	(segment
		(start 94.586552 -273.666966)
		(end 94.586552 -273.432016)
		(width 0.127)
		(layer "F.Cu")
		(net "SAS_HDD_RX_P2")
	)
	(segment
		(start 94.81947 -273.793966)
		(end 94.713552 -273.793966)
		(width 0.127)
		(layer "F.Cu")
		(net "SAS_HDD_RX_P2")
	)
	(segment
		(start 95.284036 -273.660616)
		(end 94.95282 -273.660616)
		(width 0.127)
		(layer "F.Cu")
		(net "SAS_HDD_RX_P2")
	)
	(segment
		(start 94.713552 -273.793966)
		(end 94.586552 -273.666966)
		(width 0.127)
		(layer "F.Cu")
		(net "SAS_HDD_RX_P2")
	)
	(segment
		(start 94.459552 -273.305016)
		(end 93.125036 -273.305016)
		(width 0.127)
		(layer "F.Cu")
		(net "SAS_HDD_RX_P2")
	)
	(segment
		(start 354.13188 -158.793942)
		(end 357.336598 -158.793942)
		(width 0.127)
		(layer "F.Cu")
		(net "SAS_HDD_RX_P19")
	)
	(segment
		(start 357.463598 -158.666942)
		(end 357.463598 -158.431992)
		(width 0.127)
		(layer "F.Cu")
		(net "SAS_HDD_RX_P19")
	)
	(segment
		(start 357.463598 -158.431992)
		(end 357.590598 -158.304992)
		(width 0.127)
		(layer "F.Cu")
		(net "SAS_HDD_RX_P19")
	)
	(segment
		(start 353.99853 -158.660592)
		(end 354.13188 -158.793942)
		(width 0.127)
		(layer "F.Cu")
		(net "SAS_HDD_RX_P19")
	)
	(segment
		(start 357.336598 -158.793942)
		(end 357.463598 -158.666942)
		(width 0.127)
		(layer "F.Cu")
		(net "SAS_HDD_RX_P19")
	)
	(segment
		(start 357.590598 -158.304992)
		(end 358.925114 -158.304992)
		(width 0.127)
		(layer "F.Cu")
		(net "SAS_HDD_RX_P19")
	)
	(segment
		(start 353.464114 -158.660592)
		(end 353.99853 -158.660592)
		(width 0.127)
		(layer "F.Cu")
		(net "SAS_HDD_RX_P19")
	)
	(segment
		(start 326.040496 -158.304992)
		(end 327.375012 -158.304992)
		(width 0.127)
		(layer "F.Cu")
		(net "SAS_HDD_RX_P18")
	)
	(segment
		(start 322.505578 -158.793942)
		(end 325.786496 -158.793942)
		(width 0.127)
		(layer "F.Cu")
		(net "SAS_HDD_RX_P18")
	)
	(segment
		(start 325.786496 -158.793942)
		(end 325.913496 -158.666942)
		(width 0.127)
		(layer "F.Cu")
		(net "SAS_HDD_RX_P18")
	)
	(segment
		(start 322.372228 -158.660592)
		(end 322.505578 -158.793942)
		(width 0.127)
		(layer "F.Cu")
		(net "SAS_HDD_RX_P18")
	)
	(segment
		(start 321.914012 -158.660592)
		(end 322.372228 -158.660592)
		(width 0.127)
		(layer "F.Cu")
		(net "SAS_HDD_RX_P18")
	)
	(segment
		(start 325.913496 -158.431992)
		(end 326.040496 -158.304992)
		(width 0.127)
		(layer "F.Cu")
		(net "SAS_HDD_RX_P18")
	)
	(segment
		(start 325.913496 -158.666942)
		(end 325.913496 -158.431992)
		(width 0.127)
		(layer "F.Cu")
		(net "SAS_HDD_RX_P18")
	)
	(segment
		(start 189.363604 -158.793942)
		(end 189.236604 -158.666942)
		(width 0.127)
		(layer "F.Cu")
		(net "SAS_HDD_RX_P17")
	)
	(segment
		(start 189.469522 -158.793942)
		(end 189.363604 -158.793942)
		(width 0.127)
		(layer "F.Cu")
		(net "SAS_HDD_RX_P17")
	)
	(segment
		(start 189.109604 -158.304992)
		(end 187.775088 -158.304992)
		(width 0.127)
		(layer "F.Cu")
		(net "SAS_HDD_RX_P17")
	)
	(segment
		(start 189.934088 -158.660592)
		(end 189.602872 -158.660592)
		(width 0.127)
		(layer "F.Cu")
		(net "SAS_HDD_RX_P17")
	)
	(segment
		(start 189.602872 -158.660592)
		(end 189.469522 -158.793942)
		(width 0.127)
		(layer "F.Cu")
		(net "SAS_HDD_RX_P17")
	)
	(segment
		(start 189.236604 -158.431992)
		(end 189.109604 -158.304992)
		(width 0.127)
		(layer "F.Cu")
		(net "SAS_HDD_RX_P17")
	)
	(segment
		(start 189.236604 -158.666942)
		(end 189.236604 -158.431992)
		(width 0.127)
		(layer "F.Cu")
		(net "SAS_HDD_RX_P17")
	)
	(segment
		(start 157.559502 -158.304992)
		(end 156.224986 -158.304992)
		(width 0.127)
		(layer "F.Cu")
		(net "SAS_HDD_RX_P16")
	)
	(segment
		(start 157.91942 -158.793942)
		(end 157.813502 -158.793942)
		(width 0.127)
		(layer "F.Cu")
		(net "SAS_HDD_RX_P16")
	)
	(segment
		(start 157.686502 -158.431992)
		(end 157.559502 -158.304992)
		(width 0.127)
		(layer "F.Cu")
		(net "SAS_HDD_RX_P16")
	)
	(segment
		(start 157.813502 -158.793942)
		(end 157.686502 -158.666942)
		(width 0.127)
		(layer "F.Cu")
		(net "SAS_HDD_RX_P16")
	)
	(segment
		(start 157.686502 -158.666942)
		(end 157.686502 -158.431992)
		(width 0.127)
		(layer "F.Cu")
		(net "SAS_HDD_RX_P16")
	)
	(segment
		(start 158.383986 -158.660592)
		(end 158.05277 -158.660592)
		(width 0.127)
		(layer "F.Cu")
		(net "SAS_HDD_RX_P16")
	)
	(segment
		(start 158.05277 -158.660592)
		(end 157.91942 -158.793942)
		(width 0.127)
		(layer "F.Cu")
		(net "SAS_HDD_RX_P16")
	)
	(segment
		(start 126.502668 -158.660592)
		(end 126.369318 -158.793942)
		(width 0.127)
		(layer "F.Cu")
		(net "SAS_HDD_RX_P15")
	)
	(segment
		(start 126.2634 -158.793942)
		(end 126.1364 -158.666942)
		(width 0.127)
		(layer "F.Cu")
		(net "SAS_HDD_RX_P15")
	)
	(segment
		(start 126.1364 -158.666942)
		(end 126.1364 -158.431992)
		(width 0.127)
		(layer "F.Cu")
		(net "SAS_HDD_RX_P15")
	)
	(segment
		(start 126.833884 -158.660592)
		(end 126.502668 -158.660592)
		(width 0.127)
		(layer "F.Cu")
		(net "SAS_HDD_RX_P15")
	)
	(segment
		(start 126.369318 -158.793942)
		(end 126.2634 -158.793942)
		(width 0.127)
		(layer "F.Cu")
		(net "SAS_HDD_RX_P15")
	)
	(segment
		(start 126.0094 -158.304992)
		(end 124.674884 -158.304992)
		(width 0.127)
		(layer "F.Cu")
		(net "SAS_HDD_RX_P15")
	)
	(segment
		(start 126.1364 -158.431992)
		(end 126.0094 -158.304992)
		(width 0.127)
		(layer "F.Cu")
		(net "SAS_HDD_RX_P15")
	)
	(segment
		(start 94.95282 -158.660592)
		(end 94.81947 -158.793942)
		(width 0.127)
		(layer "F.Cu")
		(net "SAS_HDD_RX_P14")
	)
	(segment
		(start 94.81947 -158.793942)
		(end 94.713552 -158.793942)
		(width 0.127)
		(layer "F.Cu")
		(net "SAS_HDD_RX_P14")
	)
	(segment
		(start 94.586552 -158.431992)
		(end 94.459552 -158.304992)
		(width 0.127)
		(layer "F.Cu")
		(net "SAS_HDD_RX_P14")
	)
	(segment
		(start 94.713552 -158.793942)
		(end 94.586552 -158.666942)
		(width 0.127)
		(layer "F.Cu")
		(net "SAS_HDD_RX_P14")
	)
	(segment
		(start 94.586552 -158.666942)
		(end 94.586552 -158.431992)
		(width 0.127)
		(layer "F.Cu")
		(net "SAS_HDD_RX_P14")
	)
	(segment
		(start 94.459552 -158.304992)
		(end 93.125036 -158.304992)
		(width 0.127)
		(layer "F.Cu")
		(net "SAS_HDD_RX_P14")
	)
	(segment
		(start 95.284036 -158.660592)
		(end 94.95282 -158.660592)
		(width 0.127)
		(layer "F.Cu")
		(net "SAS_HDD_RX_P14")
	)
	(segment
		(start 63.733934 -158.660592)
		(end 63.402718 -158.660592)
		(width 0.127)
		(layer "F.Cu")
		(net "SAS_HDD_RX_P13")
	)
	(segment
		(start 62.90945 -158.304992)
		(end 61.574934 -158.304992)
		(width 0.127)
		(layer "F.Cu")
		(net "SAS_HDD_RX_P13")
	)
	(segment
		(start 63.16345 -158.793942)
		(end 63.03645 -158.666942)
		(width 0.127)
		(layer "F.Cu")
		(net "SAS_HDD_RX_P13")
	)
	(segment
		(start 63.402718 -158.660592)
		(end 63.269368 -158.793942)
		(width 0.127)
		(layer "F.Cu")
		(net "SAS_HDD_RX_P13")
	)
	(segment
		(start 63.269368 -158.793942)
		(end 63.16345 -158.793942)
		(width 0.127)
		(layer "F.Cu")
		(net "SAS_HDD_RX_P13")
	)
	(segment
		(start 63.03645 -158.666942)
		(end 63.03645 -158.431992)
		(width 0.127)
		(layer "F.Cu")
		(net "SAS_HDD_RX_P13")
	)
	(segment
		(start 63.03645 -158.431992)
		(end 62.90945 -158.304992)
		(width 0.127)
		(layer "F.Cu")
		(net "SAS_HDD_RX_P13")
	)
	(segment
		(start 31.359602 -158.304992)
		(end 30.025086 -158.304992)
		(width 0.127)
		(layer "F.Cu")
		(net "SAS_HDD_RX_P12")
	)
	(segment
		(start 31.85287 -158.660592)
		(end 31.71952 -158.793942)
		(width 0.127)
		(layer "F.Cu")
		(net "SAS_HDD_RX_P12")
	)
	(segment
		(start 31.486602 -158.666942)
		(end 31.486602 -158.431992)
		(width 0.127)
		(layer "F.Cu")
		(net "SAS_HDD_RX_P12")
	)
	(segment
		(start 31.486602 -158.431992)
		(end 31.359602 -158.304992)
		(width 0.127)
		(layer "F.Cu")
		(net "SAS_HDD_RX_P12")
	)
	(segment
		(start 32.184086 -158.660592)
		(end 31.85287 -158.660592)
		(width 0.127)
		(layer "F.Cu")
		(net "SAS_HDD_RX_P12")
	)
	(segment
		(start 31.71952 -158.793942)
		(end 31.613602 -158.793942)
		(width 0.127)
		(layer "F.Cu")
		(net "SAS_HDD_RX_P12")
	)
	(segment
		(start 31.613602 -158.793942)
		(end 31.486602 -158.666942)
		(width 0.127)
		(layer "F.Cu")
		(net "SAS_HDD_RX_P12")
	)
	(segment
		(start 483.790498 -273.305016)
		(end 485.125014 -273.305016)
		(width 0.127)
		(layer "F.Cu")
		(net "SAS_HDD_RX_P11")
	)
	(segment
		(start 479.664014 -273.660616)
		(end 480.19843 -273.660616)
		(width 0.127)
		(layer "F.Cu")
		(net "SAS_HDD_RX_P11")
	)
	(segment
		(start 480.33178 -273.793966)
		(end 483.536498 -273.793966)
		(width 0.127)
		(layer "F.Cu")
		(net "SAS_HDD_RX_P11")
	)
	(segment
		(start 483.663498 -273.666966)
		(end 483.663498 -273.432016)
		(width 0.127)
		(layer "F.Cu")
		(net "SAS_HDD_RX_P11")
	)
	(segment
		(start 483.536498 -273.793966)
		(end 483.663498 -273.666966)
		(width 0.127)
		(layer "F.Cu")
		(net "SAS_HDD_RX_P11")
	)
	(segment
		(start 483.663498 -273.432016)
		(end 483.790498 -273.305016)
		(width 0.127)
		(layer "F.Cu")
		(net "SAS_HDD_RX_P11")
	)
	(segment
		(start 480.19843 -273.660616)
		(end 480.33178 -273.793966)
		(width 0.127)
		(layer "F.Cu")
		(net "SAS_HDD_RX_P11")
	)
	(segment
		(start 448.730878 -273.793966)
		(end 451.986396 -273.793966)
		(width 0.127)
		(layer "F.Cu")
		(net "SAS_HDD_RX_P10")
	)
	(segment
		(start 452.113396 -273.432016)
		(end 452.240396 -273.305016)
		(width 0.127)
		(layer "F.Cu")
		(net "SAS_HDD_RX_P10")
	)
	(segment
		(start 448.113912 -273.660616)
		(end 448.597528 -273.660616)
		(width 0.127)
		(layer "F.Cu")
		(net "SAS_HDD_RX_P10")
	)
	(segment
		(start 452.113396 -273.666966)
		(end 452.113396 -273.432016)
		(width 0.127)
		(layer "F.Cu")
		(net "SAS_HDD_RX_P10")
	)
	(segment
		(start 451.986396 -273.793966)
		(end 452.113396 -273.666966)
		(width 0.127)
		(layer "F.Cu")
		(net "SAS_HDD_RX_P10")
	)
	(segment
		(start 452.240396 -273.305016)
		(end 453.574912 -273.305016)
		(width 0.127)
		(layer "F.Cu")
		(net "SAS_HDD_RX_P10")
	)
	(segment
		(start 448.597528 -273.660616)
		(end 448.730878 -273.793966)
		(width 0.127)
		(layer "F.Cu")
		(net "SAS_HDD_RX_P10")
	)
	(segment
		(start 62.90945 -273.305016)
		(end 61.574934 -273.305016)
		(width 0.127)
		(layer "F.Cu")
		(net "SAS_HDD_RX_P1")
	)
	(segment
		(start 63.03645 -273.432016)
		(end 62.90945 -273.305016)
		(width 0.127)
		(layer "F.Cu")
		(net "SAS_HDD_RX_P1")
	)
	(segment
		(start 63.402718 -273.660616)
		(end 63.269368 -273.793966)
		(width 0.127)
		(layer "F.Cu")
		(net "SAS_HDD_RX_P1")
	)
	(segment
		(start 63.03645 -273.666966)
		(end 63.03645 -273.432016)
		(width 0.127)
		(layer "F.Cu")
		(net "SAS_HDD_RX_P1")
	)
	(segment
		(start 63.733934 -273.660616)
		(end 63.402718 -273.660616)
		(width 0.127)
		(layer "F.Cu")
		(net "SAS_HDD_RX_P1")
	)
	(segment
		(start 63.16345 -273.793966)
		(end 63.03645 -273.666966)
		(width 0.127)
		(layer "F.Cu")
		(net "SAS_HDD_RX_P1")
	)
	(segment
		(start 63.269368 -273.793966)
		(end 63.16345 -273.793966)
		(width 0.127)
		(layer "F.Cu")
		(net "SAS_HDD_RX_P1")
	)
	(segment
		(start 31.359602 -273.305016)
		(end 30.025086 -273.305016)
		(width 0.127)
		(layer "F.Cu")
		(net "SAS_HDD_RX_P0")
	)
	(segment
		(start 32.184086 -273.660616)
		(end 31.85287 -273.660616)
		(width 0.127)
		(layer "F.Cu")
		(net "SAS_HDD_RX_P0")
	)
	(segment
		(start 31.85287 -273.660616)
		(end 31.71952 -273.793966)
		(width 0.127)
		(layer "F.Cu")
		(net "SAS_HDD_RX_P0")
	)
	(segment
		(start 31.613602 -273.793966)
		(end 31.486602 -273.666966)
		(width 0.127)
		(layer "F.Cu")
		(net "SAS_HDD_RX_P0")
	)
	(segment
		(start 31.486602 -273.432016)
		(end 31.359602 -273.305016)
		(width 0.127)
		(layer "F.Cu")
		(net "SAS_HDD_RX_P0")
	)
	(segment
		(start 31.71952 -273.793966)
		(end 31.613602 -273.793966)
		(width 0.127)
		(layer "F.Cu")
		(net "SAS_HDD_RX_P0")
	)
	(segment
		(start 31.486602 -273.666966)
		(end 31.486602 -273.432016)
		(width 0.127)
		(layer "F.Cu")
		(net "SAS_HDD_RX_P0")
	)
	(segment
		(start 417.25723 -274.086066)
		(end 420.436548 -274.086066)
		(width 0.127)
		(layer "F.Cu")
		(net "SAS_HDD_RX_N9")
	)
	(segment
		(start 420.563548 -274.448016)
		(end 420.690548 -274.575016)
		(width 0.127)
		(layer "F.Cu")
		(net "SAS_HDD_RX_N9")
	)
	(segment
		(start 420.563548 -274.213066)
		(end 420.563548 -274.448016)
		(width 0.127)
		(layer "F.Cu")
		(net "SAS_HDD_RX_N9")
	)
	(segment
		(start 420.436548 -274.086066)
		(end 420.563548 -274.213066)
		(width 0.127)
		(layer "F.Cu")
		(net "SAS_HDD_RX_N9")
	)
	(segment
		(start 420.690548 -274.575016)
		(end 422.025064 -274.575016)
		(width 0.127)
		(layer "F.Cu")
		(net "SAS_HDD_RX_N9")
	)
	(segment
		(start 417.12388 -274.219416)
		(end 417.25723 -274.086066)
		(width 0.127)
		(layer "F.Cu")
		(net "SAS_HDD_RX_N9")
	)
	(segment
		(start 416.564064 -274.219416)
		(end 417.12388 -274.219416)
		(width 0.127)
		(layer "F.Cu")
		(net "SAS_HDD_RX_N9")
	)
	(segment
		(start 389.013446 -274.213066)
		(end 389.013446 -274.448016)
		(width 0.127)
		(layer "F.Cu")
		(net "SAS_HDD_RX_N8")
	)
	(segment
		(start 385.013962 -274.219416)
		(end 385.497578 -274.219416)
		(width 0.127)
		(layer "F.Cu")
		(net "SAS_HDD_RX_N8")
	)
	(segment
		(start 389.140446 -274.575016)
		(end 390.474962 -274.575016)
		(width 0.127)
		(layer "F.Cu")
		(net "SAS_HDD_RX_N8")
	)
	(segment
		(start 385.630928 -274.086066)
		(end 388.886446 -274.086066)
		(width 0.127)
		(layer "F.Cu")
		(net "SAS_HDD_RX_N8")
	)
	(segment
		(start 388.886446 -274.086066)
		(end 389.013446 -274.213066)
		(width 0.127)
		(layer "F.Cu")
		(net "SAS_HDD_RX_N8")
	)
	(segment
		(start 385.497578 -274.219416)
		(end 385.630928 -274.086066)
		(width 0.127)
		(layer "F.Cu")
		(net "SAS_HDD_RX_N8")
	)
	(segment
		(start 389.013446 -274.448016)
		(end 389.140446 -274.575016)
		(width 0.127)
		(layer "F.Cu")
		(net "SAS_HDD_RX_N8")
	)
	(segment
		(start 354.02393 -274.219416)
		(end 354.15728 -274.086066)
		(width 0.127)
		(layer "F.Cu")
		(net "SAS_HDD_RX_N7")
	)
	(segment
		(start 357.590598 -274.575016)
		(end 358.925114 -274.575016)
		(width 0.127)
		(layer "F.Cu")
		(net "SAS_HDD_RX_N7")
	)
	(segment
		(start 354.15728 -274.086066)
		(end 357.336598 -274.086066)
		(width 0.127)
		(layer "F.Cu")
		(net "SAS_HDD_RX_N7")
	)
	(segment
		(start 357.463598 -274.213066)
		(end 357.463598 -274.448016)
		(width 0.127)
		(layer "F.Cu")
		(net "SAS_HDD_RX_N7")
	)
	(segment
		(start 357.336598 -274.086066)
		(end 357.463598 -274.213066)
		(width 0.127)
		(layer "F.Cu")
		(net "SAS_HDD_RX_N7")
	)
	(segment
		(start 357.463598 -274.448016)
		(end 357.590598 -274.575016)
		(width 0.127)
		(layer "F.Cu")
		(net "SAS_HDD_RX_N7")
	)
	(segment
		(start 353.464114 -274.219416)
		(end 354.02393 -274.219416)
		(width 0.127)
		(layer "F.Cu")
		(net "SAS_HDD_RX_N7")
	)
	(segment
		(start 325.913496 -274.448016)
		(end 326.040496 -274.575016)
		(width 0.127)
		(layer "F.Cu")
		(net "SAS_HDD_RX_N6")
	)
	(segment
		(start 321.914012 -274.219416)
		(end 322.448428 -274.219416)
		(width 0.127)
		(layer "F.Cu")
		(net "SAS_HDD_RX_N6")
	)
	(segment
		(start 322.581778 -274.086066)
		(end 325.786496 -274.086066)
		(width 0.127)
		(layer "F.Cu")
		(net "SAS_HDD_RX_N6")
	)
	(segment
		(start 326.040496 -274.575016)
		(end 327.375012 -274.575016)
		(width 0.127)
		(layer "F.Cu")
		(net "SAS_HDD_RX_N6")
	)
	(segment
		(start 325.786496 -274.086066)
		(end 325.913496 -274.213066)
		(width 0.127)
		(layer "F.Cu")
		(net "SAS_HDD_RX_N6")
	)
	(segment
		(start 322.448428 -274.219416)
		(end 322.581778 -274.086066)
		(width 0.127)
		(layer "F.Cu")
		(net "SAS_HDD_RX_N6")
	)
	(segment
		(start 325.913496 -274.213066)
		(end 325.913496 -274.448016)
		(width 0.127)
		(layer "F.Cu")
		(net "SAS_HDD_RX_N6")
	)
	(segment
		(start 189.363604 -274.086066)
		(end 189.236604 -274.213066)
		(width 0.127)
		(layer "F.Cu")
		(net "SAS_HDD_RX_N5")
	)
	(segment
		(start 189.602872 -274.219416)
		(end 189.469522 -274.086066)
		(width 0.127)
		(layer "F.Cu")
		(net "SAS_HDD_RX_N5")
	)
	(segment
		(start 189.236604 -274.213066)
		(end 189.236604 -274.448016)
		(width 0.127)
		(layer "F.Cu")
		(net "SAS_HDD_RX_N5")
	)
	(segment
		(start 189.236604 -274.448016)
		(end 189.109604 -274.575016)
		(width 0.127)
		(layer "F.Cu")
		(net "SAS_HDD_RX_N5")
	)
	(segment
		(start 189.469522 -274.086066)
		(end 189.363604 -274.086066)
		(width 0.127)
		(layer "F.Cu")
		(net "SAS_HDD_RX_N5")
	)
	(segment
		(start 189.934088 -274.219416)
		(end 189.602872 -274.219416)
		(width 0.127)
		(layer "F.Cu")
		(net "SAS_HDD_RX_N5")
	)
	(segment
		(start 189.109604 -274.575016)
		(end 187.775088 -274.575016)
		(width 0.127)
		(layer "F.Cu")
		(net "SAS_HDD_RX_N5")
	)
	(segment
		(start 158.05277 -274.219416)
		(end 157.91942 -274.086066)
		(width 0.127)
		(layer "F.Cu")
		(net "SAS_HDD_RX_N4")
	)
	(segment
		(start 157.91942 -274.086066)
		(end 157.813502 -274.086066)
		(width 0.127)
		(layer "F.Cu")
		(net "SAS_HDD_RX_N4")
	)
	(segment
		(start 157.813502 -274.086066)
		(end 157.686502 -274.213066)
		(width 0.127)
		(layer "F.Cu")
		(net "SAS_HDD_RX_N4")
	)
	(segment
		(start 157.686502 -274.448016)
		(end 157.559502 -274.575016)
		(width 0.127)
		(layer "F.Cu")
		(net "SAS_HDD_RX_N4")
	)
	(segment
		(start 157.559502 -274.575016)
		(end 156.224986 -274.575016)
		(width 0.127)
		(layer "F.Cu")
		(net "SAS_HDD_RX_N4")
	)
	(segment
		(start 158.383986 -274.219416)
		(end 158.05277 -274.219416)
		(width 0.127)
		(layer "F.Cu")
		(net "SAS_HDD_RX_N4")
	)
	(segment
		(start 157.686502 -274.213066)
		(end 157.686502 -274.448016)
		(width 0.127)
		(layer "F.Cu")
		(net "SAS_HDD_RX_N4")
	)
	(segment
		(start 483.663498 -44.447968)
		(end 483.790498 -44.574968)
		(width 0.127)
		(layer "F.Cu")
		(net "SAS_HDD_RX_N35")
	)
	(segment
		(start 479.664014 -44.219368)
		(end 480.17303 -44.219368)
		(width 0.127)
		(layer "F.Cu")
		(net "SAS_HDD_RX_N35")
	)
	(segment
		(start 480.30638 -44.086018)
		(end 483.536498 -44.086018)
		(width 0.127)
		(layer "F.Cu")
		(net "SAS_HDD_RX_N35")
	)
	(segment
		(start 483.663498 -44.213018)
		(end 483.663498 -44.447968)
		(width 0.127)
		(layer "F.Cu")
		(net "SAS_HDD_RX_N35")
	)
	(segment
		(start 483.790498 -44.574968)
		(end 485.125014 -44.574968)
		(width 0.127)
		(layer "F.Cu")
		(net "SAS_HDD_RX_N35")
	)
	(segment
		(start 483.536498 -44.086018)
		(end 483.663498 -44.213018)
		(width 0.127)
		(layer "F.Cu")
		(net "SAS_HDD_RX_N35")
	)
	(segment
		(start 480.17303 -44.219368)
		(end 480.30638 -44.086018)
		(width 0.127)
		(layer "F.Cu")
		(net "SAS_HDD_RX_N35")
	)
	(segment
		(start 448.756278 -44.086018)
		(end 451.986396 -44.086018)
		(width 0.127)
		(layer "F.Cu")
		(net "SAS_HDD_RX_N34")
	)
	(segment
		(start 451.986396 -44.086018)
		(end 452.113396 -44.213018)
		(width 0.127)
		(layer "F.Cu")
		(net "SAS_HDD_RX_N34")
	)
	(segment
		(start 452.240396 -44.574968)
		(end 453.574912 -44.574968)
		(width 0.127)
		(layer "F.Cu")
		(net "SAS_HDD_RX_N34")
	)
	(segment
		(start 448.622928 -44.219368)
		(end 448.756278 -44.086018)
		(width 0.127)
		(layer "F.Cu")
		(net "SAS_HDD_RX_N34")
	)
	(segment
		(start 452.113396 -44.213018)
		(end 452.113396 -44.447968)
		(width 0.127)
		(layer "F.Cu")
		(net "SAS_HDD_RX_N34")
	)
	(segment
		(start 452.113396 -44.447968)
		(end 452.240396 -44.574968)
		(width 0.127)
		(layer "F.Cu")
		(net "SAS_HDD_RX_N34")
	)
	(segment
		(start 448.113912 -44.219368)
		(end 448.622928 -44.219368)
		(width 0.127)
		(layer "F.Cu")
		(net "SAS_HDD_RX_N34")
	)
	(segment
		(start 417.07308 -44.219368)
		(end 417.20643 -44.086018)
		(width 0.127)
		(layer "F.Cu")
		(net "SAS_HDD_RX_N33")
	)
	(segment
		(start 416.564064 -44.219368)
		(end 417.07308 -44.219368)
		(width 0.127)
		(layer "F.Cu")
		(net "SAS_HDD_RX_N33")
	)
	(segment
		(start 420.690548 -44.574968)
		(end 422.025064 -44.574968)
		(width 0.127)
		(layer "F.Cu")
		(net "SAS_HDD_RX_N33")
	)
	(segment
		(start 420.436548 -44.086018)
		(end 420.563548 -44.213018)
		(width 0.127)
		(layer "F.Cu")
		(net "SAS_HDD_RX_N33")
	)
	(segment
		(start 417.20643 -44.086018)
		(end 420.436548 -44.086018)
		(width 0.127)
		(layer "F.Cu")
		(net "SAS_HDD_RX_N33")
	)
	(segment
		(start 420.563548 -44.447968)
		(end 420.690548 -44.574968)
		(width 0.127)
		(layer "F.Cu")
		(net "SAS_HDD_RX_N33")
	)
	(segment
		(start 420.563548 -44.213018)
		(end 420.563548 -44.447968)
		(width 0.127)
		(layer "F.Cu")
		(net "SAS_HDD_RX_N33")
	)
	(segment
		(start 385.013962 -44.219368)
		(end 385.472178 -44.219368)
		(width 0.127)
		(layer "F.Cu")
		(net "SAS_HDD_RX_N32")
	)
	(segment
		(start 385.472178 -44.219368)
		(end 385.605528 -44.086018)
		(width 0.127)
		(layer "F.Cu")
		(net "SAS_HDD_RX_N32")
	)
	(segment
		(start 389.140446 -44.574968)
		(end 390.474962 -44.574968)
		(width 0.127)
		(layer "F.Cu")
		(net "SAS_HDD_RX_N32")
	)
	(segment
		(start 389.013446 -44.447968)
		(end 389.140446 -44.574968)
		(width 0.127)
		(layer "F.Cu")
		(net "SAS_HDD_RX_N32")
	)
	(segment
		(start 385.605528 -44.086018)
		(end 388.886446 -44.086018)
		(width 0.127)
		(layer "F.Cu")
		(net "SAS_HDD_RX_N32")
	)
	(segment
		(start 389.013446 -44.213018)
		(end 389.013446 -44.447968)
		(width 0.127)
		(layer "F.Cu")
		(net "SAS_HDD_RX_N32")
	)
	(segment
		(start 388.886446 -44.086018)
		(end 389.013446 -44.213018)
		(width 0.127)
		(layer "F.Cu")
		(net "SAS_HDD_RX_N32")
	)
	(segment
		(start 353.464114 -44.219368)
		(end 353.87153 -44.219368)
		(width 0.127)
		(layer "F.Cu")
		(net "SAS_HDD_RX_N31")
	)
	(segment
		(start 357.590598 -44.574968)
		(end 358.925114 -44.574968)
		(width 0.127)
		(layer "F.Cu")
		(net "SAS_HDD_RX_N31")
	)
	(segment
		(start 357.463598 -44.447968)
		(end 357.590598 -44.574968)
		(width 0.127)
		(layer "F.Cu")
		(net "SAS_HDD_RX_N31")
	)
	(segment
		(start 353.87153 -44.219368)
		(end 354.00488 -44.086018)
		(width 0.127)
		(layer "F.Cu")
		(net "SAS_HDD_RX_N31")
	)
	(segment
		(start 357.336598 -44.086018)
		(end 357.463598 -44.213018)
		(width 0.127)
		(layer "F.Cu")
		(net "SAS_HDD_RX_N31")
	)
	(segment
		(start 357.463598 -44.213018)
		(end 357.463598 -44.447968)
		(width 0.127)
		(layer "F.Cu")
		(net "SAS_HDD_RX_N31")
	)
	(segment
		(start 354.00488 -44.086018)
		(end 357.336598 -44.086018)
		(width 0.127)
		(layer "F.Cu")
		(net "SAS_HDD_RX_N31")
	)
	(segment
		(start 325.913496 -44.447968)
		(end 326.040496 -44.574968)
		(width 0.127)
		(layer "F.Cu")
		(net "SAS_HDD_RX_N30")
	)
	(segment
		(start 321.914012 -44.219368)
		(end 322.397628 -44.219368)
		(width 0.127)
		(layer "F.Cu")
		(net "SAS_HDD_RX_N30")
	)
	(segment
		(start 325.913496 -44.213018)
		(end 325.913496 -44.447968)
		(width 0.127)
		(layer "F.Cu")
		(net "SAS_HDD_RX_N30")
	)
	(segment
		(start 322.397628 -44.219368)
		(end 322.530978 -44.086018)
		(width 0.127)
		(layer "F.Cu")
		(net "SAS_HDD_RX_N30")
	)
	(segment
		(start 326.040496 -44.574968)
		(end 327.375012 -44.574968)
		(width 0.127)
		(layer "F.Cu")
		(net "SAS_HDD_RX_N30")
	)
	(segment
		(start 322.530978 -44.086018)
		(end 325.786496 -44.086018)
		(width 0.127)
		(layer "F.Cu")
		(net "SAS_HDD_RX_N30")
	)
	(segment
		(start 325.786496 -44.086018)
		(end 325.913496 -44.213018)
		(width 0.127)
		(layer "F.Cu")
		(net "SAS_HDD_RX_N30")
	)
	(segment
		(start 126.0094 -274.575016)
		(end 124.674884 -274.575016)
		(width 0.127)
		(layer "F.Cu")
		(net "SAS_HDD_RX_N3")
	)
	(segment
		(start 126.1364 -274.213066)
		(end 126.1364 -274.448016)
		(width 0.127)
		(layer "F.Cu")
		(net "SAS_HDD_RX_N3")
	)
	(segment
		(start 126.502668 -274.219416)
		(end 126.369318 -274.086066)
		(width 0.127)
		(layer "F.Cu")
		(net "SAS_HDD_RX_N3")
	)
	(segment
		(start 126.2634 -274.086066)
		(end 126.1364 -274.213066)
		(width 0.127)
		(layer "F.Cu")
		(net "SAS_HDD_RX_N3")
	)
	(segment
		(start 126.1364 -274.448016)
		(end 126.0094 -274.575016)
		(width 0.127)
		(layer "F.Cu")
		(net "SAS_HDD_RX_N3")
	)
	(segment
		(start 126.369318 -274.086066)
		(end 126.2634 -274.086066)
		(width 0.127)
		(layer "F.Cu")
		(net "SAS_HDD_RX_N3")
	)
	(segment
		(start 126.833884 -274.219416)
		(end 126.502668 -274.219416)
		(width 0.127)
		(layer "F.Cu")
		(net "SAS_HDD_RX_N3")
	)
	(segment
		(start 189.934088 -44.219368)
		(end 189.602872 -44.219368)
		(width 0.127)
		(layer "F.Cu")
		(net "SAS_HDD_RX_N29")
	)
	(segment
		(start 189.236604 -44.213018)
		(end 189.236604 -44.447968)
		(width 0.127)
		(layer "F.Cu")
		(net "SAS_HDD_RX_N29")
	)
	(segment
		(start 189.469522 -44.086018)
		(end 189.363604 -44.086018)
		(width 0.127)
		(layer "F.Cu")
		(net "SAS_HDD_RX_N29")
	)
	(segment
		(start 189.236604 -44.447968)
		(end 189.109604 -44.574968)
		(width 0.127)
		(layer "F.Cu")
		(net "SAS_HDD_RX_N29")
	)
	(segment
		(start 189.602872 -44.219368)
		(end 189.469522 -44.086018)
		(width 0.127)
		(layer "F.Cu")
		(net "SAS_HDD_RX_N29")
	)
	(segment
		(start 189.363604 -44.086018)
		(end 189.236604 -44.213018)
		(width 0.127)
		(layer "F.Cu")
		(net "SAS_HDD_RX_N29")
	)
	(segment
		(start 189.109604 -44.574968)
		(end 187.775088 -44.574968)
		(width 0.127)
		(layer "F.Cu")
		(net "SAS_HDD_RX_N29")
	)
	(segment
		(start 158.05277 -44.219368)
		(end 157.91942 -44.086018)
		(width 0.127)
		(layer "F.Cu")
		(net "SAS_HDD_RX_N28")
	)
	(segment
		(start 157.686502 -44.447968)
		(end 157.559502 -44.574968)
		(width 0.127)
		(layer "F.Cu")
		(net "SAS_HDD_RX_N28")
	)
	(segment
		(start 157.686502 -44.213018)
		(end 157.686502 -44.447968)
		(width 0.127)
		(layer "F.Cu")
		(net "SAS_HDD_RX_N28")
	)
	(segment
		(start 158.383986 -44.219368)
		(end 158.05277 -44.219368)
		(width 0.127)
		(layer "F.Cu")
		(net "SAS_HDD_RX_N28")
	)
	(segment
		(start 157.813502 -44.086018)
		(end 157.686502 -44.213018)
		(width 0.127)
		(layer "F.Cu")
		(net "SAS_HDD_RX_N28")
	)
	(segment
		(start 157.91942 -44.086018)
		(end 157.813502 -44.086018)
		(width 0.127)
		(layer "F.Cu")
		(net "SAS_HDD_RX_N28")
	)
	(segment
		(start 157.559502 -44.574968)
		(end 156.224986 -44.574968)
		(width 0.127)
		(layer "F.Cu")
		(net "SAS_HDD_RX_N28")
	)
	(segment
		(start 126.1364 -44.447968)
		(end 126.0094 -44.574968)
		(width 0.127)
		(layer "F.Cu")
		(net "SAS_HDD_RX_N27")
	)
	(segment
		(start 126.1364 -44.213018)
		(end 126.1364 -44.447968)
		(width 0.127)
		(layer "F.Cu")
		(net "SAS_HDD_RX_N27")
	)
	(segment
		(start 126.2634 -44.086018)
		(end 126.1364 -44.213018)
		(width 0.127)
		(layer "F.Cu")
		(net "SAS_HDD_RX_N27")
	)
	(segment
		(start 126.833884 -44.219368)
		(end 126.502668 -44.219368)
		(width 0.127)
		(layer "F.Cu")
		(net "SAS_HDD_RX_N27")
	)
	(segment
		(start 126.0094 -44.574968)
		(end 124.674884 -44.574968)
		(width 0.127)
		(layer "F.Cu")
		(net "SAS_HDD_RX_N27")
	)
	(segment
		(start 126.502668 -44.219368)
		(end 126.369318 -44.086018)
		(width 0.127)
		(layer "F.Cu")
		(net "SAS_HDD_RX_N27")
	)
	(segment
		(start 126.369318 -44.086018)
		(end 126.2634 -44.086018)
		(width 0.127)
		(layer "F.Cu")
		(net "SAS_HDD_RX_N27")
	)
	(segment
		(start 94.586552 -44.447968)
		(end 94.459552 -44.574968)
		(width 0.127)
		(layer "F.Cu")
		(net "SAS_HDD_RX_N26")
	)
	(segment
		(start 94.713552 -44.086018)
		(end 94.586552 -44.213018)
		(width 0.127)
		(layer "F.Cu")
		(net "SAS_HDD_RX_N26")
	)
	(segment
		(start 94.81947 -44.086018)
		(end 94.713552 -44.086018)
		(width 0.127)
		(layer "F.Cu")
		(net "SAS_HDD_RX_N26")
	)
	(segment
		(start 95.284036 -44.219368)
		(end 94.95282 -44.219368)
		(width 0.127)
		(layer "F.Cu")
		(net "SAS_HDD_RX_N26")
	)
	(segment
		(start 94.586552 -44.213018)
		(end 94.586552 -44.447968)
		(width 0.127)
		(layer "F.Cu")
		(net "SAS_HDD_RX_N26")
	)
	(segment
		(start 94.459552 -44.574968)
		(end 93.125036 -44.574968)
		(width 0.127)
		(layer "F.Cu")
		(net "SAS_HDD_RX_N26")
	)
	(segment
		(start 94.95282 -44.219368)
		(end 94.81947 -44.086018)
		(width 0.127)
		(layer "F.Cu")
		(net "SAS_HDD_RX_N26")
	)
	(segment
		(start 63.733934 -44.219368)
		(end 63.402718 -44.219368)
		(width 0.127)
		(layer "F.Cu")
		(net "SAS_HDD_RX_N25")
	)
	(segment
		(start 63.402718 -44.219368)
		(end 63.269368 -44.086018)
		(width 0.127)
		(layer "F.Cu")
		(net "SAS_HDD_RX_N25")
	)
	(segment
		(start 63.16345 -44.086018)
		(end 63.03645 -44.213018)
		(width 0.127)
		(layer "F.Cu")
		(net "SAS_HDD_RX_N25")
	)
	(segment
		(start 63.269368 -44.086018)
		(end 63.16345 -44.086018)
		(width 0.127)
		(layer "F.Cu")
		(net "SAS_HDD_RX_N25")
	)
	(segment
		(start 62.90945 -44.574968)
		(end 61.574934 -44.574968)
		(width 0.127)
		(layer "F.Cu")
		(net "SAS_HDD_RX_N25")
	)
	(segment
		(start 63.03645 -44.213018)
		(end 63.03645 -44.447968)
		(width 0.127)
		(layer "F.Cu")
		(net "SAS_HDD_RX_N25")
	)
	(segment
		(start 63.03645 -44.447968)
		(end 62.90945 -44.574968)
		(width 0.127)
		(layer "F.Cu")
		(net "SAS_HDD_RX_N25")
	)
	(segment
		(start 32.184086 -44.219368)
		(end 31.85287 -44.219368)
		(width 0.127)
		(layer "F.Cu")
		(net "SAS_HDD_RX_N24")
	)
	(segment
		(start 31.486602 -44.447968)
		(end 31.359602 -44.574968)
		(width 0.127)
		(layer "F.Cu")
		(net "SAS_HDD_RX_N24")
	)
	(segment
		(start 31.613602 -44.086018)
		(end 31.486602 -44.213018)
		(width 0.127)
		(layer "F.Cu")
		(net "SAS_HDD_RX_N24")
	)
	(segment
		(start 31.71952 -44.086018)
		(end 31.613602 -44.086018)
		(width 0.127)
		(layer "F.Cu")
		(net "SAS_HDD_RX_N24")
	)
	(segment
		(start 31.85287 -44.219368)
		(end 31.71952 -44.086018)
		(width 0.127)
		(layer "F.Cu")
		(net "SAS_HDD_RX_N24")
	)
	(segment
		(start 31.359602 -44.574968)
		(end 30.025086 -44.574968)
		(width 0.127)
		(layer "F.Cu")
		(net "SAS_HDD_RX_N24")
	)
	(segment
		(start 31.486602 -44.213018)
		(end 31.486602 -44.447968)
		(width 0.127)
		(layer "F.Cu")
		(net "SAS_HDD_RX_N24")
	)
	(segment
		(start 483.790498 -159.574992)
		(end 485.125014 -159.574992)
		(width 0.127)
		(layer "F.Cu")
		(net "SAS_HDD_RX_N23")
	)
	(segment
		(start 483.536498 -159.086042)
		(end 483.663498 -159.213042)
		(width 0.127)
		(layer "F.Cu")
		(net "SAS_HDD_RX_N23")
	)
	(segment
		(start 483.663498 -159.213042)
		(end 483.663498 -159.447992)
		(width 0.127)
		(layer "F.Cu")
		(net "SAS_HDD_RX_N23")
	)
	(segment
		(start 483.663498 -159.447992)
		(end 483.790498 -159.574992)
		(width 0.127)
		(layer "F.Cu")
		(net "SAS_HDD_RX_N23")
	)
	(segment
		(start 480.38258 -159.086042)
		(end 483.536498 -159.086042)
		(width 0.127)
		(layer "F.Cu")
		(net "SAS_HDD_RX_N23")
	)
	(segment
		(start 480.24923 -159.219392)
		(end 480.38258 -159.086042)
		(width 0.127)
		(layer "F.Cu")
		(net "SAS_HDD_RX_N23")
	)
	(segment
		(start 479.664014 -159.219392)
		(end 480.24923 -159.219392)
		(width 0.127)
		(layer "F.Cu")
		(net "SAS_HDD_RX_N23")
	)
	(segment
		(start 451.986396 -159.086042)
		(end 442.355478 -159.086042)
		(width 0.127)
		(layer "F.Cu")
		(net "SAS_HDD_RX_N22")
	)
	(segment
		(start 452.113396 -159.447992)
		(end 452.113396 -159.213042)
		(width 0.127)
		(layer "F.Cu")
		(net "SAS_HDD_RX_N22")
	)
	(segment
		(start 442.222128 -159.219392)
		(end 441.763912 -159.219392)
		(width 0.127)
		(layer "F.Cu")
		(net "SAS_HDD_RX_N22")
	)
	(segment
		(start 452.240396 -159.574992)
		(end 452.113396 -159.447992)
		(width 0.127)
		(layer "F.Cu")
		(net "SAS_HDD_RX_N22")
	)
	(segment
		(start 452.113396 -159.213042)
		(end 451.986396 -159.086042)
		(width 0.127)
		(layer "F.Cu")
		(net "SAS_HDD_RX_N22")
	)
	(segment
		(start 453.574912 -159.574992)
		(end 452.240396 -159.574992)
		(width 0.127)
		(layer "F.Cu")
		(net "SAS_HDD_RX_N22")
	)
	(segment
		(start 442.355478 -159.086042)
		(end 442.222128 -159.219392)
		(width 0.127)
		(layer "F.Cu")
		(net "SAS_HDD_RX_N22")
	)
	(segment
		(start 416.564064 -159.219392)
		(end 416.99688 -159.219392)
		(width 0.127)
		(layer "F.Cu")
		(net "SAS_HDD_RX_N21")
	)
	(segment
		(start 420.563548 -159.213042)
		(end 420.563548 -159.447992)
		(width 0.127)
		(layer "F.Cu")
		(net "SAS_HDD_RX_N21")
	)
	(segment
		(start 417.13023 -159.086042)
		(end 420.436548 -159.086042)
		(width 0.127)
		(layer "F.Cu")
		(net "SAS_HDD_RX_N21")
	)
	(segment
		(start 420.436548 -159.086042)
		(end 420.563548 -159.213042)
		(width 0.127)
		(layer "F.Cu")
		(net "SAS_HDD_RX_N21")
	)
	(segment
		(start 420.690548 -159.574992)
		(end 422.025064 -159.574992)
		(width 0.127)
		(layer "F.Cu")
		(net "SAS_HDD_RX_N21")
	)
	(segment
		(start 416.99688 -159.219392)
		(end 417.13023 -159.086042)
		(width 0.127)
		(layer "F.Cu")
		(net "SAS_HDD_RX_N21")
	)
	(segment
		(start 420.563548 -159.447992)
		(end 420.690548 -159.574992)
		(width 0.127)
		(layer "F.Cu")
		(net "SAS_HDD_RX_N21")
	)
	(segment
		(start 388.886446 -159.086042)
		(end 389.013446 -159.213042)
		(width 0.127)
		(layer "F.Cu")
		(net "SAS_HDD_RX_N20")
	)
	(segment
		(start 389.013446 -159.447992)
		(end 389.140446 -159.574992)
		(width 0.127)
		(layer "F.Cu")
		(net "SAS_HDD_RX_N20")
	)
	(segment
		(start 389.013446 -159.213042)
		(end 389.013446 -159.447992)
		(width 0.127)
		(layer "F.Cu")
		(net "SAS_HDD_RX_N20")
	)
	(segment
		(start 385.554728 -159.086042)
		(end 388.886446 -159.086042)
		(width 0.127)
		(layer "F.Cu")
		(net "SAS_HDD_RX_N20")
	)
	(segment
		(start 389.140446 -159.574992)
		(end 390.474962 -159.574992)
		(width 0.127)
		(layer "F.Cu")
		(net "SAS_HDD_RX_N20")
	)
	(segment
		(start 385.013962 -159.219392)
		(end 385.421378 -159.219392)
		(width 0.127)
		(layer "F.Cu")
		(net "SAS_HDD_RX_N20")
	)
	(segment
		(start 385.421378 -159.219392)
		(end 385.554728 -159.086042)
		(width 0.127)
		(layer "F.Cu")
		(net "SAS_HDD_RX_N20")
	)
	(segment
		(start 94.459552 -274.575016)
		(end 93.125036 -274.575016)
		(width 0.127)
		(layer "F.Cu")
		(net "SAS_HDD_RX_N2")
	)
	(segment
		(start 94.586552 -274.448016)
		(end 94.459552 -274.575016)
		(width 0.127)
		(layer "F.Cu")
		(net "SAS_HDD_RX_N2")
	)
	(segment
		(start 94.95282 -274.219416)
		(end 94.81947 -274.086066)
		(width 0.127)
		(layer "F.Cu")
		(net "SAS_HDD_RX_N2")
	)
	(segment
		(start 94.81947 -274.086066)
		(end 94.713552 -274.086066)
		(width 0.127)
		(layer "F.Cu")
		(net "SAS_HDD_RX_N2")
	)
	(segment
		(start 94.713552 -274.086066)
		(end 94.586552 -274.213066)
		(width 0.127)
		(layer "F.Cu")
		(net "SAS_HDD_RX_N2")
	)
	(segment
		(start 94.586552 -274.213066)
		(end 94.586552 -274.448016)
		(width 0.127)
		(layer "F.Cu")
		(net "SAS_HDD_RX_N2")
	)
	(segment
		(start 95.284036 -274.219416)
		(end 94.95282 -274.219416)
		(width 0.127)
		(layer "F.Cu")
		(net "SAS_HDD_RX_N2")
	)
	(segment
		(start 357.590598 -159.574992)
		(end 358.925114 -159.574992)
		(width 0.127)
		(layer "F.Cu")
		(net "SAS_HDD_RX_N19")
	)
	(segment
		(start 353.99853 -159.219392)
		(end 354.13188 -159.086042)
		(width 0.127)
		(layer "F.Cu")
		(net "SAS_HDD_RX_N19")
	)
	(segment
		(start 357.463598 -159.447992)
		(end 357.590598 -159.574992)
		(width 0.127)
		(layer "F.Cu")
		(net "SAS_HDD_RX_N19")
	)
	(segment
		(start 353.464114 -159.219392)
		(end 353.99853 -159.219392)
		(width 0.127)
		(layer "F.Cu")
		(net "SAS_HDD_RX_N19")
	)
	(segment
		(start 357.463598 -159.213042)
		(end 357.463598 -159.447992)
		(width 0.127)
		(layer "F.Cu")
		(net "SAS_HDD_RX_N19")
	)
	(segment
		(start 357.336598 -159.086042)
		(end 357.463598 -159.213042)
		(width 0.127)
		(layer "F.Cu")
		(net "SAS_HDD_RX_N19")
	)
	(segment
		(start 354.13188 -159.086042)
		(end 357.336598 -159.086042)
		(width 0.127)
		(layer "F.Cu")
		(net "SAS_HDD_RX_N19")
	)
	(segment
		(start 322.372228 -159.219392)
		(end 322.505578 -159.086042)
		(width 0.127)
		(layer "F.Cu")
		(net "SAS_HDD_RX_N18")
	)
	(segment
		(start 325.786496 -159.086042)
		(end 325.913496 -159.213042)
		(width 0.127)
		(layer "F.Cu")
		(net "SAS_HDD_RX_N18")
	)
	(segment
		(start 325.913496 -159.213042)
		(end 325.913496 -159.447992)
		(width 0.127)
		(layer "F.Cu")
		(net "SAS_HDD_RX_N18")
	)
	(segment
		(start 325.913496 -159.447992)
		(end 326.040496 -159.574992)
		(width 0.127)
		(layer "F.Cu")
		(net "SAS_HDD_RX_N18")
	)
	(segment
		(start 322.505578 -159.086042)
		(end 325.786496 -159.086042)
		(width 0.127)
		(layer "F.Cu")
		(net "SAS_HDD_RX_N18")
	)
	(segment
		(start 326.040496 -159.574992)
		(end 327.375012 -159.574992)
		(width 0.127)
		(layer "F.Cu")
		(net "SAS_HDD_RX_N18")
	)
	(segment
		(start 321.914012 -159.219392)
		(end 322.372228 -159.219392)
		(width 0.127)
		(layer "F.Cu")
		(net "SAS_HDD_RX_N18")
	)
	(segment
		(start 189.934088 -159.219392)
		(end 189.602872 -159.219392)
		(width 0.127)
		(layer "F.Cu")
		(net "SAS_HDD_RX_N17")
	)
	(segment
		(start 189.602872 -159.219392)
		(end 189.469522 -159.086042)
		(width 0.127)
		(layer "F.Cu")
		(net "SAS_HDD_RX_N17")
	)
	(segment
		(start 189.363604 -159.086042)
		(end 189.236604 -159.213042)
		(width 0.127)
		(layer "F.Cu")
		(net "SAS_HDD_RX_N17")
	)
	(segment
		(start 189.236604 -159.447992)
		(end 189.109604 -159.574992)
		(width 0.127)
		(layer "F.Cu")
		(net "SAS_HDD_RX_N17")
	)
	(segment
		(start 189.109604 -159.574992)
		(end 187.775088 -159.574992)
		(width 0.127)
		(layer "F.Cu")
		(net "SAS_HDD_RX_N17")
	)
	(segment
		(start 189.469522 -159.086042)
		(end 189.363604 -159.086042)
		(width 0.127)
		(layer "F.Cu")
		(net "SAS_HDD_RX_N17")
	)
	(segment
		(start 189.236604 -159.213042)
		(end 189.236604 -159.447992)
		(width 0.127)
		(layer "F.Cu")
		(net "SAS_HDD_RX_N17")
	)
	(segment
		(start 158.05277 -159.219392)
		(end 157.91942 -159.086042)
		(width 0.127)
		(layer "F.Cu")
		(net "SAS_HDD_RX_N16")
	)
	(segment
		(start 157.813502 -159.086042)
		(end 157.686502 -159.213042)
		(width 0.127)
		(layer "F.Cu")
		(net "SAS_HDD_RX_N16")
	)
	(segment
		(start 157.91942 -159.086042)
		(end 157.813502 -159.086042)
		(width 0.127)
		(layer "F.Cu")
		(net "SAS_HDD_RX_N16")
	)
	(segment
		(start 157.559502 -159.574992)
		(end 156.224986 -159.574992)
		(width 0.127)
		(layer "F.Cu")
		(net "SAS_HDD_RX_N16")
	)
	(segment
		(start 157.686502 -159.213042)
		(end 157.686502 -159.447992)
		(width 0.127)
		(layer "F.Cu")
		(net "SAS_HDD_RX_N16")
	)
	(segment
		(start 157.686502 -159.447992)
		(end 157.559502 -159.574992)
		(width 0.127)
		(layer "F.Cu")
		(net "SAS_HDD_RX_N16")
	)
	(segment
		(start 158.383986 -159.219392)
		(end 158.05277 -159.219392)
		(width 0.127)
		(layer "F.Cu")
		(net "SAS_HDD_RX_N16")
	)
	(segment
		(start 126.369318 -159.086042)
		(end 126.2634 -159.086042)
		(width 0.127)
		(layer "F.Cu")
		(net "SAS_HDD_RX_N15")
	)
	(segment
		(start 126.502668 -159.219392)
		(end 126.369318 -159.086042)
		(width 0.127)
		(layer "F.Cu")
		(net "SAS_HDD_RX_N15")
	)
	(segment
		(start 126.0094 -159.574992)
		(end 124.674884 -159.574992)
		(width 0.127)
		(layer "F.Cu")
		(net "SAS_HDD_RX_N15")
	)
	(segment
		(start 126.1364 -159.213042)
		(end 126.1364 -159.447992)
		(width 0.127)
		(layer "F.Cu")
		(net "SAS_HDD_RX_N15")
	)
	(segment
		(start 126.833884 -159.219392)
		(end 126.502668 -159.219392)
		(width 0.127)
		(layer "F.Cu")
		(net "SAS_HDD_RX_N15")
	)
	(segment
		(start 126.1364 -159.447992)
		(end 126.0094 -159.574992)
		(width 0.127)
		(layer "F.Cu")
		(net "SAS_HDD_RX_N15")
	)
	(segment
		(start 126.2634 -159.086042)
		(end 126.1364 -159.213042)
		(width 0.127)
		(layer "F.Cu")
		(net "SAS_HDD_RX_N15")
	)
	(segment
		(start 94.586552 -159.447992)
		(end 94.459552 -159.574992)
		(width 0.127)
		(layer "F.Cu")
		(net "SAS_HDD_RX_N14")
	)
	(segment
		(start 94.459552 -159.574992)
		(end 93.125036 -159.574992)
		(width 0.127)
		(layer "F.Cu")
		(net "SAS_HDD_RX_N14")
	)
	(segment
		(start 94.81947 -159.086042)
		(end 94.713552 -159.086042)
		(width 0.127)
		(layer "F.Cu")
		(net "SAS_HDD_RX_N14")
	)
	(segment
		(start 94.713552 -159.086042)
		(end 94.586552 -159.213042)
		(width 0.127)
		(layer "F.Cu")
		(net "SAS_HDD_RX_N14")
	)
	(segment
		(start 94.586552 -159.213042)
		(end 94.586552 -159.447992)
		(width 0.127)
		(layer "F.Cu")
		(net "SAS_HDD_RX_N14")
	)
	(segment
		(start 94.95282 -159.219392)
		(end 94.81947 -159.086042)
		(width 0.127)
		(layer "F.Cu")
		(net "SAS_HDD_RX_N14")
	)
	(segment
		(start 95.284036 -159.219392)
		(end 94.95282 -159.219392)
		(width 0.127)
		(layer "F.Cu")
		(net "SAS_HDD_RX_N14")
	)
	(segment
		(start 63.16345 -159.086042)
		(end 63.03645 -159.213042)
		(width 0.127)
		(layer "F.Cu")
		(net "SAS_HDD_RX_N13")
	)
	(segment
		(start 63.03645 -159.213042)
		(end 63.03645 -159.447992)
		(width 0.127)
		(layer "F.Cu")
		(net "SAS_HDD_RX_N13")
	)
	(segment
		(start 63.402718 -159.219392)
		(end 63.269368 -159.086042)
		(width 0.127)
		(layer "F.Cu")
		(net "SAS_HDD_RX_N13")
	)
	(segment
		(start 63.269368 -159.086042)
		(end 63.16345 -159.086042)
		(width 0.127)
		(layer "F.Cu")
		(net "SAS_HDD_RX_N13")
	)
	(segment
		(start 63.03645 -159.447992)
		(end 62.90945 -159.574992)
		(width 0.127)
		(layer "F.Cu")
		(net "SAS_HDD_RX_N13")
	)
	(segment
		(start 62.90945 -159.574992)
		(end 61.574934 -159.574992)
		(width 0.127)
		(layer "F.Cu")
		(net "SAS_HDD_RX_N13")
	)
	(segment
		(start 63.733934 -159.219392)
		(end 63.402718 -159.219392)
		(width 0.127)
		(layer "F.Cu")
		(net "SAS_HDD_RX_N13")
	)
	(segment
		(start 31.71952 -159.086042)
		(end 31.613602 -159.086042)
		(width 0.127)
		(layer "F.Cu")
		(net "SAS_HDD_RX_N12")
	)
	(segment
		(start 31.486602 -159.213042)
		(end 31.486602 -159.447992)
		(width 0.127)
		(layer "F.Cu")
		(net "SAS_HDD_RX_N12")
	)
	(segment
		(start 31.613602 -159.086042)
		(end 31.486602 -159.213042)
		(width 0.127)
		(layer "F.Cu")
		(net "SAS_HDD_RX_N12")
	)
	(segment
		(start 32.184086 -159.219392)
		(end 31.85287 -159.219392)
		(width 0.127)
		(layer "F.Cu")
		(net "SAS_HDD_RX_N12")
	)
	(segment
		(start 31.486602 -159.447992)
		(end 31.359602 -159.574992)
		(width 0.127)
		(layer "F.Cu")
		(net "SAS_HDD_RX_N12")
	)
	(segment
		(start 31.85287 -159.219392)
		(end 31.71952 -159.086042)
		(width 0.127)
		(layer "F.Cu")
		(net "SAS_HDD_RX_N12")
	)
	(segment
		(start 31.359602 -159.574992)
		(end 30.025086 -159.574992)
		(width 0.127)
		(layer "F.Cu")
		(net "SAS_HDD_RX_N12")
	)
	(segment
		(start 483.663498 -274.213066)
		(end 483.663498 -274.448016)
		(width 0.127)
		(layer "F.Cu")
		(net "SAS_HDD_RX_N11")
	)
	(segment
		(start 483.790498 -274.575016)
		(end 485.125014 -274.575016)
		(width 0.127)
		(layer "F.Cu")
		(net "SAS_HDD_RX_N11")
	)
	(segment
		(start 483.536498 -274.086066)
		(end 483.663498 -274.213066)
		(width 0.127)
		(layer "F.Cu")
		(net "SAS_HDD_RX_N11")
	)
	(segment
		(start 483.663498 -274.448016)
		(end 483.790498 -274.575016)
		(width 0.127)
		(layer "F.Cu")
		(net "SAS_HDD_RX_N11")
	)
	(segment
		(start 480.33178 -274.086066)
		(end 483.536498 -274.086066)
		(width 0.127)
		(layer "F.Cu")
		(net "SAS_HDD_RX_N11")
	)
	(segment
		(start 480.19843 -274.219416)
		(end 480.33178 -274.086066)
		(width 0.127)
		(layer "F.Cu")
		(net "SAS_HDD_RX_N11")
	)
	(segment
		(start 479.664014 -274.219416)
		(end 480.19843 -274.219416)
		(width 0.127)
		(layer "F.Cu")
		(net "SAS_HDD_RX_N11")
	)
	(segment
		(start 452.240396 -274.575016)
		(end 453.574912 -274.575016)
		(width 0.127)
		(layer "F.Cu")
		(net "SAS_HDD_RX_N10")
	)
	(segment
		(start 452.113396 -274.448016)
		(end 452.240396 -274.575016)
		(width 0.127)
		(layer "F.Cu")
		(net "SAS_HDD_RX_N10")
	)
	(segment
		(start 448.730878 -274.086066)
		(end 451.986396 -274.086066)
		(width 0.127)
		(layer "F.Cu")
		(net "SAS_HDD_RX_N10")
	)
	(segment
		(start 448.113912 -274.219416)
		(end 448.597528 -274.219416)
		(width 0.127)
		(layer "F.Cu")
		(net "SAS_HDD_RX_N10")
	)
	(segment
		(start 448.597528 -274.219416)
		(end 448.730878 -274.086066)
		(width 0.127)
		(layer "F.Cu")
		(net "SAS_HDD_RX_N10")
	)
	(segment
		(start 451.986396 -274.086066)
		(end 452.113396 -274.213066)
		(width 0.127)
		(layer "F.Cu")
		(net "SAS_HDD_RX_N10")
	)
	(segment
		(start 452.113396 -274.213066)
		(end 452.113396 -274.448016)
		(width 0.127)
		(layer "F.Cu")
		(net "SAS_HDD_RX_N10")
	)
	(segment
		(start 63.16345 -274.086066)
		(end 63.03645 -274.213066)
		(width 0.127)
		(layer "F.Cu")
		(net "SAS_HDD_RX_N1")
	)
	(segment
		(start 62.90945 -274.575016)
		(end 61.574934 -274.575016)
		(width 0.127)
		(layer "F.Cu")
		(net "SAS_HDD_RX_N1")
	)
	(segment
		(start 63.03645 -274.213066)
		(end 63.03645 -274.448016)
		(width 0.127)
		(layer "F.Cu")
		(net "SAS_HDD_RX_N1")
	)
	(segment
		(start 63.03645 -274.448016)
		(end 62.90945 -274.575016)
		(width 0.127)
		(layer "F.Cu")
		(net "SAS_HDD_RX_N1")
	)
	(segment
		(start 63.402718 -274.219416)
		(end 63.269368 -274.086066)
		(width 0.127)
		(layer "F.Cu")
		(net "SAS_HDD_RX_N1")
	)
	(segment
		(start 63.269368 -274.086066)
		(end 63.16345 -274.086066)
		(width 0.127)
		(layer "F.Cu")
		(net "SAS_HDD_RX_N1")
	)
	(segment
		(start 63.733934 -274.219416)
		(end 63.402718 -274.219416)
		(width 0.127)
		(layer "F.Cu")
		(net "SAS_HDD_RX_N1")
	)
	(segment
		(start 31.613602 -274.086066)
		(end 31.486602 -274.213066)
		(width 0.127)
		(layer "F.Cu")
		(net "SAS_HDD_RX_N0")
	)
	(segment
		(start 31.486602 -274.448016)
		(end 31.359602 -274.575016)
		(width 0.127)
		(layer "F.Cu")
		(net "SAS_HDD_RX_N0")
	)
	(segment
		(start 31.486602 -274.213066)
		(end 31.486602 -274.448016)
		(width 0.127)
		(layer "F.Cu")
		(net "SAS_HDD_RX_N0")
	)
	(segment
		(start 32.184086 -274.219416)
		(end 31.85287 -274.219416)
		(width 0.127)
		(layer "F.Cu")
		(net "SAS_HDD_RX_N0")
	)
	(segment
		(start 31.71952 -274.086066)
		(end 31.613602 -274.086066)
		(width 0.127)
		(layer "F.Cu")
		(net "SAS_HDD_RX_N0")
	)
	(segment
		(start 31.85287 -274.219416)
		(end 31.71952 -274.086066)
		(width 0.127)
		(layer "F.Cu")
		(net "SAS_HDD_RX_N0")
	)
	(segment
		(start 31.359602 -274.575016)
		(end 30.025086 -274.575016)
		(width 0.127)
		(layer "F.Cu")
		(net "SAS_HDD_RX_N0")
	)
	(via
		(at 427.517052 -292.778942)
		(size 0.6604)
		(drill 0.3302)
		(layers "F.Cu" "B.Cu")
		(net "P5V_HDD9")
	)
	(via
		(at 395.96695 -292.778942)
		(size 0.6604)
		(drill 0.3302)
		(layers "F.Cu" "B.Cu")
		(net "P5V_HDD8")
	)
	(via
		(at 364.417102 -292.778942)
		(size 0.6604)
		(drill 0.3302)
		(layers "F.Cu" "B.Cu")
		(net "P5V_HDD7")
	)
	(via
		(at 332.867 -292.778942)
		(size 0.6604)
		(drill 0.3302)
		(layers "F.Cu" "B.Cu")
		(net "P5V_HDD6")
	)
	(via
		(at 177.8254 -289.433)
		(size 0.6604)
		(drill 0.3302)
		(layers "F.Cu" "B.Cu")
		(net "P5V_HDD5")
	)
	(via
		(at 146.304 -289.4838)
		(size 0.6604)
		(drill 0.3302)
		(layers "F.Cu" "B.Cu")
		(net "P5V_HDD4")
	)
	(via
		(at 475.2848 -59.4614)
		(size 0.6604)
		(drill 0.3302)
		(layers "F.Cu" "B.Cu")
		(net "P5V_HDD35")
	)
	(via
		(at 459.0669 -62.778894)
		(size 0.6604)
		(drill 0.3302)
		(layers "F.Cu" "B.Cu")
		(net "P5V_HDD34")
	)
	(via
		(at 427.517052 -62.778894)
		(size 0.6604)
		(drill 0.3302)
		(layers "F.Cu" "B.Cu")
		(net "P5V_HDD33")
	)
	(via
		(at 395.96695 -62.778894)
		(size 0.6604)
		(drill 0.3302)
		(layers "F.Cu" "B.Cu")
		(net "P5V_HDD32")
	)
	(via
		(at 364.417102 -62.778894)
		(size 0.6604)
		(drill 0.3302)
		(layers "F.Cu" "B.Cu")
		(net "P5V_HDD31")
	)
	(via
		(at 332.867 -62.778894)
		(size 0.6604)
		(drill 0.3302)
		(layers "F.Cu" "B.Cu")
		(net "P5V_HDD30")
	)
	(via
		(at 130.625596 -295.064942)
		(size 0.6604)
		(drill 0.3302)
		(layers "F.Cu" "B.Cu")
		(net "P5V_HDD3")
	)
	(via
		(at 177.7746 -59.3598)
		(size 0.6604)
		(drill 0.3302)
		(layers "F.Cu" "B.Cu")
		(net "P5V_HDD29")
	)
	(via
		(at 146.4818 -59.436)
		(size 0.6604)
		(drill 0.3302)
		(layers "F.Cu" "B.Cu")
		(net "P5V_HDD28")
	)
	(via
		(at 114.7572 -59.436)
		(size 0.6604)
		(drill 0.3302)
		(layers "F.Cu" "B.Cu")
		(net "P5V_HDD27")
	)
	(via
		(at 83.2104 -59.436)
		(size 0.6604)
		(drill 0.3302)
		(layers "F.Cu" "B.Cu")
		(net "P5V_HDD26")
	)
	(via
		(at 51.6636 -59.436)
		(size 0.6604)
		(drill 0.3302)
		(layers "F.Cu" "B.Cu")
		(net "P5V_HDD25")
	)
	(via
		(at 20.1168 -59.3852)
		(size 0.6604)
		(drill 0.3302)
		(layers "F.Cu" "B.Cu")
		(net "P5V_HDD24")
	)
	(via
		(at 475.234 -174.3964)
		(size 0.6604)
		(drill 0.3302)
		(layers "F.Cu" "B.Cu")
		(net "P5V_HDD23")
	)
	(via
		(at 459.0669 -177.778918)
		(size 0.6604)
		(drill 0.3302)
		(layers "F.Cu" "B.Cu")
		(net "P5V_HDD22")
	)
	(via
		(at 427.517052 -177.778918)
		(size 0.6604)
		(drill 0.3302)
		(layers "F.Cu" "B.Cu")
		(net "P5V_HDD21")
	)
	(via
		(at 395.96695 -177.778918)
		(size 0.6604)
		(drill 0.3302)
		(layers "F.Cu" "B.Cu")
		(net "P5V_HDD20")
	)
	(via
		(at 83.2104 -289.4076)
		(size 0.6604)
		(drill 0.3302)
		(layers "F.Cu" "B.Cu")
		(net "P5V_HDD2")
	)
	(via
		(at 364.417102 -177.778918)
		(size 0.6604)
		(drill 0.3302)
		(layers "F.Cu" "B.Cu")
		(net "P5V_HDD19")
	)
	(via
		(at 332.867 -177.778918)
		(size 0.6604)
		(drill 0.3302)
		(layers "F.Cu" "B.Cu")
		(net "P5V_HDD18")
	)
	(via
		(at 178.054 -174.4218)
		(size 0.6604)
		(drill 0.3302)
		(layers "F.Cu" "B.Cu")
		(net "P5V_HDD17")
	)
	(via
		(at 146.3802 -174.4472)
		(size 0.6604)
		(drill 0.3302)
		(layers "F.Cu" "B.Cu")
		(net "P5V_HDD16")
	)
	(via
		(at 114.808 -174.3964)
		(size 0.6604)
		(drill 0.3302)
		(layers "F.Cu" "B.Cu")
		(net "P5V_HDD15")
	)
	(via
		(at 83.312 -174.4218)
		(size 0.6604)
		(drill 0.3302)
		(layers "F.Cu" "B.Cu")
		(net "P5V_HDD14")
	)
	(via
		(at 51.7144 -174.4472)
		(size 0.6604)
		(drill 0.3302)
		(layers "F.Cu" "B.Cu")
		(net "P5V_HDD13")
	)
	(via
		(at 20.066 -174.371)
		(size 0.6604)
		(drill 0.3302)
		(layers "F.Cu" "B.Cu")
		(net "P5V_HDD12")
	)
	(via
		(at 476.76943 -289.258248)
		(size 0.6604)
		(drill 0.3302)
		(layers "F.Cu" "B.Cu")
		(net "P5V_HDD11")
	)
	(via
		(at 459.0669 -292.778942)
		(size 0.6604)
		(drill 0.3302)
		(layers "F.Cu" "B.Cu")
		(net "P5V_HDD10")
	)
	(via
		(at 51.5874 -289.433)
		(size 0.6604)
		(drill 0.3302)
		(layers "F.Cu" "B.Cu")
		(net "P5V_HDD1")
	)
	(segment
		(start 235.534708 -348.766892)
		(end 234.7722 -349.5294)
		(width 0.17145)
		(layer "F.Cu")
		(net "P3V3_SENSE")
	)
	(segment
		(start 234.3658 -349.5294)
		(end 234.7722 -349.5294)
		(width 0.17145)
		(layer "F.Cu")
		(net "P3V3_SENSE")
	)
	(segment
		(start 237.996476 -348.766892)
		(end 236.802676 -348.766892)
		(width 0.17145)
		(layer "F.Cu")
		(net "P3V3_SENSE")
	)
	(segment
		(start 234.021122 -349.184722)
		(end 234.3658 -349.5294)
		(width 0.17145)
		(layer "F.Cu")
		(net "P3V3_SENSE")
	)
	(segment
		(start 236.802676 -348.766892)
		(end 235.761276 -348.766892)
		(width 0.17145)
		(layer "F.Cu")
		(net "P3V3_SENSE")
	)
	(segment
		(start 235.761276 -348.766892)
		(end 235.534708 -348.766892)
		(width 0.17145)
		(layer "F.Cu")
		(net "P3V3_SENSE")
	)
	(segment
		(start 233.140504 -349.184722)
		(end 234.021122 -349.184722)
		(width 0.17145)
		(layer "F.Cu")
		(net "P3V3_SENSE")
	)
	(via
		(at 234.7722 -349.5294)
		(size 0.6604)
		(drill 0.3302)
		(layers "F.Cu" "B.Cu")
		(net "P3V3_SENSE")
	)
	(via
		(at 433.56149 -299.945552)
		(size 0.6604)
		(drill 0.3302)
		(layers "F.Cu" "B.Cu")
		(net "P12V_HDD9")
	)
	(via
		(at 397.553942 -301.17542)
		(size 0.6604)
		(drill 0.3302)
		(layers "F.Cu" "B.Cu")
		(net "P12V_HDD8")
	)
	(via
		(at 370.416836 -299.795946)
		(size 0.6604)
		(drill 0.3302)
		(layers "F.Cu" "B.Cu")
		(net "P12V_HDD7")
	)
	(via
		(at 338.894928 -300.091602)
		(size 0.6604)
		(drill 0.3302)
		(layers "F.Cu" "B.Cu")
		(net "P12V_HDD6")
	)
	(via
		(at 175.26 -296.588942)
		(size 0.6604)
		(drill 0.3302)
		(layers "F.Cu" "B.Cu")
		(net "P12V_HDD5")
	)
	(via
		(at 143.709898 -296.588942)
		(size 0.6604)
		(drill 0.3302)
		(layers "F.Cu" "B.Cu")
		(net "P12V_HDD4")
	)
	(via
		(at 472.609926 -66.588894)
		(size 0.6604)
		(drill 0.3302)
		(layers "F.Cu" "B.Cu")
		(net "P12V_HDD35")
	)
	(via
		(at 465.156042 -69.82587)
		(size 0.6604)
		(drill 0.3302)
		(layers "F.Cu" "B.Cu")
		(net "P12V_HDD34")
	)
	(via
		(at 433.486814 -70.095364)
		(size 0.6604)
		(drill 0.3302)
		(layers "F.Cu" "B.Cu")
		(net "P12V_HDD33")
	)
	(via
		(at 402.07311 -69.608192)
		(size 0.6604)
		(drill 0.3302)
		(layers "F.Cu" "B.Cu")
		(net "P12V_HDD32")
	)
	(via
		(at 370.356892 -69.676264)
		(size 0.6604)
		(drill 0.3302)
		(layers "F.Cu" "B.Cu")
		(net "P12V_HDD31")
	)
	(via
		(at 338.971636 -69.811138)
		(size 0.6604)
		(drill 0.3302)
		(layers "F.Cu" "B.Cu")
		(net "P12V_HDD30")
	)
	(via
		(at 115.868196 -296.563542)
		(size 0.6604)
		(drill 0.3302)
		(layers "F.Cu" "B.Cu")
		(net "P12V_HDD3")
	)
	(via
		(at 175.26 -66.588894)
		(size 0.6604)
		(drill 0.3302)
		(layers "F.Cu" "B.Cu")
		(net "P12V_HDD29")
	)
	(via
		(at 143.709898 -66.588894)
		(size 0.6604)
		(drill 0.3302)
		(layers "F.Cu" "B.Cu")
		(net "P12V_HDD28")
	)
	(via
		(at 112.159796 -66.588894)
		(size 0.6604)
		(drill 0.3302)
		(layers "F.Cu" "B.Cu")
		(net "P12V_HDD27")
	)
	(via
		(at 80.609948 -66.588894)
		(size 0.6604)
		(drill 0.3302)
		(layers "F.Cu" "B.Cu")
		(net "P12V_HDD26")
	)
	(via
		(at 49.059846 -66.588894)
		(size 0.6604)
		(drill 0.3302)
		(layers "F.Cu" "B.Cu")
		(net "P12V_HDD25")
	)
	(via
		(at 17.509998 -66.588894)
		(size 0.6604)
		(drill 0.3302)
		(layers "F.Cu" "B.Cu")
		(net "P12V_HDD24")
	)
	(via
		(at 470.923112 -181.273196)
		(size 0.6604)
		(drill 0.3302)
		(layers "F.Cu" "B.Cu")
		(net "P12V_HDD23")
	)
	(via
		(at 465.0359 -185.525918)
		(size 0.6604)
		(drill 0.3302)
		(layers "F.Cu" "B.Cu")
		(net "P12V_HDD22")
	)
	(via
		(at 433.49672 -184.84977)
		(size 0.6604)
		(drill 0.3302)
		(layers "F.Cu" "B.Cu")
		(net "P12V_HDD21")
	)
	(via
		(at 402.00326 -184.73166)
		(size 0.6604)
		(drill 0.3302)
		(layers "F.Cu" "B.Cu")
		(net "P12V_HDD20")
	)
	(via
		(at 80.609948 -296.588942)
		(size 0.6604)
		(drill 0.3302)
		(layers "F.Cu" "B.Cu")
		(net "P12V_HDD2")
	)
	(via
		(at 370.403882 -185.028586)
		(size 0.6604)
		(drill 0.3302)
		(layers "F.Cu" "B.Cu")
		(net "P12V_HDD19")
	)
	(via
		(at 338.93379 -184.55005)
		(size 0.6604)
		(drill 0.3302)
		(layers "F.Cu" "B.Cu")
		(net "P12V_HDD18")
	)
	(via
		(at 175.26 -181.588918)
		(size 0.6604)
		(drill 0.3302)
		(layers "F.Cu" "B.Cu")
		(net "P12V_HDD17")
	)
	(via
		(at 143.709898 -181.588918)
		(size 0.6604)
		(drill 0.3302)
		(layers "F.Cu" "B.Cu")
		(net "P12V_HDD16")
	)
	(via
		(at 112.159796 -181.588918)
		(size 0.6604)
		(drill 0.3302)
		(layers "F.Cu" "B.Cu")
		(net "P12V_HDD15")
	)
	(via
		(at 80.609948 -181.588918)
		(size 0.6604)
		(drill 0.3302)
		(layers "F.Cu" "B.Cu")
		(net "P12V_HDD14")
	)
	(via
		(at 49.059846 -181.588918)
		(size 0.6604)
		(drill 0.3302)
		(layers "F.Cu" "B.Cu")
		(net "P12V_HDD13")
	)
	(via
		(at 17.509998 -181.588918)
		(size 0.6604)
		(drill 0.3302)
		(layers "F.Cu" "B.Cu")
		(net "P12V_HDD12")
	)
	(via
		(at 475.437708 -300.38548)
		(size 0.6604)
		(drill 0.3302)
		(layers "F.Cu" "B.Cu")
		(net "P12V_HDD11")
	)
	(via
		(at 465.096606 -300.080426)
		(size 0.6604)
		(drill 0.3302)
		(layers "F.Cu" "B.Cu")
		(net "P12V_HDD10")
	)
	(via
		(at 49.059846 -296.588942)
		(size 0.6604)
		(drill 0.3302)
		(layers "F.Cu" "B.Cu")
		(net "P12V_HDD1")
	)
	(segment
		(start 254.044196 -259.42671)
		(end 253.603506 -259.8674)
		(width 0.17145)
		(layer "F.Cu")
		(net "IO_EXP6_SDA")
	)
	(segment
		(start 253.603506 -260.880098)
		(end 253.603506 -259.8674)
		(width 0.17145)
		(layer "F.Cu")
		(net "IO_EXP6_SDA")
	)
	(segment
		(start 254.044196 -257.79476)
		(end 254.044196 -259.42671)
		(width 0.17145)
		(layer "F.Cu")
		(net "IO_EXP6_SDA")
	)
	(via
		(at 253.603506 -259.8674)
		(size 0.6604)
		(drill 0.3302)
		(layers "F.Cu" "B.Cu")
		(net "IO_EXP6_SDA")
	)
	(segment
		(start 254.811276 -260.88086)
		(end 254.811276 -259.891276)
		(width 0.17145)
		(layer "F.Cu")
		(net "IO_EXP6_SCL")
	)
	(segment
		(start 254.811276 -259.891276)
		(end 254.762 -259.842)
		(width 0.17145)
		(layer "F.Cu")
		(net "IO_EXP6_SCL")
	)
	(segment
		(start 254.694436 -259.774436)
		(end 254.762 -259.842)
		(width 0.17145)
		(layer "F.Cu")
		(net "IO_EXP6_SCL")
	)
	(segment
		(start 254.694436 -257.79476)
		(end 254.694436 -259.774436)
		(width 0.17145)
		(layer "F.Cu")
		(net "IO_EXP6_SCL")
	)
	(via
		(at 254.762 -259.842)
		(size 0.6604)
		(drill 0.3302)
		(layers "F.Cu" "B.Cu")
		(net "IO_EXP6_SCL")
	)
	(segment
		(start 255.700276 -249.32386)
		(end 255.700276 -250.4694)
		(width 0.17145)
		(layer "F.Cu")
		(net "IO_EXP6_A2")
	)
	(segment
		(start 254.694436 -251.47524)
		(end 255.700276 -250.4694)
		(width 0.17145)
		(layer "F.Cu")
		(net "IO_EXP6_A2")
	)
	(segment
		(start 254.694436 -252.15596)
		(end 254.694436 -251.47524)
		(width 0.17145)
		(layer "F.Cu")
		(net "IO_EXP6_A2")
	)
	(segment
		(start 256.843276 -249.32386)
		(end 255.700276 -249.32386)
		(width 0.17145)
		(layer "F.Cu")
		(net "IO_EXP6_A2")
	)
	(via
		(at 255.700276 -250.4694)
		(size 0.6604)
		(drill 0.3302)
		(layers "F.Cu" "B.Cu")
		(net "IO_EXP6_A2")
	)
	(segment
		(start 253.414276 -249.32386)
		(end 254.557276 -249.32386)
		(width 0.17145)
		(layer "F.Cu")
		(net "IO_EXP6_A1")
	)
	(segment
		(start 254.557276 -249.70613)
		(end 254.044196 -250.21921)
		(width 0.17145)
		(layer "F.Cu")
		(net "IO_EXP6_A1")
	)
	(segment
		(start 254.557276 -249.32386)
		(end 254.557276 -249.70613)
		(width 0.17145)
		(layer "F.Cu")
		(net "IO_EXP6_A1")
	)
	(segment
		(start 254.044196 -250.4694)
		(end 254.044196 -252.15596)
		(width 0.17145)
		(layer "F.Cu")
		(net "IO_EXP6_A1")
	)
	(segment
		(start 254.044196 -250.21921)
		(end 254.044196 -250.4694)
		(width 0.17145)
		(layer "F.Cu")
		(net "IO_EXP6_A1")
	)
	(via
		(at 254.044196 -250.4694)
		(size 0.6604)
		(drill 0.3302)
		(layers "F.Cu" "B.Cu")
		(net "IO_EXP6_A1")
	)
	(segment
		(start 255.852676 -259.207)
		(end 256.3368 -259.207)
		(width 0.17145)
		(layer "F.Cu")
		(net "IO_EXP6_A0")
	)
	(segment
		(start 255.344676 -257.79476)
		(end 255.344676 -258.699)
		(width 0.17145)
		(layer "F.Cu")
		(net "IO_EXP6_A0")
	)
	(segment
		(start 257.173476 -260.90626)
		(end 257.173476 -260.043676)
		(width 0.17145)
		(layer "F.Cu")
		(net "IO_EXP6_A0")
	)
	(segment
		(start 258.367276 -260.90626)
		(end 257.173476 -260.90626)
		(width 0.17145)
		(layer "F.Cu")
		(net "IO_EXP6_A0")
	)
	(segment
		(start 257.173476 -260.043676)
		(end 256.3368 -259.207)
		(width 0.17145)
		(layer "F.Cu")
		(net "IO_EXP6_A0")
	)
	(segment
		(start 255.344676 -258.699)
		(end 255.852676 -259.207)
		(width 0.17145)
		(layer "F.Cu")
		(net "IO_EXP6_A0")
	)
	(via
		(at 256.3368 -259.207)
		(size 0.6604)
		(drill 0.3302)
		(layers "F.Cu" "B.Cu")
		(net "IO_EXP6_A0")
	)
	(segment
		(start 240.4618 -259.1562)
		(end 240.4872 -259.1308)
		(width 0.17145)
		(layer "F.Cu")
		(net "IO_EXP5_SDA")
	)
	(segment
		(start 241.54892 -257.7084)
		(end 241.54892 -258.52628)
		(width 0.17145)
		(layer "F.Cu")
		(net "IO_EXP5_SDA")
	)
	(segment
		(start 240.9444 -259.1308)
		(end 240.4872 -259.1308)
		(width 0.17145)
		(layer "F.Cu")
		(net "IO_EXP5_SDA")
	)
	(segment
		(start 241.54892 -258.52628)
		(end 240.9444 -259.1308)
		(width 0.17145)
		(layer "F.Cu")
		(net "IO_EXP5_SDA")
	)
	(segment
		(start 240.4618 -260.1087)
		(end 240.4618 -259.1562)
		(width 0.17145)
		(layer "F.Cu")
		(net "IO_EXP5_SDA")
	)
	(via
		(at 240.4872 -259.1308)
		(size 0.6604)
		(drill 0.3302)
		(layers "F.Cu" "B.Cu")
		(net "IO_EXP5_SDA")
	)
	(segment
		(start 242.19916 -257.7084)
		(end 242.19916 -258.71424)
		(width 0.17145)
		(layer "F.Cu")
		(net "IO_EXP5_SCL")
	)
	(segment
		(start 241.6048 -259.3086)
		(end 241.7572 -259.1562)
		(width 0.17145)
		(layer "F.Cu")
		(net "IO_EXP5_SCL")
	)
	(segment
		(start 241.6048 -260.1087)
		(end 241.6048 -259.3086)
		(width 0.17145)
		(layer "F.Cu")
		(net "IO_EXP5_SCL")
	)
	(segment
		(start 242.19916 -258.71424)
		(end 241.7572 -259.1562)
		(width 0.17145)
		(layer "F.Cu")
		(net "IO_EXP5_SCL")
	)
	(via
		(at 241.7572 -259.1562)
		(size 0.6604)
		(drill 0.3302)
		(layers "F.Cu" "B.Cu")
		(net "IO_EXP5_SCL")
	)
	(segment
		(start 240.284 -250.204732)
		(end 240.6396 -250.560332)
		(width 0.17145)
		(layer "F.Cu")
		(net "IO_EXP5_INT_N")
	)
	(segment
		(start 240.89868 -250.819412)
		(end 240.6396 -250.560332)
		(width 0.17145)
		(layer "F.Cu")
		(net "IO_EXP5_INT_N")
	)
	(segment
		(start 240.89868 -252.0696)
		(end 240.89868 -250.819412)
		(width 0.17145)
		(layer "F.Cu")
		(net "IO_EXP5_INT_N")
	)
	(segment
		(start 240.284 -249.6185)
		(end 240.284 -250.204732)
		(width 0.17145)
		(layer "F.Cu")
		(net "IO_EXP5_INT_N")
	)
	(via
		(at 240.6396 -250.560332)
		(size 0.6604)
		(drill 0.3302)
		(layers "F.Cu" "B.Cu")
		(net "IO_EXP5_INT_N")
	)
	(segment
		(start 244.856 -249.6185)
		(end 243.713 -249.6185)
		(width 0.17145)
		(layer "F.Cu")
		(net "IO_EXP5_A2")
	)
	(segment
		(start 242.19916 -251.29744)
		(end 242.9002 -250.5964)
		(width 0.17145)
		(layer "F.Cu")
		(net "IO_EXP5_A2")
	)
	(segment
		(start 242.19916 -252.0696)
		(end 242.19916 -251.29744)
		(width 0.17145)
		(layer "F.Cu")
		(net "IO_EXP5_A2")
	)
	(segment
		(start 243.713 -249.7836)
		(end 242.9002 -250.5964)
		(width 0.17145)
		(layer "F.Cu")
		(net "IO_EXP5_A2")
	)
	(segment
		(start 243.713 -249.6185)
		(end 243.713 -249.7836)
		(width 0.17145)
		(layer "F.Cu")
		(net "IO_EXP5_A2")
	)
	(via
		(at 242.9002 -250.5964)
		(size 0.6604)
		(drill 0.3302)
		(layers "F.Cu" "B.Cu")
		(net "IO_EXP5_A2")
	)
	(segment
		(start 242.57 -249.6185)
		(end 241.427 -249.6185)
		(width 0.17145)
		(layer "F.Cu")
		(net "IO_EXP5_A1")
	)
	(segment
		(start 241.427 -249.6185)
		(end 241.427 -250.2916)
		(width 0.17145)
		(layer "F.Cu")
		(net "IO_EXP5_A1")
	)
	(segment
		(start 241.54892 -252.0696)
		(end 241.54892 -251.1806)
		(width 0.17145)
		(layer "F.Cu")
		(net "IO_EXP5_A1")
	)
	(segment
		(start 241.427 -250.2916)
		(end 241.7318 -250.5964)
		(width 0.17145)
		(layer "F.Cu")
		(net "IO_EXP5_A1")
	)
	(segment
		(start 241.7318 -250.99772)
		(end 241.7318 -250.5964)
		(width 0.17145)
		(layer "F.Cu")
		(net "IO_EXP5_A1")
	)
	(segment
		(start 241.54892 -251.1806)
		(end 241.7318 -250.99772)
		(width 0.17145)
		(layer "F.Cu")
		(net "IO_EXP5_A1")
	)
	(via
		(at 241.7318 -250.5964)
		(size 0.6604)
		(drill 0.3302)
		(layers "F.Cu" "B.Cu")
		(net "IO_EXP5_A1")
	)
	(segment
		(start 242.8494 -259.7023)
		(end 242.7478 -259.8039)
		(width 0.17145)
		(layer "F.Cu")
		(net "IO_EXP5_A0")
	)
	(segment
		(start 242.8494 -259.1562)
		(end 242.8494 -257.7084)
		(width 0.17145)
		(layer "F.Cu")
		(net "IO_EXP5_A0")
	)
	(segment
		(start 242.8494 -259.1562)
		(end 242.8494 -259.7023)
		(width 0.17145)
		(layer "F.Cu")
		(net "IO_EXP5_A0")
	)
	(segment
		(start 242.7478 -259.8039)
		(end 242.7478 -260.1087)
		(width 0.17145)
		(layer "F.Cu")
		(net "IO_EXP5_A0")
	)
	(segment
		(start 242.7478 -260.1087)
		(end 243.9416 -260.1087)
		(width 0.17145)
		(layer "F.Cu")
		(net "IO_EXP5_A0")
	)
	(via
		(at 242.8494 -259.1562)
		(size 0.6604)
		(drill 0.3302)
		(layers "F.Cu" "B.Cu")
		(net "IO_EXP5_A0")
	)
	(segment
		(start 236.3724 -249.809)
		(end 235.845604 -250.335796)
		(width 0.17145)
		(layer "F.Cu")
		(net "IO_EXP4_SDA")
	)
	(segment
		(start 236.3724 -249.4153)
		(end 236.3724 -249.809)
		(width 0.17145)
		(layer "F.Cu")
		(net "IO_EXP4_SDA")
	)
	(segment
		(start 234.82808 -251.082556)
		(end 235.57484 -250.335796)
		(width 0.17145)
		(layer "F.Cu")
		(net "IO_EXP4_SDA")
	)
	(segment
		(start 235.845604 -250.335796)
		(end 235.57484 -250.335796)
		(width 0.17145)
		(layer "F.Cu")
		(net "IO_EXP4_SDA")
	)
	(segment
		(start 234.82808 -251.8156)
		(end 234.82808 -251.082556)
		(width 0.17145)
		(layer "F.Cu")
		(net "IO_EXP4_SDA")
	)
	(via
		(at 235.57484 -250.335796)
		(size 0.6604)
		(drill 0.3302)
		(layers "F.Cu" "B.Cu")
		(net "IO_EXP4_SDA")
	)
	(segment
		(start 235.2294 -249.6058)
		(end 234.4674 -250.3678)
		(width 0.17145)
		(layer "F.Cu")
		(net "IO_EXP4_SCL")
	)
	(segment
		(start 234.17784 -251.8156)
		(end 234.17784 -250.65736)
		(width 0.17145)
		(layer "F.Cu")
		(net "IO_EXP4_SCL")
	)
	(segment
		(start 234.17784 -250.65736)
		(end 234.4674 -250.3678)
		(width 0.17145)
		(layer "F.Cu")
		(net "IO_EXP4_SCL")
	)
	(segment
		(start 235.2294 -249.4153)
		(end 235.2294 -249.6058)
		(width 0.17145)
		(layer "F.Cu")
		(net "IO_EXP4_SCL")
	)
	(via
		(at 234.4674 -250.3678)
		(size 0.6604)
		(drill 0.3302)
		(layers "F.Cu" "B.Cu")
		(net "IO_EXP4_SCL")
	)
	(segment
		(start 237.048802 -261.133082)
		(end 237.048802 -260.327902)
		(width 0.17145)
		(layer "F.Cu")
		(net "IO_EXP4_INT_N")
	)
	(segment
		(start 237.048802 -260.327902)
		(end 236.808264 -260.087364)
		(width 0.17145)
		(layer "F.Cu")
		(net "IO_EXP4_INT_N")
	)
	(segment
		(start 235.47832 -257.4544)
		(end 235.47832 -258.75742)
		(width 0.17145)
		(layer "F.Cu")
		(net "IO_EXP4_INT_N")
	)
	(segment
		(start 235.47832 -258.75742)
		(end 236.808264 -260.087364)
		(width 0.17145)
		(layer "F.Cu")
		(net "IO_EXP4_INT_N")
	)
	(via
		(at 236.808264 -260.087364)
		(size 0.6604)
		(drill 0.3302)
		(layers "F.Cu" "B.Cu")
		(net "IO_EXP4_INT_N")
	)
	(segment
		(start 234.17784 -257.4544)
		(end 234.17784 -259.82676)
		(width 0.17145)
		(layer "F.Cu")
		(net "IO_EXP4_A2")
	)
	(segment
		(start 233.903266 -261.277862)
		(end 233.894122 -261.287006)
		(width 0.17145)
		(layer "F.Cu")
		(net "IO_EXP4_A2")
	)
	(segment
		(start 232.859326 -261.287006)
		(end 232.859326 -261.145274)
		(width 0.17145)
		(layer "F.Cu")
		(net "IO_EXP4_A2")
	)
	(segment
		(start 234.17784 -259.82676)
		(end 233.807 -260.1976)
		(width 0.17145)
		(layer "F.Cu")
		(net "IO_EXP4_A2")
	)
	(segment
		(start 232.859326 -261.145274)
		(end 233.807 -260.1976)
		(width 0.17145)
		(layer "F.Cu")
		(net "IO_EXP4_A2")
	)
	(segment
		(start 233.894122 -261.287006)
		(end 232.859326 -261.287006)
		(width 0.17145)
		(layer "F.Cu")
		(net "IO_EXP4_A2")
	)
	(via
		(at 233.807 -260.1976)
		(size 0.6604)
		(drill 0.3302)
		(layers "F.Cu" "B.Cu")
		(net "IO_EXP4_A2")
	)
	(segment
		(start 234.963462 -261.27329)
		(end 234.963462 -260.393942)
		(width 0.17145)
		(layer "F.Cu")
		(net "IO_EXP4_A1")
	)
	(segment
		(start 234.82808 -257.4544)
		(end 234.82808 -259.51688)
		(width 0.17145)
		(layer "F.Cu")
		(net "IO_EXP4_A1")
	)
	(segment
		(start 234.963462 -260.393942)
		(end 235.334302 -260.023102)
		(width 0.17145)
		(layer "F.Cu")
		(net "IO_EXP4_A1")
	)
	(segment
		(start 235.99267 -261.24154)
		(end 235.96092 -261.27329)
		(width 0.17145)
		(layer "F.Cu")
		(net "IO_EXP4_A1")
	)
	(segment
		(start 235.96092 -261.27329)
		(end 234.963462 -261.27329)
		(width 0.17145)
		(layer "F.Cu")
		(net "IO_EXP4_A1")
	)
	(segment
		(start 234.82808 -259.51688)
		(end 235.334302 -260.023102)
		(width 0.17145)
		(layer "F.Cu")
		(net "IO_EXP4_A1")
	)
	(via
		(at 235.334302 -260.023102)
		(size 0.6604)
		(drill 0.3302)
		(layers "F.Cu" "B.Cu")
		(net "IO_EXP4_A1")
	)
	(segment
		(start 232.9434 -249.4153)
		(end 232.9434 -250.0884)
		(width 0.17145)
		(layer "F.Cu")
		(net "IO_EXP4_A0")
	)
	(segment
		(start 234.0864 -249.4153)
		(end 232.9434 -249.4153)
		(width 0.17145)
		(layer "F.Cu")
		(net "IO_EXP4_A0")
	)
	(segment
		(start 233.5276 -251.8156)
		(end 233.5276 -250.6726)
		(width 0.17145)
		(layer "F.Cu")
		(net "IO_EXP4_A0")
	)
	(segment
		(start 233.5276 -250.6726)
		(end 233.22788 -250.37288)
		(width 0.17145)
		(layer "F.Cu")
		(net "IO_EXP4_A0")
	)
	(segment
		(start 232.9434 -250.0884)
		(end 233.22788 -250.37288)
		(width 0.17145)
		(layer "F.Cu")
		(net "IO_EXP4_A0")
	)
	(via
		(at 233.22788 -250.37288)
		(size 0.6604)
		(drill 0.3302)
		(layers "F.Cu" "B.Cu")
		(net "IO_EXP4_A0")
	)
	(segment
		(start 261.28599 -230.785162)
		(end 261.28599 -231.01681)
		(width 0.17145)
		(layer "F.Cu")
		(net "IO_EXP3_SDA")
	)
	(segment
		(start 259.8674 -234.0356)
		(end 259.8674 -232.4354)
		(width 0.17145)
		(layer "F.Cu")
		(net "IO_EXP3_SDA")
	)
	(segment
		(start 261.28599 -231.01681)
		(end 260.4516 -231.8512)
		(width 0.17145)
		(layer "F.Cu")
		(net "IO_EXP3_SDA")
	)
	(segment
		(start 259.8674 -232.4354)
		(end 260.4516 -231.8512)
		(width 0.17145)
		(layer "F.Cu")
		(net "IO_EXP3_SDA")
	)
	(via
		(at 260.4516 -231.8512)
		(size 0.6604)
		(drill 0.3302)
		(layers "F.Cu" "B.Cu")
		(net "IO_EXP3_SDA")
	)
	(segment
		(start 258.882134 -231.464866)
		(end 258.882134 -232.024174)
		(width 0.17145)
		(layer "F.Cu")
		(net "IO_EXP3_SCL")
	)
	(segment
		(start 259.20192 -231.14508)
		(end 258.882134 -231.464866)
		(width 0.17145)
		(layer "F.Cu")
		(net "IO_EXP3_SCL")
	)
	(segment
		(start 259.21716 -232.6132)
		(end 258.882134 -232.278174)
		(width 0.17145)
		(layer "F.Cu")
		(net "IO_EXP3_SCL")
	)
	(segment
		(start 259.20192 -230.6955)
		(end 259.20192 -231.14508)
		(width 0.17145)
		(layer "F.Cu")
		(net "IO_EXP3_SCL")
	)
	(segment
		(start 258.882134 -232.278174)
		(end 258.882134 -232.024174)
		(width 0.17145)
		(layer "F.Cu")
		(net "IO_EXP3_SCL")
	)
	(segment
		(start 259.21716 -234.0356)
		(end 259.21716 -232.6132)
		(width 0.17145)
		(layer "F.Cu")
		(net "IO_EXP3_SCL")
	)
	(via
		(at 258.882134 -232.024174)
		(size 0.6604)
		(drill 0.3302)
		(layers "F.Cu" "B.Cu")
		(net "IO_EXP3_SCL")
	)
	(segment
		(start 265.8237 -233.045)
		(end 267.099542 -231.769158)
		(width 0.17145)
		(layer "F.Cu")
		(net "IO_EXP3_A2")
	)
	(segment
		(start 261.81812 -234.0356)
		(end 261.81812 -233.294936)
		(width 0.17145)
		(layer "F.Cu")
		(net "IO_EXP3_A2")
	)
	(segment
		(start 267.5128 -230.7463)
		(end 267.5128 -231.3559)
		(width 0.17145)
		(layer "F.Cu")
		(net "IO_EXP3_A2")
	)
	(segment
		(start 268.6558 -230.7463)
		(end 267.5128 -230.7463)
		(width 0.17145)
		(layer "F.Cu")
		(net "IO_EXP3_A2")
	)
	(segment
		(start 261.81812 -233.294936)
		(end 262.068056 -233.045)
		(width 0.17145)
		(layer "F.Cu")
		(net "IO_EXP3_A2")
	)
	(segment
		(start 267.5128 -231.3559)
		(end 267.099542 -231.769158)
		(width 0.17145)
		(layer "F.Cu")
		(net "IO_EXP3_A2")
	)
	(segment
		(start 262.068056 -233.045)
		(end 265.8237 -233.045)
		(width 0.17145)
		(layer "F.Cu")
		(net "IO_EXP3_A2")
	)
	(via
		(at 267.099542 -231.769158)
		(size 0.6604)
		(drill 0.3302)
		(layers "F.Cu" "B.Cu")
		(net "IO_EXP3_A2")
	)
	(segment
		(start 264.1346 -232.4354)
		(end 264.70737 -231.86263)
		(width 0.17145)
		(layer "F.Cu")
		(net "IO_EXP3_A1")
	)
	(segment
		(start 265.1506 -231.4194)
		(end 264.70737 -231.86263)
		(width 0.17145)
		(layer "F.Cu")
		(net "IO_EXP3_A1")
	)
	(segment
		(start 261.9502 -232.4354)
		(end 264.1346 -232.4354)
		(width 0.17145)
		(layer "F.Cu")
		(net "IO_EXP3_A1")
	)
	(segment
		(start 265.1506 -230.7463)
		(end 265.1506 -231.4194)
		(width 0.17145)
		(layer "F.Cu")
		(net "IO_EXP3_A1")
	)
	(segment
		(start 261.16788 -234.0356)
		(end 261.16788 -233.21772)
		(width 0.17145)
		(layer "F.Cu")
		(net "IO_EXP3_A1")
	)
	(segment
		(start 266.2936 -230.7463)
		(end 265.1506 -230.7463)
		(width 0.17145)
		(layer "F.Cu")
		(net "IO_EXP3_A1")
	)
	(segment
		(start 261.16788 -233.21772)
		(end 261.9502 -232.4354)
		(width 0.17145)
		(layer "F.Cu")
		(net "IO_EXP3_A1")
	)
	(via
		(at 264.70737 -231.86263)
		(size 0.6604)
		(drill 0.3302)
		(layers "F.Cu" "B.Cu")
		(net "IO_EXP3_A1")
	)
	(segment
		(start 260.65353 -233.004614)
		(end 261.737094 -231.92105)
		(width 0.17145)
		(layer "F.Cu")
		(net "IO_EXP3_A0")
	)
	(segment
		(start 260.51764 -234.0356)
		(end 260.51764 -233.15676)
		(width 0.17145)
		(layer "F.Cu")
		(net "IO_EXP3_A0")
	)
	(segment
		(start 262.7376 -230.7463)
		(end 262.7376 -231.5464)
		(width 0.17145)
		(layer "F.Cu")
		(net "IO_EXP3_A0")
	)
	(segment
		(start 260.65353 -233.02087)
		(end 260.65353 -233.004614)
		(width 0.17145)
		(layer "F.Cu")
		(net "IO_EXP3_A0")
	)
	(segment
		(start 263.9314 -230.7463)
		(end 262.7376 -230.7463)
		(width 0.17145)
		(layer "F.Cu")
		(net "IO_EXP3_A0")
	)
	(segment
		(start 260.51764 -233.15676)
		(end 260.65353 -233.02087)
		(width 0.17145)
		(layer "F.Cu")
		(net "IO_EXP3_A0")
	)
	(segment
		(start 261.75335 -231.92105)
		(end 261.9248 -231.7496)
		(width 0.17145)
		(layer "F.Cu")
		(net "IO_EXP3_A0")
	)
	(segment
		(start 261.9248 -231.7496)
		(end 262.5344 -231.7496)
		(width 0.17145)
		(layer "F.Cu")
		(net "IO_EXP3_A0")
	)
	(segment
		(start 262.7376 -231.5464)
		(end 262.5344 -231.7496)
		(width 0.17145)
		(layer "F.Cu")
		(net "IO_EXP3_A0")
	)
	(segment
		(start 261.737094 -231.92105)
		(end 261.75335 -231.92105)
		(width 0.17145)
		(layer "F.Cu")
		(net "IO_EXP3_A0")
	)
	(via
		(at 262.5344 -231.7496)
		(size 0.6604)
		(drill 0.3302)
		(layers "F.Cu" "B.Cu")
		(net "IO_EXP3_A0")
	)
	(segment
		(start 242.189 -241.2492)
		(end 241.4016 -241.2492)
		(width 0.17145)
		(layer "F.Cu")
		(net "IO_EXP2_SDA")
	)
	(segment
		(start 242.81892 -240.61928)
		(end 242.189 -241.2492)
		(width 0.17145)
		(layer "F.Cu")
		(net "IO_EXP2_SDA")
	)
	(segment
		(start 242.81892 -239.8014)
		(end 242.81892 -240.61928)
		(width 0.17145)
		(layer "F.Cu")
		(net "IO_EXP2_SDA")
	)
	(segment
		(start 241.4016 -241.2492)
		(end 241.4016 -242.2271)
		(width 0.17145)
		(layer "F.Cu")
		(net "IO_EXP2_SDA")
	)
	(via
		(at 241.4016 -241.2492)
		(size 0.6604)
		(drill 0.3302)
		(layers "F.Cu" "B.Cu")
		(net "IO_EXP2_SDA")
	)
	(segment
		(start 243.46916 -240.83264)
		(end 243.0272 -241.2746)
		(width 0.17145)
		(layer "F.Cu")
		(net "IO_EXP2_SCL")
	)
	(segment
		(start 243.46916 -239.8014)
		(end 243.46916 -240.83264)
		(width 0.17145)
		(layer "F.Cu")
		(net "IO_EXP2_SCL")
	)
	(segment
		(start 242.5446 -241.7572)
		(end 243.0272 -241.2746)
		(width 0.17145)
		(layer "F.Cu")
		(net "IO_EXP2_SCL")
	)
	(segment
		(start 242.5446 -242.2271)
		(end 242.5446 -241.7572)
		(width 0.17145)
		(layer "F.Cu")
		(net "IO_EXP2_SCL")
	)
	(via
		(at 243.0272 -241.2746)
		(size 0.6604)
		(drill 0.3302)
		(layers "F.Cu" "B.Cu")
		(net "IO_EXP2_SCL")
	)
	(segment
		(start 242.16868 -232.6386)
		(end 242.14328 -232.6132)
		(width 0.17145)
		(layer "F.Cu")
		(net "IO_EXP2_INT_N")
	)
	(segment
		(start 241.935 -232.40492)
		(end 242.14328 -232.6132)
		(width 0.17145)
		(layer "F.Cu")
		(net "IO_EXP2_INT_N")
	)
	(segment
		(start 241.935 -231.5845)
		(end 241.935 -232.40492)
		(width 0.17145)
		(layer "F.Cu")
		(net "IO_EXP2_INT_N")
	)
	(segment
		(start 242.16868 -234.1626)
		(end 242.16868 -232.6386)
		(width 0.17145)
		(layer "F.Cu")
		(net "IO_EXP2_INT_N")
	)
	(via
		(at 242.14328 -232.6132)
		(size 0.6604)
		(drill 0.3302)
		(layers "F.Cu" "B.Cu")
		(net "IO_EXP2_INT_N")
	)
	(segment
		(start 243.46916 -234.1626)
		(end 243.46916 -233.54284)
		(width 0.17145)
		(layer "F.Cu")
		(net "IO_EXP2_A2")
	)
	(segment
		(start 244.194584 -233.045)
		(end 244.618764 -232.62082)
		(width 0.17145)
		(layer "F.Cu")
		(net "IO_EXP2_A2")
	)
	(segment
		(start 243.967 -233.045)
		(end 244.194584 -233.045)
		(width 0.17145)
		(layer "F.Cu")
		(net "IO_EXP2_A2")
	)
	(segment
		(start 245.364 -231.875584)
		(end 245.364 -231.5845)
		(width 0.17145)
		(layer "F.Cu")
		(net "IO_EXP2_A2")
	)
	(segment
		(start 244.618764 -232.62082)
		(end 245.364 -231.875584)
		(width 0.17145)
		(layer "F.Cu")
		(net "IO_EXP2_A2")
	)
	(segment
		(start 245.364 -231.5845)
		(end 246.507 -231.5845)
		(width 0.17145)
		(layer "F.Cu")
		(net "IO_EXP2_A2")
	)
	(segment
		(start 243.46916 -233.54284)
		(end 243.967 -233.045)
		(width 0.17145)
		(layer "F.Cu")
		(net "IO_EXP2_A2")
	)
	(via
		(at 244.618764 -232.62082)
		(size 0.6604)
		(drill 0.3302)
		(layers "F.Cu" "B.Cu")
		(net "IO_EXP2_A2")
	)
	(segment
		(start 244.221 -231.775)
		(end 244.221 -231.5845)
		(width 0.17145)
		(layer "F.Cu")
		(net "IO_EXP2_A1")
	)
	(segment
		(start 242.81892 -233.17708)
		(end 243.3828 -232.6132)
		(width 0.17145)
		(layer "F.Cu")
		(net "IO_EXP2_A1")
	)
	(segment
		(start 244.221 -231.5845)
		(end 243.078 -231.5845)
		(width 0.17145)
		(layer "F.Cu")
		(net "IO_EXP2_A1")
	)
	(segment
		(start 242.81892 -234.1626)
		(end 242.81892 -233.17708)
		(width 0.17145)
		(layer "F.Cu")
		(net "IO_EXP2_A1")
	)
	(segment
		(start 243.3828 -232.6132)
		(end 244.221 -231.775)
		(width 0.17145)
		(layer "F.Cu")
		(net "IO_EXP2_A1")
	)
	(via
		(at 243.3828 -232.6132)
		(size 0.6604)
		(drill 0.3302)
		(layers "F.Cu" "B.Cu")
		(net "IO_EXP2_A1")
	)
	(segment
		(start 243.6876 -241.681)
		(end 244.1194 -241.2492)
		(width 0.17145)
		(layer "F.Cu")
		(net "IO_EXP2_A0")
	)
	(segment
		(start 243.6876 -242.2271)
		(end 243.6876 -241.681)
		(width 0.17145)
		(layer "F.Cu")
		(net "IO_EXP2_A0")
	)
	(segment
		(start 244.1194 -241.2492)
		(end 244.1194 -239.8014)
		(width 0.17145)
		(layer "F.Cu")
		(net "IO_EXP2_A0")
	)
	(segment
		(start 244.8306 -242.2271)
		(end 243.6876 -242.2271)
		(width 0.17145)
		(layer "F.Cu")
		(net "IO_EXP2_A0")
	)
	(via
		(at 244.1194 -241.2492)
		(size 0.6604)
		(drill 0.3302)
		(layers "F.Cu" "B.Cu")
		(net "IO_EXP2_A0")
	)
	(segment
		(start 234.8484 -232.7148)
		(end 235.7374 -232.7148)
		(width 0.17145)
		(layer "F.Cu")
		(net "IO_EXP1_SDA")
	)
	(segment
		(start 234.19308 -234.1626)
		(end 234.19308 -233.37012)
		(width 0.17145)
		(layer "F.Cu")
		(net "IO_EXP1_SDA")
	)
	(segment
		(start 235.7374 -231.7623)
		(end 235.7374 -232.7148)
		(width 0.17145)
		(layer "F.Cu")
		(net "IO_EXP1_SDA")
	)
	(segment
		(start 234.19308 -233.37012)
		(end 234.8484 -232.7148)
		(width 0.17145)
		(layer "F.Cu")
		(net "IO_EXP1_SDA")
	)
	(via
		(at 235.7374 -232.7148)
		(size 0.6604)
		(drill 0.3302)
		(layers "F.Cu" "B.Cu")
		(net "IO_EXP1_SDA")
	)
	(segment
		(start 234.5944 -232.0544)
		(end 233.9594 -232.6894)
		(width 0.17145)
		(layer "F.Cu")
		(net "IO_EXP1_SCL")
	)
	(segment
		(start 233.54284 -234.1626)
		(end 233.54284 -233.10596)
		(width 0.17145)
		(layer "F.Cu")
		(net "IO_EXP1_SCL")
	)
	(segment
		(start 234.5944 -231.7623)
		(end 234.5944 -232.0544)
		(width 0.17145)
		(layer "F.Cu")
		(net "IO_EXP1_SCL")
	)
	(segment
		(start 233.54284 -233.10596)
		(end 233.9594 -232.6894)
		(width 0.17145)
		(layer "F.Cu")
		(net "IO_EXP1_SCL")
	)
	(via
		(at 233.9594 -232.6894)
		(size 0.6604)
		(drill 0.3302)
		(layers "F.Cu" "B.Cu")
		(net "IO_EXP1_SCL")
	)
	(segment
		(start 237.028736 -242.52174)
		(end 236.20984 -242.52174)
		(width 0.17145)
		(layer "F.Cu")
		(net "IO_EXP1_INT_N")
	)
	(segment
		(start 237.962694 -243.455698)
		(end 237.028736 -242.52174)
		(width 0.17145)
		(layer "F.Cu")
		(net "IO_EXP1_INT_N")
	)
	(segment
		(start 237.962694 -243.702078)
		(end 237.962694 -243.455698)
		(width 0.17145)
		(layer "F.Cu")
		(net "IO_EXP1_INT_N")
	)
	(segment
		(start 234.84332 -241.15522)
		(end 236.20984 -242.52174)
		(width 0.17145)
		(layer "F.Cu")
		(net "IO_EXP1_INT_N")
	)
	(segment
		(start 234.84332 -239.8014)
		(end 234.84332 -241.15522)
		(width 0.17145)
		(layer "F.Cu")
		(net "IO_EXP1_INT_N")
	)
	(via
		(at 236.20984 -242.52174)
		(size 0.6604)
		(drill 0.3302)
		(layers "F.Cu" "B.Cu")
		(net "IO_EXP1_INT_N")
	)
	(segment
		(start 233.54284 -239.8014)
		(end 233.54284 -242.47856)
		(width 0.17145)
		(layer "F.Cu")
		(net "IO_EXP1_A2")
	)
	(segment
		(start 233.54284 -242.47856)
		(end 233.318558 -242.702842)
		(width 0.17145)
		(layer "F.Cu")
		(net "IO_EXP1_A2")
	)
	(segment
		(start 232.791 -243.6749)
		(end 232.791 -243.2304)
		(width 0.17145)
		(layer "F.Cu")
		(net "IO_EXP1_A2")
	)
	(segment
		(start 232.791 -243.2304)
		(end 233.318558 -242.702842)
		(width 0.17145)
		(layer "F.Cu")
		(net "IO_EXP1_A2")
	)
	(segment
		(start 232.795572 -243.670328)
		(end 232.791 -243.6749)
		(width 0.17145)
		(layer "F.Cu")
		(net "IO_EXP1_A2")
	)
	(segment
		(start 233.834178 -243.670328)
		(end 232.795572 -243.670328)
		(width 0.17145)
		(layer "F.Cu")
		(net "IO_EXP1_A2")
	)
	(via
		(at 233.318558 -242.702842)
		(size 0.6604)
		(drill 0.3302)
		(layers "F.Cu" "B.Cu")
		(net "IO_EXP1_A2")
	)
	(segment
		(start 235.676694 -243.347494)
		(end 235.676694 -243.702078)
		(width 0.17145)
		(layer "F.Cu")
		(net "IO_EXP1_A1")
	)
	(segment
		(start 235.676694 -243.702078)
		(end 236.819694 -243.702078)
		(width 0.17145)
		(layer "F.Cu")
		(net "IO_EXP1_A1")
	)
	(segment
		(start 234.69219 -242.36299)
		(end 235.676694 -243.347494)
		(width 0.17145)
		(layer "F.Cu")
		(net "IO_EXP1_A1")
	)
	(segment
		(start 234.19308 -241.86388)
		(end 234.69219 -242.36299)
		(width 0.17145)
		(layer "F.Cu")
		(net "IO_EXP1_A1")
	)
	(segment
		(start 234.19308 -239.8014)
		(end 234.19308 -241.86388)
		(width 0.17145)
		(layer "F.Cu")
		(net "IO_EXP1_A1")
	)
	(via
		(at 234.69219 -242.36299)
		(size 0.6604)
		(drill 0.3302)
		(layers "F.Cu" "B.Cu")
		(net "IO_EXP1_A1")
	)
	(segment
		(start 232.8926 -233.045)
		(end 232.576116 -232.728516)
		(width 0.17145)
		(layer "F.Cu")
		(net "IO_EXP1_A0")
	)
	(segment
		(start 232.8926 -234.1626)
		(end 232.8926 -233.045)
		(width 0.17145)
		(layer "F.Cu")
		(net "IO_EXP1_A0")
	)
	(segment
		(start 232.3084 -232.4608)
		(end 232.576116 -232.728516)
		(width 0.17145)
		(layer "F.Cu")
		(net "IO_EXP1_A0")
	)
	(segment
		(start 232.3084 -231.7623)
		(end 232.3084 -232.4608)
		(width 0.17145)
		(layer "F.Cu")
		(net "IO_EXP1_A0")
	)
	(segment
		(start 233.4514 -231.7623)
		(end 232.3084 -231.7623)
		(width 0.17145)
		(layer "F.Cu")
		(net "IO_EXP1_A0")
	)
	(via
		(at 232.576116 -232.728516)
		(size 0.6604)
		(drill 0.3302)
		(layers "F.Cu" "B.Cu")
		(net "IO_EXP1_A0")
	)
	(segment
		(start 416.353752 -292.169342)
		(end 416.353752 -291.127942)
		(width 0.17145)
		(layer "F.Cu")
		(net "HDD_PRSNT_9")
	)
	(segment
		(start 416.353752 -291.127942)
		(end 416.396678 -291.085016)
		(width 0.17145)
		(layer "F.Cu")
		(net "HDD_PRSNT_9")
	)
	(segment
		(start 416.396678 -291.085016)
		(end 422.025064 -291.085016)
		(width 0.17145)
		(layer "F.Cu")
		(net "HDD_PRSNT_9")
	)
	(segment
		(start 416.341052 -292.182042)
		(end 416.353752 -292.169342)
		(width 0.17145)
		(layer "F.Cu")
		(net "HDD_PRSNT_9")
	)
	(segment
		(start 416.341052 -295.064942)
		(end 416.341052 -292.182042)
		(width 0.17145)
		(layer "F.Cu")
		(net "HDD_PRSNT_9")
	)
	(segment
		(start 381.80645 -292.194742)
		(end 381.80645 -292.612318)
		(width 0.17145)
		(layer "F.Cu")
		(net "HDD_PRSNT_8")
	)
	(segment
		(start 381.80645 -291.127942)
		(end 381.80645 -292.194742)
		(width 0.17145)
		(layer "F.Cu")
		(net "HDD_PRSNT_8")
	)
	(segment
		(start 382.1938 -293.859204)
		(end 382.1938 -295.0718)
		(width 0.17145)
		(layer "F.Cu")
		(net "HDD_PRSNT_8")
	)
	(segment
		(start 390.474962 -291.085016)
		(end 381.849376 -291.085016)
		(width 0.17145)
		(layer "F.Cu")
		(net "HDD_PRSNT_8")
	)
	(segment
		(start 381.849376 -291.085016)
		(end 381.80645 -291.127942)
		(width 0.17145)
		(layer "F.Cu")
		(net "HDD_PRSNT_8")
	)
	(segment
		(start 382.1938 -292.999668)
		(end 382.1938 -293.859204)
		(width 0.17145)
		(layer "F.Cu")
		(net "HDD_PRSNT_8")
	)
	(segment
		(start 381.80645 -292.612318)
		(end 382.1938 -292.999668)
		(width 0.17145)
		(layer "F.Cu")
		(net "HDD_PRSNT_8")
	)
	(via
		(at 382.1938 -293.859204)
		(size 0.6604)
		(drill 0.3302)
		(layers "F.Cu" "B.Cu")
		(net "HDD_PRSNT_8")
	)
	(segment
		(start 350.256602 -293.868602)
		(end 350.256602 -293.5224)
		(width 0.17145)
		(layer "F.Cu")
		(net "HDD_PRSNT_7")
	)
	(segment
		(start 350.52 -295.0718)
		(end 350.52 -294.132)
		(width 0.17145)
		(layer "F.Cu")
		(net "HDD_PRSNT_7")
	)
	(segment
		(start 350.256602 -291.127942)
		(end 350.299528 -291.085016)
		(width 0.17145)
		(layer "F.Cu")
		(net "HDD_PRSNT_7")
	)
	(segment
		(start 350.52 -294.132)
		(end 350.256602 -293.868602)
		(width 0.17145)
		(layer "F.Cu")
		(net "HDD_PRSNT_7")
	)
	(segment
		(start 350.256602 -292.169342)
		(end 350.256602 -291.127942)
		(width 0.17145)
		(layer "F.Cu")
		(net "HDD_PRSNT_7")
	)
	(segment
		(start 350.299528 -291.085016)
		(end 358.925114 -291.085016)
		(width 0.17145)
		(layer "F.Cu")
		(net "HDD_PRSNT_7")
	)
	(segment
		(start 350.256602 -293.5224)
		(end 350.256602 -292.169342)
		(width 0.17145)
		(layer "F.Cu")
		(net "HDD_PRSNT_7")
	)
	(via
		(at 350.256602 -293.5224)
		(size 0.6604)
		(drill 0.3302)
		(layers "F.Cu" "B.Cu")
		(net "HDD_PRSNT_7")
	)
	(segment
		(start 318.7065 -291.127942)
		(end 318.749426 -291.085016)
		(width 0.17145)
		(layer "F.Cu")
		(net "HDD_PRSNT_6")
	)
	(segment
		(start 318.7065 -292.143942)
		(end 318.7065 -291.127942)
		(width 0.17145)
		(layer "F.Cu")
		(net "HDD_PRSNT_6")
	)
	(segment
		(start 318.9732 -295.0972)
		(end 318.9732 -294.259)
		(width 0.17145)
		(layer "F.Cu")
		(net "HDD_PRSNT_6")
	)
	(segment
		(start 318.7065 -293.477442)
		(end 318.7065 -292.143942)
		(width 0.17145)
		(layer "F.Cu")
		(net "HDD_PRSNT_6")
	)
	(segment
		(start 318.9732 -294.259)
		(end 318.7065 -293.9923)
		(width 0.17145)
		(layer "F.Cu")
		(net "HDD_PRSNT_6")
	)
	(segment
		(start 318.7065 -293.9923)
		(end 318.7065 -293.477442)
		(width 0.17145)
		(layer "F.Cu")
		(net "HDD_PRSNT_6")
	)
	(segment
		(start 318.749426 -291.085016)
		(end 327.375012 -291.085016)
		(width 0.17145)
		(layer "F.Cu")
		(net "HDD_PRSNT_6")
	)
	(via
		(at 318.7065 -293.477442)
		(size 0.6604)
		(drill 0.3302)
		(layers "F.Cu" "B.Cu")
		(net "HDD_PRSNT_6")
	)
	(segment
		(start 191.135 -291.6555)
		(end 192.786 -291.6555)
		(width 0.17145)
		(layer "F.Cu")
		(net "HDD_PRSNT_5")
	)
	(segment
		(start 192.786 -291.6555)
		(end 193.1035 -291.973)
		(width 0.17145)
		(layer "F.Cu")
		(net "HDD_PRSNT_5")
	)
	(segment
		(start 193.1035 -293.116)
		(end 193.1035 -293.6875)
		(width 0.17145)
		(layer "F.Cu")
		(net "HDD_PRSNT_5")
	)
	(segment
		(start 187.775088 -291.085016)
		(end 189.609984 -291.085016)
		(width 0.17145)
		(layer "F.Cu")
		(net "HDD_PRSNT_5")
	)
	(segment
		(start 193.1035 -291.973)
		(end 193.1035 -293.116)
		(width 0.17145)
		(layer "F.Cu")
		(net "HDD_PRSNT_5")
	)
	(segment
		(start 192.786 -294.005)
		(end 191.135 -294.005)
		(width 0.17145)
		(layer "F.Cu")
		(net "HDD_PRSNT_5")
	)
	(segment
		(start 190.1825 -290.5125)
		(end 191.135 -290.5125)
		(width 0.17145)
		(layer "F.Cu")
		(net "HDD_PRSNT_5")
	)
	(segment
		(start 189.609984 -291.085016)
		(end 190.1825 -290.5125)
		(width 0.17145)
		(layer "F.Cu")
		(net "HDD_PRSNT_5")
	)
	(segment
		(start 193.1035 -293.6875)
		(end 192.786 -294.005)
		(width 0.17145)
		(layer "F.Cu")
		(net "HDD_PRSNT_5")
	)
	(segment
		(start 191.135 -290.5125)
		(end 191.135 -291.6555)
		(width 0.17145)
		(layer "F.Cu")
		(net "HDD_PRSNT_5")
	)
	(via
		(at 193.1035 -293.116)
		(size 0.6604)
		(drill 0.3302)
		(layers "F.Cu" "B.Cu")
		(net "HDD_PRSNT_5")
	)
	(segment
		(start 161.553398 -291.127942)
		(end 161.510472 -291.085016)
		(width 0.17145)
		(layer "F.Cu")
		(net "HDD_PRSNT_4")
	)
	(segment
		(start 161.553398 -293.540942)
		(end 161.553398 -292.169342)
		(width 0.17145)
		(layer "F.Cu")
		(net "HDD_PRSNT_4")
	)
	(segment
		(start 161.510472 -291.085016)
		(end 156.224986 -291.085016)
		(width 0.17145)
		(layer "F.Cu")
		(net "HDD_PRSNT_4")
	)
	(segment
		(start 161.616898 -295.064942)
		(end 161.553398 -295.001442)
		(width 0.17145)
		(layer "F.Cu")
		(net "HDD_PRSNT_4")
	)
	(segment
		(start 161.553398 -292.169342)
		(end 161.553398 -291.127942)
		(width 0.17145)
		(layer "F.Cu")
		(net "HDD_PRSNT_4")
	)
	(segment
		(start 161.553398 -295.001442)
		(end 161.553398 -293.540942)
		(width 0.17145)
		(layer "F.Cu")
		(net "HDD_PRSNT_4")
	)
	(via
		(at 161.553398 -293.540942)
		(size 0.6604)
		(drill 0.3302)
		(layers "F.Cu" "B.Cu")
		(net "HDD_PRSNT_4")
	)
	(segment
		(start 476.0976 -48.448976)
		(end 476.1611 -48.512476)
		(width 0.17145)
		(layer "F.Cu")
		(net "HDD_PRSNT_35")
	)
	(segment
		(start 478.4725 -48.512476)
		(end 478.917 -48.956976)
		(width 0.17145)
		(layer "F.Cu")
		(net "HDD_PRSNT_35")
	)
	(segment
		(start 478.917 -57.592976)
		(end 482.408992 -61.084968)
		(width 0.17145)
		(layer "F.Cu")
		(net "HDD_PRSNT_35")
	)
	(segment
		(start 476.1611 -48.512476)
		(end 477.2406 -48.512476)
		(width 0.17145)
		(layer "F.Cu")
		(net "HDD_PRSNT_35")
	)
	(segment
		(start 474.853 -48.448976)
		(end 476.0976 -48.448976)
		(width 0.17145)
		(layer "F.Cu")
		(net "HDD_PRSNT_35")
	)
	(segment
		(start 478.917 -48.956976)
		(end 478.917 -57.592976)
		(width 0.17145)
		(layer "F.Cu")
		(net "HDD_PRSNT_35")
	)
	(segment
		(start 482.408992 -61.084968)
		(end 485.125014 -61.084968)
		(width 0.17145)
		(layer "F.Cu")
		(net "HDD_PRSNT_35")
	)
	(segment
		(start 478.282 -48.512476)
		(end 478.4725 -48.512476)
		(width 0.17145)
		(layer "F.Cu")
		(net "HDD_PRSNT_35")
	)
	(segment
		(start 477.2406 -48.512476)
		(end 478.282 -48.512476)
		(width 0.17145)
		(layer "F.Cu")
		(net "HDD_PRSNT_35")
	)
	(via
		(at 476.0976 -48.448976)
		(size 0.6604)
		(drill 0.3302)
		(layers "F.Cu" "B.Cu")
		(net "HDD_PRSNT_35")
	)
	(segment
		(start 445.482726 -61.084968)
		(end 453.574912 -61.084968)
		(width 0.17145)
		(layer "F.Cu")
		(net "HDD_PRSNT_34")
	)
	(segment
		(start 445.4017 -63.515494)
		(end 445.4652 -63.451994)
		(width 0.17145)
		(layer "F.Cu")
		(net "HDD_PRSNT_34")
	)
	(segment
		(start 445.4652 -63.451994)
		(end 445.4652 -62.143894)
		(width 0.17145)
		(layer "F.Cu")
		(net "HDD_PRSNT_34")
	)
	(segment
		(start 445.4017 -65.039494)
		(end 445.4017 -63.515494)
		(width 0.17145)
		(layer "F.Cu")
		(net "HDD_PRSNT_34")
	)
	(segment
		(start 445.4652 -61.102494)
		(end 445.482726 -61.084968)
		(width 0.17145)
		(layer "F.Cu")
		(net "HDD_PRSNT_34")
	)
	(segment
		(start 445.4652 -62.143894)
		(end 445.4652 -61.102494)
		(width 0.17145)
		(layer "F.Cu")
		(net "HDD_PRSNT_34")
	)
	(via
		(at 445.4017 -63.515494)
		(size 0.6604)
		(drill 0.3302)
		(layers "F.Cu" "B.Cu")
		(net "HDD_PRSNT_34")
	)
	(segment
		(start 413.762952 -62.143894)
		(end 413.762952 -63.451994)
		(width 0.17145)
		(layer "F.Cu")
		(net "HDD_PRSNT_33")
	)
	(segment
		(start 413.762952 -61.102494)
		(end 413.762952 -62.143894)
		(width 0.17145)
		(layer "F.Cu")
		(net "HDD_PRSNT_33")
	)
	(segment
		(start 413.762952 -63.451994)
		(end 413.699452 -63.515494)
		(width 0.17145)
		(layer "F.Cu")
		(net "HDD_PRSNT_33")
	)
	(segment
		(start 413.699452 -65.039494)
		(end 413.699452 -63.515494)
		(width 0.17145)
		(layer "F.Cu")
		(net "HDD_PRSNT_33")
	)
	(segment
		(start 413.780478 -61.084968)
		(end 413.762952 -61.102494)
		(width 0.17145)
		(layer "F.Cu")
		(net "HDD_PRSNT_33")
	)
	(segment
		(start 422.025064 -61.084968)
		(end 413.780478 -61.084968)
		(width 0.17145)
		(layer "F.Cu")
		(net "HDD_PRSNT_33")
	)
	(via
		(at 413.699452 -63.515494)
		(size 0.6604)
		(drill 0.3302)
		(layers "F.Cu" "B.Cu")
		(net "HDD_PRSNT_33")
	)
	(segment
		(start 381.76835 -65.039494)
		(end 381.76835 -63.515494)
		(width 0.17145)
		(layer "F.Cu")
		(net "HDD_PRSNT_32")
	)
	(segment
		(start 381.76835 -63.515494)
		(end 381.83185 -63.451994)
		(width 0.17145)
		(layer "F.Cu")
		(net "HDD_PRSNT_32")
	)
	(segment
		(start 381.83185 -61.102494)
		(end 381.849376 -61.084968)
		(width 0.17145)
		(layer "F.Cu")
		(net "HDD_PRSNT_32")
	)
	(segment
		(start 381.83185 -62.143894)
		(end 381.83185 -61.102494)
		(width 0.17145)
		(layer "F.Cu")
		(net "HDD_PRSNT_32")
	)
	(segment
		(start 381.849376 -61.084968)
		(end 390.474962 -61.084968)
		(width 0.17145)
		(layer "F.Cu")
		(net "HDD_PRSNT_32")
	)
	(segment
		(start 381.83185 -63.451994)
		(end 381.83185 -62.143894)
		(width 0.17145)
		(layer "F.Cu")
		(net "HDD_PRSNT_32")
	)
	(via
		(at 381.76835 -63.515494)
		(size 0.6604)
		(drill 0.3302)
		(layers "F.Cu" "B.Cu")
		(net "HDD_PRSNT_32")
	)
	(segment
		(start 350.764602 -61.127894)
		(end 350.764602 -62.18555)
		(width 0.17145)
		(layer "F.Cu")
		(net "HDD_PRSNT_31")
	)
	(segment
		(start 350.701102 -65.064894)
		(end 350.701102 -63.8556)
		(width 0.17145)
		(layer "F.Cu")
		(net "HDD_PRSNT_31")
	)
	(segment
		(start 350.763586 -62.186566)
		(end 350.763586 -63.47841)
		(width 0.17145)
		(layer "F.Cu")
		(net "HDD_PRSNT_31")
	)
	(segment
		(start 350.807528 -61.084968)
		(end 350.764602 -61.127894)
		(width 0.17145)
		(layer "F.Cu")
		(net "HDD_PRSNT_31")
	)
	(segment
		(start 350.764602 -62.18555)
		(end 350.763586 -62.186566)
		(width 0.17145)
		(layer "F.Cu")
		(net "HDD_PRSNT_31")
	)
	(segment
		(start 358.925114 -61.084968)
		(end 350.807528 -61.084968)
		(width 0.17145)
		(layer "F.Cu")
		(net "HDD_PRSNT_31")
	)
	(segment
		(start 350.763586 -63.47841)
		(end 350.701102 -63.540894)
		(width 0.17145)
		(layer "F.Cu")
		(net "HDD_PRSNT_31")
	)
	(segment
		(start 350.701102 -63.540894)
		(end 350.701102 -63.8556)
		(width 0.17145)
		(layer "F.Cu")
		(net "HDD_PRSNT_31")
	)
	(via
		(at 350.701102 -63.8556)
		(size 0.6604)
		(drill 0.3302)
		(layers "F.Cu" "B.Cu")
		(net "HDD_PRSNT_31")
	)
	(segment
		(start 319.151 -63.540894)
		(end 319.2145 -63.477394)
		(width 0.17145)
		(layer "F.Cu")
		(net "HDD_PRSNT_30")
	)
	(segment
		(start 319.2145 -62.194694)
		(end 319.2145 -61.127894)
		(width 0.17145)
		(layer "F.Cu")
		(net "HDD_PRSNT_30")
	)
	(segment
		(start 319.257426 -61.084968)
		(end 319.2145 -61.127894)
		(width 0.17145)
		(layer "F.Cu")
		(net "HDD_PRSNT_30")
	)
	(segment
		(start 319.2145 -63.477394)
		(end 319.2145 -62.194694)
		(width 0.17145)
		(layer "F.Cu")
		(net "HDD_PRSNT_30")
	)
	(segment
		(start 319.151 -65.064894)
		(end 319.151 -63.540894)
		(width 0.17145)
		(layer "F.Cu")
		(net "HDD_PRSNT_30")
	)
	(segment
		(start 327.375012 -61.084968)
		(end 319.257426 -61.084968)
		(width 0.17145)
		(layer "F.Cu")
		(net "HDD_PRSNT_30")
	)
	(via
		(at 319.151 -63.540894)
		(size 0.6604)
		(drill 0.3302)
		(layers "F.Cu" "B.Cu")
		(net "HDD_PRSNT_30")
	)
	(segment
		(start 126.955296 -291.077142)
		(end 126.955296 -290.061142)
		(width 0.17145)
		(layer "F.Cu")
		(net "HDD_PRSNT_3")
	)
	(segment
		(start 124.674884 -291.085016)
		(end 126.947422 -291.085016)
		(width 0.17145)
		(layer "F.Cu")
		(net "HDD_PRSNT_3")
	)
	(segment
		(start 126.955296 -290.061142)
		(end 126.955296 -287.254442)
		(width 0.17145)
		(layer "F.Cu")
		(net "HDD_PRSNT_3")
	)
	(segment
		(start 126.947422 -291.085016)
		(end 126.955296 -291.077142)
		(width 0.17145)
		(layer "F.Cu")
		(net "HDD_PRSNT_3")
	)
	(segment
		(start 126.955296 -287.254442)
		(end 126.967996 -287.241742)
		(width 0.17145)
		(layer "F.Cu")
		(net "HDD_PRSNT_3")
	)
	(segment
		(start 190.3603 -52.197)
		(end 190.3603 -53.2384)
		(width 0.17145)
		(layer "F.Cu")
		(net "HDD_PRSNT_29")
	)
	(segment
		(start 192.532 -56.769)
		(end 192.532 -59.817)
		(width 0.17145)
		(layer "F.Cu")
		(net "HDD_PRSNT_29")
	)
	(segment
		(start 192.28308 -40.545512)
		(end 192.28308 -40.561768)
		(width 0.17145)
		(layer "F.Cu")
		(net "HDD_PRSNT_29")
	)
	(segment
		(start 190.3603 -54.5973)
		(end 192.532 -56.769)
		(width 0.17145)
		(layer "F.Cu")
		(net "HDD_PRSNT_29")
	)
	(segment
		(start 191.264032 -61.084968)
		(end 187.775088 -61.084968)
		(width 0.17145)
		(layer "F.Cu")
		(net "HDD_PRSNT_29")
	)
	(segment
		(start 190.3603 -53.2384)
		(end 190.3603 -54.5973)
		(width 0.17145)
		(layer "F.Cu")
		(net "HDD_PRSNT_29")
	)
	(segment
		(start 190.3603 -50.739294)
		(end 189.799468 -50.178462)
		(width 0.17145)
		(layer "F.Cu")
		(net "HDD_PRSNT_29")
	)
	(segment
		(start 190.3603 -52.197)
		(end 190.3603 -50.739294)
		(width 0.17145)
		(layer "F.Cu")
		(net "HDD_PRSNT_29")
	)
	(segment
		(start 192.532 -59.817)
		(end 191.264032 -61.084968)
		(width 0.17145)
		(layer "F.Cu")
		(net "HDD_PRSNT_29")
	)
	(segment
		(start 190.807086 -40.545512)
		(end 192.28308 -40.545512)
		(width 0.17145)
		(layer "F.Cu")
		(net "HDD_PRSNT_29")
	)
	(via
		(at 189.799468 -50.178462)
		(size 0.5588)
		(drill 0.3048)
		(layers "F.Cu" "B.Cu")
		(net "HDD_PRSNT_29")
	)
	(via
		(at 192.28308 -40.561768)
		(size 0.5588)
		(drill 0.3048)
		(layers "F.Cu" "B.Cu")
		(net "HDD_PRSNT_29")
	)
	(via
		(at 192.532 -56.769)
		(size 0.6604)
		(drill 0.3302)
		(layers "F.Cu" "B.Cu")
		(net "HDD_PRSNT_29")
	)
	(segment
		(start 191.263524 -41.581324)
		(end 191.263524 -49.556162)
		(width 0.12065)
		(layer "In4.Cu")
		(net "HDD_PRSNT_29")
	)
	(segment
		(start 192.28308 -40.561768)
		(end 191.263524 -41.581324)
		(width 0.12065)
		(layer "In4.Cu")
		(net "HDD_PRSNT_29")
	)
	(segment
		(start 191.263524 -49.556162)
		(end 190.641224 -50.178462)
		(width 0.12065)
		(layer "In4.Cu")
		(net "HDD_PRSNT_29")
	)
	(segment
		(start 190.641224 -50.178462)
		(end 189.799468 -50.178462)
		(width 0.12065)
		(layer "In4.Cu")
		(net "HDD_PRSNT_29")
	)
	(segment
		(start 161.553398 -62.169294)
		(end 161.553398 -61.127894)
		(width 0.17145)
		(layer "F.Cu")
		(net "HDD_PRSNT_28")
	)
	(segment
		(start 161.553398 -65.001394)
		(end 161.616898 -65.064894)
		(width 0.17145)
		(layer "F.Cu")
		(net "HDD_PRSNT_28")
	)
	(segment
		(start 161.553398 -61.127894)
		(end 161.510472 -61.084968)
		(width 0.17145)
		(layer "F.Cu")
		(net "HDD_PRSNT_28")
	)
	(segment
		(start 161.553398 -63.540894)
		(end 161.553398 -65.001394)
		(width 0.17145)
		(layer "F.Cu")
		(net "HDD_PRSNT_28")
	)
	(segment
		(start 161.553398 -62.169294)
		(end 161.553398 -63.540894)
		(width 0.17145)
		(layer "F.Cu")
		(net "HDD_PRSNT_28")
	)
	(segment
		(start 161.510472 -61.084968)
		(end 156.224986 -61.084968)
		(width 0.17145)
		(layer "F.Cu")
		(net "HDD_PRSNT_28")
	)
	(via
		(at 161.553398 -63.540894)
		(size 0.6604)
		(drill 0.3302)
		(layers "F.Cu" "B.Cu")
		(net "HDD_PRSNT_28")
	)
	(segment
		(start 130.003296 -61.127894)
		(end 129.96037 -61.084968)
		(width 0.17145)
		(layer "F.Cu")
		(net "HDD_PRSNT_27")
	)
	(segment
		(start 130.003296 -62.143894)
		(end 130.003296 -63.540894)
		(width 0.17145)
		(layer "F.Cu")
		(net "HDD_PRSNT_27")
	)
	(segment
		(start 130.003296 -65.001394)
		(end 130.066796 -65.064894)
		(width 0.17145)
		(layer "F.Cu")
		(net "HDD_PRSNT_27")
	)
	(segment
		(start 129.96037 -61.084968)
		(end 124.674884 -61.084968)
		(width 0.17145)
		(layer "F.Cu")
		(net "HDD_PRSNT_27")
	)
	(segment
		(start 130.003296 -63.540894)
		(end 130.003296 -65.001394)
		(width 0.17145)
		(layer "F.Cu")
		(net "HDD_PRSNT_27")
	)
	(segment
		(start 130.003296 -62.143894)
		(end 130.003296 -61.127894)
		(width 0.17145)
		(layer "F.Cu")
		(net "HDD_PRSNT_27")
	)
	(via
		(at 130.003296 -63.540894)
		(size 0.6604)
		(drill 0.3302)
		(layers "F.Cu" "B.Cu")
		(net "HDD_PRSNT_27")
	)
	(segment
		(start 98.453448 -61.127894)
		(end 98.410522 -61.084968)
		(width 0.17145)
		(layer "F.Cu")
		(net "HDD_PRSNT_26")
	)
	(segment
		(start 98.453448 -63.769494)
		(end 98.453448 -62.169294)
		(width 0.17145)
		(layer "F.Cu")
		(net "HDD_PRSNT_26")
	)
	(segment
		(start 98.516948 -65.064894)
		(end 98.453448 -65.001394)
		(width 0.17145)
		(layer "F.Cu")
		(net "HDD_PRSNT_26")
	)
	(segment
		(start 98.453448 -62.169294)
		(end 98.453448 -61.127894)
		(width 0.17145)
		(layer "F.Cu")
		(net "HDD_PRSNT_26")
	)
	(segment
		(start 98.453448 -65.001394)
		(end 98.453448 -63.769494)
		(width 0.17145)
		(layer "F.Cu")
		(net "HDD_PRSNT_26")
	)
	(segment
		(start 98.410522 -61.084968)
		(end 93.125036 -61.084968)
		(width 0.17145)
		(layer "F.Cu")
		(net "HDD_PRSNT_26")
	)
	(via
		(at 98.453448 -63.769494)
		(size 0.6604)
		(drill 0.3302)
		(layers "F.Cu" "B.Cu")
		(net "HDD_PRSNT_26")
	)
	(segment
		(start 66.903346 -65.001394)
		(end 66.966846 -65.064894)
		(width 0.17145)
		(layer "F.Cu")
		(net "HDD_PRSNT_25")
	)
	(segment
		(start 66.903346 -63.540894)
		(end 66.903346 -65.001394)
		(width 0.17145)
		(layer "F.Cu")
		(net "HDD_PRSNT_25")
	)
	(segment
		(start 66.86042 -61.084968)
		(end 61.574934 -61.084968)
		(width 0.17145)
		(layer "F.Cu")
		(net "HDD_PRSNT_25")
	)
	(segment
		(start 66.903346 -61.127894)
		(end 66.86042 -61.084968)
		(width 0.17145)
		(layer "F.Cu")
		(net "HDD_PRSNT_25")
	)
	(segment
		(start 66.903346 -62.169294)
		(end 66.903346 -63.540894)
		(width 0.17145)
		(layer "F.Cu")
		(net "HDD_PRSNT_25")
	)
	(segment
		(start 66.903346 -62.169294)
		(end 66.903346 -61.127894)
		(width 0.17145)
		(layer "F.Cu")
		(net "HDD_PRSNT_25")
	)
	(via
		(at 66.903346 -63.540894)
		(size 0.6604)
		(drill 0.3302)
		(layers "F.Cu" "B.Cu")
		(net "HDD_PRSNT_25")
	)
	(segment
		(start 35.310572 -61.084968)
		(end 30.025086 -61.084968)
		(width 0.17145)
		(layer "F.Cu")
		(net "HDD_PRSNT_24")
	)
	(segment
		(start 35.353498 -63.540894)
		(end 35.353498 -65.001394)
		(width 0.17145)
		(layer "F.Cu")
		(net "HDD_PRSNT_24")
	)
	(segment
		(start 35.353498 -62.169294)
		(end 35.353498 -61.127894)
		(width 0.17145)
		(layer "F.Cu")
		(net "HDD_PRSNT_24")
	)
	(segment
		(start 35.353498 -61.127894)
		(end 35.310572 -61.084968)
		(width 0.17145)
		(layer "F.Cu")
		(net "HDD_PRSNT_24")
	)
	(segment
		(start 35.353498 -65.001394)
		(end 35.416998 -65.064894)
		(width 0.17145)
		(layer "F.Cu")
		(net "HDD_PRSNT_24")
	)
	(segment
		(start 35.353498 -62.169294)
		(end 35.353498 -63.540894)
		(width 0.17145)
		(layer "F.Cu")
		(net "HDD_PRSNT_24")
	)
	(via
		(at 35.353498 -63.540894)
		(size 0.6604)
		(drill 0.3302)
		(layers "F.Cu" "B.Cu")
		(net "HDD_PRSNT_24")
	)
	(segment
		(start 478.917 -172.593)
		(end 478.917 -163.957)
		(width 0.17145)
		(layer "F.Cu")
		(net "HDD_PRSNT_23")
	)
	(segment
		(start 478.917 -163.957)
		(end 478.4725 -163.5125)
		(width 0.17145)
		(layer "F.Cu")
		(net "HDD_PRSNT_23")
	)
	(segment
		(start 478.4725 -163.5125)
		(end 478.282 -163.5125)
		(width 0.17145)
		(layer "F.Cu")
		(net "HDD_PRSNT_23")
	)
	(segment
		(start 478.282 -163.5125)
		(end 477.2406 -163.5125)
		(width 0.17145)
		(layer "F.Cu")
		(net "HDD_PRSNT_23")
	)
	(segment
		(start 482.408992 -176.084992)
		(end 478.917 -172.593)
		(width 0.17145)
		(layer "F.Cu")
		(net "HDD_PRSNT_23")
	)
	(segment
		(start 474.853 -163.449)
		(end 476.123 -163.449)
		(width 0.17145)
		(layer "F.Cu")
		(net "HDD_PRSNT_23")
	)
	(segment
		(start 476.1865 -163.5125)
		(end 476.123 -163.449)
		(width 0.17145)
		(layer "F.Cu")
		(net "HDD_PRSNT_23")
	)
	(segment
		(start 485.125014 -176.084992)
		(end 482.408992 -176.084992)
		(width 0.17145)
		(layer "F.Cu")
		(net "HDD_PRSNT_23")
	)
	(segment
		(start 477.2406 -163.5125)
		(end 476.1865 -163.5125)
		(width 0.17145)
		(layer "F.Cu")
		(net "HDD_PRSNT_23")
	)
	(via
		(at 476.123 -163.449)
		(size 0.6604)
		(drill 0.3302)
		(layers "F.Cu" "B.Cu")
		(net "HDD_PRSNT_23")
	)
	(segment
		(start 447.167 -184.15)
		(end 447.167 -183.1975)
		(width 0.17145)
		(layer "F.Cu")
		(net "HDD_PRSNT_22")
	)
	(segment
		(start 445.886586 -180.63464)
		(end 445.886586 -181.66334)
		(width 0.17145)
		(layer "F.Cu")
		(net "HDD_PRSNT_22")
	)
	(segment
		(start 445.886586 -180.63464)
		(end 445.886586 -178.651916)
		(width 0.17145)
		(layer "F.Cu")
		(net "HDD_PRSNT_22")
	)
	(segment
		(start 448.45351 -176.084992)
		(end 453.574912 -176.084992)
		(width 0.17145)
		(layer "F.Cu")
		(net "HDD_PRSNT_22")
	)
	(segment
		(start 446.214246 -181.991)
		(end 446.9765 -181.991)
		(width 0.17145)
		(layer "F.Cu")
		(net "HDD_PRSNT_22")
	)
	(segment
		(start 446.9765 -183.007)
		(end 446.9765 -181.991)
		(width 0.17145)
		(layer "F.Cu")
		(net "HDD_PRSNT_22")
	)
	(segment
		(start 445.886586 -181.66334)
		(end 446.214246 -181.991)
		(width 0.17145)
		(layer "F.Cu")
		(net "HDD_PRSNT_22")
	)
	(segment
		(start 445.886586 -178.651916)
		(end 448.45351 -176.084992)
		(width 0.17145)
		(layer "F.Cu")
		(net "HDD_PRSNT_22")
	)
	(segment
		(start 447.167 -183.1975)
		(end 446.9765 -183.007)
		(width 0.17145)
		(layer "F.Cu")
		(net "HDD_PRSNT_22")
	)
	(via
		(at 445.886586 -180.63464)
		(size 0.6604)
		(drill 0.3302)
		(layers "F.Cu" "B.Cu")
		(net "HDD_PRSNT_22")
	)
	(segment
		(start 413.293052 -178.540918)
		(end 413.356552 -178.477418)
		(width 0.17145)
		(layer "F.Cu")
		(net "HDD_PRSNT_21")
	)
	(segment
		(start 413.356552 -177.169318)
		(end 413.356552 -176.127918)
		(width 0.17145)
		(layer "F.Cu")
		(net "HDD_PRSNT_21")
	)
	(segment
		(start 413.356552 -178.477418)
		(end 413.356552 -177.169318)
		(width 0.17145)
		(layer "F.Cu")
		(net "HDD_PRSNT_21")
	)
	(segment
		(start 413.293052 -180.064918)
		(end 413.293052 -178.540918)
		(width 0.17145)
		(layer "F.Cu")
		(net "HDD_PRSNT_21")
	)
	(segment
		(start 413.399478 -176.084992)
		(end 422.025064 -176.084992)
		(width 0.17145)
		(layer "F.Cu")
		(net "HDD_PRSNT_21")
	)
	(segment
		(start 413.356552 -176.127918)
		(end 413.399478 -176.084992)
		(width 0.17145)
		(layer "F.Cu")
		(net "HDD_PRSNT_21")
	)
	(via
		(at 413.293052 -178.540918)
		(size 0.6604)
		(drill 0.3302)
		(layers "F.Cu" "B.Cu")
		(net "HDD_PRSNT_21")
	)
	(segment
		(start 381.74295 -180.064918)
		(end 381.74295 -178.540918)
		(width 0.17145)
		(layer "F.Cu")
		(net "HDD_PRSNT_20")
	)
	(segment
		(start 381.80645 -177.169318)
		(end 381.80645 -176.127918)
		(width 0.17145)
		(layer "F.Cu")
		(net "HDD_PRSNT_20")
	)
	(segment
		(start 381.74295 -178.540918)
		(end 381.80645 -178.477418)
		(width 0.17145)
		(layer "F.Cu")
		(net "HDD_PRSNT_20")
	)
	(segment
		(start 381.849376 -176.084992)
		(end 390.474962 -176.084992)
		(width 0.17145)
		(layer "F.Cu")
		(net "HDD_PRSNT_20")
	)
	(segment
		(start 381.80645 -178.477418)
		(end 381.80645 -177.169318)
		(width 0.17145)
		(layer "F.Cu")
		(net "HDD_PRSNT_20")
	)
	(segment
		(start 381.80645 -176.127918)
		(end 381.849376 -176.084992)
		(width 0.17145)
		(layer "F.Cu")
		(net "HDD_PRSNT_20")
	)
	(via
		(at 381.74295 -178.540918)
		(size 0.6604)
		(drill 0.3302)
		(layers "F.Cu" "B.Cu")
		(net "HDD_PRSNT_20")
	)
	(segment
		(start 98.453448 -292.169342)
		(end 98.453448 -291.127942)
		(width 0.17145)
		(layer "F.Cu")
		(net "HDD_PRSNT_2")
	)
	(segment
		(start 98.453448 -293.540942)
		(end 98.453448 -292.169342)
		(width 0.17145)
		(layer "F.Cu")
		(net "HDD_PRSNT_2")
	)
	(segment
		(start 98.466148 -295.064942)
		(end 98.453448 -295.052242)
		(width 0.17145)
		(layer "F.Cu")
		(net "HDD_PRSNT_2")
	)
	(segment
		(start 98.453448 -295.052242)
		(end 98.453448 -293.540942)
		(width 0.17145)
		(layer "F.Cu")
		(net "HDD_PRSNT_2")
	)
	(segment
		(start 98.410522 -291.085016)
		(end 93.125036 -291.085016)
		(width 0.17145)
		(layer "F.Cu")
		(net "HDD_PRSNT_2")
	)
	(segment
		(start 98.453448 -291.127942)
		(end 98.410522 -291.085016)
		(width 0.17145)
		(layer "F.Cu")
		(net "HDD_PRSNT_2")
	)
	(via
		(at 98.453448 -293.540942)
		(size 0.6604)
		(drill 0.3302)
		(layers "F.Cu" "B.Cu")
		(net "HDD_PRSNT_2")
	)
	(segment
		(start 350.256602 -176.127918)
		(end 350.299528 -176.084992)
		(width 0.17145)
		(layer "F.Cu")
		(net "HDD_PRSNT_19")
	)
	(segment
		(start 350.193102 -180.064918)
		(end 350.193102 -178.540918)
		(width 0.17145)
		(layer "F.Cu")
		(net "HDD_PRSNT_19")
	)
	(segment
		(start 350.256602 -178.477418)
		(end 350.256602 -177.169318)
		(width 0.17145)
		(layer "F.Cu")
		(net "HDD_PRSNT_19")
	)
	(segment
		(start 350.256602 -177.169318)
		(end 350.256602 -176.127918)
		(width 0.17145)
		(layer "F.Cu")
		(net "HDD_PRSNT_19")
	)
	(segment
		(start 350.193102 -178.540918)
		(end 350.256602 -178.477418)
		(width 0.17145)
		(layer "F.Cu")
		(net "HDD_PRSNT_19")
	)
	(segment
		(start 350.299528 -176.084992)
		(end 358.925114 -176.084992)
		(width 0.17145)
		(layer "F.Cu")
		(net "HDD_PRSNT_19")
	)
	(via
		(at 350.193102 -178.540918)
		(size 0.6604)
		(drill 0.3302)
		(layers "F.Cu" "B.Cu")
		(net "HDD_PRSNT_19")
	)
	(segment
		(start 318.643 -180.064918)
		(end 318.643 -178.540918)
		(width 0.17145)
		(layer "F.Cu")
		(net "HDD_PRSNT_18")
	)
	(segment
		(start 318.749426 -176.084992)
		(end 327.375012 -176.084992)
		(width 0.17145)
		(layer "F.Cu")
		(net "HDD_PRSNT_18")
	)
	(segment
		(start 318.7065 -178.477418)
		(end 318.7065 -177.2539)
		(width 0.17145)
		(layer "F.Cu")
		(net "HDD_PRSNT_18")
	)
	(segment
		(start 318.7065 -176.127918)
		(end 318.749426 -176.084992)
		(width 0.17145)
		(layer "F.Cu")
		(net "HDD_PRSNT_18")
	)
	(segment
		(start 318.7065 -177.2539)
		(end 318.7065 -176.127918)
		(width 0.17145)
		(layer "F.Cu")
		(net "HDD_PRSNT_18")
	)
	(segment
		(start 318.643 -178.540918)
		(end 318.7065 -178.477418)
		(width 0.17145)
		(layer "F.Cu")
		(net "HDD_PRSNT_18")
	)
	(via
		(at 318.643 -178.540918)
		(size 0.6604)
		(drill 0.3302)
		(layers "F.Cu" "B.Cu")
		(net "HDD_PRSNT_18")
	)
	(segment
		(start 190.0555 -175.4505)
		(end 189.421008 -176.084992)
		(width 0.17145)
		(layer "F.Cu")
		(net "HDD_PRSNT_17")
	)
	(segment
		(start 190.0555 -172.1358)
		(end 190.0555 -173.1772)
		(width 0.17145)
		(layer "F.Cu")
		(net "HDD_PRSNT_17")
	)
	(segment
		(start 189.421008 -176.084992)
		(end 187.775088 -176.084992)
		(width 0.17145)
		(layer "F.Cu")
		(net "HDD_PRSNT_17")
	)
	(segment
		(start 190.0555 -171.5135)
		(end 190.0555 -172.1358)
		(width 0.17145)
		(layer "F.Cu")
		(net "HDD_PRSNT_17")
	)
	(segment
		(start 190.246 -171.323)
		(end 190.0555 -171.5135)
		(width 0.17145)
		(layer "F.Cu")
		(net "HDD_PRSNT_17")
	)
	(segment
		(start 190.246 -170.688)
		(end 190.246 -171.323)
		(width 0.17145)
		(layer "F.Cu")
		(net "HDD_PRSNT_17")
	)
	(segment
		(start 190.0555 -173.1772)
		(end 190.0555 -175.4505)
		(width 0.17145)
		(layer "F.Cu")
		(net "HDD_PRSNT_17")
	)
	(segment
		(start 161.553398 -177.169318)
		(end 161.553398 -176.127918)
		(width 0.17145)
		(layer "F.Cu")
		(net "HDD_PRSNT_16")
	)
	(segment
		(start 161.553398 -178.540918)
		(end 161.553398 -177.169318)
		(width 0.17145)
		(layer "F.Cu")
		(net "HDD_PRSNT_16")
	)
	(segment
		(start 161.553398 -176.127918)
		(end 161.510472 -176.084992)
		(width 0.17145)
		(layer "F.Cu")
		(net "HDD_PRSNT_16")
	)
	(segment
		(start 161.510472 -176.084992)
		(end 156.224986 -176.084992)
		(width 0.17145)
		(layer "F.Cu")
		(net "HDD_PRSNT_16")
	)
	(segment
		(start 161.616898 -180.064918)
		(end 161.553398 -180.001418)
		(width 0.17145)
		(layer "F.Cu")
		(net "HDD_PRSNT_16")
	)
	(segment
		(start 161.553398 -180.001418)
		(end 161.553398 -178.540918)
		(width 0.17145)
		(layer "F.Cu")
		(net "HDD_PRSNT_16")
	)
	(via
		(at 161.553398 -178.540918)
		(size 0.6604)
		(drill 0.3302)
		(layers "F.Cu" "B.Cu")
		(net "HDD_PRSNT_16")
	)
	(segment
		(start 130.003296 -177.143918)
		(end 130.003296 -176.127918)
		(width 0.17145)
		(layer "F.Cu")
		(net "HDD_PRSNT_15")
	)
	(segment
		(start 130.066796 -180.064918)
		(end 130.003296 -180.001418)
		(width 0.17145)
		(layer "F.Cu")
		(net "HDD_PRSNT_15")
	)
	(segment
		(start 130.003296 -176.127918)
		(end 129.96037 -176.084992)
		(width 0.17145)
		(layer "F.Cu")
		(net "HDD_PRSNT_15")
	)
	(segment
		(start 130.003296 -178.540918)
		(end 130.003296 -177.143918)
		(width 0.17145)
		(layer "F.Cu")
		(net "HDD_PRSNT_15")
	)
	(segment
		(start 130.003296 -180.001418)
		(end 130.003296 -178.540918)
		(width 0.17145)
		(layer "F.Cu")
		(net "HDD_PRSNT_15")
	)
	(segment
		(start 129.96037 -176.084992)
		(end 124.674884 -176.084992)
		(width 0.17145)
		(layer "F.Cu")
		(net "HDD_PRSNT_15")
	)
	(via
		(at 130.003296 -178.540918)
		(size 0.6604)
		(drill 0.3302)
		(layers "F.Cu" "B.Cu")
		(net "HDD_PRSNT_15")
	)
	(segment
		(start 98.453448 -180.001418)
		(end 98.453448 -178.540918)
		(width 0.17145)
		(layer "F.Cu")
		(net "HDD_PRSNT_14")
	)
	(segment
		(start 98.453448 -177.169318)
		(end 98.453448 -176.127918)
		(width 0.17145)
		(layer "F.Cu")
		(net "HDD_PRSNT_14")
	)
	(segment
		(start 98.410522 -176.084992)
		(end 93.125036 -176.084992)
		(width 0.17145)
		(layer "F.Cu")
		(net "HDD_PRSNT_14")
	)
	(segment
		(start 98.453448 -178.540918)
		(end 98.453448 -177.169318)
		(width 0.17145)
		(layer "F.Cu")
		(net "HDD_PRSNT_14")
	)
	(segment
		(start 98.453448 -176.127918)
		(end 98.410522 -176.084992)
		(width 0.17145)
		(layer "F.Cu")
		(net "HDD_PRSNT_14")
	)
	(segment
		(start 98.516948 -180.064918)
		(end 98.453448 -180.001418)
		(width 0.17145)
		(layer "F.Cu")
		(net "HDD_PRSNT_14")
	)
	(via
		(at 98.453448 -178.540918)
		(size 0.6604)
		(drill 0.3302)
		(layers "F.Cu" "B.Cu")
		(net "HDD_PRSNT_14")
	)
	(segment
		(start 66.903346 -177.169318)
		(end 66.903346 -176.127918)
		(width 0.17145)
		(layer "F.Cu")
		(net "HDD_PRSNT_13")
	)
	(segment
		(start 66.86042 -176.084992)
		(end 61.574934 -176.084992)
		(width 0.17145)
		(layer "F.Cu")
		(net "HDD_PRSNT_13")
	)
	(segment
		(start 66.903346 -176.127918)
		(end 66.86042 -176.084992)
		(width 0.17145)
		(layer "F.Cu")
		(net "HDD_PRSNT_13")
	)
	(segment
		(start 66.966846 -180.064918)
		(end 66.903346 -180.001418)
		(width 0.17145)
		(layer "F.Cu")
		(net "HDD_PRSNT_13")
	)
	(segment
		(start 66.903346 -178.540918)
		(end 66.903346 -177.169318)
		(width 0.17145)
		(layer "F.Cu")
		(net "HDD_PRSNT_13")
	)
	(segment
		(start 66.903346 -180.001418)
		(end 66.903346 -178.540918)
		(width 0.17145)
		(layer "F.Cu")
		(net "HDD_PRSNT_13")
	)
	(via
		(at 66.903346 -178.540918)
		(size 0.6604)
		(drill 0.3302)
		(layers "F.Cu" "B.Cu")
		(net "HDD_PRSNT_13")
	)
	(segment
		(start 35.353498 -176.127918)
		(end 35.310572 -176.084992)
		(width 0.17145)
		(layer "F.Cu")
		(net "HDD_PRSNT_12")
	)
	(segment
		(start 35.353498 -178.540918)
		(end 35.353498 -177.169318)
		(width 0.17145)
		(layer "F.Cu")
		(net "HDD_PRSNT_12")
	)
	(segment
		(start 35.353498 -177.169318)
		(end 35.353498 -176.127918)
		(width 0.17145)
		(layer "F.Cu")
		(net "HDD_PRSNT_12")
	)
	(segment
		(start 35.310572 -176.084992)
		(end 30.025086 -176.084992)
		(width 0.17145)
		(layer "F.Cu")
		(net "HDD_PRSNT_12")
	)
	(segment
		(start 35.353498 -180.001418)
		(end 35.353498 -178.540918)
		(width 0.17145)
		(layer "F.Cu")
		(net "HDD_PRSNT_12")
	)
	(segment
		(start 35.416998 -180.064918)
		(end 35.353498 -180.001418)
		(width 0.17145)
		(layer "F.Cu")
		(net "HDD_PRSNT_12")
	)
	(via
		(at 35.353498 -178.540918)
		(size 0.6604)
		(drill 0.3302)
		(layers "F.Cu" "B.Cu")
		(net "HDD_PRSNT_12")
	)
	(segment
		(start 482.740208 -289.71113)
		(end 482.740208 -288.77133)
		(width 0.17145)
		(layer "F.Cu")
		(net "HDD_PRSNT_11")
	)
	(segment
		(start 476.4532 -272.174716)
		(end 476.64497 -271.982946)
		(width 0.17145)
		(layer "F.Cu")
		(net "HDD_PRSNT_11")
	)
	(segment
		(start 483.107492 -291.085016)
		(end 482.74097 -290.718494)
		(width 0.17145)
		(layer "F.Cu")
		(net "HDD_PRSNT_11")
	)
	(segment
		(start 479.335592 -286.328358)
		(end 478.981008 -285.973774)
		(width 0.17145)
		(layer "F.Cu")
		(net "HDD_PRSNT_11")
	)
	(segment
		(start 476.4532 -275.722334)
		(end 476.4532 -272.174716)
		(width 0.17145)
		(layer "F.Cu")
		(net "HDD_PRSNT_11")
	)
	(segment
		(start 477.85909 -270.768826)
		(end 476.64497 -271.982946)
		(width 0.17145)
		(layer "F.Cu")
		(net "HDD_PRSNT_11")
	)
	(segment
		(start 480.297236 -286.328358)
		(end 479.335592 -286.328358)
		(width 0.17145)
		(layer "F.Cu")
		(net "HDD_PRSNT_11")
	)
	(segment
		(start 485.125014 -291.085016)
		(end 483.107492 -291.085016)
		(width 0.17145)
		(layer "F.Cu")
		(net "HDD_PRSNT_11")
	)
	(segment
		(start 477.07169 -276.340824)
		(end 476.4532 -275.722334)
		(width 0.17145)
		(layer "F.Cu")
		(net "HDD_PRSNT_11")
	)
	(segment
		(start 478.981008 -276.809454)
		(end 478.512378 -276.340824)
		(width 0.17145)
		(layer "F.Cu")
		(net "HDD_PRSNT_11")
	)
	(segment
		(start 477.85909 -267.77442)
		(end 477.85909 -269.224252)
		(width 0.17145)
		(layer "F.Cu")
		(net "HDD_PRSNT_11")
	)
	(segment
		(start 482.74097 -289.711892)
		(end 482.740208 -289.71113)
		(width 0.17145)
		(layer "F.Cu")
		(net "HDD_PRSNT_11")
	)
	(segment
		(start 477.85909 -269.224252)
		(end 477.85909 -270.265652)
		(width 0.17145)
		(layer "F.Cu")
		(net "HDD_PRSNT_11")
	)
	(segment
		(start 478.981008 -285.973774)
		(end 478.981008 -276.809454)
		(width 0.17145)
		(layer "F.Cu")
		(net "HDD_PRSNT_11")
	)
	(segment
		(start 477.858328 -267.773658)
		(end 477.85909 -267.77442)
		(width 0.17145)
		(layer "F.Cu")
		(net "HDD_PRSNT_11")
	)
	(segment
		(start 478.512378 -276.340824)
		(end 477.07169 -276.340824)
		(width 0.17145)
		(layer "F.Cu")
		(net "HDD_PRSNT_11")
	)
	(segment
		(start 477.85909 -270.265652)
		(end 477.85909 -270.768826)
		(width 0.17145)
		(layer "F.Cu")
		(net "HDD_PRSNT_11")
	)
	(segment
		(start 482.74097 -290.718494)
		(end 482.74097 -289.711892)
		(width 0.17145)
		(layer "F.Cu")
		(net "HDD_PRSNT_11")
	)
	(segment
		(start 482.740208 -288.77133)
		(end 480.297236 -286.328358)
		(width 0.17145)
		(layer "F.Cu")
		(net "HDD_PRSNT_11")
	)
	(via
		(at 476.64497 -271.982946)
		(size 0.6604)
		(drill 0.3302)
		(layers "F.Cu" "B.Cu")
		(net "HDD_PRSNT_11")
	)
	(segment
		(start 444.9064 -294.1828)
		(end 444.9064 -293.502842)
		(width 0.17145)
		(layer "F.Cu")
		(net "HDD_PRSNT_10")
	)
	(segment
		(start 444.9064 -291.127942)
		(end 444.949326 -291.085016)
		(width 0.17145)
		(layer "F.Cu")
		(net "HDD_PRSNT_10")
	)
	(segment
		(start 445.1858 -294.4622)
		(end 444.9064 -294.1828)
		(width 0.17145)
		(layer "F.Cu")
		(net "HDD_PRSNT_10")
	)
	(segment
		(start 444.9064 -292.169342)
		(end 444.9064 -291.127942)
		(width 0.17145)
		(layer "F.Cu")
		(net "HDD_PRSNT_10")
	)
	(segment
		(start 444.9064 -293.502842)
		(end 444.9064 -292.169342)
		(width 0.17145)
		(layer "F.Cu")
		(net "HDD_PRSNT_10")
	)
	(segment
		(start 445.1858 -295.0972)
		(end 445.1858 -294.4622)
		(width 0.17145)
		(layer "F.Cu")
		(net "HDD_PRSNT_10")
	)
	(segment
		(start 444.949326 -291.085016)
		(end 453.574912 -291.085016)
		(width 0.17145)
		(layer "F.Cu")
		(net "HDD_PRSNT_10")
	)
	(via
		(at 444.9064 -293.502842)
		(size 0.6604)
		(drill 0.3302)
		(layers "F.Cu" "B.Cu")
		(net "HDD_PRSNT_10")
	)
	(segment
		(start 66.903346 -292.169342)
		(end 66.903346 -291.127942)
		(width 0.17145)
		(layer "F.Cu")
		(net "HDD_PRSNT_1")
	)
	(segment
		(start 66.86042 -291.085016)
		(end 61.574934 -291.085016)
		(width 0.17145)
		(layer "F.Cu")
		(net "HDD_PRSNT_1")
	)
	(segment
		(start 66.903346 -293.540942)
		(end 66.903346 -292.169342)
		(width 0.17145)
		(layer "F.Cu")
		(net "HDD_PRSNT_1")
	)
	(segment
		(start 66.903346 -291.127942)
		(end 66.86042 -291.085016)
		(width 0.17145)
		(layer "F.Cu")
		(net "HDD_PRSNT_1")
	)
	(segment
		(start 66.903346 -295.001442)
		(end 66.903346 -293.540942)
		(width 0.17145)
		(layer "F.Cu")
		(net "HDD_PRSNT_1")
	)
	(segment
		(start 66.966846 -295.064942)
		(end 66.903346 -295.001442)
		(width 0.17145)
		(layer "F.Cu")
		(net "HDD_PRSNT_1")
	)
	(via
		(at 66.903346 -293.540942)
		(size 0.6604)
		(drill 0.3302)
		(layers "F.Cu" "B.Cu")
		(net "HDD_PRSNT_1")
	)
	(segment
		(start 357.100124 -79.784956)
		(end 355.217222 -79.784956)
		(width 0.508)
		(layer "F.Cu")
		(net "GND")
	)
	(segment
		(start 185.686192 -60.595002)
		(end 186.466226 -59.814968)
		(width 0.508)
		(layer "F.Cu")
		(net "GND")
	)
	(segment
		(start 312.151268 -57.18175)
		(end 311.11825 -57.18175)
		(width 0.508)
		(layer "F.Cu")
		(net "GND")
	)
	(segment
		(start 165.279578 -181.406038)
		(end 165.279578 -180.46573)
		(width 0.508)
		(layer "F.Cu")
		(net "GND")
	)
	(segment
		(start 151.554942 -285.230062)
		(end 153.361898 -285.230062)
		(width 0.508)
		(layer "F.Cu")
		(net "GND")
	)
	(segment
		(start 114.430556 -162.615118)
		(end 113.683796 -162.615118)
		(width 0.4064)
		(layer "F.Cu")
		(net "GND")
	)
	(segment
		(start 59.7662 -290.2458)
		(end 60.196984 -289.815016)
		(width 0.508)
		(layer "F.Cu")
		(net "GND")
	)
	(segment
		(start 424.469052 -305.097942)
		(end 424.469052 -306.113942)
		(width 0.508)
		(layer "F.Cu")
		(net "GND")
	)
	(segment
		(start 109.450886 -131.135628)
		(end 109.453934 -131.138676)
		(width 0.508)
		(layer "F.Cu")
		(net "GND")
	)
	(segment
		(start 255.0922 -289.7505)
		(end 255.0922 -289.050476)
		(width 0.508)
		(layer "F.Cu")
		(net "GND")
	)
	(segment
		(start 485.125014 -45.844968)
		(end 483.404926 -45.844968)
		(width 0.508)
		(layer "F.Cu")
		(net "GND")
	)
	(segment
		(start 457.3651 -275.903182)
		(end 457.3651 -276.649942)
		(width 0.4064)
		(layer "F.Cu")
		(net "GND")
	)
	(segment
		(start 465.177632 -129.99974)
		(end 465.177632 -130.368294)
		(width 0.508)
		(layer "F.Cu")
		(net "GND")
	)
	(segment
		(start 52.681886 -162.208718)
		(end 53.555646 -162.208718)
		(width 0.4064)
		(layer "F.Cu")
		(net "GND")
	)
	(segment
		(start 453.574912 -182.434992)
		(end 451.854824 -182.434992)
		(width 0.508)
		(layer "F.Cu")
		(net "GND")
	)
	(segment
		(start 151.554942 -52.829968)
		(end 153.361898 -52.829968)
		(width 0.508)
		(layer "F.Cu")
		(net "GND")
	)
	(segment
		(start 162.442398 -176.127918)
		(end 162.442398 -175.238918)
		(width 0.508)
		(layer "F.Cu")
		(net "GND")
	)
	(segment
		(start 373.38 -147.32)
		(end 373.5578 -147.1422)
		(width 0.508)
		(layer "F.Cu")
		(net "GND")
	)
	(segment
		(start 331.1652 -275.903182)
		(end 331.1652 -276.649942)
		(width 0.4064)
		(layer "F.Cu")
		(net "GND")
	)
	(segment
		(start 219.604082 -391.710672)
		(end 220.121734 -392.228324)
		(width 0.508)
		(layer "F.Cu")
		(net "GND")
	)
	(segment
		(start 370.572792 -243.741194)
		(end 370.572792 -245.329456)
		(width 0.508)
		(layer "F.Cu")
		(net "GND")
	)
	(segment
		(start 331.1652 -46.241462)
		(end 331.1652 -45.903134)
		(width 0.4064)
		(layer "F.Cu")
		(net "GND")
	)
	(segment
		(start 257.4036 -289.7505)
		(end 257.4036 -288.925)
		(width 0.508)
		(layer "F.Cu")
		(net "GND")
	)
	(segment
		(start 39.043864 -297.266868)
		(end 39.043864 -298.397422)
		(width 0.508)
		(layer "F.Cu")
		(net "GND")
	)
	(segment
		(start 426.120052 -189.920118)
		(end 426.120052 -191.113918)
		(width 0.508)
		(layer "F.Cu")
		(net "GND")
	)
	(segment
		(start 146.2278 -134.323074)
		(end 146.2278 -135.402574)
		(width 0.3048)
		(layer "F.Cu")
		(net "GND")
	)
	(segment
		(start 228.32568 -257.4544)
		(end 228.32568 -259.08)
		(width 0.3556)
		(layer "F.Cu")
		(net "GND")
	)
	(segment
		(start 370.906294 -149.417024)
		(end 370.906294 -150.494492)
		(width 0.508)
		(layer "F.Cu")
		(net "GND")
	)
	(segment
		(start 448.61607 -255.199642)
		(end 448.61607 -256.176018)
		(width 0.508)
		(layer "F.Cu")
		(net "GND")
	)
	(segment
		(start 331.4954 -272.141442)
		(end 331.4954 -271.315942)
		(width 0.508)
		(layer "F.Cu")
		(net "GND")
	)
	(segment
		(start 385.804918 -167.829992)
		(end 387.611874 -167.829992)
		(width 0.508)
		(layer "F.Cu")
		(net "GND")
	)
	(segment
		(start 176.403 -289.603942)
		(end 176.403 -291.000942)
		(width 0.508)
		(layer "F.Cu")
		(net "GND")
	)
	(segment
		(start 151.554942 -170.230038)
		(end 153.361898 -170.230038)
		(width 0.508)
		(layer "F.Cu")
		(net "GND")
	)
	(segment
		(start 365.299244 -66.366898)
		(end 364.442248 -67.223894)
		(width 0.508)
		(layer "F.Cu")
		(net "GND")
	)
	(segment
		(start 144.4498 -47.6504)
		(end 144.89938 -47.6504)
		(width 0.4064)
		(layer "F.Cu")
		(net "GND")
	)
	(segment
		(start 174.0535 -282.034742)
		(end 174.0535 -282.872942)
		(width 0.508)
		(layer "F.Cu")
		(net "GND")
	)
	(segment
		(start 80.724248 -26.360374)
		(end 80.724248 -25.12187)
		(width 0.508)
		(layer "F.Cu")
		(net "GND")
	)
	(segment
		(start 61.574934 -174.814992)
		(end 59.854846 -174.814992)
		(width 0.508)
		(layer "F.Cu")
		(net "GND")
	)
	(segment
		(start 344.026998 -22.063202)
		(end 343.205054 -22.885146)
		(width 0.508)
		(layer "F.Cu")
		(net "GND")
	)
	(segment
		(start 354.25507 -285.230062)
		(end 356.062026 -285.230062)
		(width 0.508)
		(layer "F.Cu")
		(net "GND")
	)
	(segment
		(start 156.224986 -297.435016)
		(end 154.504898 -297.435016)
		(width 0.508)
		(layer "F.Cu")
		(net "GND")
	)
	(segment
		(start 390.474962 -279.655016)
		(end 388.754874 -279.655016)
		(width 0.508)
		(layer "F.Cu")
		(net "GND")
	)
	(segment
		(start 393.93495 -182.604918)
		(end 392.91895 -182.604918)
		(width 0.508)
		(layer "F.Cu")
		(net "GND")
	)
	(segment
		(start 240.56975 -348.718378)
		(end 240.56975 -347.72854)
		(width 0.508)
		(layer "F.Cu")
		(net "GND")
	)
	(segment
		(start 412.873952 -61.102494)
		(end 411.7594 -61.102494)
		(width 0.508)
		(layer "F.Cu")
		(net "GND")
	)
	(segment
		(start 268.816582 18.762218)
		(end 268.676882 18.901918)
		(width 0.508)
		(layer "F.Cu")
		(net "GND")
	)
	(segment
		(start 327.375012 -49.654968)
		(end 329.566778 -49.654968)
		(width 0.508)
		(layer "F.Cu")
		(net "GND")
	)
	(segment
		(start 120.00484 -285.230062)
		(end 118.197884 -285.230062)
		(width 0.508)
		(layer "F.Cu")
		(net "GND")
	)
	(segment
		(start 427.834552 -279.596342)
		(end 428.787052 -279.596342)
		(width 0.508)
		(layer "F.Cu")
		(net "GND")
	)
	(segment
		(start 327.375012 -160.844992)
		(end 325.654924 -160.844992)
		(width 0.508)
		(layer "F.Cu")
		(net "GND")
	)
	(segment
		(start 335.0514 -20.0152)
		(end 335.0514 -19.338036)
		(width 0.508)
		(layer "F.Cu")
		(net "GND")
	)
	(segment
		(start 257.7846 -139.7)
		(end 258.6482 -139.7)
		(width 0.508)
		(layer "F.Cu")
		(net "GND")
	)
	(segment
		(start 458.5589 -67.223894)
		(end 459.9559 -67.223894)
		(width 0.508)
		(layer "F.Cu")
		(net "GND")
	)
	(segment
		(start 186.466226 -59.814968)
		(end 187.775088 -59.814968)
		(width 0.508)
		(layer "F.Cu")
		(net "GND")
	)
	(segment
		(start 447.8655 -181.991)
		(end 448.747134 -181.991)
		(width 0.508)
		(layer "F.Cu")
		(net "GND")
	)
	(segment
		(start 470.336118 -44.73829)
		(end 470.336118 -45.48505)
		(width 0.4064)
		(layer "F.Cu")
		(net "GND")
	)
	(segment
		(start 313.914282 -128.752854)
		(end 313.911996 -128.75514)
		(width 0.508)
		(layer "F.Cu")
		(net "GND")
	)
	(segment
		(start 341.971376 -130.38201)
		(end 341.971376 -128.719834)
		(width 0.508)
		(layer "F.Cu")
		(net "GND")
	)
	(segment
		(start 28.200096 -266.035028)
		(end 30.082998 -266.035028)
		(width 0.508)
		(layer "F.Cu")
		(net "GND")
	)
	(segment
		(start 485.125014 -62.354968)
		(end 483.404926 -62.354968)
		(width 0.508)
		(layer "F.Cu")
		(net "GND")
	)
	(segment
		(start 373.5578 -147.1422)
		(end 373.5578 -146.2659)
		(width 0.508)
		(layer "F.Cu")
		(net "GND")
	)
	(segment
		(start 187.775088 -279.655016)
		(end 186.055 -279.655016)
		(width 0.508)
		(layer "F.Cu")
		(net "GND")
	)
	(segment
		(start 19.780758 -162.615118)
		(end 19.033998 -162.615118)
		(width 0.4064)
		(layer "F.Cu")
		(net "GND")
	)
	(segment
		(start 334.68437 -28.651454)
		(end 334.68437 -27.405584)
		(width 0.508)
		(layer "F.Cu")
		(net "GND")
	)
	(segment
		(start 142.579598 -283.126942)
		(end 142.579598 -284.701742)
		(width 0.508)
		(layer "F.Cu")
		(net "GND")
	)
	(segment
		(start 39.043356 -183.080914)
		(end 39.043356 -183.068214)
		(width 0.508)
		(layer "F.Cu")
		(net "GND")
	)
	(segment
		(start 30.025086 -182.434992)
		(end 28.304998 -182.434992)
		(width 0.508)
		(layer "F.Cu")
		(net "GND")
	)
	(segment
		(start 242.7478 -260.9977)
		(end 242.7478 -261.7978)
		(width 0.508)
		(layer "F.Cu")
		(net "GND")
	)
	(segment
		(start 485.125014 -299.975016)
		(end 483.404926 -299.975016)
		(width 0.508)
		(layer "F.Cu")
		(net "GND")
	)
	(segment
		(start 79.581248 -26.169874)
		(end 79.581248 -25.07107)
		(width 0.508)
		(layer "F.Cu")
		(net "GND")
	)
	(segment
		(start 263.9314 -229.8573)
		(end 265.1506 -229.8573)
		(width 0.508)
		(layer "F.Cu")
		(net "GND")
	)
	(segment
		(start 385.804918 -170.230038)
		(end 387.611874 -170.230038)
		(width 0.508)
		(layer "F.Cu")
		(net "GND")
	)
	(segment
		(start 183.105044 -165.429946)
		(end 184.912 -165.429946)
		(width 0.508)
		(layer "F.Cu")
		(net "GND")
	)
	(segment
		(start 459.3844 -49.596294)
		(end 460.3369 -49.596294)
		(width 0.508)
		(layer "F.Cu")
		(net "GND")
	)
	(segment
		(start 23.440898 -278.554942)
		(end 23.440898 -279.443942)
		(width 0.508)
		(layer "F.Cu")
		(net "GND")
	)
	(segment
		(start 174.12843 -54.022244)
		(end 174.12843 -54.052724)
		(width 0.508)
		(layer "F.Cu")
		(net "GND")
	)
	(segment
		(start 56.90489 -52.829968)
		(end 58.711846 -52.829968)
		(width 0.508)
		(layer "F.Cu")
		(net "GND")
	)
	(segment
		(start 475.234 -272.6182)
		(end 475.234 -272.99158)
		(width 0.3556)
		(layer "F.Cu")
		(net "GND")
	)
	(segment
		(start 474.577918 -292.940232)
		(end 473.545408 -292.940232)
		(width 0.508)
		(layer "F.Cu")
		(net "GND")
	)
	(segment
		(start 274.2184 12.8778)
		(end 273.54784 13.54836)
		(width 0.381)
		(layer "F.Cu")
		(net "GND")
	)
	(segment
		(start 248.452132 -296.075862)
		(end 248.44121 -296.075862)
		(width 0.381)
		(layer "F.Cu")
		(net "GND")
	)
	(segment
		(start 326.50938 -36.03498)
		(end 325.550022 -36.03498)
		(width 0.508)
		(layer "F.Cu")
		(net "GND")
	)
	(segment
		(start 93.125036 -299.975016)
		(end 91.404948 -299.975016)
		(width 0.508)
		(layer "F.Cu")
		(net "GND")
	)
	(segment
		(start 284.4038 -271.8689)
		(end 284.4038 -271.0688)
		(width 0.508)
		(layer "F.Cu")
		(net "GND")
	)
	(segment
		(start 448.61607 -256.176018)
		(end 448.783202 -256.34315)
		(width 0.508)
		(layer "F.Cu")
		(net "GND")
	)
	(segment
		(start 91.300046 -194.78498)
		(end 93.182948 -194.78498)
		(width 0.508)
		(layer "F.Cu")
		(net "GND")
	)
	(segment
		(start 56.90489 -280.42997)
		(end 58.711846 -280.42997)
		(width 0.508)
		(layer "F.Cu")
		(net "GND")
	)
	(segment
		(start 298.243498 -283.6545)
		(end 297.831256 -284.066742)
		(width 0.508)
		(layer "F.Cu")
		(net "GND")
	)
	(segment
		(start 30.267402 -245.086124)
		(end 29.970476 -245.38305)
		(width 0.508)
		(layer "F.Cu")
		(net "GND")
	)
	(segment
		(start 147.281138 -49.494694)
		(end 148.205698 -49.494694)
		(width 0.4064)
		(layer "F.Cu")
		(net "GND")
	)
	(segment
		(start 19.668998 -62.778894)
		(end 18.652998 -62.778894)
		(width 0.508)
		(layer "F.Cu")
		(net "GND")
	)
	(segment
		(start 222.885 -363.8804)
		(end 222.8342 -363.8296)
		(width 0.508)
		(layer "F.Cu")
		(net "GND")
	)
	(segment
		(start 124.674884 -279.655016)
		(end 122.954796 -279.655016)
		(width 0.508)
		(layer "F.Cu")
		(net "GND")
	)
	(segment
		(start 235.27766 -235.798868)
		(end 236.024928 -235.0516)
		(width 0.508)
		(layer "F.Cu")
		(net "GND")
	)
	(segment
		(start 201.799952 -2.95021)
		(end 200.41743 -2.95021)
		(width 0.508)
		(layer "F.Cu")
		(net "GND")
	)
	(segment
		(start 162.442398 -291.127942)
		(end 163.322 -291.127942)
		(width 0.508)
		(layer "F.Cu")
		(net "GND")
	)
	(segment
		(start 165.287706 -297.080686)
		(end 165.287706 -297.791886)
		(width 0.508)
		(layer "F.Cu")
		(net "GND")
	)
	(segment
		(start 270.383 -279.4)
		(end 270.383 -278.4221)
		(width 0.508)
		(layer "F.Cu")
		(net "GND")
	)
	(segment
		(start 256.2098 -237.49)
		(end 256.2098 -236.6137)
		(width 0.508)
		(layer "F.Cu")
		(net "GND")
	)
	(segment
		(start 102.147624 -297.57243)
		(end 101.466396 -296.891202)
		(width 0.508)
		(layer "F.Cu")
		(net "GND")
	)
	(segment
		(start 471.275918 -156.078174)
		(end 472.164918 -156.078174)
		(width 0.508)
		(layer "F.Cu")
		(net "GND")
	)
	(segment
		(start 139.950698 -294.683942)
		(end 138.756898 -294.683942)
		(width 0.508)
		(layer "F.Cu")
		(net "GND")
	)
	(segment
		(start 156.224986 -177.354992)
		(end 154.504898 -177.354992)
		(width 0.508)
		(layer "F.Cu")
		(net "GND")
	)
	(segment
		(start 135.045196 -292.804342)
		(end 135.97128 -292.804342)
		(width 0.508)
		(layer "F.Cu")
		(net "GND")
	)
	(segment
		(start 327.406 -78.613)
		(end 326.234044 -79.784956)
		(width 0.508)
		(layer "F.Cu")
		(net "GND")
	)
	(segment
		(start 92.751148 -23.47468)
		(end 92.751148 -22.537674)
		(width 0.508)
		(layer "F.Cu")
		(net "GND")
	)
	(segment
		(start 61.574934 -275.845016)
		(end 59.854846 -275.845016)
		(width 0.508)
		(layer "F.Cu")
		(net "GND")
	)
	(segment
		(start 156.224986 -49.654968)
		(end 153.743152 -49.654968)
		(width 0.508)
		(layer "F.Cu")
		(net "GND")
	)
	(segment
		(start 141.548866 -131.211574)
		(end 141.548866 -130.386074)
		(width 0.508)
		(layer "F.Cu")
		(net "GND")
	)
	(segment
		(start 56.90489 -167.829992)
		(end 58.711846 -167.829992)
		(width 0.508)
		(layer "F.Cu")
		(net "GND")
	)
	(segment
		(start 453.574912 -62.354968)
		(end 451.854824 -62.354968)
		(width 0.508)
		(layer "F.Cu")
		(net "GND")
	)
	(segment
		(start 177.53076 -277.615142)
		(end 176.784 -277.615142)
		(width 0.4064)
		(layer "F.Cu")
		(net "GND")
	)
	(segment
		(start 422.025064 -275.845016)
		(end 420.304976 -275.845016)
		(width 0.508)
		(layer "F.Cu")
		(net "GND")
	)
	(segment
		(start 390.474962 -299.975016)
		(end 388.754874 -299.975016)
		(width 0.508)
		(layer "F.Cu")
		(net "GND")
	)
	(segment
		(start 454.758552 -246.047006)
		(end 454.758552 -245.542562)
		(width 0.508)
		(layer "F.Cu")
		(net "GND")
	)
	(segment
		(start 313.911996 -131.412488)
		(end 313.892184 -131.4323)
		(width 0.508)
		(layer "F.Cu")
		(net "GND")
	)
	(segment
		(start 390.474962 -157.034992)
		(end 388.754874 -157.034992)
		(width 0.508)
		(layer "F.Cu")
		(net "GND")
	)
	(segment
		(start 61.574934 -62.354968)
		(end 59.854846 -62.354968)
		(width 0.508)
		(layer "F.Cu")
		(net "GND")
	)
	(segment
		(start 187.775088 -292.355016)
		(end 186.055 -292.355016)
		(width 0.508)
		(layer "F.Cu")
		(net "GND")
	)
	(segment
		(start 370.572792 -245.329456)
		(end 370.577618 -245.334282)
		(width 0.508)
		(layer "F.Cu")
		(net "GND")
	)
	(segment
		(start 420.200074 -151.035004)
		(end 422.082976 -151.035004)
		(width 0.508)
		(layer "F.Cu")
		(net "GND")
	)
	(segment
		(start 329.819 -305.928522)
		(end 330.21651 -306.326032)
		(width 0.508)
		(layer "F.Cu")
		(net "GND")
	)
	(segment
		(start 232.358184 -388.72287)
		(end 233.30027 -388.72287)
		(width 0.508)
		(layer "F.Cu")
		(net "GND")
	)
	(segment
		(start 187.775088 -67.434968)
		(end 186.055 -67.434968)
		(width 0.508)
		(layer "F.Cu")
		(net "GND")
	)
	(segment
		(start 121.960386 -52.379626)
		(end 121.510044 -52.829968)
		(width 0.508)
		(layer "F.Cu")
		(net "GND")
	)
	(segment
		(start 183.105044 -280.42997)
		(end 184.912 -280.42997)
		(width 0.508)
		(layer "F.Cu")
		(net "GND")
	)
	(segment
		(start 127.844296 -290.061142)
		(end 128.7018 -290.061142)
		(width 0.508)
		(layer "F.Cu")
		(net "GND")
	)
	(segment
		(start 124.674884 -164.654992)
		(end 122.954796 -164.654992)
		(width 0.508)
		(layer "F.Cu")
		(net "GND")
	)
	(segment
		(start 413.307784 -289.196018)
		(end 413.307784 -290.333176)
		(width 0.508)
		(layer "F.Cu")
		(net "GND")
	)
	(segment
		(start 91.300046 -79.784956)
		(end 93.182948 -79.784956)
		(width 0.508)
		(layer "F.Cu")
		(net "GND")
	)
	(segment
		(start 448.904868 -55.230014)
		(end 447.163444 -55.230014)
		(width 0.508)
		(layer "F.Cu")
		(net "GND")
	)
	(segment
		(start 145.868898 -62.778894)
		(end 144.71269 -62.778894)
		(width 0.508)
		(layer "F.Cu")
		(net "GND")
	)
	(segment
		(start 61.574934 -177.354992)
		(end 59.854846 -177.354992)
		(width 0.508)
		(layer "F.Cu")
		(net "GND")
	)
	(segment
		(start 52.631086 -49.494694)
		(end 53.555646 -49.494694)
		(width 0.4064)
		(layer "F.Cu")
		(net "GND")
	)
	(segment
		(start 133.497066 -137.548874)
		(end 135.029956 -137.548874)
		(width 0.254)
		(layer "F.Cu")
		(net "GND")
	)
	(segment
		(start 70.603872 -184.10809)
		(end 70.603872 -183.01589)
		(width 0.508)
		(layer "F.Cu")
		(net "GND")
	)
	(segment
		(start 338.38769 -130.376676)
		(end 338.385404 -130.378962)
		(width 0.508)
		(layer "F.Cu")
		(net "GND")
	)
	(segment
		(start 113.302796 -59.603894)
		(end 113.302796 -61.000894)
		(width 0.508)
		(layer "F.Cu")
		(net "GND")
	)
	(segment
		(start 259.744972 10.1854)
		(end 259.744972 9.3726)
		(width 0.508)
		(layer "F.Cu")
		(net "GND")
	)
	(segment
		(start 82.880708 -162.615118)
		(end 82.133948 -162.615118)
		(width 0.4064)
		(layer "F.Cu")
		(net "GND")
	)
	(segment
		(start 76.822808 -294.683942)
		(end 76.850748 -294.683942)
		(width 0.508)
		(layer "F.Cu")
		(net "GND")
	)
	(segment
		(start 457.6699 -304.920142)
		(end 457.6699 -306.113942)
		(width 0.508)
		(layer "F.Cu")
		(net "GND")
	)
	(segment
		(start 45.300646 -64.683894)
		(end 44.106846 -64.683894)
		(width 0.508)
		(layer "F.Cu")
		(net "GND")
	)
	(segment
		(start 154.399996 -151.035004)
		(end 156.282898 -151.035004)
		(width 0.508)
		(layer "F.Cu")
		(net "GND")
	)
	(segment
		(start 283.0576 14.138148)
		(end 282.152852 14.138148)
		(width 0.508)
		(layer "F.Cu")
		(net "GND")
	)
	(segment
		(start 262.24992 -212.046566)
		(end 261.231888 -212.046566)
		(width 0.508)
		(layer "F.Cu")
		(net "GND")
	)
	(segment
		(start 257.790188 -138.482578)
		(end 258.653788 -138.482578)
		(width 0.508)
		(layer "F.Cu")
		(net "GND")
	)
	(segment
		(start 23.936198 -185.322718)
		(end 22.666198 -185.322718)
		(width 0.508)
		(layer "F.Cu")
		(net "GND")
	)
	(segment
		(start 145.868898 -177.778918)
		(end 144.852898 -177.778918)
		(width 0.508)
		(layer "F.Cu")
		(net "GND")
	)
	(segment
		(start 25.355042 -50.429922)
		(end 27.161998 -50.429922)
		(width 0.508)
		(layer "F.Cu")
		(net "GND")
	)
	(segment
		(start 459.7019 -304.920142)
		(end 459.7019 -306.113942)
		(width 0.508)
		(layer "F.Cu")
		(net "GND")
	)
	(segment
		(start 402.122894 -243.773198)
		(end 402.122894 -245.31066)
		(width 0.508)
		(layer "F.Cu")
		(net "GND")
	)
	(segment
		(start 48.771302 -148.71065)
		(end 48.771302 -149.79015)
		(width 0.508)
		(layer "F.Cu")
		(net "GND")
	)
	(segment
		(start 224.8662 -348.2467)
		(end 225.174048 -348.2467)
		(width 0.3556)
		(layer "F.Cu")
		(net "GND")
	)
	(segment
		(start 7.890256 -177.872136)
		(end 7.890256 -179.045616)
		(width 0.508)
		(layer "F.Cu")
		(net "GND")
	)
	(segment
		(start 124.674884 -67.434968)
		(end 122.218196 -67.434968)
		(width 0.508)
		(layer "F.Cu")
		(net "GND")
	)
	(segment
		(start 478.282 -47.623476)
		(end 478.282 -47.383446)
		(width 0.508)
		(layer "F.Cu")
		(net "GND")
	)
	(segment
		(start 457.699872 -189.965076)
		(end 457.699872 -191.158876)
		(width 0.508)
		(layer "F.Cu")
		(net "GND")
	)
	(segment
		(start 241.76101 -379.837696)
		(end 241.76101 -378.830586)
		(width 0.508)
		(layer "F.Cu")
		(net "GND")
	)
	(segment
		(start 453.574912 -184.974992)
		(end 451.854824 -184.974992)
		(width 0.508)
		(layer "F.Cu")
		(net "GND")
	)
	(segment
		(start 81.752948 -289.603942)
		(end 81.752948 -291.000942)
		(width 0.508)
		(layer "F.Cu")
		(net "GND")
	)
	(segment
		(start 187.775088 -275.845016)
		(end 186.055 -275.845016)
		(width 0.508)
		(layer "F.Cu")
		(net "GND")
	)
	(segment
		(start 122.849894 -194.78498)
		(end 124.732796 -194.78498)
		(width 0.508)
		(layer "F.Cu")
		(net "GND")
	)
	(segment
		(start 157.518862 -128.66497)
		(end 157.518862 -130.046476)
		(width 0.508)
		(layer "F.Cu")
		(net "GND")
	)
	(segment
		(start 187.775088 -272.035016)
		(end 186.055 -272.035016)
		(width 0.508)
		(layer "F.Cu")
		(net "GND")
	)
	(segment
		(start 154.399996 -35.742626)
		(end 154.399996 -36.03498)
		(width 0.508)
		(layer "F.Cu")
		(net "GND")
	)
	(segment
		(start 238.005874 -231.659938)
		(end 238.005874 -232.342436)
		(width 0.508)
		(layer "F.Cu")
		(net "GND")
	)
	(segment
		(start 357.100124 -151.035004)
		(end 358.983026 -151.035004)
		(width 0.508)
		(layer "F.Cu")
		(net "GND")
	)
	(segment
		(start 226.186746 -347.234002)
		(end 227.501704 -347.234002)
		(width 0.3556)
		(layer "F.Cu")
		(net "GND")
	)
	(segment
		(start 396.60195 -304.920142)
		(end 396.60195 -306.113942)
		(width 0.508)
		(layer "F.Cu")
		(net "GND")
	)
	(segment
		(start 420.062406 -68.012564)
		(end 420.640002 -67.434968)
		(width 0.508)
		(layer "F.Cu")
		(net "GND")
	)
	(segment
		(start 259.50164 11.64336)
		(end 259.50164 12.530328)
		(width 0.381)
		(layer "F.Cu")
		(net "GND")
	)
	(segment
		(start 327.375012 -297.435016)
		(end 325.654924 -297.435016)
		(width 0.508)
		(layer "F.Cu")
		(net "GND")
	)
	(segment
		(start 183.105044 -170.230038)
		(end 184.912 -170.230038)
		(width 0.508)
		(layer "F.Cu")
		(net "GND")
	)
	(segment
		(start 342.594184 -246.249952)
		(end 342.594184 -245.28907)
		(width 0.508)
		(layer "F.Cu")
		(net "GND")
	)
	(segment
		(start 31.829502 -254.43815)
		(end 31.380938 -254.886714)
		(width 0.508)
		(layer "F.Cu")
		(net "GND")
	)
	(segment
		(start 59.749944 -266.035028)
		(end 61.632846 -266.035028)
		(width 0.508)
		(layer "F.Cu")
		(net "GND")
	)
	(segment
		(start 88.454992 -50.429922)
		(end 90.261948 -50.429922)
		(width 0.508)
		(layer "F.Cu")
		(net "GND")
	)
	(segment
		(start 433.723542 -130.336036)
		(end 433.725828 -130.33375)
		(width 0.508)
		(layer "F.Cu")
		(net "GND")
	)
	(segment
		(start 357.100124 -194.78498)
		(end 355.15423 -194.78498)
		(width 0.508)
		(layer "F.Cu")
		(net "GND")
	)
	(segment
		(start 466.402674 -289.729926)
		(end 466.453474 -289.780726)
		(width 0.508)
		(layer "F.Cu")
		(net "GND")
	)
	(segment
		(start 174.1297 -54.022244)
		(end 174.12843 -54.022244)
		(width 0.508)
		(layer "F.Cu")
		(net "GND")
	)
	(segment
		(start 422.025064 -164.654992)
		(end 420.304976 -164.654992)
		(width 0.508)
		(layer "F.Cu")
		(net "GND")
	)
	(segment
		(start 485.125014 -164.654992)
		(end 483.404926 -164.654992)
		(width 0.508)
		(layer "F.Cu")
		(net "GND")
	)
	(segment
		(start 145.980658 -277.615142)
		(end 145.233898 -277.615142)
		(width 0.4064)
		(layer "F.Cu")
		(net "GND")
	)
	(segment
		(start 338.4804 -14.351)
		(end 338.4804 -15.0368)
		(width 0.381)
		(layer "F.Cu")
		(net "GND")
	)
	(segment
		(start 225.174048 -348.2467)
		(end 226.186746 -347.234002)
		(width 0.3556)
		(layer "F.Cu")
		(net "GND")
	)
	(segment
		(start 55.790846 -305.224942)
		(end 55.790846 -306.240942)
		(width 0.508)
		(layer "F.Cu")
		(net "GND")
	)
	(segment
		(start 253.9238 -289.7505)
		(end 255.0922 -289.7505)
		(width 0.508)
		(layer "F.Cu")
		(net "GND")
	)
	(segment
		(start 176.353978 -27.240738)
		(end 177.154078 -27.240738)
		(width 0.508)
		(layer "F.Cu")
		(net "GND")
	)
	(segment
		(start 354.25507 -50.429922)
		(end 354.25507 -49.634902)
		(width 0.508)
		(layer "F.Cu")
		(net "GND")
	)
	(segment
		(start 365.274098 -181.294024)
		(end 364.344204 -182.223918)
		(width 0.508)
		(layer "F.Cu")
		(net "GND")
	)
	(segment
		(start 362.715302 -45.903134)
		(end 362.715302 -47.232824)
		(width 0.4064)
		(layer "F.Cu")
		(net "GND")
	)
	(segment
		(start 25.355042 -282.830016)
		(end 27.161998 -282.830016)
		(width 0.508)
		(layer "F.Cu")
		(net "GND")
	)
	(segment
		(start 70.631304 -304.106834)
		(end 70.631304 -304.12817)
		(width 0.508)
		(layer "F.Cu")
		(net "GND")
	)
	(segment
		(start 118.585996 -185.322718)
		(end 117.315996 -185.322718)
		(width 0.508)
		(layer "F.Cu")
		(net "GND")
	)
	(segment
		(start 250.94438 -256.033778)
		(end 250.94438 -255.055878)
		(width 0.508)
		(layer "F.Cu")
		(net "GND")
	)
	(segment
		(start 67.792346 -176.127918)
		(end 67.792346 -175.238918)
		(width 0.508)
		(layer "F.Cu")
		(net "GND")
	)
	(segment
		(start 147.281138 -164.494718)
		(end 148.205698 -164.494718)
		(width 0.4064)
		(layer "F.Cu")
		(net "GND")
	)
	(segment
		(start 224.7011 -386.262372)
		(end 226.741228 -386.262372)
		(width 0.508)
		(layer "F.Cu")
		(net "GND")
	)
	(segment
		(start 419.90899 -297.435016)
		(end 422.025064 -297.435016)
		(width 0.508)
		(layer "F.Cu")
		(net "GND")
	)
	(segment
		(start 426.120052 -304.920142)
		(end 426.120052 -306.113942)
		(width 0.508)
		(layer "F.Cu")
		(net "GND")
	)
	(segment
		(start 390.474962 -69.974968)
		(end 388.754874 -69.974968)
		(width 0.508)
		(layer "F.Cu")
		(net "GND")
	)
	(segment
		(start 388.649972 -194.78498)
		(end 390.532874 -194.78498)
		(width 0.508)
		(layer "F.Cu")
		(net "GND")
	)
	(segment
		(start 468.76843 -131.200144)
		(end 468.76843 -130.376168)
		(width 0.508)
		(layer "F.Cu")
		(net "GND")
	)
	(segment
		(start 428.152052 -74.920094)
		(end 428.152052 -76.113894)
		(width 0.508)
		(layer "F.Cu")
		(net "GND")
	)
	(segment
		(start 230.0986 -391.033)
		(end 230.0986 -392.0744)
		(width 0.508)
		(layer "F.Cu")
		(net "GND")
	)
	(segment
		(start 273.485102 31.074868)
		(end 273.485102 29.35478)
		(width 0.508)
		(layer "F.Cu")
		(net "GND")
	)
	(segment
		(start 371.62359 -128.68529)
		(end 372.995952 -128.68529)
		(width 0.508)
		(layer "F.Cu")
		(net "GND")
	)
	(segment
		(start 474.768926 -177.778918)
		(end 473.752926 -177.778918)
		(width 0.508)
		(layer "F.Cu")
		(net "GND")
	)
	(segment
		(start 324.886574 -272.05559)
		(end 324.907148 -272.035016)
		(width 0.508)
		(layer "F.Cu")
		(net "GND")
	)
	(segment
		(start 25.355042 -55.230014)
		(end 27.161998 -55.230014)
		(width 0.508)
		(layer "F.Cu")
		(net "GND")
	)
	(segment
		(start 342.594184 -245.28907)
		(end 342.594184 -243.795804)
		(width 0.508)
		(layer "F.Cu")
		(net "GND")
	)
	(segment
		(start 459.2447 -159.602678)
		(end 459.2447 -158.855918)
		(width 0.4064)
		(layer "F.Cu")
		(net "GND")
	)
	(segment
		(start 332.105 -42.140886)
		(end 331.290422 -42.140886)
		(width 0.508)
		(layer "F.Cu")
		(net "GND")
	)
	(segment
		(start 150.136098 -300.322742)
		(end 148.866098 -300.322742)
		(width 0.508)
		(layer "F.Cu")
		(net "GND")
	)
	(segment
		(start 448.904868 -52.829968)
		(end 450.711824 -52.829968)
		(width 0.508)
		(layer "F.Cu")
		(net "GND")
	)
	(segment
		(start 444.5762 -61.102494)
		(end 443.6364 -61.102494)
		(width 0.508)
		(layer "F.Cu")
		(net "GND")
	)
	(segment
		(start 154.106372 -42.81932)
		(end 154.890724 -42.034968)
		(width 0.508)
		(layer "F.Cu")
		(net "GND")
	)
	(segment
		(start 221.021402 -213.436962)
		(end 221.021402 -212.382862)
		(width 0.508)
		(layer "F.Cu")
		(net "GND")
	)
	(segment
		(start 154.422094 -67.039236)
		(end 154.817826 -67.434968)
		(width 0.508)
		(layer "F.Cu")
		(net "GND")
	)
	(segment
		(start 317.62065 -246.188992)
		(end 317.62065 -245.365016)
		(width 0.508)
		(layer "F.Cu")
		(net "GND")
	)
	(segment
		(start 473.36202 -275.57222)
		(end 473.3798 -275.59)
		(width 0.3556)
		(layer "F.Cu")
		(net "GND")
	)
	(segment
		(start 114.430556 -47.615094)
		(end 113.683796 -47.615094)
		(width 0.4064)
		(layer "F.Cu")
		(net "GND")
	)
	(segment
		(start 333.7433 -296.16146)
		(end 332.680818 -297.223942)
		(width 0.508)
		(layer "F.Cu")
		(net "GND")
	)
	(segment
		(start 120.740932 -55.230014)
		(end 120.00484 -55.230014)
		(width 0.508)
		(layer "F.Cu")
		(net "GND")
	)
	(segment
		(start 457.3651 -160.903158)
		(end 457.3651 -161.649918)
		(width 0.4064)
		(layer "F.Cu")
		(net "GND")
	)
	(segment
		(start 471.479626 -53.126894)
		(end 471.479626 -54.015894)
		(width 0.508)
		(layer "F.Cu")
		(net "GND")
	)
	(segment
		(start 236.031278 -263.136888)
		(end 236.031278 -263.114282)
		(width 0.508)
		(layer "F.Cu")
		(net "GND")
	)
	(segment
		(start 176.293018 -28.635452)
		(end 176.84623 -28.635452)
		(width 0.508)
		(layer "F.Cu")
		(net "GND")
	)
	(segment
		(start 396.14475 -159.602678)
		(end 396.14475 -158.855918)
		(width 0.4064)
		(layer "F.Cu")
		(net "GND")
	)
	(segment
		(start 329.819 -190.097918)
		(end 329.819 -191.113918)
		(width 0.508)
		(layer "F.Cu")
		(net "GND")
	)
	(segment
		(start 122.849894 -151.035004)
		(end 124.732796 -151.035004)
		(width 0.508)
		(layer "F.Cu")
		(net "GND")
	)
	(segment
		(start 255.090676 -289.048952)
		(end 255.090676 -288.9504)
		(width 0.508)
		(layer "F.Cu")
		(net "GND")
	)
	(segment
		(start 133.702552 -302.941228)
		(end 133.702552 -304.227738)
		(width 0.508)
		(layer "F.Cu")
		(net "GND")
	)
	(segment
		(start 392.91895 -75.097894)
		(end 392.91895 -76.113894)
		(width 0.508)
		(layer "F.Cu")
		(net "GND")
	)
	(segment
		(start 93.125036 -62.354968)
		(end 91.404948 -62.354968)
		(width 0.508)
		(layer "F.Cu")
		(net "GND")
	)
	(segment
		(start 93.125036 -292.355016)
		(end 91.404948 -292.355016)
		(width 0.508)
		(layer "F.Cu")
		(net "GND")
	)
	(segment
		(start 325.757032 -42.034968)
		(end 327.375012 -42.034968)
		(width 0.508)
		(layer "F.Cu")
		(net "GND")
	)
	(segment
		(start 485.125014 -160.844992)
		(end 483.404926 -160.844992)
		(width 0.508)
		(layer "F.Cu")
		(net "GND")
	)
	(segment
		(start 124.674884 -160.844992)
		(end 122.954796 -160.844992)
		(width 0.508)
		(layer "F.Cu")
		(net "GND")
	)
	(segment
		(start 318.708786 -60.060586)
		(end 317.60414 -60.060586)
		(width 0.508)
		(layer "F.Cu")
		(net "GND")
	)
	(segment
		(start 113.302796 -174.603918)
		(end 113.302796 -176.000918)
		(width 0.508)
		(layer "F.Cu")
		(net "GND")
	)
	(segment
		(start 115.182142 -275.942044)
		(end 115.182142 -276.6822)
		(width 0.4064)
		(layer "F.Cu")
		(net "GND")
	)
	(segment
		(start 359.0036 -145.1229)
		(end 359.0036 -146.05)
		(width 0.508)
		(layer "F.Cu")
		(net "GND")
	)
	(segment
		(start 311.11825 -57.18175)
		(end 311.0992 -57.2008)
		(width 0.508)
		(layer "F.Cu")
		(net "GND")
	)
	(segment
		(start 299.795946 -25.74544)
		(end 300.758352 -25.74544)
		(width 0.508)
		(layer "F.Cu")
		(net "GND")
	)
	(segment
		(start 473.849192 -287.195514)
		(end 473.849192 -286.120332)
		(width 0.508)
		(layer "F.Cu")
		(net "GND")
	)
	(segment
		(start 51.381406 -160.329118)
		(end 50.583846 -160.329118)
		(width 0.4064)
		(layer "F.Cu")
		(net "GND")
	)
	(segment
		(start 239.491266 -346.787978)
		(end 239.491266 -347.716856)
		(width 0.508)
		(layer "F.Cu")
		(net "GND")
	)
	(segment
		(start 224.80016 -2.95021)
		(end 224.80016 -5.176012)
		(width 0.508)
		(layer "F.Cu")
		(net "GND")
	)
	(segment
		(start 362.715302 -275.903182)
		(end 362.715302 -276.649942)
		(width 0.4064)
		(layer "F.Cu")
		(net "GND")
	)
	(segment
		(start 187.775088 -42.034968)
		(end 186.055 -42.034968)
		(width 0.508)
		(layer "F.Cu")
		(net "GND")
	)
	(segment
		(start 472.215718 -158.437834)
		(end 472.215718 -157.513274)
		(width 0.4064)
		(layer "F.Cu")
		(net "GND")
	)
	(segment
		(start 417.35502 -167.829992)
		(end 419.161976 -167.829992)
		(width 0.508)
		(layer "F.Cu")
		(net "GND")
	)
	(segment
		(start 184.05983 -35.291014)
		(end 184.803796 -36.03498)
		(width 0.508)
		(layer "F.Cu")
		(net "GND")
	)
	(segment
		(start 387.435344 -37.939726)
		(end 388.649972 -36.725098)
		(width 0.508)
		(layer "F.Cu")
		(net "GND")
	)
	(segment
		(start 317.5381 -61.127894)
		(end 317.041022 -61.624972)
		(width 0.508)
		(layer "F.Cu")
		(net "GND")
	)
	(segment
		(start 451.749922 -79.784956)
		(end 453.632824 -79.784956)
		(width 0.508)
		(layer "F.Cu")
		(net "GND")
	)
	(segment
		(start 272.8976 19.587972)
		(end 272.8976 20.574)
		(width 0.508)
		(layer "F.Cu")
		(net "GND")
	)
	(segment
		(start 156.2354 -131.2799)
		(end 156.2354 -130.374898)
		(width 0.508)
		(layer "F.Cu")
		(net "GND")
	)
	(segment
		(start 412.467552 -176.127918)
		(end 412.467552 -175.238918)
		(width 0.508)
		(layer "F.Cu")
		(net "GND")
	)
	(segment
		(start 451.749922 -309.785004)
		(end 453.632824 -309.785004)
		(width 0.508)
		(layer "F.Cu")
		(net "GND")
	)
	(segment
		(start 133.731254 -295.423336)
		(end 133.731254 -296.302684)
		(width 0.508)
		(layer "F.Cu")
		(net "GND")
	)
	(segment
		(start 269.57655 11.1633)
		(end 269.57655 10.256012)
		(width 0.508)
		(layer "F.Cu")
		(net "GND")
	)
	(segment
		(start 281.2034 -279.3746)
		(end 281.2034 -278.3967)
		(width 0.508)
		(layer "F.Cu")
		(net "GND")
	)
	(segment
		(start 187.775088 -45.844968)
		(end 186.055 -45.844968)
		(width 0.508)
		(layer "F.Cu")
		(net "GND")
	)
	(segment
		(start 245.364 -230.6955)
		(end 244.221 -230.6955)
		(width 0.508)
		(layer "F.Cu")
		(net "GND")
	)
	(segment
		(start 93.125036 -279.655016)
		(end 91.404948 -279.655016)
		(width 0.508)
		(layer "F.Cu")
		(net "GND")
	)
	(segment
		(start 30.025086 -67.434968)
		(end 28.304998 -67.434968)
		(width 0.508)
		(layer "F.Cu")
		(net "GND")
	)
	(segment
		(start 87.036148 -300.322742)
		(end 85.766148 -300.322742)
		(width 0.508)
		(layer "F.Cu")
		(net "GND")
	)
	(segment
		(start 300.37786 -65.95745)
		(end 300.37786 -65.452752)
		(width 0.3048)
		(layer "F.Cu")
		(net "GND")
	)
	(segment
		(start 118.585996 -70.322694)
		(end 117.315996 -70.322694)
		(width 0.508)
		(layer "F.Cu")
		(net "GND")
	)
	(segment
		(start 171.5008 -294.683942)
		(end 169.5958 -294.683942)
		(width 0.508)
		(layer "F.Cu")
		(net "GND")
	)
	(segment
		(start 333.0448 -274.602702)
		(end 333.0448 -273.855942)
		(width 0.4064)
		(layer "F.Cu")
		(net "GND")
	)
	(segment
		(start 19.668998 -177.778918)
		(end 18.652998 -177.778918)
		(width 0.508)
		(layer "F.Cu")
		(net "GND")
	)
	(segment
		(start 121.197878 -50.429922)
		(end 120.00484 -50.429922)
		(width 0.508)
		(layer "F.Cu")
		(net "GND")
	)
	(segment
		(start 61.574934 -67.434968)
		(end 59.854846 -67.434968)
		(width 0.508)
		(layer "F.Cu")
		(net "GND")
	)
	(segment
		(start 374.144032 -245.303802)
		(end 374.144032 -243.785136)
		(width 0.508)
		(layer "F.Cu")
		(net "GND")
	)
	(segment
		(start 88.454992 -282.830016)
		(end 90.261948 -282.830016)
		(width 0.508)
		(layer "F.Cu")
		(net "GND")
	)
	(segment
		(start 422.025064 -272.035016)
		(end 420.304976 -272.035016)
		(width 0.508)
		(layer "F.Cu")
		(net "GND")
	)
	(segment
		(start 125.813058 -45.844968)
		(end 124.674884 -45.844968)
		(width 0.508)
		(layer "F.Cu")
		(net "GND")
	)
	(segment
		(start 93.125036 -275.845016)
		(end 91.404948 -275.845016)
		(width 0.508)
		(layer "F.Cu")
		(net "GND")
	)
	(segment
		(start 364.594902 -159.602678)
		(end 364.594902 -158.855918)
		(width 0.4064)
		(layer "F.Cu")
		(net "GND")
	)
	(segment
		(start 31.829502 -253.35865)
		(end 31.829502 -254.43815)
		(width 0.508)
		(layer "F.Cu")
		(net "GND")
	)
	(segment
		(start 239.50295 -347.72854)
		(end 239.50295 -348.718378)
		(width 0.508)
		(layer "F.Cu")
		(net "GND")
	)
	(segment
		(start 165.408864 -294.84574)
		(end 165.408864 -295.668954)
		(width 0.508)
		(layer "F.Cu")
		(net "GND")
	)
	(segment
		(start 405.719534 -245.335806)
		(end 405.719534 -246.245888)
		(width 0.508)
		(layer "F.Cu")
		(net "GND")
	)
	(segment
		(start 365.052102 -304.920142)
		(end 365.052102 -306.113942)
		(width 0.508)
		(layer "F.Cu")
		(net "GND")
	)
	(segment
		(start 91.300046 -266.035028)
		(end 93.182948 -266.035028)
		(width 0.508)
		(layer "F.Cu")
		(net "GND")
	)
	(segment
		(start 25.355042 -167.829992)
		(end 27.161998 -167.829992)
		(width 0.508)
		(layer "F.Cu")
		(net "GND")
	)
	(segment
		(start 229.855014 -368.315494)
		(end 229.855014 -370.063014)
		(width 0.3048)
		(layer "F.Cu")
		(net "GND")
	)
	(segment
		(start 358.925114 -272.035016)
		(end 357.205026 -272.035016)
		(width 0.508)
		(layer "F.Cu")
		(net "GND")
	)
	(segment
		(start 485.125014 -184.974992)
		(end 483.404926 -184.974992)
		(width 0.508)
		(layer "F.Cu")
		(net "GND")
	)
	(segment
		(start 298.91609 -156.129228)
		(end 298.91609 -157.209236)
		(width 0.508)
		(layer "F.Cu")
		(net "GND")
	)
	(segment
		(start 471.536014 -280.158698)
		(end 471.536014 -280.928064)
		(width 0.508)
		(layer "F.Cu")
		(net "GND")
	)
	(segment
		(start 117.60327 -49.494694)
		(end 118.090696 -49.007268)
		(width 0.508)
		(layer "F.Cu")
		(net "GND")
	)
	(segment
		(start 158.787338 -27.338782)
		(end 159.772096 -27.338782)
		(width 0.508)
		(layer "F.Cu")
		(net "GND")
	)
	(segment
		(start 61.574934 -292.355016)
		(end 59.854846 -292.355016)
		(width 0.508)
		(layer "F.Cu")
		(net "GND")
	)
	(segment
		(start 183.105044 -55.230014)
		(end 184.912 -55.230014)
		(width 0.508)
		(layer "F.Cu")
		(net "GND")
	)
	(segment
		(start 278.7904 20.945348)
		(end 279.610566 20.945348)
		(width 0.508)
		(layer "F.Cu")
		(net "GND")
	)
	(segment
		(start 475.144592 -289.103816)
		(end 475.278196 -289.23742)
		(width 0.508)
		(layer "F.Cu")
		(net "GND")
	)
	(segment
		(start 451.749922 -151.035004)
		(end 453.632824 -151.035004)
		(width 0.508)
		(layer "F.Cu")
		(net "GND")
	)
	(segment
		(start 156.224986 -182.434992)
		(end 154.504898 -182.434992)
		(width 0.508)
		(layer "F.Cu")
		(net "GND")
	)
	(segment
		(start 420.200074 -36.03498)
		(end 422.082976 -36.03498)
		(width 0.508)
		(layer "F.Cu")
		(net "GND")
	)
	(segment
		(start 70.758304 -294.191182)
		(end 70.758304 -295.07815)
		(width 0.508)
		(layer "F.Cu")
		(net "GND")
	)
	(segment
		(start 36.242498 -291.127942)
		(end 36.242498 -290.238942)
		(width 0.508)
		(layer "F.Cu")
		(net "GND")
	)
	(segment
		(start 133.497066 -136.736074)
		(end 133.497066 -137.548874)
		(width 0.508)
		(layer "F.Cu")
		(net "GND")
	)
	(segment
		(start 422.025064 -279.655016)
		(end 420.304976 -279.655016)
		(width 0.508)
		(layer "F.Cu")
		(net "GND")
	)
	(segment
		(start 479.036126 -185.322718)
		(end 477.766126 -185.322718)
		(width 0.508)
		(layer "F.Cu")
		(net "GND")
	)
	(segment
		(start 363.655102 -157.141418)
		(end 363.655102 -156.315918)
		(width 0.508)
		(layer "F.Cu")
		(net "GND")
	)
	(segment
		(start 354.25507 -282.830016)
		(end 351.915476 -282.830016)
		(width 0.508)
		(layer "F.Cu")
		(net "GND")
	)
	(segment
		(start 124.674884 -184.974992)
		(end 122.954796 -184.974992)
		(width 0.508)
		(layer "F.Cu")
		(net "GND")
	)
	(segment
		(start 30.025086 -174.814992)
		(end 28.304998 -174.814992)
		(width 0.508)
		(layer "F.Cu")
		(net "GND")
	)
	(segment
		(start 324.907148 -272.035016)
		(end 327.375012 -272.035016)
		(width 0.508)
		(layer "F.Cu")
		(net "GND")
	)
	(segment
		(start 24.240998 -305.224942)
		(end 24.240998 -306.240942)
		(width 0.508)
		(layer "F.Cu")
		(net "GND")
	)
	(segment
		(start 120.00484 -280.42997)
		(end 121.811796 -280.42997)
		(width 0.508)
		(layer "F.Cu")
		(net "GND")
	)
	(segment
		(start 466.3948 -288.71418)
		(end 466.3948 -289.722052)
		(width 0.508)
		(layer "F.Cu")
		(net "GND")
	)
	(segment
		(start 111.029496 -53.126894)
		(end 111.029496 -54.015894)
		(width 0.508)
		(layer "F.Cu")
		(net "GND")
	)
	(segment
		(start 224.475802 -209.864198)
		(end 224.475802 -210.630262)
		(width 0.381)
		(layer "F.Cu")
		(net "GND")
	)
	(segment
		(start 478.74809 -270.265652)
		(end 478.74809 -271.1196)
		(width 0.508)
		(layer "F.Cu")
		(net "GND")
	)
	(segment
		(start 39.04107 -187.962794)
		(end 39.04107 -189.187074)
		(width 0.508)
		(layer "F.Cu")
		(net "GND")
	)
	(segment
		(start 253.873 -302.387)
		(end 253.365 -302.895)
		(width 0.508)
		(layer "F.Cu")
		(net "GND")
	)
	(segment
		(start 76.822808 -295.951148)
		(end 76.822808 -294.683942)
		(width 0.508)
		(layer "F.Cu")
		(net "GND")
	)
	(segment
		(start 395.45895 -297.223942)
		(end 396.85595 -297.223942)
		(width 0.508)
		(layer "F.Cu")
		(net "GND")
	)
	(segment
		(start 276.2758 -285.1531)
		(end 276.2758 -285.9532)
		(width 0.508)
		(layer "F.Cu")
		(net "GND")
	)
	(segment
		(start 135.857996 -291.077142)
		(end 135.857996 -289.502596)
		(width 0.508)
		(layer "F.Cu")
		(net "GND")
	)
	(segment
		(start 161.134552 -128.655572)
		(end 161.134552 -130.037078)
		(width 0.508)
		(layer "F.Cu")
		(net "GND")
	)
	(segment
		(start 312.343038 -290.91255)
		(end 312.343038 -291.73932)
		(width 0.508)
		(layer "F.Cu")
		(net "GND")
	)
	(segment
		(start 84.181188 -164.494718)
		(end 85.105748 -164.494718)
		(width 0.4064)
		(layer "F.Cu")
		(net "GND")
	)
	(segment
		(start 183.105044 -167.829992)
		(end 184.912 -167.829992)
		(width 0.508)
		(layer "F.Cu")
		(net "GND")
	)
	(segment
		(start 115.731036 -164.494718)
		(end 116.655596 -164.494718)
		(width 0.4064)
		(layer "F.Cu")
		(net "GND")
	)
	(segment
		(start 327.375012 -184.974992)
		(end 325.654924 -184.974992)
		(width 0.508)
		(layer "F.Cu")
		(net "GND")
	)
	(segment
		(start 394.56995 -74.920094)
		(end 394.56995 -76.113894)
		(width 0.508)
		(layer "F.Cu")
		(net "GND")
	)
	(segment
		(start 7.791704 -169.549572)
		(end 7.791704 -168.596056)
		(width 0.508)
		(layer "F.Cu")
		(net "GND")
	)
	(segment
		(start 45.300646 -179.683918)
		(end 44.106846 -179.683918)
		(width 0.508)
		(layer "F.Cu")
		(net "GND")
	)
	(segment
		(start 316.266576 -291.63137)
		(end 316.625478 -291.63137)
		(width 0.508)
		(layer "F.Cu")
		(net "GND")
	)
	(segment
		(start 235.652564 -244.615208)
		(end 234.86618 -244.615208)
		(width 0.508)
		(layer "F.Cu")
		(net "GND")
	)
	(segment
		(start 483.300024 -79.784956)
		(end 485.182926 -79.784956)
		(width 0.508)
		(layer "F.Cu")
		(net "GND")
	)
	(segment
		(start 249.32132 -234.1626)
		(end 249.32132 -236.900212)
		(width 0.3556)
		(layer "F.Cu")
		(net "GND")
	)
	(segment
		(start 358.925114 -182.434992)
		(end 357.205026 -182.434992)
		(width 0.508)
		(layer "F.Cu")
		(net "GND")
	)
	(segment
		(start 118.890796 -190.224918)
		(end 118.890796 -191.240918)
		(width 0.508)
		(layer "F.Cu")
		(net "GND")
	)
	(segment
		(start 358.925114 -184.974992)
		(end 357.205026 -184.974992)
		(width 0.508)
		(layer "F.Cu")
		(net "GND")
	)
	(segment
		(start 453.574912 -299.975016)
		(end 451.854824 -299.975016)
		(width 0.508)
		(layer "F.Cu")
		(net "GND")
	)
	(segment
		(start 97.860358 -296.23512)
		(end 97.84334 -296.252138)
		(width 0.508)
		(layer "F.Cu")
		(net "GND")
	)
	(segment
		(start 61.574934 -59.814968)
		(end 59.854846 -59.814968)
		(width 0.508)
		(layer "F.Cu")
		(net "GND")
	)
	(segment
		(start 254.39116 15.78864)
		(end 254.39116 15.231872)
		(width 0.381)
		(layer "F.Cu")
		(net "GND")
	)
	(segment
		(start 259.588 -289.94989)
		(end 259.588 -290.957)
		(width 0.508)
		(layer "F.Cu")
		(net "GND")
	)
	(segment
		(start 483.3874 -292.0238)
		(end 483.718616 -292.355016)
		(width 0.508)
		(layer "F.Cu")
		(net "GND")
	)
	(segment
		(start 56.90489 -55.230014)
		(end 58.711846 -55.230014)
		(width 0.508)
		(layer "F.Cu")
		(net "GND")
	)
	(segment
		(start 124.674884 -299.975016)
		(end 122.954796 -299.975016)
		(width 0.508)
		(layer "F.Cu")
		(net "GND")
	)
	(segment
		(start 175.114204 -60.103512)
		(end 176.011586 -61.000894)
		(width 0.508)
		(layer "F.Cu")
		(net "GND")
	)
	(segment
		(start 394.56995 -304.920142)
		(end 394.56995 -307.059838)
		(width 0.508)
		(layer "F.Cu")
		(net "GND")
	)
	(segment
		(start 474.768926 -62.778894)
		(end 473.752926 -62.778894)
		(width 0.508)
		(layer "F.Cu")
		(net "GND")
	)
	(segment
		(start 425.815252 -45.903134)
		(end 425.815252 -46.649894)
		(width 0.4064)
		(layer "F.Cu")
		(net "GND")
	)
	(segment
		(start 18.652998 -59.603894)
		(end 18.652998 -61.000894)
		(width 0.508)
		(layer "F.Cu")
		(net "GND")
	)
	(segment
		(start 55.486046 -300.322742)
		(end 54.216046 -300.322742)
		(width 0.508)
		(layer "F.Cu")
		(net "GND")
	)
	(segment
		(start 325.550022 -309.785004)
		(end 327.432924 -309.785004)
		(width 0.508)
		(layer "F.Cu")
		(net "GND")
	)
	(segment
		(start 433.725828 -130.33375)
		(end 433.725828 -131.33451)
		(width 0.508)
		(layer "F.Cu")
		(net "GND")
	)
	(segment
		(start 156.224986 -184.974992)
		(end 154.504898 -184.974992)
		(width 0.508)
		(layer "F.Cu")
		(net "GND")
	)
	(segment
		(start 118.090696 -49.007268)
		(end 118.090696 -48.554894)
		(width 0.508)
		(layer "F.Cu")
		(net "GND")
	)
	(segment
		(start 390.474962 -297.435016)
		(end 388.754874 -297.435016)
		(width 0.508)
		(layer "F.Cu")
		(net "GND")
	)
	(segment
		(start 314.032138 -242.327938)
		(end 313.1058 -241.4016)
		(width 0.508)
		(layer "F.Cu")
		(net "GND")
	)
	(segment
		(start 55.790846 -75.224894)
		(end 55.790846 -76.240894)
		(width 0.508)
		(layer "F.Cu")
		(net "GND")
	)
	(segment
		(start 357.124 -60.1218)
		(end 357.430832 -59.814968)
		(width 0.508)
		(layer "F.Cu")
		(net "GND")
	)
	(segment
		(start 272.8976 10.739628)
		(end 272.8976 9.9314)
		(width 0.508)
		(layer "F.Cu")
		(net "GND")
	)
	(segment
		(start 61.574934 -279.655016)
		(end 59.854846 -279.655016)
		(width 0.508)
		(layer "F.Cu")
		(net "GND")
	)
	(segment
		(start 419.852348 -170.231816)
		(end 419.852348 -170.230038)
		(width 0.508)
		(layer "F.Cu")
		(net "GND")
	)
	(segment
		(start 121.64822 -36.03498)
		(end 122.849894 -36.03498)
		(width 0.508)
		(layer "F.Cu")
		(net "GND")
	)
	(segment
		(start 118.890796 -75.224894)
		(end 118.890796 -76.240894)
		(width 0.508)
		(layer "F.Cu")
		(net "GND")
	)
	(segment
		(start 56.90489 -165.429946)
		(end 58.711846 -165.429946)
		(width 0.508)
		(layer "F.Cu")
		(net "GND")
	)
	(segment
		(start 362.385102 -67.604894)
		(end 361.369102 -67.604894)
		(width 0.508)
		(layer "F.Cu")
		(net "GND")
	)
	(segment
		(start 61.574934 -157.034992)
		(end 59.854846 -157.034992)
		(width 0.508)
		(layer "F.Cu")
		(net "GND")
	)
	(segment
		(start 338.03717 -15.48003)
		(end 338.03717 -16.542766)
		(width 0.381)
		(layer "F.Cu")
		(net "GND")
	)
	(segment
		(start 133.660134 -184.154064)
		(end 133.660134 -183.061864)
		(width 0.508)
		(layer "F.Cu")
		(net "GND")
	)
	(segment
		(start 332.105 -157.141418)
		(end 332.105 -156.315918)
		(width 0.508)
		(layer "F.Cu")
		(net "GND")
	)
	(segment
		(start 24.240998 -190.224918)
		(end 24.240998 -191.240918)
		(width 0.508)
		(layer "F.Cu")
		(net "GND")
	)
	(segment
		(start 55.486046 -70.322694)
		(end 54.216046 -70.322694)
		(width 0.508)
		(layer "F.Cu")
		(net "GND")
	)
	(segment
		(start 339.022944 -245.314724)
		(end 339.02777 -245.31955)
		(width 0.508)
		(layer "F.Cu")
		(net "GND")
	)
	(segment
		(start 30.025086 -164.654992)
		(end 28.304998 -164.654992)
		(width 0.508)
		(layer "F.Cu")
		(net "GND")
	)
	(segment
		(start 263.09828 15.58417)
		(end 263.09828 16.75892)
		(width 0.381)
		(layer "F.Cu")
		(net "GND")
	)
	(segment
		(start 87.340948 -305.224942)
		(end 87.340948 -306.240942)
		(width 0.508)
		(layer "F.Cu")
		(net "GND")
	)
	(segment
		(start 124.674884 -62.354968)
		(end 122.954796 -62.354968)
		(width 0.508)
		(layer "F.Cu")
		(net "GND")
	)
	(segment
		(start 99.342448 -61.127894)
		(end 99.342448 -60.442094)
		(width 0.508)
		(layer "F.Cu")
		(net "GND")
	)
	(segment
		(start 21.081238 -279.494742)
		(end 22.005798 -279.494742)
		(width 0.4064)
		(layer "F.Cu")
		(net "GND")
	)
	(segment
		(start 191.2493 -53.2384)
		(end 191.2493 -54.2163)
		(width 0.508)
		(layer "F.Cu")
		(net "GND")
	)
	(segment
		(start 16.379698 -53.177694)
		(end 16.379698 -54.041294)
		(width 0.508)
		(layer "F.Cu")
		(net "GND")
	)
	(segment
		(start 121.510044 -52.829968)
		(end 120.00484 -52.829968)
		(width 0.508)
		(layer "F.Cu")
		(net "GND")
	)
	(segment
		(start 121.960386 -51.11623)
		(end 121.960386 -52.379626)
		(width 0.508)
		(layer "F.Cu")
		(net "GND")
	)
	(segment
		(start 330.835 -297.604942)
		(end 329.819 -297.604942)
		(width 0.508)
		(layer "F.Cu")
		(net "GND")
	)
	(segment
		(start 30.025086 -299.975016)
		(end 28.304998 -299.975016)
		(width 0.508)
		(layer "F.Cu")
		(net "GND")
	)
	(segment
		(start 150.440898 -75.224894)
		(end 150.440898 -76.240894)
		(width 0.508)
		(layer "F.Cu")
		(net "GND")
	)
	(segment
		(start 236.871256 -342.864948)
		(end 236.871256 -341.9094)
		(width 0.508)
		(layer "F.Cu")
		(net "GND")
	)
	(segment
		(start 473.752926 -175.175926)
		(end 473.752926 -176.000918)
		(width 0.508)
		(layer "F.Cu")
		(net "GND")
	)
	(segment
		(start 156.224986 -160.844992)
		(end 154.504898 -160.844992)
		(width 0.508)
		(layer "F.Cu")
		(net "GND")
	)
	(segment
		(start 405.70023 -131.232148)
		(end 405.70023 -130.408172)
		(width 0.508)
		(layer "F.Cu")
		(net "GND")
	)
	(segment
		(start 183.105044 -50.429922)
		(end 184.912 -50.429922)
		(width 0.508)
		(layer "F.Cu")
		(net "GND")
	)
	(segment
		(start 13.738352 -128.751838)
		(end 13.738352 -130.133344)
		(width 0.508)
		(layer "F.Cu")
		(net "GND")
	)
	(segment
		(start 30.025086 -49.654968)
		(end 28.304998 -49.654968)
		(width 0.508)
		(layer "F.Cu")
		(net "GND")
	)
	(segment
		(start 28.200096 -79.784956)
		(end 30.082998 -79.784956)
		(width 0.508)
		(layer "F.Cu")
		(net "GND")
	)
	(segment
		(start 232.791 -245.772686)
		(end 232.791 -244.5639)
		(width 0.508)
		(layer "F.Cu")
		(net "GND")
	)
	(segment
		(start 7.797038 -171.432982)
		(end 7.797038 -172.606462)
		(width 0.508)
		(layer "F.Cu")
		(net "GND")
	)
	(segment
		(start 70.61708 -180.440838)
		(end 70.618096 -180.440838)
		(width 0.508)
		(layer "F.Cu")
		(net "GND")
	)
	(segment
		(start 453.574912 -275.845016)
		(end 451.854824 -275.845016)
		(width 0.508)
		(layer "F.Cu")
		(net "GND")
	)
	(segment
		(start 413.460692 -281.942032)
		(end 413.453326 -281.949398)
		(width 0.508)
		(layer "F.Cu")
		(net "GND")
	)
	(segment
		(start 453.574912 -45.844968)
		(end 451.854824 -45.844968)
		(width 0.508)
		(layer "F.Cu")
		(net "GND")
	)
	(segment
		(start 453.574912 -297.435016)
		(end 451.854824 -297.435016)
		(width 0.508)
		(layer "F.Cu")
		(net "GND")
	)
	(segment
		(start 327.375012 -275.845016)
		(end 325.654924 -275.845016)
		(width 0.508)
		(layer "F.Cu")
		(net "GND")
	)
	(segment
		(start 23.936198 -70.322694)
		(end 22.666198 -70.322694)
		(width 0.508)
		(layer "F.Cu")
		(net "GND")
	)
	(segment
		(start 165.279578 -180.46573)
		(end 165.280594 -180.46573)
		(width 0.508)
		(layer "F.Cu")
		(net "GND")
	)
	(segment
		(start 253.873 -301.6885)
		(end 253.873 -302.387)
		(width 0.508)
		(layer "F.Cu")
		(net "GND")
	)
	(segment
		(start 363.1692 -76.835)
		(end 363.020102 -76.685902)
		(width 0.508)
		(layer "F.Cu")
		(net "GND")
	)
	(segment
		(start 236.802676 -349.655892)
		(end 236.802676 -350.51873)
		(width 0.508)
		(layer "F.Cu")
		(net "GND")
	)
	(segment
		(start 174.1297 -168.152318)
		(end 174.1297 -169.015918)
		(width 0.508)
		(layer "F.Cu")
		(net "GND")
	)
	(segment
		(start 59.749944 -151.035004)
		(end 61.734954 -151.035004)
		(width 0.508)
		(layer "F.Cu")
		(net "GND")
	)
	(segment
		(start 314.032138 -243.698268)
		(end 314.032138 -242.327938)
		(width 0.508)
		(layer "F.Cu")
		(net "GND")
	)
	(segment
		(start 329.819 -305.097942)
		(end 329.819 -305.928522)
		(width 0.508)
		(layer "F.Cu")
		(net "GND")
	)
	(segment
		(start 30.267402 -243.74475)
		(end 30.267402 -245.086124)
		(width 0.508)
		(layer "F.Cu")
		(net "GND")
	)
	(segment
		(start 267.87475 11.0998)
		(end 267.87475 10.230612)
		(width 0.508)
		(layer "F.Cu")
		(net "GND")
	)
	(segment
		(start 149.640798 -48.554894)
		(end 149.640798 -49.39538)
		(width 0.508)
		(layer "F.Cu")
		(net "GND")
	)
	(segment
		(start 222.885 -364.6805)
		(end 222.885 -363.8804)
		(width 0.508)
		(layer "F.Cu")
		(net "GND")
	)
	(segment
		(start 126.43739 -45.220636)
		(end 125.813058 -45.844968)
		(width 0.508)
		(layer "F.Cu")
		(net "GND")
	)
	(segment
		(start 50.202846 -174.603918)
		(end 50.202846 -176.000918)
		(width 0.508)
		(layer "F.Cu")
		(net "GND")
	)
	(segment
		(start 364.442248 -67.223894)
		(end 363.909102 -67.223894)
		(width 0.508)
		(layer "F.Cu")
		(net "GND")
	)
	(segment
		(start 187.775088 -160.844992)
		(end 186.055 -160.844992)
		(width 0.508)
		(layer "F.Cu")
		(net "GND")
	)
	(segment
		(start 457.0349 -297.604942)
		(end 456.0189 -297.604942)
		(width 0.508)
		(layer "F.Cu")
		(net "GND")
	)
	(segment
		(start 281.3558 19.5072)
		(end 281.269948 19.421348)
		(width 0.381)
		(layer "F.Cu")
		(net "GND")
	)
	(segment
		(start 235.761276 -349.655892)
		(end 235.761276 -350.51873)
		(width 0.508)
		(layer "F.Cu")
		(net "GND")
	)
	(segment
		(start 365.8362 -48.820324)
		(end 365.8362 -47.752)
		(width 0.508)
		(layer "F.Cu")
		(net "GND")
	)
	(segment
		(start 102.174294 -302.951896)
		(end 102.174294 -302.947324)
		(width 0.508)
		(layer "F.Cu")
		(net "GND")
	)
	(segment
		(start 257.5941 -14.9606)
		(end 258.4704 -14.9606)
		(width 0.508)
		(layer "F.Cu")
		(net "GND")
	)
	(segment
		(start 61.574934 -182.434992)
		(end 59.854846 -182.434992)
		(width 0.508)
		(layer "F.Cu")
		(net "GND")
	)
	(segment
		(start 165.26637 -183.040782)
		(end 165.269672 -183.040782)
		(width 0.508)
		(layer "F.Cu")
		(net "GND")
	)
	(segment
		(start 361.369102 -77.143102)
		(end 362.3056 -78.0796)
		(width 0.508)
		(layer "F.Cu")
		(net "GND")
	)
	(segment
		(start 76.850748 -64.683894)
		(end 75.656948 -64.683894)
		(width 0.508)
		(layer "F.Cu")
		(net "GND")
	)
	(segment
		(start 256.5273 -238.506)
		(end 256.5273 -237.8075)
		(width 0.508)
		(layer "F.Cu")
		(net "GND")
	)
	(segment
		(start 265.1506 -228.998272)
		(end 265.146028 -228.998272)
		(width 0.508)
		(layer "F.Cu")
		(net "GND")
	)
	(segment
		(start 388.649972 -151.035004)
		(end 390.532874 -151.035004)
		(width 0.508)
		(layer "F.Cu")
		(net "GND")
	)
	(segment
		(start 327.375012 -164.654992)
		(end 325.654924 -164.654992)
		(width 0.508)
		(layer "F.Cu")
		(net "GND")
	)
	(segment
		(start 115.731036 -49.494694)
		(end 117.124988 -49.494694)
		(width 0.4064)
		(layer "F.Cu")
		(net "GND")
	)
	(segment
		(start 395.20495 -157.141418)
		(end 395.20495 -156.315918)
		(width 0.508)
		(layer "F.Cu")
		(net "GND")
	)
	(segment
		(start 265.747754 -110.339886)
		(end 264.879582 -110.339886)
		(width 0.508)
		(layer "F.Cu")
		(net "GND")
	)
	(segment
		(start 238.005874 -232.342436)
		(end 238.155734 -232.492296)
		(width 0.508)
		(layer "F.Cu")
		(net "GND")
	)
	(segment
		(start 485.125014 -42.034968)
		(end 483.404926 -42.034968)
		(width 0.508)
		(layer "F.Cu")
		(net "GND")
	)
	(segment
		(start 393.93495 -297.604942)
		(end 392.91895 -297.604942)
		(width 0.508)
		(layer "F.Cu")
		(net "GND")
	)
	(segment
		(start 325.3232 -42.4688)
		(end 325.757032 -42.034968)
		(width 0.508)
		(layer "F.Cu")
		(net "GND")
	)
	(segment
		(start 475.144592 -287.818322)
		(end 475.144592 -289.103816)
		(width 0.508)
		(layer "F.Cu")
		(net "GND")
	)
	(segment
		(start 170.523408 -27.3431)
		(end 171.691808 -27.3431)
		(width 0.381)
		(layer "F.Cu")
		(net "GND")
	)
	(segment
		(start 130.892296 -176.127918)
		(end 130.892296 -175.238918)
		(width 0.508)
		(layer "F.Cu")
		(net "GND")
	)
	(segment
		(start 342.594184 -243.795804)
		(end 342.627712 -243.762276)
		(width 0.508)
		(layer "F.Cu")
		(net "GND")
	)
	(segment
		(start 354.25507 -165.429946)
		(end 356.062026 -165.429946)
		(width 0.508)
		(layer "F.Cu")
		(net "GND")
	)
	(segment
		(start 219.604082 -390.445498)
		(end 219.604082 -391.710672)
		(width 0.508)
		(layer "F.Cu")
		(net "GND")
	)
	(segment
		(start 102.13975 -182.997602)
		(end 102.143052 -182.997602)
		(width 0.508)
		(layer "F.Cu")
		(net "GND")
	)
	(segment
		(start 317.62065 -245.365016)
		(end 317.615824 -245.36019)
		(width 0.508)
		(layer "F.Cu")
		(net "GND")
	)
	(segment
		(start 139.950698 -179.683918)
		(end 138.756898 -179.683918)
		(width 0.508)
		(layer "F.Cu")
		(net "GND")
	)
	(segment
		(start 426.755052 -157.141418)
		(end 426.755052 -156.315918)
		(width 0.508)
		(layer "F.Cu")
		(net "GND")
	)
	(segment
		(start 392.91895 -306.026058)
		(end 392.912092 -306.026058)
		(width 0.508)
		(layer "F.Cu")
		(net "GND")
	)
	(segment
		(start 39.053262 -180.505862)
		(end 39.054278 -180.505862)
		(width 0.508)
		(layer "F.Cu")
		(net "GND")
	)
	(segment
		(start 474.4974 -268.9225)
		(end 474.4974 -268.07414)
		(width 0.508)
		(layer "F.Cu")
		(net "GND")
	)
	(segment
		(start 272.24736 16.90624)
		(end 272.24736 16.213328)
		(width 0.381)
		(layer "F.Cu")
		(net "GND")
	)
	(segment
		(start 363.020102 -76.685902)
		(end 363.020102 -74.920094)
		(width 0.508)
		(layer "F.Cu")
		(net "GND")
	)
	(segment
		(start 89.154 -17.9578)
		(end 88.78697 -17.59077)
		(width 0.3048)
		(layer "F.Cu")
		(net "GND")
	)
	(segment
		(start 124.674884 -289.815016)
		(end 122.954796 -289.815016)
		(width 0.508)
		(layer "F.Cu")
		(net "GND")
	)
	(segment
		(start 239.649 -256.2733)
		(end 238.9505 -256.2733)
		(width 0.508)
		(layer "F.Cu")
		(net "GND")
	)
	(segment
		(start 70.61708 -181.381146)
		(end 70.61708 -180.440838)
		(width 0.508)
		(layer "F.Cu")
		(net "GND")
	)
	(segment
		(start 479.340926 -75.224894)
		(end 477.802194 -75.224894)
		(width 0.508)
		(layer "F.Cu")
		(net "GND")
	)
	(segment
		(start 338.38769 -128.720088)
		(end 338.38769 -130.376676)
		(width 0.508)
		(layer "F.Cu")
		(net "GND")
	)
	(segment
		(start 133.66115 -187.943744)
		(end 133.66115 -189.168024)
		(width 0.508)
		(layer "F.Cu")
		(net "GND")
	)
	(segment
		(start 187.775088 -62.354968)
		(end 186.055 -62.354968)
		(width 0.508)
		(layer "F.Cu")
		(net "GND")
	)
	(segment
		(start 124.674884 -177.354992)
		(end 122.954796 -177.354992)
		(width 0.508)
		(layer "F.Cu")
		(net "GND")
	)
	(segment
		(start 475.234 -272.99158)
		(end 475.24162 -272.9992)
		(width 0.3556)
		(layer "F.Cu")
		(net "GND")
	)
	(segment
		(start 336.174334 -21.00707)
		(end 336.174334 -20.111466)
		(width 0.508)
		(layer "F.Cu")
		(net "GND")
	)
	(segment
		(start 235.331 -381.7493)
		(end 235.331 -380.9238)
		(width 0.508)
		(layer "F.Cu")
		(net "GND")
	)
	(segment
		(start 313.911996 -128.75514)
		(end 313.911996 -130.411728)
		(width 0.508)
		(layer "F.Cu")
		(net "GND")
	)
	(segment
		(start 99.342448 -291.127942)
		(end 99.342448 -290.238942)
		(width 0.508)
		(layer "F.Cu")
		(net "GND")
	)
	(segment
		(start 70.603872 -183.01589)
		(end 70.607174 -183.01589)
		(width 0.508)
		(layer "F.Cu")
		(net "GND")
	)
	(segment
		(start 300.51121 -67.2846)
		(end 300.51121 -66.0908)
		(width 0.3048)
		(layer "F.Cu")
		(net "GND")
	)
	(segment
		(start 70.649084 -301.29988)
		(end 70.649084 -300.46676)
		(width 0.508)
		(layer "F.Cu")
		(net "GND")
	)
	(segment
		(start 322.704968 -167.829992)
		(end 324.511924 -167.829992)
		(width 0.508)
		(layer "F.Cu")
		(net "GND")
	)
	(segment
		(start 169.200068 -27.043126)
		(end 170.223434 -27.043126)
		(width 0.381)
		(layer "F.Cu")
		(net "GND")
	)
	(segment
		(start 457.0349 -67.604894)
		(end 456.0189 -67.604894)
		(width 0.508)
		(layer "F.Cu")
		(net "GND")
	)
	(segment
		(start 267.73632 -275.3106)
		(end 267.73632 -273.73072)
		(width 0.3556)
		(layer "F.Cu")
		(net "GND")
	)
	(segment
		(start 453.574912 -177.354992)
		(end 451.854824 -177.354992)
		(width 0.508)
		(layer "F.Cu")
		(net "GND")
	)
	(segment
		(start 45.300646 -294.683942)
		(end 44.106846 -294.683942)
		(width 0.508)
		(layer "F.Cu")
		(net "GND")
	)
	(segment
		(start 239.694466 -242.293648)
		(end 239.234472 -241.833654)
		(width 0.508)
		(layer "F.Cu")
		(net "GND")
	)
	(segment
		(start 346.637102 -292.918896)
		(end 346.625926 -292.918896)
		(width 0.508)
		(layer "F.Cu")
		(net "GND")
	)
	(segment
		(start 317.8175 -176.127918)
		(end 317.8175 -175.8061)
		(width 0.508)
		(layer "F.Cu")
		(net "GND")
	)
	(segment
		(start 232.777284 -262.292338)
		(end 232.777284 -263.001252)
		(width 0.508)
		(layer "F.Cu")
		(net "GND")
	)
	(segment
		(start 310.25084 -60.017914)
		(end 310.25084 -60.478162)
		(width 0.508)
		(layer "F.Cu")
		(net "GND")
	)
	(segment
		(start 390.474962 -184.974992)
		(end 388.754874 -184.974992)
		(width 0.508)
		(layer "F.Cu")
		(net "GND")
	)
	(segment
		(start 235.809536 -342.857328)
		(end 235.809536 -341.99449)
		(width 0.508)
		(layer "F.Cu")
		(net "GND")
	)
	(segment
		(start 226.8347 -377.4567)
		(end 226.8347 -378.333)
		(width 0.508)
		(layer "F.Cu")
		(net "GND")
	)
	(segment
		(start 144.934686 -47.615094)
		(end 145.980658 -47.615094)
		(width 0.4064)
		(layer "F.Cu")
		(net "GND")
	)
	(segment
		(start 162.213036 -131.059428)
		(end 162.216084 -131.062476)
		(width 0.508)
		(layer "F.Cu")
		(net "GND")
	)
	(segment
		(start 88.454992 -167.829992)
		(end 90.261948 -167.829992)
		(width 0.508)
		(layer "F.Cu")
		(net "GND")
	)
	(segment
		(start 388.649972 -266.035028)
		(end 390.532874 -266.035028)
		(width 0.508)
		(layer "F.Cu")
		(net "GND")
	)
	(segment
		(start 84.181188 -279.494742)
		(end 85.105748 -279.494742)
		(width 0.4064)
		(layer "F.Cu")
		(net "GND")
	)
	(segment
		(start 457.3651 -46.371764)
		(end 457.3651 -45.903134)
		(width 0.4064)
		(layer "F.Cu")
		(net "GND")
	)
	(segment
		(start 248.452132 -294.299132)
		(end 248.452132 -296.075862)
		(width 0.381)
		(layer "F.Cu")
		(net "GND")
	)
	(segment
		(start 256.843276 -248.20118)
		(end 257.483102 -247.561354)
		(width 0.508)
		(layer "F.Cu")
		(net "GND")
	)
	(segment
		(start 153.547318 -49.850802)
		(end 152.968198 -50.429922)
		(width 0.508)
		(layer "F.Cu")
		(net "GND")
	)
	(segment
		(start 239.973104 -237.49)
		(end 241.00663 -237.49)
		(width 0.508)
		(layer "F.Cu")
		(net "GND")
	)
	(segment
		(start 465.177632 -130.368294)
		(end 465.177632 -131.369054)
		(width 0.508)
		(layer "F.Cu")
		(net "GND")
	)
	(segment
		(start 30.025086 -275.845016)
		(end 28.304998 -275.845016)
		(width 0.508)
		(layer "F.Cu")
		(net "GND")
	)
	(segment
		(start 171.5008 -64.683894)
		(end 170.307 -64.683894)
		(width 0.508)
		(layer "F.Cu")
		(net "GND")
	)
	(segment
		(start 282.7782 12.2936)
		(end 282.7782 11.2014)
		(width 0.508)
		(layer "F.Cu")
		(net "GND")
	)
	(segment
		(start 61.574934 -297.435016)
		(end 59.854846 -297.435016)
		(width 0.508)
		(layer "F.Cu")
		(net "GND")
	)
	(segment
		(start 405.727662 -243.783612)
		(end 405.719534 -243.79174)
		(width 0.508)
		(layer "F.Cu")
		(net "GND")
	)
	(segment
		(start 257.7592 15.7734)
		(end 258.20116 15.33144)
		(width 0.3048)
		(layer "F.Cu")
		(net "GND")
	)
	(segment
		(start 458.3049 -42.141394)
		(end 458.3049 -41.315894)
		(width 0.508)
		(layer "F.Cu")
		(net "GND")
	)
	(segment
		(start 362.385102 -182.604918)
		(end 361.369102 -182.604918)
		(width 0.508)
		(layer "F.Cu")
		(net "GND")
	)
	(segment
		(start 390.474962 -62.354968)
		(end 388.754874 -62.354968)
		(width 0.508)
		(layer "F.Cu")
		(net "GND")
	)
	(segment
		(start 356.289102 -49.337468)
		(end 356.606602 -49.654968)
		(width 0.508)
		(layer "F.Cu")
		(net "GND")
	)
	(segment
		(start 485.125014 -182.434992)
		(end 483.404926 -182.434992)
		(width 0.508)
		(layer "F.Cu")
		(net "GND")
	)
	(segment
		(start 256.3114 12.3444)
		(end 255.5621 13.0937)
		(width 0.381)
		(layer "F.Cu")
		(net "GND")
	)
	(segment
		(start 39.098728 -301.29988)
		(end 39.098728 -300.46676)
		(width 0.508)
		(layer "F.Cu")
		(net "GND")
	)
	(segment
		(start 221.590362 -117.98427)
		(end 221.357698 -117.751606)
		(width 0.508)
		(layer "F.Cu")
		(net "GND")
	)
	(segment
		(start 475.278196 -289.23742)
		(end 473.961968 -289.23742)
		(width 0.508)
		(layer "F.Cu")
		(net "GND")
	)
	(segment
		(start 317.8175 -291.127942)
		(end 317.8175 -289.9918)
		(width 0.508)
		(layer "F.Cu")
		(net "GND")
	)
	(segment
		(start 312.34888 -291.746686)
		(end 312.34888 -292.961314)
		(width 0.508)
		(layer "F.Cu")
		(net "GND")
	)
	(segment
		(start 394.26515 -45.903134)
		(end 394.26515 -46.649894)
		(width 0.4064)
		(layer "F.Cu")
		(net "GND")
	)
	(segment
		(start 456.0189 -182.604918)
		(end 456.67041 -182.604918)
		(width 0.508)
		(layer "F.Cu")
		(net "GND")
	)
	(segment
		(start 233.4514 -230.8733)
		(end 233.4514 -229.934262)
		(width 0.508)
		(layer "F.Cu")
		(net "GND")
	)
	(segment
		(start 152.968198 -50.429922)
		(end 151.554942 -50.429922)
		(width 0.508)
		(layer "F.Cu")
		(net "GND")
	)
	(segment
		(start 48.771302 -149.79015)
		(end 48.322738 -150.238714)
		(width 0.508)
		(layer "F.Cu")
		(net "GND")
	)
	(segment
		(start 233.299 -380.9238)
		(end 233.299 -381.7493)
		(width 0.508)
		(layer "F.Cu")
		(net "GND")
	)
	(segment
		(start 279.80132 -275.5646)
		(end 279.80132 -277.14448)
		(width 0.3556)
		(layer "F.Cu")
		(net "GND")
	)
	(segment
		(start 277.8506 16.383)
		(end 277.33244 16.90116)
		(width 0.381)
		(layer "F.Cu")
		(net "GND")
	)
	(segment
		(start 143.072866 -129.928874)
		(end 143.072866 -128.709674)
		(width 0.508)
		(layer "F.Cu")
		(net "GND")
	)
	(segment
		(start 364.344204 -182.223918)
		(end 363.909102 -182.223918)
		(width 0.508)
		(layer "F.Cu")
		(net "GND")
	)
	(segment
		(start 145.868898 -292.778942)
		(end 144.852898 -292.778942)
		(width 0.508)
		(layer "F.Cu")
		(net "GND")
	)
	(segment
		(start 327.375012 -182.434992)
		(end 325.654924 -182.434992)
		(width 0.508)
		(layer "F.Cu")
		(net "GND")
	)
	(segment
		(start 390.474962 -160.844992)
		(end 388.754874 -160.844992)
		(width 0.508)
		(layer "F.Cu")
		(net "GND")
	)
	(segment
		(start 333.502 -74.920094)
		(end 333.502 -76.9366)
		(width 0.508)
		(layer "F.Cu")
		(net "GND")
	)
	(segment
		(start 478.282 -162.3314)
		(end 478.8662 -161.7472)
		(width 0.508)
		(layer "F.Cu")
		(net "GND")
	)
	(segment
		(start 333.1845 -49.596294)
		(end 333.66837 -49.596294)
		(width 0.508)
		(layer "F.Cu")
		(net "GND")
	)
	(segment
		(start 470.336118 -159.738314)
		(end 470.336118 -161.374074)
		(width 0.4064)
		(layer "F.Cu")
		(net "GND")
	)
	(segment
		(start 30.025086 -42.034968)
		(end 28.304998 -42.034968)
		(width 0.508)
		(layer "F.Cu")
		(net "GND")
	)
	(segment
		(start 380.91745 -291.127942)
		(end 380.91745 -290.238942)
		(width 0.508)
		(layer "F.Cu")
		(net "GND")
	)
	(segment
		(start 454.758552 -245.542562)
		(end 454.243694 -245.027704)
		(width 0.508)
		(layer "F.Cu")
		(net "GND")
	)
	(segment
		(start 327.119488 -266.035028)
		(end 325.550022 -266.035028)
		(width 0.508)
		(layer "F.Cu")
		(net "GND")
	)
	(segment
		(start 21.081238 -49.494694)
		(end 22.005798 -49.494694)
		(width 0.4064)
		(layer "F.Cu")
		(net "GND")
	)
	(segment
		(start 156.224986 -279.655016)
		(end 154.504898 -279.655016)
		(width 0.508)
		(layer "F.Cu")
		(net "GND")
	)
	(segment
		(start 133.407658 -130.271012)
		(end 133.407658 -131.145026)
		(width 0.508)
		(layer "F.Cu")
		(net "GND")
	)
	(segment
		(start 175.95723 -292.778942)
		(end 175.938434 -292.797738)
		(width 0.508)
		(layer "F.Cu")
		(net "GND")
	)
	(segment
		(start 139.950698 -64.683894)
		(end 139.950698 -66.75374)
		(width 0.508)
		(layer "F.Cu")
		(net "GND")
	)
	(segment
		(start 52.3875 -163.576)
		(end 53.34 -163.576)
		(width 0.508)
		(layer "F.Cu")
		(net "GND")
	)
	(segment
		(start 144.71269 -62.778894)
		(end 144.528286 -62.963298)
		(width 0.508)
		(layer "F.Cu")
		(net "GND")
	)
	(segment
		(start 402.109432 -130.400298)
		(end 402.109432 -131.401058)
		(width 0.508)
		(layer "F.Cu")
		(net "GND")
	)
	(segment
		(start 56.90489 -50.429922)
		(end 58.925714 -50.429922)
		(width 0.508)
		(layer "F.Cu")
		(net "GND")
	)
	(segment
		(start 379.5014 -133.7056)
		(end 379.5014 -134.8486)
		(width 0.508)
		(layer "F.Cu")
		(net "GND")
	)
	(segment
		(start 235.676694 -244.591078)
		(end 235.652564 -244.615208)
		(width 0.508)
		(layer "F.Cu")
		(net "GND")
	)
	(segment
		(start 82.880708 -47.615094)
		(end 82.133948 -47.615094)
		(width 0.4064)
		(layer "F.Cu")
		(net "GND")
	)
	(segment
		(start 235.8644 29.2608)
		(end 238.264192 29.2608)
		(width 0.508)
		(layer "F.Cu")
		(net "GND")
	)
	(segment
		(start 262.255 -271.8435)
		(end 262.255 -271.0434)
		(width 0.508)
		(layer "F.Cu")
		(net "GND")
	)
	(segment
		(start 168.13911 -26.968958)
		(end 168.213278 -27.043126)
		(width 0.508)
		(layer "F.Cu")
		(net "GND")
	)
	(segment
		(start 394.56995 -189.920118)
		(end 394.56995 -191.113918)
		(width 0.508)
		(layer "F.Cu")
		(net "GND")
	)
	(segment
		(start 285.5214 -284.9753)
		(end 285.5214 -285.7754)
		(width 0.508)
		(layer "F.Cu")
		(net "GND")
	)
	(segment
		(start 187.543694 -77.879448)
		(end 185.950098 -79.473044)
		(width 0.508)
		(layer "F.Cu")
		(net "GND")
	)
	(segment
		(start 45.298868 -128.74117)
		(end 45.298868 -130.122676)
		(width 0.508)
		(layer "F.Cu")
		(net "GND")
	)
	(segment
		(start 392.91895 -190.097918)
		(end 392.91895 -191.113918)
		(width 0.508)
		(layer "F.Cu")
		(net "GND")
	)
	(segment
		(start 420.200074 -79.784956)
		(end 422.082976 -79.784956)
		(width 0.508)
		(layer "F.Cu")
		(net "GND")
	)
	(segment
		(start 79.479648 -53.126894)
		(end 79.479648 -53.594762)
		(width 0.508)
		(layer "F.Cu")
		(net "GND")
	)
	(segment
		(start 30.025086 -292.355016)
		(end 28.304998 -292.355016)
		(width 0.508)
		(layer "F.Cu")
		(net "GND")
	)
	(segment
		(start 28.200096 -194.78498)
		(end 30.082998 -194.78498)
		(width 0.508)
		(layer "F.Cu")
		(net "GND")
	)
	(segment
		(start 385.804918 -282.830016)
		(end 387.611874 -282.830016)
		(width 0.508)
		(layer "F.Cu")
		(net "GND")
	)
	(segment
		(start 217.07475 -385.7625)
		(end 213.722458 -385.7625)
		(width 0.508)
		(layer "F.Cu")
		(net "GND")
	)
	(segment
		(start 142.604998 -168.126918)
		(end 142.604998 -169.015918)
		(width 0.508)
		(layer "F.Cu")
		(net "GND")
	)
	(segment
		(start 240.124742 -255.599946)
		(end 240.319052 -255.599946)
		(width 0.508)
		(layer "F.Cu")
		(net "GND")
	)
	(segment
		(start 248.2596 -294.1066)
		(end 248.452132 -294.299132)
		(width 0.381)
		(layer "F.Cu")
		(net "GND")
	)
	(segment
		(start 349.875602 -61.127894)
		(end 349.875602 -60.2234)
		(width 0.508)
		(layer "F.Cu")
		(net "GND")
	)
	(segment
		(start 327.375012 -279.655016)
		(end 325.654924 -279.655016)
		(width 0.508)
		(layer "F.Cu")
		(net "GND")
	)
	(segment
		(start 151.554942 -167.829992)
		(end 153.361898 -167.829992)
		(width 0.508)
		(layer "F.Cu")
		(net "GND")
	)
	(segment
		(start 186.685174 -49.654968)
		(end 187.775088 -49.654968)
		(width 0.508)
		(layer "F.Cu")
		(net "GND")
	)
	(segment
		(start 395.20495 -272.141442)
		(end 395.20495 -271.315942)
		(width 0.508)
		(layer "F.Cu")
		(net "GND")
	)
	(segment
		(start 330.726796 -46.679866)
		(end 331.1652 -46.241462)
		(width 0.4064)
		(layer "F.Cu")
		(net "GND")
	)
	(segment
		(start 39.207948 -295.07815)
		(end 39.208202 -295.07815)
		(width 0.508)
		(layer "F.Cu")
		(net "GND")
	)
	(segment
		(start 265.865102 31.074868)
		(end 265.865102 29.35478)
		(width 0.508)
		(layer "F.Cu")
		(net "GND")
	)
	(segment
		(start 253.414276 -248.43486)
		(end 253.414276 -247.63476)
		(width 0.508)
		(layer "F.Cu")
		(net "GND")
	)
	(segment
		(start 23.440898 -48.554894)
		(end 23.440898 -49.443894)
		(width 0.508)
		(layer "F.Cu")
		(net "GND")
	)
	(segment
		(start 178.88204 -164.875718)
		(end 179.7558 -164.875718)
		(width 0.4064)
		(layer "F.Cu")
		(net "GND")
	)
	(segment
		(start 76.838302 -128.74117)
		(end 76.838302 -130.122676)
		(width 0.508)
		(layer "F.Cu")
		(net "GND")
	)
	(segment
		(start 61.574934 -160.844992)
		(end 59.854846 -160.844992)
		(width 0.508)
		(layer "F.Cu")
		(net "GND")
	)
	(segment
		(start 358.925114 -45.844968)
		(end 357.205026 -45.844968)
		(width 0.508)
		(layer "F.Cu")
		(net "GND")
	)
	(segment
		(start 117.061742 -274.641564)
		(end 117.061742 -273.691604)
		(width 0.4064)
		(layer "F.Cu")
		(net "GND")
	)
	(segment
		(start 265.471402 -214.795862)
		(end 265.471402 -213.4616)
		(width 0.381)
		(layer "F.Cu")
		(net "GND")
	)
	(segment
		(start 93.125036 -184.974992)
		(end 91.404948 -184.974992)
		(width 0.508)
		(layer "F.Cu")
		(net "GND")
	)
	(segment
		(start 130.274568 -187.045346)
		(end 130.274568 -186.00293)
		(width 0.508)
		(layer "F.Cu")
		(net "GND")
	)
	(segment
		(start 357.100124 -266.035028)
		(end 358.983026 -266.035028)
		(width 0.508)
		(layer "F.Cu")
		(net "GND")
	)
	(segment
		(start 329.819 -67.604894)
		(end 329.819 -68.8594)
		(width 0.508)
		(layer "F.Cu")
		(net "GND")
	)
	(segment
		(start 187.775088 -184.974992)
		(end 186.055 -184.974992)
		(width 0.508)
		(layer "F.Cu")
		(net "GND")
	)
	(segment
		(start 390.474962 -292.355016)
		(end 388.754874 -292.355016)
		(width 0.508)
		(layer "F.Cu")
		(net "GND")
	)
	(segment
		(start 327.434956 -266.350496)
		(end 327.119488 -266.035028)
		(width 0.508)
		(layer "F.Cu")
		(net "GND")
	)
	(segment
		(start 361.369102 -190.097918)
		(end 361.369102 -191.113918)
		(width 0.508)
		(layer "F.Cu")
		(net "GND")
	)
	(segment
		(start 220.6244 -377.406408)
		(end 220.6244 -376.62104)
		(width 0.508)
		(layer "F.Cu")
		(net "GND")
	)
	(segment
		(start 479.036126 -300.322742)
		(end 477.766126 -300.322742)
		(width 0.508)
		(layer "F.Cu")
		(net "GND")
	)
	(segment
		(start 28.200096 -309.785004)
		(end 30.082998 -309.785004)
		(width 0.508)
		(layer "F.Cu")
		(net "GND")
	)
	(segment
		(start 135.173466 -137.692384)
		(end 136.365234 -137.692384)
		(width 0.254)
		(layer "F.Cu")
		(net "GND")
	)
	(segment
		(start 223.839024 -348.2213)
		(end 224.8408 -348.2213)
		(width 0.508)
		(layer "F.Cu")
		(net "GND")
	)
	(segment
		(start 427.009052 -67.223894)
		(end 428.406052 -67.223894)
		(width 0.508)
		(layer "F.Cu")
		(net "GND")
	)
	(segment
		(start 243.6876 -243.1161)
		(end 243.6876 -243.9162)
		(width 0.508)
		(layer "F.Cu")
		(net "GND")
	)
	(segment
		(start 298.831 -283.6545)
		(end 298.243498 -283.6545)
		(width 0.508)
		(layer "F.Cu")
		(net "GND")
	)
	(segment
		(start 7.685024 -284.60319)
		(end 7.685024 -283.649674)
		(width 0.508)
		(layer "F.Cu")
		(net "GND")
	)
	(segment
		(start 285.623 -271.8689)
		(end 285.623 -271.0688)
		(width 0.508)
		(layer "F.Cu")
		(net "GND")
	)
	(segment
		(start 7.783576 -292.925754)
		(end 7.783576 -294.099234)
		(width 0.508)
		(layer "F.Cu")
		(net "GND")
	)
	(segment
		(start 372.0338 -147.5486)
		(end 372.0338 -148.7424)
		(width 0.508)
		(layer "F.Cu")
		(net "GND")
	)
	(segment
		(start 181.1909 -48.554894)
		(end 181.1909 -49.443894)
		(width 0.508)
		(layer "F.Cu")
		(net "GND")
	)
	(segment
		(start 314.026804 -245.357142)
		(end 314.026804 -243.703602)
		(width 0.508)
		(layer "F.Cu")
		(net "GND")
	)
	(segment
		(start 59.749944 -194.78498)
		(end 61.632846 -194.78498)
		(width 0.508)
		(layer "F.Cu")
		(net "GND")
	)
	(segment
		(start 388.649972 -36.725098)
		(end 388.649972 -36.03498)
		(width 0.508)
		(layer "F.Cu")
		(net "GND")
	)
	(segment
		(start 235.25099 -235.798868)
		(end 235.27766 -235.798868)
		(width 0.508)
		(layer "F.Cu")
		(net "GND")
	)
	(segment
		(start 87.036148 -185.322718)
		(end 85.766148 -185.322718)
		(width 0.508)
		(layer "F.Cu")
		(net "GND")
	)
	(segment
		(start 149.640798 -163.554918)
		(end 149.640798 -164.443918)
		(width 0.508)
		(layer "F.Cu")
		(net "GND")
	)
	(segment
		(start 149.640798 -278.554942)
		(end 149.640798 -279.443942)
		(width 0.508)
		(layer "F.Cu")
		(net "GND")
	)
	(segment
		(start 448.904868 -165.429946)
		(end 450.711824 -165.429946)
		(width 0.508)
		(layer "F.Cu")
		(net "GND")
	)
	(segment
		(start 185.950098 -266.035028)
		(end 187.833 -266.035028)
		(width 0.508)
		(layer "F.Cu")
		(net "GND")
	)
	(segment
		(start 318.9224 -60.2742)
		(end 318.708786 -60.060586)
		(width 0.508)
		(layer "F.Cu")
		(net "GND")
	)
	(segment
		(start 256.843276 -248.43486)
		(end 256.843276 -248.20118)
		(width 0.508)
		(layer "F.Cu")
		(net "GND")
	)
	(segment
		(start 223.887792 -345.073478)
		(end 224.866454 -345.073478)
		(width 0.508)
		(layer "F.Cu")
		(net "GND")
	)
	(segment
		(start 333.501746 -28.22575)
		(end 333.501746 -27.24912)
		(width 0.508)
		(layer "F.Cu")
		(net "GND")
	)
	(segment
		(start 55.0164 -49.468024)
		(end 54.991 -49.468024)
		(width 0.508)
		(layer "F.Cu")
		(net "GND")
	)
	(segment
		(start 364.594902 -274.602702)
		(end 364.594902 -273.855942)
		(width 0.4064)
		(layer "F.Cu")
		(net "GND")
	)
	(segment
		(start 468.850726 -64.683894)
		(end 467.656926 -64.683894)
		(width 0.508)
		(layer "F.Cu")
		(net "GND")
	)
	(segment
		(start 317.497968 -130.414776)
		(end 317.497968 -128.7526)
		(width 0.508)
		(layer "F.Cu")
		(net "GND")
	)
	(segment
		(start 232.9434 -247.275858)
		(end 233.618786 -246.600472)
		(width 0.508)
		(layer "F.Cu")
		(net "GND")
	)
	(segment
		(start 276.2758 10.7188)
		(end 276.2758 9.623044)
		(width 0.508)
		(layer "F.Cu")
		(net "GND")
	)
	(segment
		(start 156.270452 -309.613554)
		(end 156.099002 -309.785004)
		(width 0.508)
		(layer "F.Cu")
		(net "GND")
	)
	(segment
		(start 447.010536 -246.166894)
		(end 447.010536 -245.302024)
		(width 0.508)
		(layer "F.Cu")
		(net "GND")
	)
	(segment
		(start 156.224986 -272.035016)
		(end 154.504898 -272.035016)
		(width 0.508)
		(layer "F.Cu")
		(net "GND")
	)
	(segment
		(start 272.669 -271.8435)
		(end 272.669 -271.0434)
		(width 0.508)
		(layer "F.Cu")
		(net "GND")
	)
	(segment
		(start 343.205054 -24.41829)
		(end 343.205054 -22.885146)
		(width 0.3048)
		(layer "F.Cu")
		(net "GND")
	)
	(segment
		(start 426.755052 -42.141394)
		(end 426.755052 -41.315894)
		(width 0.508)
		(layer "F.Cu")
		(net "GND")
	)
	(segment
		(start 417.35502 -52.829968)
		(end 419.161976 -52.829968)
		(width 0.508)
		(layer "F.Cu")
		(net "GND")
	)
	(segment
		(start 191.135 -289.6235)
		(end 192.0875 -289.6235)
		(width 0.508)
		(layer "F.Cu")
		(net "GND")
	)
	(segment
		(start 478.282 -162.6235)
		(end 478.282 -162.3314)
		(width 0.508)
		(layer "F.Cu")
		(net "GND")
	)
	(segment
		(start 428.152052 -304.920142)
		(end 428.152052 -306.113942)
		(width 0.508)
		(layer "F.Cu")
		(net "GND")
	)
	(segment
		(start 333.44993 -67.223894)
		(end 332.359 -67.223894)
		(width 0.508)
		(layer "F.Cu")
		(net "GND")
	)
	(segment
		(start 135.605266 -143.771874)
		(end 135.605266 -142.628874)
		(width 0.508)
		(layer "F.Cu")
		(net "GND")
	)
	(segment
		(start 457.3905 -272.090642)
		(end 457.3905 -271.265142)
		(width 0.508)
		(layer "F.Cu")
		(net "GND")
	)
	(segment
		(start 116.121942 -272.281904)
		(end 117.010942 -272.281904)
		(width 0.508)
		(layer "F.Cu")
		(net "GND")
	)
	(segment
		(start 233.4514 -229.934262)
		(end 232.378504 -228.861366)
		(width 0.508)
		(layer "F.Cu")
		(net "GND")
	)
	(segment
		(start 377.835414 -136.045448)
		(end 375.719848 -136.045448)
		(width 0.508)
		(layer "F.Cu")
		(net "GND")
	)
	(segment
		(start 332.105 -42.141394)
		(end 332.105 -42.140886)
		(width 0.508)
		(layer "F.Cu")
		(net "GND")
	)
	(segment
		(start 51.330606 -47.615094)
		(end 50.583846 -47.615094)
		(width 0.4064)
		(layer "F.Cu")
		(net "GND")
	)
	(segment
		(start 338.15909 -245.31955)
		(end 338.09178 -245.38686)
		(width 0.508)
		(layer "F.Cu")
		(net "GND")
	)
	(segment
		(start 39.040054 -183.080914)
		(end 39.043356 -183.080914)
		(width 0.508)
		(layer "F.Cu")
		(net "GND")
	)
	(segment
		(start 185.950098 -194.78498)
		(end 187.833 -194.78498)
		(width 0.508)
		(layer "F.Cu")
		(net "GND")
	)
	(segment
		(start 402.111718 -128.741424)
		(end 402.111718 -130.398012)
		(width 0.508)
		(layer "F.Cu")
		(net "GND")
	)
	(segment
		(start 177.419 -62.778894)
		(end 176.403 -62.778894)
		(width 0.508)
		(layer "F.Cu")
		(net "GND")
	)
	(segment
		(start 450.88556 -42.094912)
		(end 450.945504 -42.034968)
		(width 0.508)
		(layer "F.Cu")
		(net "GND")
	)
	(segment
		(start 327.375012 -289.815016)
		(end 325.654924 -289.815016)
		(width 0.508)
		(layer "F.Cu")
		(net "GND")
	)
	(segment
		(start 14.816836 -131.181094)
		(end 14.819884 -131.184142)
		(width 0.508)
		(layer "F.Cu")
		(net "GND")
	)
	(segment
		(start 264.746232 19.287744)
		(end 265.6332 19.287744)
		(width 0.508)
		(layer "F.Cu")
		(net "GND")
	)
	(segment
		(start 84.587334 -31.85287)
		(end 84.587334 -32.938466)
		(width 0.508)
		(layer "F.Cu")
		(net "GND")
	)
	(segment
		(start 255.5621 13.0937)
		(end 255.5621 13.352272)
		(width 0.381)
		(layer "F.Cu")
		(net "GND")
	)
	(segment
		(start 483.300024 -36.03498)
		(end 485.182926 -36.03498)
		(width 0.508)
		(layer "F.Cu")
		(net "GND")
	)
	(segment
		(start 456.048872 -190.142876)
		(end 456.048872 -191.158876)
		(width 0.508)
		(layer "F.Cu")
		(net "GND")
	)
	(segment
		(start 368.192304 -128.681734)
		(end 368.192304 -125.852428)
		(width 0.508)
		(layer "F.Cu")
		(net "GND")
	)
	(segment
		(start 333.1845 -279.596342)
		(end 334.0862 -279.596342)
		(width 0.508)
		(layer "F.Cu")
		(net "GND")
	)
	(segment
		(start 485.125014 -69.974968)
		(end 483.404926 -69.974968)
		(width 0.508)
		(layer "F.Cu")
		(net "GND")
	)
	(segment
		(start 153.745184 -45.844968)
		(end 156.224986 -45.844968)
		(width 0.508)
		(layer "F.Cu")
		(net "GND")
	)
	(segment
		(start 118.890796 -305.224942)
		(end 118.890796 -306.240942)
		(width 0.508)
		(layer "F.Cu")
		(net "GND")
	)
	(segment
		(start 331.47 -304.920142)
		(end 331.47 -306.113942)
		(width 0.508)
		(layer "F.Cu")
		(net "GND")
	)
	(segment
		(start 104.756712 -128.74117)
		(end 104.756712 -130.122676)
		(width 0.508)
		(layer "F.Cu")
		(net "GND")
	)
	(segment
		(start 351.802954 -55.545736)
		(end 352.118676 -55.230014)
		(width 0.508)
		(layer "F.Cu")
		(net "GND")
	)
	(segment
		(start 422.025064 -177.354992)
		(end 420.304976 -177.354992)
		(width 0.508)
		(layer "F.Cu")
		(net "GND")
	)
	(segment
		(start 420.200074 -266.035028)
		(end 422.082976 -266.035028)
		(width 0.508)
		(layer "F.Cu")
		(net "GND")
	)
	(segment
		(start 333.66837 -49.596294)
		(end 334.222852 -49.041812)
		(width 0.508)
		(layer "F.Cu")
		(net "GND")
	)
	(segment
		(start 428.152052 -189.920118)
		(end 428.152052 -191.113918)
		(width 0.508)
		(layer "F.Cu")
		(net "GND")
	)
	(segment
		(start 451.749922 -36.03498)
		(end 453.632824 -36.03498)
		(width 0.508)
		(layer "F.Cu")
		(net "GND")
	)
	(segment
		(start 390.474962 -272.035016)
		(end 388.754874 -272.035016)
		(width 0.508)
		(layer "F.Cu")
		(net "GND")
	)
	(segment
		(start 239.649 -256.075688)
		(end 240.124742 -255.599946)
		(width 0.508)
		(layer "F.Cu")
		(net "GND")
	)
	(segment
		(start 165.267386 -187.922662)
		(end 165.267386 -189.146942)
		(width 0.508)
		(layer "F.Cu")
		(net "GND")
	)
	(segment
		(start 93.125036 -174.814992)
		(end 91.404948 -174.814992)
		(width 0.508)
		(layer "F.Cu")
		(net "GND")
	)
	(segment
		(start 138.007852 -141.406626)
		(end 139.361418 -141.406626)
		(width 0.508)
		(layer "F.Cu")
		(net "GND")
	)
	(segment
		(start 361.369102 -305.097942)
		(end 361.369102 -306.113942)
		(width 0.508)
		(layer "F.Cu")
		(net "GND")
	)
	(segment
		(start 373.02567 -128.655572)
		(end 373.02567 -125.361446)
		(width 0.508)
		(layer "F.Cu")
		(net "GND")
	)
	(segment
		(start 36.242498 -176.127918)
		(end 36.242498 -175.238918)
		(width 0.508)
		(layer "F.Cu")
		(net "GND")
	)
	(segment
		(start 420.640002 -67.434968)
		(end 422.025064 -67.434968)
		(width 0.508)
		(layer "F.Cu")
		(net "GND")
	)
	(segment
		(start 365.661702 -164.596318)
		(end 365.687102 -164.570918)
		(width 0.508)
		(layer "F.Cu")
		(net "GND")
	)
	(segment
		(start 99.342448 -60.442094)
		(end 99.139248 -60.238894)
		(width 0.508)
		(layer "F.Cu")
		(net "GND")
	)
	(segment
		(start 130.892296 -61.127894)
		(end 131.62153 -61.127894)
		(width 0.508)
		(layer "F.Cu")
		(net "GND")
	)
	(segment
		(start 60.196984 -289.815016)
		(end 61.574934 -289.815016)
		(width 0.508)
		(layer "F.Cu")
		(net "GND")
	)
	(segment
		(start 457.704952 -46.711616)
		(end 457.3651 -46.371764)
		(width 0.4064)
		(layer "F.Cu")
		(net "GND")
	)
	(segment
		(start 222.476822 -137.77087)
		(end 218.463368 -137.77087)
		(width 0.508)
		(layer "F.Cu")
		(net "GND")
	)
	(segment
		(start 216.243916 -390.80186)
		(end 216.490042 -390.80186)
		(width 0.508)
		(layer "F.Cu")
		(net "GND")
	)
	(segment
		(start 128.713484 -128.750568)
		(end 128.713484 -130.132074)
		(width 0.508)
		(layer "F.Cu")
		(net "GND")
	)
	(segment
		(start 465.177632 -131.369054)
		(end 465.15782 -131.388866)
		(width 0.508)
		(layer "F.Cu")
		(net "GND")
	)
	(segment
		(start 79.479648 -168.126918)
		(end 79.479648 -169.015918)
		(width 0.508)
		(layer "F.Cu")
		(net "GND")
	)
	(segment
		(start 370.906294 -150.494492)
		(end 370.909596 -150.494492)
		(width 0.508)
		(layer "F.Cu")
		(net "GND")
	)
	(segment
		(start 255.143 -301.6885)
		(end 255.143 -301.9806)
		(width 0.508)
		(layer "F.Cu")
		(net "GND")
	)
	(segment
		(start 154.890724 -42.034968)
		(end 156.224986 -42.034968)
		(width 0.508)
		(layer "F.Cu")
		(net "GND")
	)
	(segment
		(start 244.221 -230.6955)
		(end 244.221 -230.2256)
		(width 0.508)
		(layer "F.Cu")
		(net "GND")
	)
	(segment
		(start 316.62624 -59.90844)
		(end 315.0616 -59.90844)
		(width 0.381)
		(layer "F.Cu")
		(net "GND")
	)
	(segment
		(start 396.60195 -74.920094)
		(end 396.60195 -76.113894)
		(width 0.508)
		(layer "F.Cu")
		(net "GND")
	)
	(segment
		(start 480.45497 -167.829992)
		(end 482.261926 -167.829992)
		(width 0.508)
		(layer "F.Cu")
		(net "GND")
	)
	(segment
		(start 252.220476 -256.43586)
		(end 252.220476 -255.45796)
		(width 0.508)
		(layer "F.Cu")
		(net "GND")
	)
	(segment
		(start 149.633686 -55.230014)
		(end 151.554942 -55.230014)
		(width 0.508)
		(layer "F.Cu")
		(net "GND")
	)
	(segment
		(start 124.674884 -59.814968)
		(end 122.954796 -59.814968)
		(width 0.508)
		(layer "F.Cu")
		(net "GND")
	)
	(segment
		(start 86.989666 -14.92123)
		(end 87.94623 -14.92123)
		(width 0.508)
		(layer "F.Cu")
		(net "GND")
	)
	(segment
		(start 111.054896 -168.126918)
		(end 111.054896 -169.015918)
		(width 0.508)
		(layer "F.Cu")
		(net "GND")
	)
	(segment
		(start 91.300046 -309.785004)
		(end 93.182948 -309.785004)
		(width 0.508)
		(layer "F.Cu")
		(net "GND")
	)
	(segment
		(start 485.125014 -49.654968)
		(end 483.404926 -49.654968)
		(width 0.508)
		(layer "F.Cu")
		(net "GND")
	)
	(segment
		(start 315.928756 -291.29355)
		(end 316.266576 -291.63137)
		(width 0.508)
		(layer "F.Cu")
		(net "GND")
	)
	(segment
		(start 283.21 20.119086)
		(end 283.21 19.685)
		(width 0.508)
		(layer "F.Cu")
		(net "GND")
	)
	(segment
		(start 333.502 -304.920142)
		(end 333.502 -306.113942)
		(width 0.508)
		(layer "F.Cu")
		(net "GND")
	)
	(segment
		(start 437.31434 -131.167886)
		(end 437.31434 -130.34391)
		(width 0.508)
		(layer "F.Cu")
		(net "GND")
	)
	(segment
		(start 30.025086 -177.354992)
		(end 28.304998 -177.354992)
		(width 0.508)
		(layer "F.Cu")
		(net "GND")
	)
	(segment
		(start 413.401002 -286.530034)
		(end 413.401002 -287.54705)
		(width 0.508)
		(layer "F.Cu")
		(net "GND")
	)
	(segment
		(start 396.28445 -49.596294)
		(end 397.23695 -49.596294)
		(width 0.508)
		(layer "F.Cu")
		(net "GND")
	)
	(segment
		(start 234.943396 -236.992414)
		(end 235.809282 -236.992414)
		(width 0.508)
		(layer "F.Cu")
		(net "GND")
	)
	(segment
		(start 471.479626 -168.126918)
		(end 471.479626 -169.015918)
		(width 0.508)
		(layer "F.Cu")
		(net "GND")
	)
	(segment
		(start 55.0164 -49.4538)
		(end 55.0164 -49.468024)
		(width 0.508)
		(layer "F.Cu")
		(net "GND")
	)
	(segment
		(start 374.144032 -243.785136)
		(end 374.17756 -243.751608)
		(width 0.508)
		(layer "F.Cu")
		(net "GND")
	)
	(segment
		(start 335.0514 -19.338036)
		(end 335.29397 -19.095466)
		(width 0.508)
		(layer "F.Cu")
		(net "GND")
	)
	(segment
		(start 93.125036 -182.434992)
		(end 91.404948 -182.434992)
		(width 0.508)
		(layer "F.Cu")
		(net "GND")
	)
	(segment
		(start 263.398 -271.8435)
		(end 263.398 -271.0434)
		(width 0.508)
		(layer "F.Cu")
		(net "GND")
	)
	(segment
		(start 422.025064 -42.034968)
		(end 420.304976 -42.034968)
		(width 0.508)
		(layer "F.Cu")
		(net "GND")
	)
	(segment
		(start 338.455 -14.351)
		(end 338.4804 -14.351)
		(width 0.381)
		(layer "F.Cu")
		(net "GND")
	)
	(segment
		(start 338.38769 -131.377436)
		(end 338.365592 -131.399534)
		(width 0.508)
		(layer "F.Cu")
		(net "GND")
	)
	(segment
		(start 30.025086 -272.035016)
		(end 28.304998 -272.035016)
		(width 0.508)
		(layer "F.Cu")
		(net "GND")
	)
	(segment
		(start 358.925114 -164.654992)
		(end 357.205026 -164.654992)
		(width 0.508)
		(layer "F.Cu")
		(net "GND")
	)
	(segment
		(start 162.213036 -130.185414)
		(end 162.213036 -131.059428)
		(width 0.508)
		(layer "F.Cu")
		(net "GND")
	)
	(segment
		(start 465.179918 -128.70942)
		(end 465.179918 -129.997454)
		(width 0.508)
		(layer "F.Cu")
		(net "GND")
	)
	(segment
		(start 235.527088 -263.136888)
		(end 236.031278 -263.136888)
		(width 0.508)
		(layer "F.Cu")
		(net "GND")
	)
	(segment
		(start 327.375012 -157.034992)
		(end 325.654924 -157.034992)
		(width 0.508)
		(layer "F.Cu")
		(net "GND")
	)
	(segment
		(start 262.89 16.9672)
		(end 262.753348 17.103852)
		(width 0.508)
		(layer "F.Cu")
		(net "GND")
	)
	(segment
		(start 396.14475 -274.602702)
		(end 396.14475 -273.855942)
		(width 0.4064)
		(layer "F.Cu")
		(net "GND")
	)
	(segment
		(start 224.80016 -5.176012)
		(end 224.801684 -5.177536)
		(width 0.508)
		(layer "F.Cu")
		(net "GND")
	)
	(segment
		(start 358.925114 -275.845016)
		(end 357.205026 -275.845016)
		(width 0.508)
		(layer "F.Cu")
		(net "GND")
	)
	(segment
		(start 427.694852 -44.602654)
		(end 427.694852 -43.855894)
		(width 0.4064)
		(layer "F.Cu")
		(net "GND")
	)
	(segment
		(start 144.4498 -47.66564)
		(end 144.4498 -47.6504)
		(width 0.4064)
		(layer "F.Cu")
		(net "GND")
	)
	(segment
		(start 268.816582 16.915638)
		(end 268.816582 18.48358)
		(width 0.381)
		(layer "F.Cu")
		(net "GND")
	)
	(segment
		(start 480.45497 -282.830016)
		(end 482.261926 -282.830016)
		(width 0.508)
		(layer "F.Cu")
		(net "GND")
	)
	(segment
		(start 243.713 -248.7295)
		(end 243.713 -248.36755)
		(width 0.508)
		(layer "F.Cu")
		(net "GND")
	)
	(segment
		(start 354.25507 -170.230038)
		(end 356.062026 -170.230038)
		(width 0.508)
		(layer "F.Cu")
		(net "GND")
	)
	(segment
		(start 93.125036 -67.434968)
		(end 91.404948 -67.434968)
		(width 0.508)
		(layer "F.Cu")
		(net "GND")
	)
	(segment
		(start 325.527162 -51.64836)
		(end 324.308724 -50.429922)
		(width 0.508)
		(layer "F.Cu")
		(net "GND")
	)
	(segment
		(start 118.585996 -300.322742)
		(end 117.315996 -300.322742)
		(width 0.508)
		(layer "F.Cu")
		(net "GND")
	)
	(segment
		(start 174.1297 -53.152294)
		(end 174.1297 -54.022244)
		(width 0.508)
		(layer "F.Cu")
		(net "GND")
	)
	(segment
		(start 80.180434 -18.50517)
		(end 79.33817 -18.50517)
		(width 0.508)
		(layer "F.Cu")
		(net "GND")
	)
	(segment
		(start 358.925114 -174.814992)
		(end 357.205026 -174.814992)
		(width 0.508)
		(layer "F.Cu")
		(net "GND")
	)
	(segment
		(start 313.911996 -130.411728)
		(end 313.911996 -131.412488)
		(width 0.508)
		(layer "F.Cu")
		(net "GND")
	)
	(segment
		(start 364.734602 -279.596342)
		(end 365.687102 -279.596342)
		(width 0.508)
		(layer "F.Cu")
		(net "GND")
	)
	(segment
		(start 224.8408 -348.2213)
		(end 224.8662 -348.2467)
		(width 0.508)
		(layer "F.Cu")
		(net "GND")
	)
	(segment
		(start 460.114396 -182.223918)
		(end 458.5589 -182.223918)
		(width 0.508)
		(layer "F.Cu")
		(net "GND")
	)
	(segment
		(start 358.925114 -160.844992)
		(end 357.205026 -160.844992)
		(width 0.508)
		(layer "F.Cu")
		(net "GND")
	)
	(segment
		(start 248.05132 -252.0696)
		(end 248.05132 -250.48972)
		(width 0.3556)
		(layer "F.Cu")
		(net "GND")
	)
	(segment
		(start 443.404244 -245.278656)
		(end 443.404244 -243.76507)
		(width 0.508)
		(layer "F.Cu")
		(net "GND")
	)
	(segment
		(start 133.407658 -131.145026)
		(end 133.410706 -131.148074)
		(width 0.508)
		(layer "F.Cu")
		(net "GND")
	)
	(segment
		(start 154.399996 -79.784956)
		(end 156.282898 -79.784956)
		(width 0.508)
		(layer "F.Cu")
		(net "GND")
	)
	(segment
		(start 425.485052 -297.604942)
		(end 424.469052 -297.604942)
		(width 0.508)
		(layer "F.Cu")
		(net "GND")
	)
	(segment
		(start 154.399996 -266.035028)
		(end 156.282898 -266.035028)
		(width 0.508)
		(layer "F.Cu")
		(net "GND")
	)
	(segment
		(start 322.704968 -282.830016)
		(end 324.511924 -282.830016)
		(width 0.508)
		(layer "F.Cu")
		(net "GND")
	)
	(segment
		(start 51.218846 -62.778894)
		(end 50.202846 -62.778894)
		(width 0.508)
		(layer "F.Cu")
		(net "GND")
	)
	(segment
		(start 236.855 -380.4666)
		(end 236.855 -379.2728)
		(width 0.508)
		(layer "F.Cu")
		(net "GND")
	)
	(segment
		(start 415.464752 -291.127942)
		(end 415.464752 -289.854132)
		(width 0.508)
		(layer "F.Cu")
		(net "GND")
	)
	(segment
		(start 388.295642 -289.285172)
		(end 388.825486 -289.815016)
		(width 0.508)
		(layer "F.Cu")
		(net "GND")
	)
	(segment
		(start 322.704968 -285.230062)
		(end 324.511924 -285.230062)
		(width 0.508)
		(layer "F.Cu")
		(net "GND")
	)
	(segment
		(start 363.655102 -272.141442)
		(end 363.655102 -271.315942)
		(width 0.508)
		(layer "F.Cu")
		(net "GND")
	)
	(segment
		(start 263.09828 16.75892)
		(end 262.89 16.9672)
		(width 0.381)
		(layer "F.Cu")
		(net "GND")
	)
	(segment
		(start 465.179918 -129.997454)
		(end 465.177632 -129.99974)
		(width 0.508)
		(layer "F.Cu")
		(net "GND")
	)
	(segment
		(start 433.725828 -130.33375)
		(end 433.725828 -128.677162)
		(width 0.508)
		(layer "F.Cu")
		(net "GND")
	)
	(segment
		(start 261.9756 -284.8737)
		(end 261.9756 -285.6738)
		(width 0.508)
		(layer "F.Cu")
		(net "GND")
	)
	(segment
		(start 30.025086 -160.844992)
		(end 28.304998 -160.844992)
		(width 0.508)
		(layer "F.Cu")
		(net "GND")
	)
	(segment
		(start 358.925114 -177.354992)
		(end 357.205026 -177.354992)
		(width 0.508)
		(layer "F.Cu")
		(net "GND")
	)
	(segment
		(start 262.753348 17.103852)
		(end 262.753348 17.959832)
		(width 0.508)
		(layer "F.Cu")
		(net "GND")
	)
	(segment
		(start 102.152958 -180.42255)
		(end 102.153974 -180.42255)
		(width 0.508)
		(layer "F.Cu")
		(net "GND")
	)
	(segment
		(start 256.5273 -237.8075)
		(end 256.2098 -237.49)
		(width 0.508)
		(layer "F.Cu")
		(net "GND")
	)
	(segment
		(start 213.743032 -386.805678)
		(end 213.743032 -388.145274)
		(width 0.3556)
		(layer "F.Cu")
		(net "GND")
	)
	(segment
		(start 241.00663 -237.49)
		(end 241.960908 -237.49)
		(width 0.508)
		(layer "F.Cu")
		(net "GND")
	)
	(segment
		(start 185.950098 -151.035004)
		(end 187.833 -151.035004)
		(width 0.508)
		(layer "F.Cu")
		(net "GND")
	)
	(segment
		(start 240.23066 -242.293648)
		(end 239.694466 -242.293648)
		(width 0.508)
		(layer "F.Cu")
		(net "GND")
	)
	(segment
		(start 102.152958 -181.362858)
		(end 102.152958 -180.42255)
		(width 0.508)
		(layer "F.Cu")
		(net "GND")
	)
	(segment
		(start 50.202846 -59.603894)
		(end 50.202846 -61.000894)
		(width 0.508)
		(layer "F.Cu")
		(net "GND")
	)
	(segment
		(start 405.719534 -243.79174)
		(end 405.719534 -245.335806)
		(width 0.508)
		(layer "F.Cu")
		(net "GND")
	)
	(segment
		(start 70.607174 -183.01589)
		(end 70.607174 -183.00319)
		(width 0.508)
		(layer "F.Cu")
		(net "GND")
	)
	(segment
		(start 13.750798 -179.683918)
		(end 12.556998 -179.683918)
		(width 0.508)
		(layer "F.Cu")
		(net "GND")
	)
	(segment
		(start 61.574934 -272.035016)
		(end 59.854846 -272.035016)
		(width 0.508)
		(layer "F.Cu")
		(net "GND")
	)
	(segment
		(start 155.909264 -34.233358)
		(end 154.399996 -35.742626)
		(width 0.508)
		(layer "F.Cu")
		(net "GND")
	)
	(segment
		(start 88.454992 -52.829968)
		(end 90.261948 -52.829968)
		(width 0.508)
		(layer "F.Cu")
		(net "GND")
	)
	(segment
		(start 457.854558 -243.74094)
		(end 457.854558 -245.269004)
		(width 0.508)
		(layer "F.Cu")
		(net "GND")
	)
	(segment
		(start 385.804918 -55.230014)
		(end 387.611874 -55.230014)
		(width 0.508)
		(layer "F.Cu")
		(net "GND")
	)
	(segment
		(start 394.26515 -160.903158)
		(end 394.26515 -161.649918)
		(width 0.4064)
		(layer "F.Cu")
		(net "GND")
	)
	(segment
		(start 485.125014 -289.815016)
		(end 483.404926 -289.815016)
		(width 0.508)
		(layer "F.Cu")
		(net "GND")
	)
	(segment
		(start 317.8175 -175.8061)
		(end 318.4652 -175.1584)
		(width 0.508)
		(layer "F.Cu")
		(net "GND")
	)
	(segment
		(start 153.339038 -46.251114)
		(end 153.745184 -45.844968)
		(width 0.508)
		(layer "F.Cu")
		(net "GND")
	)
	(segment
		(start 427.834552 -49.596294)
		(end 428.787052 -49.596294)
		(width 0.508)
		(layer "F.Cu")
		(net "GND")
	)
	(segment
		(start 448.904868 -285.230062)
		(end 450.711824 -285.230062)
		(width 0.508)
		(layer "F.Cu")
		(net "GND")
	)
	(segment
		(start 82.768948 -177.778918)
		(end 81.752948 -177.778918)
		(width 0.508)
		(layer "F.Cu")
		(net "GND")
	)
	(segment
		(start 256.5273 -238.75619)
		(end 256.5273 -238.506)
		(width 0.508)
		(layer "F.Cu")
		(net "GND")
	)
	(segment
		(start 485.125014 -272.035016)
		(end 483.404926 -272.035016)
		(width 0.508)
		(layer "F.Cu")
		(net "GND")
	)
	(segment
		(start 256.2098 -236.6137)
		(end 256.4765 -236.347)
		(width 0.508)
		(layer "F.Cu")
		(net "GND")
	)
	(segment
		(start 67.792346 -291.127942)
		(end 67.792346 -289.857942)
		(width 0.508)
		(layer "F.Cu")
		(net "GND")
	)
	(segment
		(start 332.680818 -297.223942)
		(end 332.359 -297.223942)
		(width 0.508)
		(layer "F.Cu")
		(net "GND")
	)
	(segment
		(start 457.538074 -245.269004)
		(end 456.958954 -244.689884)
		(width 0.508)
		(layer "F.Cu")
		(net "GND")
	)
	(segment
		(start 139.361418 -141.406626)
		(end 139.386818 -141.432026)
		(width 0.508)
		(layer "F.Cu")
		(net "GND")
	)
	(segment
		(start 417.35502 -280.42997)
		(end 419.161976 -280.42997)
		(width 0.508)
		(layer "F.Cu")
		(net "GND")
	)
	(segment
		(start 176.983898 -148.49983)
		(end 176.983898 -147.480782)
		(width 0.508)
		(layer "F.Cu")
		(net "GND")
	)
	(segment
		(start 380.91745 -176.127918)
		(end 379.9078 -176.127918)
		(width 0.508)
		(layer "F.Cu")
		(net "GND")
	)
	(segment
		(start 11.203178 -131.192524)
		(end 11.204194 -131.19354)
		(width 0.508)
		(layer "F.Cu")
		(net "GND")
	)
	(segment
		(start 255.143 -301.9806)
		(end 255.7272 -302.5648)
		(width 0.508)
		(layer "F.Cu")
		(net "GND")
	)
	(segment
		(start 381.6096 -139.9286)
		(end 380.07671 -139.9286)
		(width 0.254)
		(layer "F.Cu")
		(net "GND")
	)
	(segment
		(start 178.83124 -279.494742)
		(end 179.7558 -279.494742)
		(width 0.4064)
		(layer "F.Cu")
		(net "GND")
	)
	(segment
		(start 250.625102 31.074868)
		(end 250.625102 29.35478)
		(width 0.508)
		(layer "F.Cu")
		(net "GND")
	)
	(segment
		(start 443.404244 -243.76507)
		(end 443.407292 -243.762022)
		(width 0.508)
		(layer "F.Cu")
		(net "GND")
	)
	(segment
		(start 74.303128 -131.156456)
		(end 74.304144 -131.157472)
		(width 0.508)
		(layer "F.Cu")
		(net "GND")
	)
	(segment
		(start 422.025064 -62.354968)
		(end 420.304976 -62.354968)
		(width 0.508)
		(layer "F.Cu")
		(net "GND")
	)
	(segment
		(start 228.864668 -385.201668)
		(end 229.72776 -386.06476)
		(width 0.381)
		(layer "F.Cu")
		(net "GND")
	)
	(segment
		(start 19.780758 -277.615142)
		(end 19.033998 -277.615142)
		(width 0.4064)
		(layer "F.Cu")
		(net "GND")
	)
	(segment
		(start 267.5128 -229.8573)
		(end 267.5128 -229.032562)
		(width 0.508)
		(layer "F.Cu")
		(net "GND")
	)
	(segment
		(start 14.816836 -130.30708)
		(end 14.816836 -131.181094)
		(width 0.508)
		(layer "F.Cu")
		(net "GND")
	)
	(segment
		(start 232.9434 -248.5263)
		(end 232.9434 -247.275858)
		(width 0.508)
		(layer "F.Cu")
		(net "GND")
	)
	(segment
		(start 394.26515 -275.903182)
		(end 394.26515 -276.649942)
		(width 0.4064)
		(layer "F.Cu")
		(net "GND")
	)
	(segment
		(start 125.818392 -49.654968)
		(end 124.674884 -49.654968)
		(width 0.508)
		(layer "F.Cu")
		(net "GND")
	)
	(segment
		(start 354.25507 -167.829992)
		(end 356.062026 -167.829992)
		(width 0.508)
		(layer "F.Cu")
		(net "GND")
	)
	(segment
		(start 54.990746 -160.887918)
		(end 54.990746 -161.776918)
		(width 0.508)
		(layer "F.Cu")
		(net "GND")
	)
	(segment
		(start 485.125014 -275.845016)
		(end 483.404926 -275.845016)
		(width 0.508)
		(layer "F.Cu")
		(net "GND")
	)
	(segment
		(start 358.925114 -279.655016)
		(end 357.205026 -279.655016)
		(width 0.508)
		(layer "F.Cu")
		(net "GND")
	)
	(segment
		(start 91.300046 -36.03498)
		(end 93.182948 -36.03498)
		(width 0.508)
		(layer "F.Cu")
		(net "GND")
	)
	(segment
		(start 244.221 -230.2256)
		(end 244.5766 -229.87)
		(width 0.508)
		(layer "F.Cu")
		(net "GND")
	)
	(segment
		(start 93.125036 -177.354992)
		(end 91.404948 -177.354992)
		(width 0.508)
		(layer "F.Cu")
		(net "GND")
	)
	(segment
		(start 483.300024 -309.785004)
		(end 485.182926 -309.785004)
		(width 0.508)
		(layer "F.Cu")
		(net "GND")
	)
	(segment
		(start 402.782278 -32.957516)
		(end 402.782278 -34.073338)
		(width 0.508)
		(layer "F.Cu")
		(net "GND")
	)
	(segment
		(start 120.985026 -36.698174)
		(end 121.64822 -36.03498)
		(width 0.508)
		(layer "F.Cu")
		(net "GND")
	)
	(segment
		(start 240.56975 -347.72854)
		(end 240.578386 -347.719904)
		(width 0.508)
		(layer "F.Cu")
		(net "GND")
	)
	(segment
		(start 130.433318 -146.540474)
		(end 131.444746 -146.540474)
		(width 0.508)
		(layer "F.Cu")
		(net "GND")
	)
	(segment
		(start 127.046736 -50.883312)
		(end 125.818392 -49.654968)
		(width 0.508)
		(layer "F.Cu")
		(net "GND")
	)
	(segment
		(start 81.752948 -174.603918)
		(end 81.752948 -176.000918)
		(width 0.508)
		(layer "F.Cu")
		(net "GND")
	)
	(segment
		(start 221.237302 -207.983074)
		(end 220.386402 -207.983074)
		(width 0.508)
		(layer "F.Cu")
		(net "GND")
	)
	(segment
		(start 358.925114 -62.354968)
		(end 356.606602 -62.354968)
		(width 0.508)
		(layer "F.Cu")
		(net "GND")
	)
	(segment
		(start 156.099002 -309.785004)
		(end 154.399996 -309.785004)
		(width 0.508)
		(layer "F.Cu")
		(net "GND")
	)
	(segment
		(start 124.674884 -275.845016)
		(end 122.954796 -275.845016)
		(width 0.508)
		(layer "F.Cu")
		(net "GND")
	)
	(segment
		(start 93.125036 -49.654968)
		(end 91.404948 -49.654968)
		(width 0.508)
		(layer "F.Cu")
		(net "GND")
	)
	(segment
		(start 357.024432 -42.034968)
		(end 358.925114 -42.034968)
		(width 0.508)
		(layer "F.Cu")
		(net "GND")
	)
	(segment
		(start 479.340926 -305.224942)
		(end 479.340926 -306.240942)
		(width 0.508)
		(layer "F.Cu")
		(net "GND")
	)
	(segment
		(start 120.998742 -309.752492)
		(end 120.998742 -309.785004)
		(width 0.508)
		(layer "F.Cu")
		(net "GND")
	)
	(segment
		(start 30.025086 -45.844968)
		(end 28.304998 -45.844968)
		(width 0.508)
		(layer "F.Cu")
		(net "GND")
	)
	(segment
		(start 365.06023 -49.596294)
		(end 365.8362 -48.820324)
		(width 0.508)
		(layer "F.Cu")
		(net "GND")
	)
	(segment
		(start 18.652998 -289.603942)
		(end 18.652998 -291.000942)
		(width 0.508)
		(layer "F.Cu")
		(net "GND")
	)
	(segment
		(start 262.794496 -344.049604)
		(end 261.994396 -344.049604)
		(width 0.508)
		(layer "F.Cu")
		(net "GND")
	)
	(segment
		(start 339.022944 -243.751862)
		(end 339.022944 -245.314724)
		(width 0.508)
		(layer "F.Cu")
		(net "GND")
	)
	(segment
		(start 257.173476 -261.79526)
		(end 257.173476 -262.59536)
		(width 0.508)
		(layer "F.Cu")
		(net "GND")
	)
	(segment
		(start 441.13323 -285.355284)
		(end 441.12815 -285.355284)
		(width 0.508)
		(layer "F.Cu")
		(net "GND")
	)
	(segment
		(start 322.704968 -165.429946)
		(end 324.511924 -165.429946)
		(width 0.508)
		(layer "F.Cu")
		(net "GND")
	)
	(segment
		(start 239.491266 -347.716856)
		(end 239.50295 -347.72854)
		(width 0.508)
		(layer "F.Cu")
		(net "GND")
	)
	(segment
		(start 142.604998 -54.207664)
		(end 143.002 -54.604666)
		(width 0.508)
		(layer "F.Cu")
		(net "GND")
	)
	(segment
		(start 19.780758 -47.615094)
		(end 19.033998 -47.615094)
		(width 0.4064)
		(layer "F.Cu")
		(net "GND")
	)
	(segment
		(start 54.990746 -49.4538)
		(end 55.0164 -49.4538)
		(width 0.508)
		(layer "F.Cu")
		(net "GND")
	)
	(segment
		(start 240.009934 -384.8608)
		(end 240.009934 -385.9403)
		(width 0.3048)
		(layer "F.Cu")
		(net "GND")
	)
	(segment
		(start 149.640798 -49.39538)
		(end 149.026626 -50.009552)
		(width 0.508)
		(layer "F.Cu")
		(net "GND")
	)
	(segment
		(start 129.794 -131.156456)
		(end 129.795016 -131.157472)
		(width 0.508)
		(layer "F.Cu")
		(net "GND")
	)
	(segment
		(start 471.301318 -41.07815)
		(end 472.190318 -41.07815)
		(width 0.508)
		(layer "F.Cu")
		(net "GND")
	)
	(segment
		(start 483.300024 -194.78498)
		(end 485.182926 -194.78498)
		(width 0.508)
		(layer "F.Cu")
		(net "GND")
	)
	(segment
		(start 121.577354 -56.066436)
		(end 120.740932 -55.230014)
		(width 0.508)
		(layer "F.Cu")
		(net "GND")
	)
	(segment
		(start 265.80211 -142.21206)
		(end 265.456924 -142.557246)
		(width 0.508)
		(layer "F.Cu")
		(net "GND")
	)
	(segment
		(start 263.832848 9.781032)
		(end 263.832848 8.842248)
		(width 0.508)
		(layer "F.Cu")
		(net "GND")
	)
	(segment
		(start 257.5941 -16.1544)
		(end 258.4704 -16.1544)
		(width 0.508)
		(layer "F.Cu")
		(net "GND")
	)
	(segment
		(start 458.5589 -297.223942)
		(end 459.9559 -297.223942)
		(width 0.508)
		(layer "F.Cu")
		(net "GND")
	)
	(segment
		(start 466.453474 -289.780726)
		(end 466.453474 -290.679886)
		(width 0.508)
		(layer "F.Cu")
		(net "GND")
	)
	(segment
		(start 70.63486 -304.106834)
		(end 70.631304 -304.106834)
		(width 0.508)
		(layer "F.Cu")
		(net "GND")
	)
	(segment
		(start 238.9505 -256.2733)
		(end 238.506 -255.8288)
		(width 0.508)
		(layer "F.Cu")
		(net "GND")
	)
	(segment
		(start 485.125014 -297.435016)
		(end 483.404926 -297.435016)
		(width 0.508)
		(layer "F.Cu")
		(net "GND")
	)
	(segment
		(start 93.125036 -157.034992)
		(end 91.404948 -157.034992)
		(width 0.508)
		(layer "F.Cu")
		(net "GND")
	)
	(segment
		(start 7.79018 -286.4866)
		(end 7.79018 -287.647888)
		(width 0.508)
		(layer "F.Cu")
		(net "GND")
	)
	(segment
		(start 314.026804 -243.703602)
		(end 314.032138 -243.698268)
		(width 0.508)
		(layer "F.Cu")
		(net "GND")
	)
	(segment
		(start 265.1506 -229.8573)
		(end 265.1506 -228.998272)
		(width 0.508)
		(layer "F.Cu")
		(net "GND")
	)
	(segment
		(start 346.637102 -290.522914)
		(end 346.637102 -291.356542)
		(width 0.508)
		(layer "F.Cu")
		(net "GND")
	)
	(segment
		(start 333.1845 -164.596318)
		(end 334.1116 -164.596318)
		(width 0.508)
		(layer "F.Cu")
		(net "GND")
	)
	(segment
		(start 16.379698 -168.152318)
		(end 16.379698 -169.015918)
		(width 0.508)
		(layer "F.Cu")
		(net "GND")
	)
	(segment
		(start 419.852348 -170.230038)
		(end 417.35502 -170.230038)
		(width 0.508)
		(layer "F.Cu")
		(net "GND")
	)
	(segment
		(start 365.341408 -44.602654)
		(end 364.594902 -44.602654)
		(width 0.4064)
		(layer "F.Cu")
		(net "GND")
	)
	(segment
		(start 98.754184 -186.981084)
		(end 98.754184 -185.938668)
		(width 0.508)
		(layer "F.Cu")
		(net "GND")
	)
	(segment
		(start 329.819 -68.8594)
		(end 329.8698 -68.9102)
		(width 0.508)
		(layer "F.Cu")
		(net "GND")
	)
	(segment
		(start 128.7145 -41.992296)
		(end 128.7145 -42.034968)
		(width 0.508)
		(layer "F.Cu")
		(net "GND")
	)
	(segment
		(start 363.655102 -42.141394)
		(end 363.655102 -41.315894)
		(width 0.508)
		(layer "F.Cu")
		(net "GND")
	)
	(segment
		(start 457.854558 -245.269004)
		(end 457.538074 -245.269004)
		(width 0.508)
		(layer "F.Cu")
		(net "GND")
	)
	(segment
		(start 181.6862 -70.322694)
		(end 180.4162 -70.322694)
		(width 0.508)
		(layer "F.Cu")
		(net "GND")
	)
	(segment
		(start 105.837228 -131.147058)
		(end 105.838244 -131.148074)
		(width 0.508)
		(layer "F.Cu")
		(net "GND")
	)
	(segment
		(start 420.176452 -69.974968)
		(end 422.025064 -69.974968)
		(width 0.508)
		(layer "F.Cu")
		(net "GND")
	)
	(segment
		(start 339.02777 -245.31955)
		(end 338.15909 -245.31955)
		(width 0.508)
		(layer "F.Cu")
		(net "GND")
	)
	(segment
		(start 241.960908 -237.49)
		(end 242.307618 -237.14329)
		(width 0.508)
		(layer "F.Cu")
		(net "GND")
	)
	(segment
		(start 433.725828 -131.33451)
		(end 433.70373 -131.356608)
		(width 0.508)
		(layer "F.Cu")
		(net "GND")
	)
	(segment
		(start 241.427 -247.958102)
		(end 241.031268 -247.56237)
		(width 0.508)
		(layer "F.Cu")
		(net "GND")
	)
	(segment
		(start 358.925114 -297.435016)
		(end 357.205026 -297.435016)
		(width 0.508)
		(layer "F.Cu")
		(net "GND")
	)
	(segment
		(start 88.454992 -55.230014)
		(end 90.261948 -55.230014)
		(width 0.508)
		(layer "F.Cu")
		(net "GND")
	)
	(segment
		(start 392.527282 -41.685464)
		(end 392.177778 -42.034968)
		(width 0.508)
		(layer "F.Cu")
		(net "GND")
	)
	(segment
		(start 441.183014 -290.951412)
		(end 441.183014 -290.035234)
		(width 0.508)
		(layer "F.Cu")
		(net "GND")
	)
	(segment
		(start 325.550022 -194.78498)
		(end 327.432924 -194.78498)
		(width 0.508)
		(layer "F.Cu")
		(net "GND")
	)
	(segment
		(start 54.990746 -48.554894)
		(end 54.990746 -49.4538)
		(width 0.508)
		(layer "F.Cu")
		(net "GND")
	)
	(segment
		(start 61.574934 -299.975016)
		(end 59.854846 -299.975016)
		(width 0.508)
		(layer "F.Cu")
		(net "GND")
	)
	(segment
		(start 485.125014 -279.655016)
		(end 483.404926 -279.655016)
		(width 0.508)
		(layer "F.Cu")
		(net "GND")
	)
	(segment
		(start 241.427 -248.7295)
		(end 241.427 -247.958102)
		(width 0.508)
		(layer "F.Cu")
		(net "GND")
	)
	(segment
		(start 177.419 -177.778918)
		(end 176.403 -177.778918)
		(width 0.508)
		(layer "F.Cu")
		(net "GND")
	)
	(segment
		(start 324.718934 -52.317396)
		(end 324.206362 -52.829968)
		(width 0.508)
		(layer "F.Cu")
		(net "GND")
	)
	(segment
		(start 181.6862 -185.322718)
		(end 180.4162 -185.322718)
		(width 0.508)
		(layer "F.Cu")
		(net "GND")
	)
	(segment
		(start 187.775088 -157.034992)
		(end 186.055 -157.034992)
		(width 0.508)
		(layer "F.Cu")
		(net "GND")
	)
	(segment
		(start 227.69068 -237.076742)
		(end 227.69068 -239.8014)
		(width 0.3556)
		(layer "F.Cu")
		(net "GND")
	)
	(segment
		(start 247.15597 -300.482762)
		(end 248.106438 -300.482762)
		(width 0.508)
		(layer "F.Cu")
		(net "GND")
	)
	(segment
		(start 460.114396 -182.225442)
		(end 460.114396 -182.223918)
		(width 0.508)
		(layer "F.Cu")
		(net "GND")
	)
	(segment
		(start 271.907 17.2466)
		(end 272.24736 16.90624)
		(width 0.381)
		(layer "F.Cu")
		(net "GND")
	)
	(segment
		(start 47.929546 -53.101494)
		(end 47.929546 -53.990494)
		(width 0.508)
		(layer "F.Cu")
		(net "GND")
	)
	(segment
		(start 330.090526 -22.210014)
		(end 330.090526 -21.405088)
		(width 0.508)
		(layer "F.Cu")
		(net "GND")
	)
	(segment
		(start 419.313614 -296.83964)
		(end 419.90899 -297.435016)
		(width 0.508)
		(layer "F.Cu")
		(net "GND")
	)
	(segment
		(start 230.0986 -392.0744)
		(end 230.124 -392.0998)
		(width 0.508)
		(layer "F.Cu")
		(net "GND")
	)
	(segment
		(start 378.290582 -291.506656)
		(end 378.293122 -291.509196)
		(width 0.508)
		(layer "F.Cu")
		(net "GND")
	)
	(segment
		(start 235.809282 -236.992414)
		(end 237.115096 -235.6866)
		(width 0.508)
		(layer "F.Cu")
		(net "GND")
	)
	(segment
		(start 135.97128 -292.804342)
		(end 135.97128 -292.803834)
		(width 0.508)
		(layer "F.Cu")
		(net "GND")
	)
	(segment
		(start 425.815252 -160.903158)
		(end 425.815252 -161.649918)
		(width 0.4064)
		(layer "F.Cu")
		(net "GND")
	)
	(segment
		(start 396.60195 -189.920118)
		(end 396.60195 -191.113918)
		(width 0.508)
		(layer "F.Cu")
		(net "GND")
	)
	(segment
		(start 24.240998 -75.224894)
		(end 24.240998 -76.240894)
		(width 0.508)
		(layer "F.Cu")
		(net "GND")
	)
	(segment
		(start 86.566248 -278.580342)
		(end 86.566248 -279.469342)
		(width 0.508)
		(layer "F.Cu")
		(net "GND")
	)
	(segment
		(start 349.367602 -176.127918)
		(end 349.367602 -175.238918)
		(width 0.508)
		(layer "F.Cu")
		(net "GND")
	)
	(segment
		(start 151.554942 -165.429946)
		(end 153.361898 -165.429946)
		(width 0.508)
		(layer "F.Cu")
		(net "GND")
	)
	(segment
		(start 473.36202 -274.84324)
		(end 473.36202 -275.57222)
		(width 0.3556)
		(layer "F.Cu")
		(net "GND")
	)
	(segment
		(start 112.201452 -294.816784)
		(end 111.024416 -294.816784)
		(width 0.508)
		(layer "F.Cu")
		(net "GND")
	)
	(segment
		(start 39.084504 -304.100992)
		(end 39.071296 -304.100992)
		(width 0.508)
		(layer "F.Cu")
		(net "GND")
	)
	(segment
		(start 413.461708 -284.213046)
		(end 413.461708 -283.070046)
		(width 0.508)
		(layer "F.Cu")
		(net "GND")
	)
	(segment
		(start 466.3948 -289.722052)
		(end 466.402674 -289.729926)
		(width 0.508)
		(layer "F.Cu")
		(net "GND")
	)
	(segment
		(start 331.47 -76.0476)
		(end 331.47 -74.920094)
		(width 0.508)
		(layer "F.Cu")
		(net "GND")
	)
	(segment
		(start 41.683178 -128.750568)
		(end 41.683178 -130.132074)
		(width 0.508)
		(layer "F.Cu")
		(net "GND")
	)
	(segment
		(start 437.309514 -130.339084)
		(end 437.309514 -128.676908)
		(width 0.508)
		(layer "F.Cu")
		(net "GND")
	)
	(segment
		(start 251.097542 -382.641348)
		(end 251.097542 -381.755396)
		(width 0.508)
		(layer "F.Cu")
		(net "GND")
	)
	(segment
		(start 422.025064 -289.815016)
		(end 420.304976 -289.815016)
		(width 0.508)
		(layer "F.Cu")
		(net "GND")
	)
	(segment
		(start 30.025086 -69.974968)
		(end 28.304998 -69.974968)
		(width 0.508)
		(layer "F.Cu")
		(net "GND")
	)
	(segment
		(start 480.45497 -280.42997)
		(end 482.261926 -280.42997)
		(width 0.508)
		(layer "F.Cu")
		(net "GND")
	)
	(segment
		(start 447.010536 -245.302024)
		(end 447.010536 -243.77396)
		(width 0.508)
		(layer "F.Cu")
		(net "GND")
	)
	(segment
		(start 220.957902 -377.73991)
		(end 220.6244 -377.406408)
		(width 0.508)
		(layer "F.Cu")
		(net "GND")
	)
	(segment
		(start 226.862132 -385.201668)
		(end 227.67671 -385.201668)
		(width 0.508)
		(layer "F.Cu")
		(net "GND")
	)
	(segment
		(start 479.340926 -190.224918)
		(end 479.340926 -191.240918)
		(width 0.508)
		(layer "F.Cu")
		(net "GND")
	)
	(segment
		(start 450.945504 -42.034968)
		(end 453.574912 -42.034968)
		(width 0.508)
		(layer "F.Cu")
		(net "GND")
	)
	(segment
		(start 30.025086 -157.034992)
		(end 28.304998 -157.034992)
		(width 0.508)
		(layer "F.Cu")
		(net "GND")
	)
	(segment
		(start 427.009052 -297.223942)
		(end 428.406052 -297.223942)
		(width 0.508)
		(layer "F.Cu")
		(net "GND")
	)
	(segment
		(start 61.574934 -49.654968)
		(end 59.854846 -49.654968)
		(width 0.508)
		(layer "F.Cu")
		(net "GND")
	)
	(segment
		(start 98.823018 -296.23512)
		(end 97.860358 -296.23512)
		(width 0.508)
		(layer "F.Cu")
		(net "GND")
	)
	(segment
		(start 156.224986 -62.354968)
		(end 154.504898 -62.354968)
		(width 0.508)
		(layer "F.Cu")
		(net "GND")
	)
	(segment
		(start 422.025064 -45.844968)
		(end 420.304976 -45.844968)
		(width 0.508)
		(layer "F.Cu")
		(net "GND")
	)
	(segment
		(start 56.90489 -285.230062)
		(end 58.711846 -285.230062)
		(width 0.508)
		(layer "F.Cu")
		(net "GND")
	)
	(segment
		(start 358.925114 -292.355016)
		(end 357.205026 -292.355016)
		(width 0.508)
		(layer "F.Cu")
		(net "GND")
	)
	(segment
		(start 317.502794 -131.243578)
		(end 317.502794 -130.419602)
		(width 0.508)
		(layer "F.Cu")
		(net "GND")
	)
	(segment
		(start 28.200096 -151.035004)
		(end 30.163262 -151.035004)
		(width 0.508)
		(layer "F.Cu")
		(net "GND")
	)
	(segment
		(start 317.60414 -60.060586)
		(end 316.778386 -60.060586)
		(width 0.508)
		(layer "F.Cu")
		(net "GND")
	)
	(segment
		(start 405.719534 -246.245888)
		(end 405.694134 -246.271288)
		(width 0.508)
		(layer "F.Cu")
		(net "GND")
	)
	(segment
		(start 156.224986 -59.814968)
		(end 154.504898 -59.814968)
		(width 0.508)
		(layer "F.Cu")
		(net "GND")
	)
	(segment
		(start 271.4498 -279.8699)
		(end 271.4498 -278.5364)
		(width 0.508)
		(layer "F.Cu")
		(net "GND")
	)
	(segment
		(start 25.355042 -170.230038)
		(end 27.161998 -170.230038)
		(width 0.508)
		(layer "F.Cu")
		(net "GND")
	)
	(segment
		(start 88.78697 -17.59077)
		(end 87.749634 -17.59077)
		(width 0.3048)
		(layer "F.Cu")
		(net "GND")
	)
	(segment
		(start 358.925114 -289.815016)
		(end 357.205026 -289.815016)
		(width 0.508)
		(layer "F.Cu")
		(net "GND")
	)
	(segment
		(start 422.025064 -299.975016)
		(end 423.768012 -299.975016)
		(width 0.508)
		(layer "F.Cu")
		(net "GND")
	)
	(segment
		(start 453.574912 -279.655016)
		(end 451.854824 -279.655016)
		(width 0.508)
		(layer "F.Cu")
		(net "GND")
	)
	(segment
		(start 122.849894 -79.784956)
		(end 124.732796 -79.784956)
		(width 0.508)
		(layer "F.Cu")
		(net "GND")
	)
	(segment
		(start 224.9424 -209.3976)
		(end 224.475802 -209.864198)
		(width 0.381)
		(layer "F.Cu")
		(net "GND")
	)
	(segment
		(start 181.991 -305.224942)
		(end 181.991 -306.240942)
		(width 0.508)
		(layer "F.Cu")
		(net "GND")
	)
	(segment
		(start 77.916786 -130.271012)
		(end 77.916786 -131.145026)
		(width 0.508)
		(layer "F.Cu")
		(net "GND")
	)
	(segment
		(start 187.775088 -177.354992)
		(end 186.055 -177.354992)
		(width 0.508)
		(layer "F.Cu")
		(net "GND")
	)
	(segment
		(start 25.355042 -165.429946)
		(end 27.161998 -165.429946)
		(width 0.508)
		(layer "F.Cu")
		(net "GND")
	)
	(segment
		(start 312.343038 -291.73932)
		(end 312.341514 -291.73932)
		(width 0.508)
		(layer "F.Cu")
		(net "GND")
	)
	(segment
		(start 61.574934 -69.974968)
		(end 59.854846 -69.974968)
		(width 0.508)
		(layer "F.Cu")
		(net "GND")
	)
	(segment
		(start 114.318796 -177.778918)
		(end 113.302796 -177.778918)
		(width 0.508)
		(layer "F.Cu")
		(net "GND")
	)
	(segment
		(start 93.125036 -289.815016)
		(end 91.404948 -289.815016)
		(width 0.508)
		(layer "F.Cu")
		(net "GND")
	)
	(segment
		(start 413.460692 -281.115516)
		(end 413.460692 -281.942032)
		(width 0.508)
		(layer "F.Cu")
		(net "GND")
	)
	(segment
		(start 187.775088 -297.435016)
		(end 186.055 -297.435016)
		(width 0.508)
		(layer "F.Cu")
		(net "GND")
	)
	(segment
		(start 91.063572 -297.462956)
		(end 91.091512 -297.435016)
		(width 0.508)
		(layer "F.Cu")
		(net "GND")
	)
	(segment
		(start 485.125014 -177.354992)
		(end 483.404926 -177.354992)
		(width 0.508)
		(layer "F.Cu")
		(net "GND")
	)
	(segment
		(start 133.736842 -297.844464)
		(end 133.736842 -298.988988)
		(width 0.508)
		(layer "F.Cu")
		(net "GND")
	)
	(segment
		(start 223.88068 -343.011252)
		(end 224.725484 -343.011252)
		(width 0.508)
		(layer "F.Cu")
		(net "GND")
	)
	(segment
		(start 390.474962 -67.434968)
		(end 388.754874 -67.434968)
		(width 0.508)
		(layer "F.Cu")
		(net "GND")
	)
	(segment
		(start 283.85389 29.249878)
		(end 282.02509 29.249878)
		(width 0.508)
		(layer "F.Cu")
		(net "GND")
	)
	(segment
		(start 30.025086 -289.815016)
		(end 28.304998 -289.815016)
		(width 0.508)
		(layer "F.Cu")
		(net "GND")
	)
	(segment
		(start 402.109432 -131.401058)
		(end 402.08962 -131.42087)
		(width 0.508)
		(layer "F.Cu")
		(net "GND")
	)
	(segment
		(start 79.479648 -53.594762)
		(end 79.839566 -53.95468)
		(width 0.508)
		(layer "F.Cu")
		(net "GND")
	)
	(segment
		(start 220.6244 -375.659142)
		(end 220.672914 -375.610628)
		(width 0.508)
		(layer "F.Cu")
		(net "GND")
	)
	(segment
		(start 448.904868 -167.829992)
		(end 450.711824 -167.829992)
		(width 0.508)
		(layer "F.Cu")
		(net "GND")
	)
	(segment
		(start 67.243706 -186.999372)
		(end 67.243706 -185.956956)
		(width 0.508)
		(layer "F.Cu")
		(net "GND")
	)
	(segment
		(start 448.904868 -282.830016)
		(end 446.79997 -282.830016)
		(width 0.508)
		(layer "F.Cu")
		(net "GND")
	)
	(segment
		(start 352.118676 -55.230014)
		(end 354.25507 -55.230014)
		(width 0.508)
		(layer "F.Cu")
		(net "GND")
	)
	(segment
		(start 472.215718 -43.43781)
		(end 472.215718 -42.51325)
		(width 0.4064)
		(layer "F.Cu")
		(net "GND")
	)
	(segment
		(start 456.0189 -305.097942)
		(end 456.0189 -306.113942)
		(width 0.508)
		(layer "F.Cu")
		(net "GND")
	)
	(segment
		(start 379.9332 -139.78509)
		(end 378.741432 -139.78509)
		(width 0.254)
		(layer "F.Cu")
		(net "GND")
	)
	(segment
		(start 480.45497 -170.230038)
		(end 482.261926 -170.230038)
		(width 0.508)
		(layer "F.Cu")
		(net "GND")
	)
	(segment
		(start 25.355042 -285.230062)
		(end 27.161998 -285.230062)
		(width 0.508)
		(layer "F.Cu")
		(net "GND")
	)
	(segment
		(start 402.122894 -245.31066)
		(end 402.12772 -245.315486)
		(width 0.508)
		(layer "F.Cu")
		(net "GND")
	)
	(segment
		(start 273.54784 13.54836)
		(end 273.54784 14.333728)
		(width 0.381)
		(layer "F.Cu")
		(net "GND")
	)
	(segment
		(start 124.674884 -297.435016)
		(end 122.954796 -297.435016)
		(width 0.508)
		(layer "F.Cu")
		(net "GND")
	)
	(segment
		(start 385.804918 -50.429922)
		(end 387.611874 -50.429922)
		(width 0.508)
		(layer "F.Cu")
		(net "GND")
	)
	(segment
		(start 35.654488 -187.064396)
		(end 35.654488 -186.02198)
		(width 0.508)
		(layer "F.Cu")
		(net "GND")
	)
	(segment
		(start 384.631438 -140.591794)
		(end 383.517394 -140.591794)
		(width 0.508)
		(layer "F.Cu")
		(net "GND")
	)
	(segment
		(start 150.136098 -70.322694)
		(end 148.020532 -70.322694)
		(width 0.508)
		(layer "F.Cu")
		(net "GND")
	)
	(segment
		(start 402.12772 -245.315486)
		(end 402.12772 -246.243094)
		(width 0.508)
		(layer "F.Cu")
		(net "GND")
	)
	(segment
		(start 334.68437 -27.405584)
		(end 334.685894 -27.405584)
		(width 0.508)
		(layer "F.Cu")
		(net "GND")
	)
	(segment
		(start 30.025086 -184.974992)
		(end 28.304998 -184.974992)
		(width 0.508)
		(layer "F.Cu")
		(net "GND")
	)
	(segment
		(start 390.474962 -182.434992)
		(end 388.754874 -182.434992)
		(width 0.508)
		(layer "F.Cu")
		(net "GND")
	)
	(segment
		(start 425.249848 -67.604894)
		(end 425.57065 -67.925696)
		(width 0.508)
		(layer "F.Cu")
		(net "GND")
	)
	(segment
		(start 257.782314 -239.612678)
		(end 257.383788 -239.612678)
		(width 0.508)
		(layer "F.Cu")
		(net "GND")
	)
	(segment
		(start 28.200096 -36.03498)
		(end 30.082998 -36.03498)
		(width 0.508)
		(layer "F.Cu")
		(net "GND")
	)
	(segment
		(start 93.125036 -164.654992)
		(end 91.404948 -164.654992)
		(width 0.508)
		(layer "F.Cu")
		(net "GND")
	)
	(segment
		(start 395.01445 -165.104318)
		(end 395.96695 -165.104318)
		(width 0.508)
		(layer "F.Cu")
		(net "GND")
	)
	(segment
		(start 124.674884 -182.434992)
		(end 122.954796 -182.434992)
		(width 0.508)
		(layer "F.Cu")
		(net "GND")
	)
	(segment
		(start 390.474962 -164.654992)
		(end 388.754874 -164.654992)
		(width 0.508)
		(layer "F.Cu")
		(net "GND")
	)
	(segment
		(start 151.554942 -280.42997)
		(end 153.361898 -280.42997)
		(width 0.508)
		(layer "F.Cu")
		(net "GND")
	)
	(segment
		(start 363.020102 -304.920142)
		(end 363.020102 -306.113942)
		(width 0.508)
		(layer "F.Cu")
		(net "GND")
	)
	(segment
		(start 453.574912 -59.814968)
		(end 451.854824 -59.814968)
		(width 0.508)
		(layer "F.Cu")
		(net "GND")
	)
	(segment
		(start 55.486046 -185.322718)
		(end 54.216046 -185.322718)
		(width 0.508)
		(layer "F.Cu")
		(net "GND")
	)
	(segment
		(start 356.606602 -49.654968)
		(end 358.925114 -49.654968)
		(width 0.508)
		(layer "F.Cu")
		(net "GND")
	)
	(segment
		(start 259.3848 -279.6159)
		(end 259.3848 -277.9522)
		(width 0.508)
		(layer "F.Cu")
		(net "GND")
	)
	(segment
		(start 388.649972 -79.784956)
		(end 390.532874 -79.784956)
		(width 0.508)
		(layer "F.Cu")
		(net "GND")
	)
	(segment
		(start 61.574934 -164.654992)
		(end 59.854846 -164.654992)
		(width 0.508)
		(layer "F.Cu")
		(net "GND")
	)
	(segment
		(start 358.925114 -69.974968)
		(end 357.205026 -69.974968)
		(width 0.508)
		(layer "F.Cu")
		(net "GND")
	)
	(segment
		(start 453.574912 -289.815016)
		(end 451.854824 -289.815016)
		(width 0.508)
		(layer "F.Cu")
		(net "GND")
	)
	(segment
		(start 176.011586 -61.000894)
		(end 176.403 -61.000894)
		(width 0.508)
		(layer "F.Cu")
		(net "GND")
	)
	(segment
		(start 59.749944 -79.784956)
		(end 61.632846 -79.784956)
		(width 0.508)
		(layer "F.Cu")
		(net "GND")
	)
	(segment
		(start 426.755052 -272.141442)
		(end 426.755052 -271.315942)
		(width 0.508)
		(layer "F.Cu")
		(net "GND")
	)
	(segment
		(start 441.165234 -292.889432)
		(end 441.165234 -294.177212)
		(width 0.508)
		(layer "F.Cu")
		(net "GND")
	)
	(segment
		(start 133.171438 -140.520674)
		(end 132.227066 -140.520674)
		(width 0.508)
		(layer "F.Cu")
		(net "GND")
	)
	(segment
		(start 235.823506 -346.345256)
		(end 235.823506 -345.482418)
		(width 0.508)
		(layer "F.Cu")
		(net "GND")
	)
	(segment
		(start 368.878866 -143.1544)
		(end 368.878866 -142.0749)
		(width 0.3048)
		(layer "F.Cu")
		(net "GND")
	)
	(segment
		(start 372.995952 -128.68529)
		(end 373.02567 -128.655572)
		(width 0.508)
		(layer "F.Cu")
		(net "GND")
	)
	(segment
		(start 468.76843 -130.376168)
		(end 468.763604 -130.371342)
		(width 0.508)
		(layer "F.Cu")
		(net "GND")
	)
	(segment
		(start 222.099632 -347.8022)
		(end 221.86773 -348.034102)
		(width 0.508)
		(layer "F.Cu")
		(net "GND")
	)
	(segment
		(start 327.375012 -59.814968)
		(end 325.654924 -59.814968)
		(width 0.508)
		(layer "F.Cu")
		(net "GND")
	)
	(segment
		(start 31.59887 -252.151642)
		(end 31.59887 -253.128018)
		(width 0.508)
		(layer "F.Cu")
		(net "GND")
	)
	(segment
		(start 120.00484 -282.830016)
		(end 121.811796 -282.830016)
		(width 0.508)
		(layer "F.Cu")
		(net "GND")
	)
	(segment
		(start 325.550022 -151.035004)
		(end 327.432924 -151.035004)
		(width 0.508)
		(layer "F.Cu")
		(net "GND")
	)
	(segment
		(start 378.293122 -291.509196)
		(end 378.293122 -292.940232)
		(width 0.508)
		(layer "F.Cu")
		(net "GND")
	)
	(segment
		(start 30.025086 -297.435016)
		(end 28.304998 -297.435016)
		(width 0.508)
		(layer "F.Cu")
		(net "GND")
	)
	(segment
		(start 73.222612 -128.750568)
		(end 73.222612 -130.132074)
		(width 0.508)
		(layer "F.Cu")
		(net "GND")
	)
	(segment
		(start 61.574934 -184.974992)
		(end 59.854846 -184.974992)
		(width 0.508)
		(layer "F.Cu")
		(net "GND")
	)
	(segment
		(start 79.479648 -283.152342)
		(end 79.479648 -284.041342)
		(width 0.508)
		(layer "F.Cu")
		(net "GND")
	)
	(segment
		(start 448.846702 -256.40665)
		(end 448.846702 -257.48615)
		(width 0.508)
		(layer "F.Cu")
		(net "GND")
	)
	(segment
		(start 23.440898 -163.554918)
		(end 23.440898 -164.443918)
		(width 0.508)
		(layer "F.Cu")
		(net "GND")
	)
	(segment
		(start 458.3049 -157.141418)
		(end 458.3049 -156.315918)
		(width 0.508)
		(layer "F.Cu")
		(net "GND")
	)
	(segment
		(start 259.585714 -289.947604)
		(end 259.588 -289.94989)
		(width 0.508)
		(layer "F.Cu")
		(net "GND")
	)
	(segment
		(start 354.25507 -280.42997)
		(end 356.062026 -280.42997)
		(width 0.508)
		(layer "F.Cu")
		(net "GND")
	)
	(segment
		(start 483.300024 -151.035004)
		(end 485.182926 -151.035004)
		(width 0.508)
		(layer "F.Cu")
		(net "GND")
	)
	(segment
		(start 108.372402 -128.731772)
		(end 108.372402 -130.113278)
		(width 0.508)
		(layer "F.Cu")
		(net "GND")
	)
	(segment
		(start 253.8222 16.3576)
		(end 254.39116 15.78864)
		(width 0.381)
		(layer "F.Cu")
		(net "GND")
	)
	(segment
		(start 187.775088 -299.975016)
		(end 186.055 -299.975016)
		(width 0.508)
		(layer "F.Cu")
		(net "GND")
	)
	(segment
		(start 151.554942 -282.830016)
		(end 153.361898 -282.830016)
		(width 0.508)
		(layer "F.Cu")
		(net "GND")
	)
	(segment
		(start 417.35502 -282.830016)
		(end 419.161976 -282.830016)
		(width 0.508)
		(layer "F.Cu")
		(net "GND")
	)
	(segment
		(start 87.340948 -190.224918)
		(end 87.340948 -191.240918)
		(width 0.508)
		(layer "F.Cu")
		(net "GND")
	)
	(segment
		(start 422.025064 -182.434992)
		(end 420.304976 -182.434992)
		(width 0.508)
		(layer "F.Cu")
		(net "GND")
	)
	(segment
		(start 149.399752 -54.99608)
		(end 149.633686 -55.230014)
		(width 0.508)
		(layer "F.Cu")
		(net "GND")
	)
	(segment
		(start 143.002 -54.604666)
		(end 143.002 -55.2704)
		(width 0.508)
		(layer "F.Cu")
		(net "GND")
	)
	(segment
		(start 326.234044 -79.784956)
		(end 325.550022 -79.784956)
		(width 0.508)
		(layer "F.Cu")
		(net "GND")
	)
	(segment
		(start 338.38769 -130.376676)
		(end 338.38769 -131.377436)
		(width 0.508)
		(layer "F.Cu")
		(net "GND")
	)
	(segment
		(start 390.474962 -275.845016)
		(end 388.754874 -275.845016)
		(width 0.508)
		(layer "F.Cu")
		(net "GND")
	)
	(segment
		(start 473.752926 -59.603894)
		(end 473.752926 -61.000894)
		(width 0.508)
		(layer "F.Cu")
		(net "GND")
	)
	(segment
		(start 165.263576 -302.93056)
		(end 165.263576 -304.047652)
		(width 0.508)
		(layer "F.Cu")
		(net "GND")
	)
	(segment
		(start 102.13975 -184.089802)
		(end 102.13975 -182.997602)
		(width 0.508)
		(layer "F.Cu")
		(net "GND")
	)
	(segment
		(start 259.9182 11.2268)
		(end 259.50164 11.64336)
		(width 0.381)
		(layer "F.Cu")
		(net "GND")
	)
	(segment
		(start 363.020102 -189.920118)
		(end 363.020102 -191.113918)
		(width 0.508)
		(layer "F.Cu")
		(net "GND")
	)
	(segment
		(start 453.574912 -160.844992)
		(end 451.854824 -160.844992)
		(width 0.508)
		(layer "F.Cu")
		(net "GND")
	)
	(segment
		(start 454.243694 -245.027704)
		(end 454.243694 -243.675154)
		(width 0.508)
		(layer "F.Cu")
		(net "GND")
	)
	(segment
		(start 181.991 -190.224918)
		(end 181.991 -191.240918)
		(width 0.508)
		(layer "F.Cu")
		(net "GND")
	)
	(segment
		(start 381.986028 -136.9314)
		(end 383.0066 -136.9314)
		(width 0.508)
		(layer "F.Cu")
		(net "GND")
	)
	(segment
		(start 260.874002 -217.132662)
		(end 260.874002 -216.078562)
		(width 0.508)
		(layer "F.Cu")
		(net "GND")
	)
	(segment
		(start 82.880708 -277.615142)
		(end 82.133948 -277.615142)
		(width 0.4064)
		(layer "F.Cu")
		(net "GND")
	)
	(segment
		(start 246.815102 31.074868)
		(end 246.815102 29.35478)
		(width 0.508)
		(layer "F.Cu")
		(net "GND")
	)
	(segment
		(start 86.540848 -163.580318)
		(end 86.540848 -164.469318)
		(width 0.508)
		(layer "F.Cu")
		(net "GND")
	)
	(segment
		(start 156.224986 -157.034992)
		(end 154.504898 -157.034992)
		(width 0.508)
		(layer "F.Cu")
		(net "GND")
	)
	(segment
		(start 86.540848 -48.554894)
		(end 86.540848 -49.443894)
		(width 0.508)
		(layer "F.Cu")
		(net "GND")
	)
	(segment
		(start 427.694852 -159.602678)
		(end 427.694852 -158.855918)
		(width 0.4064)
		(layer "F.Cu")
		(net "GND")
	)
	(segment
		(start 323.847968 -67.434968)
		(end 323.3928 -66.9798)
		(width 0.508)
		(layer "F.Cu")
		(net "GND")
	)
	(segment
		(start 274.955 -271.8435)
		(end 274.955 -271.0434)
		(width 0.508)
		(layer "F.Cu")
		(net "GND")
	)
	(segment
		(start 84.181188 -49.494694)
		(end 85.105748 -49.494694)
		(width 0.4064)
		(layer "F.Cu")
		(net "GND")
	)
	(segment
		(start 265.80211 -141.491462)
		(end 265.80211 -142.21206)
		(width 0.508)
		(layer "F.Cu")
		(net "GND")
	)
	(segment
		(start 388.649972 -309.785004)
		(end 390.621266 -309.785004)
		(width 0.508)
		(layer "F.Cu")
		(net "GND")
	)
	(segment
		(start 448.904868 -280.42997)
		(end 450.711824 -280.42997)
		(width 0.508)
		(layer "F.Cu")
		(net "GND")
	)
	(segment
		(start 334.222852 -49.041812)
		(end 334.222852 -47.956216)
		(width 0.508)
		(layer "F.Cu")
		(net "GND")
	)
	(segment
		(start 30.025086 -279.655016)
		(end 28.304998 -279.655016)
		(width 0.508)
		(layer "F.Cu")
		(net "GND")
	)
	(segment
		(start 315.93028 -292.954456)
		(end 316.779656 -292.954456)
		(width 0.508)
		(layer "F.Cu")
		(net "GND")
	)
	(segment
		(start 181.991 -75.224894)
		(end 181.991 -76.240894)
		(width 0.508)
		(layer "F.Cu")
		(net "GND")
	)
	(segment
		(start 322.704968 -280.42997)
		(end 324.511924 -280.42997)
		(width 0.508)
		(layer "F.Cu")
		(net "GND")
	)
	(segment
		(start 176.988724 -47.615094)
		(end 177.53076 -47.615094)
		(width 0.4064)
		(layer "F.Cu")
		(net "GND")
	)
	(segment
		(start 144.852898 -174.603918)
		(end 144.852898 -176.000918)
		(width 0.508)
		(layer "F.Cu")
		(net "GND")
	)
	(segment
		(start 459.2447 -44.602654)
		(end 459.2447 -43.855894)
		(width 0.4064)
		(layer "F.Cu")
		(net "GND")
	)
	(segment
		(start 269.964916 -20.18411)
		(end 269.964916 -21.192236)
		(width 0.508)
		(layer "F.Cu")
		(net "GND")
	)
	(segment
		(start 102.140766 -187.879482)
		(end 102.140766 -189.103762)
		(width 0.508)
		(layer "F.Cu")
		(net "GND")
	)
	(segment
		(start 108.400596 -64.683894)
		(end 107.2642 -64.683894)
		(width 0.508)
		(layer "F.Cu")
		(net "GND")
	)
	(segment
		(start 393.93495 -67.604894)
		(end 392.91895 -67.604894)
		(width 0.508)
		(layer "F.Cu")
		(net "GND")
	)
	(segment
		(start 129.794 -130.269996)
		(end 129.794 -131.156456)
		(width 0.508)
		(layer "F.Cu")
		(net "GND")
	)
	(segment
		(start 385.804918 -165.429946)
		(end 387.611874 -165.429946)
		(width 0.508)
		(layer "F.Cu")
		(net "GND")
	)
	(segment
		(start 395.20495 -42.141394)
		(end 395.20495 -41.315894)
		(width 0.508)
		(layer "F.Cu")
		(net "GND")
	)
	(segment
		(start 161.880804 -187.024264)
		(end 161.880804 -185.981848)
		(width 0.508)
		(layer "F.Cu")
		(net "GND")
	)
	(segment
		(start 427.009052 -182.223918)
		(end 428.406052 -182.223918)
		(width 0.508)
		(layer "F.Cu")
		(net "GND")
	)
	(segment
		(start 88.454992 -170.230038)
		(end 90.261948 -170.230038)
		(width 0.508)
		(layer "F.Cu")
		(net "GND")
	)
	(segment
		(start 128.7145 -42.034968)
		(end 124.674884 -42.034968)
		(width 0.508)
		(layer "F.Cu")
		(net "GND")
	)
	(segment
		(start 316.779656 -292.954456)
		(end 317.3984 -293.5732)
		(width 0.508)
		(layer "F.Cu")
		(net "GND")
	)
	(segment
		(start 300.51121 -66.0908)
		(end 300.37786 -65.95745)
		(width 0.3048)
		(layer "F.Cu")
		(net "GND")
	)
	(segment
		(start 222.172022 -117.98427)
		(end 221.590362 -117.98427)
		(width 0.508)
		(layer "F.Cu")
		(net "GND")
	)
	(segment
		(start 120.00484 -167.829992)
		(end 121.811796 -167.829992)
		(width 0.508)
		(layer "F.Cu")
		(net "GND")
	)
	(segment
		(start 378.230384 -286.217614)
		(end 378.230384 -287.389824)
		(width 0.508)
		(layer "F.Cu")
		(net "GND")
	)
	(segment
		(start 376.412252 -128.65608)
		(end 376.412252 -130.192272)
		(width 0.508)
		(layer "F.Cu")
		(net "GND")
	)
	(segment
		(start 459.3844 -164.596318)
		(end 460.3369 -164.596318)
		(width 0.508)
		(layer "F.Cu")
		(net "GND")
	)
	(segment
		(start 93.125036 -59.814968)
		(end 91.404948 -59.814968)
		(width 0.508)
		(layer "F.Cu")
		(net "GND")
	)
	(segment
		(start 187.775088 -164.654992)
		(end 186.055 -164.654992)
		(width 0.508)
		(layer "F.Cu")
		(net "GND")
	)
	(segment
		(start 156.224986 -174.814992)
		(end 154.504898 -174.814992)
		(width 0.508)
		(layer "F.Cu")
		(net "GND")
	)
	(segment
		(start 177.58156 -162.996118)
		(end 176.784 -162.996118)
		(width 0.4064)
		(layer "F.Cu")
		(net "GND")
	)
	(segment
		(start 453.574912 -272.035016)
		(end 451.854824 -272.035016)
		(width 0.508)
		(layer "F.Cu")
		(net "GND")
	)
	(segment
		(start 178.83124 -49.494694)
		(end 179.7558 -49.494694)
		(width 0.4064)
		(layer "F.Cu")
		(net "GND")
	)
	(segment
		(start 102.143052 -182.997602)
		(end 102.143052 -182.984902)
		(width 0.508)
		(layer "F.Cu")
		(net "GND")
	)
	(segment
		(start 325.700898 -61.846206)
		(end 326.20966 -62.354968)
		(width 0.508)
		(layer "F.Cu")
		(net "GND")
	)
	(segment
		(start 424.469052 -67.604894)
		(end 425.249848 -67.604894)
		(width 0.508)
		(layer "F.Cu")
		(net "GND")
	)
	(segment
		(start 277.33244 16.90116)
		(end 277.33244 17.788128)
		(width 0.381)
		(layer "F.Cu")
		(net "GND")
	)
	(segment
		(start 91.091512 -297.435016)
		(end 93.125036 -297.435016)
		(width 0.508)
		(layer "F.Cu")
		(net "GND")
	)
	(segment
		(start 354.25507 -52.829968)
		(end 356.062026 -52.829968)
		(width 0.508)
		(layer "F.Cu")
		(net "GND")
	)
	(segment
		(start 190.9445 -173.1772)
		(end 190.9445 -174.0662)
		(width 0.508)
		(layer "F.Cu")
		(net "GND")
	)
	(segment
		(start 99.342448 -176.127918)
		(end 99.342448 -175.238918)
		(width 0.508)
		(layer "F.Cu")
		(net "GND")
	)
	(segment
		(start 39.207948 -294.191182)
		(end 39.207948 -295.07815)
		(width 0.508)
		(layer "F.Cu")
		(net "GND")
	)
	(segment
		(start 441.12815 -285.355284)
		(end 441.128912 -285.356046)
		(width 0.508)
		(layer "F.Cu")
		(net "GND")
	)
	(segment
		(start 362.715302 -160.903158)
		(end 362.715302 -161.649918)
		(width 0.4064)
		(layer "F.Cu")
		(net "GND")
	)
	(segment
		(start 448.904868 -170.230038)
		(end 450.711824 -170.230038)
		(width 0.508)
		(layer "F.Cu")
		(net "GND")
	)
	(segment
		(start 263.76884 -234.0356)
		(end 265.34872 -234.0356)
		(width 0.3556)
		(layer "F.Cu")
		(net "GND")
	)
	(segment
		(start 255.5621 13.352272)
		(end 255.69164 13.352272)
		(width 0.381)
		(layer "F.Cu")
		(net "GND")
	)
	(segment
		(start 93.125036 -160.844992)
		(end 91.404948 -160.844992)
		(width 0.508)
		(layer "F.Cu")
		(net "GND")
	)
	(segment
		(start 459.731872 -189.965076)
		(end 459.731872 -191.158876)
		(width 0.508)
		(layer "F.Cu")
		(net "GND")
	)
	(segment
		(start 322.704968 -170.230038)
		(end 324.511924 -170.230038)
		(width 0.508)
		(layer "F.Cu")
		(net "GND")
	)
	(segment
		(start 11.203178 -130.306064)
		(end 11.203178 -131.192524)
		(width 0.508)
		(layer "F.Cu")
		(net "GND")
	)
	(segment
		(start 385.804918 -52.829968)
		(end 387.611874 -52.829968)
		(width 0.508)
		(layer "F.Cu")
		(net "GND")
	)
	(segment
		(start 144.852898 -59.603894)
		(end 144.852898 -61.000894)
		(width 0.508)
		(layer "F.Cu")
		(net "GND")
	)
	(segment
		(start 327.375012 -67.434968)
		(end 323.847968 -67.434968)
		(width 0.508)
		(layer "F.Cu")
		(net "GND")
	)
	(segment
		(start 456.0189 -75.097894)
		(end 456.0189 -76.113894)
		(width 0.508)
		(layer "F.Cu")
		(net "GND")
	)
	(segment
		(start 241.760502 -379.837696)
		(end 241.76101 -379.837696)
		(width 0.508)
		(layer "F.Cu")
		(net "GND")
	)
	(segment
		(start 388.825486 -289.815016)
		(end 390.474962 -289.815016)
		(width 0.508)
		(layer "F.Cu")
		(net "GND")
	)
	(segment
		(start 120.00484 -165.429946)
		(end 121.811796 -165.429946)
		(width 0.508)
		(layer "F.Cu")
		(net "GND")
	)
	(segment
		(start 183.105044 -52.829968)
		(end 184.912 -52.829968)
		(width 0.508)
		(layer "F.Cu")
		(net "GND")
	)
	(segment
		(start 124.674884 -292.355016)
		(end 122.954796 -292.355016)
		(width 0.508)
		(layer "F.Cu")
		(net "GND")
	)
	(segment
		(start 87.340948 -75.224894)
		(end 87.340948 -76.240894)
		(width 0.508)
		(layer "F.Cu")
		(net "GND")
	)
	(segment
		(start 70.604888 -187.89777)
		(end 70.604888 -189.12205)
		(width 0.508)
		(layer "F.Cu")
		(net "GND")
	)
	(segment
		(start 76.850748 -179.683918)
		(end 75.656948 -179.683918)
		(width 0.508)
		(layer "F.Cu")
		(net "GND")
	)
	(segment
		(start 46.377352 -130.271012)
		(end 46.377352 -131.145026)
		(width 0.508)
		(layer "F.Cu")
		(net "GND")
	)
	(segment
		(start 332.359 -182.223918)
		(end 333.756 -182.223918)
		(width 0.508)
		(layer "F.Cu")
		(net "GND")
	)
	(segment
		(start 362.385102 -297.604942)
		(end 361.369102 -297.604942)
		(width 0.508)
		(layer "F.Cu")
		(net "GND")
	)
	(segment
		(start 124.674884 -69.974968)
		(end 122.954796 -69.974968)
		(width 0.508)
		(layer "F.Cu")
		(net "GND")
	)
	(segment
		(start 444.0174 -291.127942)
		(end 444.0174 -290.238942)
		(width 0.508)
		(layer "F.Cu")
		(net "GND")
	)
	(segment
		(start 222.746824 -347.8022)
		(end 222.099632 -347.8022)
		(width 0.508)
		(layer "F.Cu")
		(net "GND")
	)
	(segment
		(start 424.469052 -75.097894)
		(end 424.469052 -76.113894)
		(width 0.508)
		(layer "F.Cu")
		(net "GND")
	)
	(segment
		(start 48.707802 -148.64715)
		(end 48.771302 -148.71065)
		(width 0.508)
		(layer "F.Cu")
		(net "GND")
	)
	(segment
		(start 255.0922 -289.050476)
		(end 255.090676 -289.048952)
		(width 0.508)
		(layer "F.Cu")
		(net "GND")
	)
	(segment
		(start 324.511924 -55.230014)
		(end 322.704968 -55.230014)
		(width 0.508)
		(layer "F.Cu")
		(net "GND")
	)
	(segment
		(start 187.775088 -69.974968)
		(end 186.055 -69.974968)
		(width 0.508)
		(layer "F.Cu")
		(net "GND")
	)
	(segment
		(start 426.120052 -74.920094)
		(end 426.120052 -76.113894)
		(width 0.508)
		(layer "F.Cu")
		(net "GND")
	)
	(segment
		(start 417.35502 -285.230062)
		(end 419.161976 -285.230062)
		(width 0.508)
		(layer "F.Cu")
		(net "GND")
	)
	(segment
		(start 341.976202 -131.210812)
		(end 341.976202 -130.386836)
		(width 0.508)
		(layer "F.Cu")
		(net "GND")
	)
	(segment
		(start 357.100124 -309.785004)
		(end 358.983026 -309.785004)
		(width 0.508)
		(layer "F.Cu")
		(net "GND")
	)
	(segment
		(start 479.036126 -70.322694)
		(end 477.766126 -70.322694)
		(width 0.508)
		(layer "F.Cu")
		(net "GND")
	)
	(segment
		(start 358.925114 -67.434968)
		(end 357.205026 -67.434968)
		(width 0.508)
		(layer "F.Cu")
		(net "GND")
	)
	(segment
		(start 270.667734 20.568412)
		(end 270.667734 21.610828)
		(width 0.508)
		(layer "F.Cu")
		(net "GND")
	)
	(segment
		(start 7.778242 -291.042344)
		(end 7.778242 -290.088828)
		(width 0.508)
		(layer "F.Cu")
		(net "GND")
	)
	(segment
		(start 25.355042 -280.42997)
		(end 27.161998 -280.42997)
		(width 0.508)
		(layer "F.Cu")
		(net "GND")
	)
	(segment
		(start 156.224986 -299.975016)
		(end 154.504898 -299.975016)
		(width 0.508)
		(layer "F.Cu")
		(net "GND")
	)
	(segment
		(start 18.652998 -174.603918)
		(end 18.652998 -176.000918)
		(width 0.508)
		(layer "F.Cu")
		(net "GND")
	)
	(segment
		(start 251.097542 -381.755396)
		(end 251.110496 -381.742442)
		(width 0.508)
		(layer "F.Cu")
		(net "GND")
	)
	(segment
		(start 390.474962 -174.814992)
		(end 388.754874 -174.814992)
		(width 0.508)
		(layer "F.Cu")
		(net "GND")
	)
	(segment
		(start 48.54067 -148.480018)
		(end 48.707802 -148.64715)
		(width 0.508)
		(layer "F.Cu")
		(net "GND")
	)
	(segment
		(start 213.722458 -385.7625)
		(end 213.211156 -386.273802)
		(width 0.508)
		(layer "F.Cu")
		(net "GND")
	)
	(segment
		(start 453.574912 -157.034992)
		(end 451.854824 -157.034992)
		(width 0.508)
		(layer "F.Cu")
		(net "GND")
	)
	(segment
		(start 419.706298 -70.445122)
		(end 420.176452 -69.974968)
		(width 0.508)
		(layer "F.Cu")
		(net "GND")
	)
	(segment
		(start 471.534998 -280.928064)
		(end 471.534998 -281.0256)
		(width 0.508)
		(layer "F.Cu")
		(net "GND")
	)
	(segment
		(start 331.1652 -160.903158)
		(end 331.1652 -161.649918)
		(width 0.4064)
		(layer "F.Cu")
		(net "GND")
	)
	(segment
		(start 471.005408 -292.934644)
		(end 470.035128 -292.934644)
		(width 0.508)
		(layer "F.Cu")
		(net "GND")
	)
	(segment
		(start 480.45497 -50.429922)
		(end 482.261926 -50.429922)
		(width 0.508)
		(layer "F.Cu")
		(net "GND")
	)
	(segment
		(start 456.67041 -182.604918)
		(end 457.028804 -182.246524)
		(width 0.508)
		(layer "F.Cu")
		(net "GND")
	)
	(segment
		(start 54.990746 -278.554942)
		(end 54.990746 -279.443942)
		(width 0.508)
		(layer "F.Cu")
		(net "GND")
	)
	(segment
		(start 275.960078 -396.682722)
		(end 276.876256 -396.682722)
		(width 0.508)
		(layer "F.Cu")
		(net "GND")
	)
	(segment
		(start 268.676882 18.901918)
		(end 268.676882 19.366738)
		(width 0.508)
		(layer "F.Cu")
		(net "GND")
	)
	(segment
		(start 413.307784 -290.333176)
		(end 413.308038 -290.333176)
		(width 0.508)
		(layer "F.Cu")
		(net "GND")
	)
	(segment
		(start 67.792346 -61.127894)
		(end 67.792346 -60.238894)
		(width 0.508)
		(layer "F.Cu")
		(net "GND")
	)
	(segment
		(start 170.223434 -27.043126)
		(end 170.523408 -27.3431)
		(width 0.381)
		(layer "F.Cu")
		(net "GND")
	)
	(segment
		(start 367.282476 -44.217844)
		(end 365.726218 -44.217844)
		(width 0.4064)
		(layer "F.Cu")
		(net "GND")
	)
	(segment
		(start 333.0448 -159.602678)
		(end 333.0448 -158.855918)
		(width 0.4064)
		(layer "F.Cu")
		(net "GND")
	)
	(segment
		(start 165.259004 -301.245778)
		(end 165.259004 -300.341538)
		(width 0.508)
		(layer "F.Cu")
		(net "GND")
	)
	(segment
		(start 31.766002 -253.29515)
		(end 31.829502 -253.35865)
		(width 0.508)
		(layer "F.Cu")
		(net "GND")
	)
	(segment
		(start 181.1909 -163.554918)
		(end 181.1909 -164.443918)
		(width 0.508)
		(layer "F.Cu")
		(net "GND")
	)
	(segment
		(start 238.264192 29.2608)
		(end 238.275114 29.249878)
		(width 0.508)
		(layer "F.Cu")
		(net "GND")
	)
	(segment
		(start 39.053262 -181.44617)
		(end 39.053262 -180.505862)
		(width 0.508)
		(layer "F.Cu")
		(net "GND")
	)
	(segment
		(start 417.35502 -55.230014)
		(end 419.161976 -55.230014)
		(width 0.508)
		(layer "F.Cu")
		(net "GND")
	)
	(segment
		(start 88.454992 -285.230062)
		(end 90.261948 -285.230062)
		(width 0.508)
		(layer "F.Cu")
		(net "GND")
	)
	(segment
		(start 39.084504 -302.951896)
		(end 39.084504 -304.100992)
		(width 0.508)
		(layer "F.Cu")
		(net "GND")
	)
	(segment
		(start 259.588 -290.957)
		(end 257.683 -292.862)
		(width 0.508)
		(layer "F.Cu")
		(net "GND")
	)
	(segment
		(start 240.578386 -347.719904)
		(end 240.578386 -346.795598)
		(width 0.508)
		(layer "F.Cu")
		(net "GND")
	)
	(segment
		(start 93.125036 -272.035016)
		(end 91.404948 -272.035016)
		(width 0.508)
		(layer "F.Cu")
		(net "GND")
	)
	(segment
		(start 236.869986 -346.337636)
		(end 236.869986 -345.474798)
		(width 0.508)
		(layer "F.Cu")
		(net "GND")
	)
	(segment
		(start 234.86618 -244.615208)
		(end 234.839002 -244.58803)
		(width 0.508)
		(layer "F.Cu")
		(net "GND")
	)
	(segment
		(start 227.67671 -385.201668)
		(end 228.864668 -385.201668)
		(width 0.381)
		(layer "F.Cu")
		(net "GND")
	)
	(segment
		(start 82.768948 -62.778894)
		(end 81.752948 -62.778894)
		(width 0.508)
		(layer "F.Cu")
		(net "GND")
	)
	(segment
		(start 234.963462 -262.573262)
		(end 235.527088 -263.136888)
		(width 0.508)
		(layer "F.Cu")
		(net "GND")
	)
	(segment
		(start 77.916786 -131.145026)
		(end 77.919834 -131.148074)
		(width 0.508)
		(layer "F.Cu")
		(net "GND")
	)
	(segment
		(start 31.59887 -253.128018)
		(end 31.766002 -253.29515)
		(width 0.508)
		(layer "F.Cu")
		(net "GND")
	)
	(segment
		(start 365.726218 -44.217844)
		(end 365.341408 -44.602654)
		(width 0.4064)
		(layer "F.Cu")
		(net "GND")
	)
	(segment
		(start 187.775088 -182.434992)
		(end 186.055 -182.434992)
		(width 0.508)
		(layer "F.Cu")
		(net "GND")
	)
	(segment
		(start 150.136098 -185.322718)
		(end 148.866098 -185.322718)
		(width 0.508)
		(layer "F.Cu")
		(net "GND")
	)
	(segment
		(start 114.318796 -62.778894)
		(end 113.302796 -62.778894)
		(width 0.508)
		(layer "F.Cu")
		(net "GND")
	)
	(segment
		(start 327.375012 -292.355016)
		(end 325.654924 -292.355016)
		(width 0.508)
		(layer "F.Cu")
		(net "GND")
	)
	(segment
		(start 422.025064 -157.034992)
		(end 420.304976 -157.034992)
		(width 0.508)
		(layer "F.Cu")
		(net "GND")
	)
	(segment
		(start 324.639432 -69.974968)
		(end 324.1548 -70.4596)
		(width 0.508)
		(layer "F.Cu")
		(net "GND")
	)
	(segment
		(start 91.300046 -151.035004)
		(end 93.182948 -151.035004)
		(width 0.508)
		(layer "F.Cu")
		(net "GND")
	)
	(segment
		(start 448.846702 -257.48615)
		(end 448.398138 -257.934714)
		(width 0.508)
		(layer "F.Cu")
		(net "GND")
	)
	(segment
		(start 329.819 -75.097894)
		(end 329.819 -76.9366)
		(width 0.508)
		(layer "F.Cu")
		(net "GND")
	)
	(segment
		(start 298.205398 -71.461122)
		(end 299.21581 -71.461122)
		(width 0.508)
		(layer "F.Cu")
		(net "GND")
	)
	(segment
		(start 133.663436 -183.061864)
		(end 133.663436 -183.049164)
		(width 0.508)
		(layer "F.Cu")
		(net "GND")
	)
	(segment
		(start 121.489724 -49.680622)
		(end 121.489724 -50.138076)
		(width 0.508)
		(layer "F.Cu")
		(net "GND")
	)
	(segment
		(start 417.35502 -165.429946)
		(end 419.161976 -165.429946)
		(width 0.508)
		(layer "F.Cu")
		(net "GND")
	)
	(segment
		(start 93.125036 -69.974968)
		(end 91.404948 -69.974968)
		(width 0.508)
		(layer "F.Cu")
		(net "GND")
	)
	(segment
		(start 108.400596 -179.683918)
		(end 107.206796 -179.683918)
		(width 0.508)
		(layer "F.Cu")
		(net "GND")
	)
	(segment
		(start 162.442398 -61.127894)
		(end 162.442398 -60.238894)
		(width 0.508)
		(layer "F.Cu")
		(net "GND")
	)
	(segment
		(start 262.003032 -342.897968)
		(end 261.874 -343.027)
		(width 0.508)
		(layer "F.Cu")
		(net "GND")
	)
	(segment
		(start 485.125014 -59.814968)
		(end 483.404926 -59.814968)
		(width 0.508)
		(layer "F.Cu")
		(net "GND")
	)
	(segment
		(start 185.9534 -50.386742)
		(end 186.685174 -49.654968)
		(width 0.508)
		(layer "F.Cu")
		(net "GND")
	)
	(segment
		(start 459.2447 -274.602702)
		(end 459.2447 -273.855942)
		(width 0.4064)
		(layer "F.Cu")
		(net "GND")
	)
	(segment
		(start 447.010536 -243.77396)
		(end 447.01206 -243.772436)
		(width 0.508)
		(layer "F.Cu")
		(net "GND")
	)
	(segment
		(start 118.090696 -163.554918)
		(end 118.090696 -164.443918)
		(width 0.508)
		(layer "F.Cu")
		(net "GND")
	)
	(segment
		(start 331.359002 -22.227032)
		(end 331.359002 -21.414486)
		(width 0.508)
		(layer "F.Cu")
		(net "GND")
	)
	(segment
		(start 128.199896 -283.101542)
		(end 128.199896 -283.990542)
		(width 0.508)
		(layer "F.Cu")
		(net "GND")
	)
	(segment
		(start 480.45497 -55.230014)
		(end 482.261926 -55.230014)
		(width 0.508)
		(layer "F.Cu")
		(net "GND")
	)
	(segment
		(start 358.970072 -37.099748)
		(end 357.905304 -36.03498)
		(width 0.508)
		(layer "F.Cu")
		(net "GND")
	)
	(segment
		(start 145.980658 -162.615118)
		(end 145.233898 -162.615118)
		(width 0.4064)
		(layer "F.Cu")
		(net "GND")
	)
	(segment
		(start 165.269672 -183.040782)
		(end 165.269672 -183.028082)
		(width 0.508)
		(layer "F.Cu")
		(net "GND")
	)
	(segment
		(start 156.201618 -34.233358)
		(end 155.909264 -34.233358)
		(width 0.508)
		(layer "F.Cu")
		(net "GND")
	)
	(segment
		(start 477.802194 -75.224894)
		(end 477.796352 -75.230736)
		(width 0.508)
		(layer "F.Cu")
		(net "GND")
	)
	(segment
		(start 61.574934 -45.844968)
		(end 59.854846 -45.844968)
		(width 0.508)
		(layer "F.Cu")
		(net "GND")
	)
	(segment
		(start 485.125014 -67.434968)
		(end 483.404926 -67.434968)
		(width 0.508)
		(layer "F.Cu")
		(net "GND")
	)
	(segment
		(start 239.649 -256.2733)
		(end 239.649 -256.075688)
		(width 0.508)
		(layer "F.Cu")
		(net "GND")
	)
	(segment
		(start 165.26637 -184.132982)
		(end 165.26637 -183.040782)
		(width 0.508)
		(layer "F.Cu")
		(net "GND")
	)
	(segment
		(start 168.213278 -27.043126)
		(end 169.200068 -27.043126)
		(width 0.508)
		(layer "F.Cu")
		(net "GND")
	)
	(segment
		(start 93.125036 -45.844968)
		(end 91.404948 -45.844968)
		(width 0.508)
		(layer "F.Cu")
		(net "GND")
	)
	(segment
		(start 158.599378 -131.070858)
		(end 158.600394 -131.071874)
		(width 0.508)
		(layer "F.Cu")
		(net "GND")
	)
	(segment
		(start 42.763694 -130.269996)
		(end 42.763694 -131.156456)
		(width 0.508)
		(layer "F.Cu")
		(net "GND")
	)
	(segment
		(start 74.303128 -130.269996)
		(end 74.303128 -131.156456)
		(width 0.508)
		(layer "F.Cu")
		(net "GND")
	)
	(segment
		(start 331.47 -189.920118)
		(end 331.47 -191.113918)
		(width 0.508)
		(layer "F.Cu")
		(net "GND")
	)
	(segment
		(start 16.379698 -283.152342)
		(end 16.379698 -284.015942)
		(width 0.508)
		(layer "F.Cu")
		(net "GND")
	)
	(segment
		(start 187.775088 -174.814992)
		(end 186.055 -174.814992)
		(width 0.508)
		(layer "F.Cu")
		(net "GND")
	)
	(segment
		(start 122.849894 -266.035028)
		(end 124.732796 -266.035028)
		(width 0.508)
		(layer "F.Cu")
		(net "GND")
	)
	(segment
		(start 448.398138 -257.934714)
		(end 447.983356 -257.934714)
		(width 0.508)
		(layer "F.Cu")
		(net "GND")
	)
	(segment
		(start 56.90489 -170.230038)
		(end 58.711846 -170.230038)
		(width 0.508)
		(layer "F.Cu")
		(net "GND")
	)
	(segment
		(start 150.440898 -190.224918)
		(end 150.440898 -191.240918)
		(width 0.508)
		(layer "F.Cu")
		(net "GND")
	)
	(segment
		(start 378.290582 -290.591748)
		(end 378.290582 -291.506656)
		(width 0.508)
		(layer "F.Cu")
		(net "GND")
	)
	(segment
		(start 50.202846 -290.873434)
		(end 50.202846 -291.000942)
		(width 0.508)
		(layer "F.Cu")
		(net "GND")
	)
	(segment
		(start 427.834552 -164.596318)
		(end 428.787052 -164.596318)
		(width 0.508)
		(layer "F.Cu")
		(net "GND")
	)
	(segment
		(start 422.025064 -49.654968)
		(end 420.304976 -49.654968)
		(width 0.508)
		(layer "F.Cu")
		(net "GND")
	)
	(segment
		(start 300.37786 -65.452752)
		(end 300.37786 -64.614552)
		(width 0.508)
		(layer "F.Cu")
		(net "GND")
	)
	(segment
		(start 124.674884 -272.035016)
		(end 122.954796 -272.035016)
		(width 0.508)
		(layer "F.Cu")
		(net "GND")
	)
	(segment
		(start 370.577618 -245.334282)
		(end 370.577618 -246.26189)
		(width 0.508)
		(layer "F.Cu")
		(net "GND")
	)
	(segment
		(start 422.025064 -59.814968)
		(end 420.304976 -59.814968)
		(width 0.508)
		(layer "F.Cu")
		(net "GND")
	)
	(segment
		(start 133.660134 -183.061864)
		(end 133.663436 -183.061864)
		(width 0.508)
		(layer "F.Cu")
		(net "GND")
	)
	(segment
		(start 117.124988 -49.494694)
		(end 117.60327 -49.494694)
		(width 0.508)
		(layer "F.Cu")
		(net "GND")
	)
	(segment
		(start 158.599378 -130.184398)
		(end 158.599378 -131.070858)
		(width 0.508)
		(layer "F.Cu")
		(net "GND")
	)
	(segment
		(start 312.341514 -291.73932)
		(end 312.34888 -291.746686)
		(width 0.508)
		(layer "F.Cu")
		(net "GND")
	)
	(segment
		(start 262.789162 -342.897968)
		(end 262.003032 -342.897968)
		(width 0.508)
		(layer "F.Cu")
		(net "GND")
	)
	(segment
		(start 105.837228 -130.260598)
		(end 105.837228 -131.147058)
		(width 0.508)
		(layer "F.Cu")
		(net "GND")
	)
	(segment
		(start 385.804918 -285.230062)
		(end 387.611874 -285.230062)
		(width 0.508)
		(layer "F.Cu")
		(net "GND")
	)
	(segment
		(start 318.3255 -61.127894)
		(end 317.5381 -61.127894)
		(width 0.508)
		(layer "F.Cu")
		(net "GND")
	)
	(segment
		(start 459.7019 -74.920094)
		(end 459.7019 -76.113894)
		(width 0.508)
		(layer "F.Cu")
		(net "GND")
	)
	(segment
		(start 381.6096 -139.9286)
		(end 381.6096 -140.7414)
		(width 0.508)
		(layer "F.Cu")
		(net "GND")
	)
	(segment
		(start 133.673342 -181.42712)
		(end 133.673342 -180.486812)
		(width 0.508)
		(layer "F.Cu")
		(net "GND")
	)
	(segment
		(start 363.909102 -297.223942)
		(end 365.306102 -297.223942)
		(width 0.508)
		(layer "F.Cu")
		(net "GND")
	)
	(segment
		(start 61.574934 -42.034968)
		(end 59.854846 -42.034968)
		(width 0.508)
		(layer "F.Cu")
		(net "GND")
	)
	(segment
		(start 402.111718 -130.398012)
		(end 402.109432 -130.400298)
		(width 0.508)
		(layer "F.Cu")
		(net "GND")
	)
	(segment
		(start 333.73441 -66.939414)
		(end 333.44993 -67.223894)
		(width 0.508)
		(layer "F.Cu")
		(net "GND")
	)
	(segment
		(start 380.07671 -139.9286)
		(end 379.9332 -139.78509)
		(width 0.254)
		(layer "F.Cu")
		(net "GND")
	)
	(segment
		(start 229.72776 -386.06476)
		(end 230.6193 -386.06476)
		(width 0.381)
		(layer "F.Cu")
		(net "GND")
	)
	(segment
		(start 133.673342 -180.486812)
		(end 133.674358 -180.486812)
		(width 0.508)
		(layer "F.Cu")
		(net "GND")
	)
	(segment
		(start 453.574912 -292.355016)
		(end 451.854824 -292.355016)
		(width 0.508)
		(layer "F.Cu")
		(net "GND")
	)
	(segment
		(start 31.380938 -254.886714)
		(end 30.966156 -254.886714)
		(width 0.508)
		(layer "F.Cu")
		(net "GND")
	)
	(segment
		(start 327.375012 -177.354992)
		(end 325.654924 -177.354992)
		(width 0.508)
		(layer "F.Cu")
		(net "GND")
	)
	(segment
		(start 13.750798 -294.683942)
		(end 12.556998 -294.683942)
		(width 0.508)
		(layer "F.Cu")
		(net "GND")
	)
	(segment
		(start 478.282 -47.383446)
		(end 478.841816 -46.82363)
		(width 0.508)
		(layer "F.Cu")
		(net "GND")
	)
	(segment
		(start 216.490042 -390.80186)
		(end 217.193368 -390.098534)
		(width 0.508)
		(layer "F.Cu")
		(net "GND")
	)
	(segment
		(start 422.025064 -184.974992)
		(end 420.304976 -184.974992)
		(width 0.508)
		(layer "F.Cu")
		(net "GND")
	)
	(segment
		(start 156.224986 -289.815016)
		(end 154.504898 -289.815016)
		(width 0.508)
		(layer "F.Cu")
		(net "GND")
	)
	(segment
		(start 346.637102 -291.356542)
		(end 346.637102 -292.918896)
		(width 0.508)
		(layer "F.Cu")
		(net "GND")
	)
	(segment
		(start 156.224986 -292.355016)
		(end 154.504898 -292.355016)
		(width 0.508)
		(layer "F.Cu")
		(net "GND")
	)
	(segment
		(start 82.811366 -18.50263)
		(end 81.92643 -18.50263)
		(width 0.508)
		(layer "F.Cu")
		(net "GND")
	)
	(segment
		(start 365.052102 -189.920118)
		(end 365.052102 -191.113918)
		(width 0.508)
		(layer "F.Cu")
		(net "GND")
	)
	(segment
		(start 281.269948 19.421348)
		(end 281.269948 18.420334)
		(width 0.381)
		(layer "F.Cu")
		(net "GND")
	)
	(segment
		(start 7.884922 -175.988726)
		(end 7.884922 -175.03521)
		(width 0.508)
		(layer "F.Cu")
		(net "GND")
	)
	(segment
		(start 364.734602 -49.596294)
		(end 365.06023 -49.596294)
		(width 0.508)
		(layer "F.Cu")
		(net "GND")
	)
	(segment
		(start 451.749922 -194.78498)
		(end 453.632824 -194.78498)
		(width 0.508)
		(layer "F.Cu")
		(net "GND")
	)
	(segment
		(start 485.125014 -157.034992)
		(end 483.404926 -157.034992)
		(width 0.508)
		(layer "F.Cu")
		(net "GND")
	)
	(segment
		(start 51.330606 -277.615142)
		(end 50.583846 -277.615142)
		(width 0.4064)
		(layer "F.Cu")
		(net "GND")
	)
	(segment
		(start 441.13323 -284.512258)
		(end 441.13323 -285.355284)
		(width 0.508)
		(layer "F.Cu")
		(net "GND")
	)
	(segment
		(start 165.408864 -295.668954)
		(end 165.408864 -296.959528)
		(width 0.508)
		(layer "F.Cu")
		(net "GND")
	)
	(segment
		(start 282.3464 -279.8191)
		(end 282.3464 -278.8412)
		(width 0.508)
		(layer "F.Cu")
		(net "GND")
	)
	(segment
		(start 422.025064 -174.814992)
		(end 420.304976 -174.814992)
		(width 0.508)
		(layer "F.Cu")
		(net "GND")
	)
	(segment
		(start 257.383788 -239.612678)
		(end 256.5273 -238.75619)
		(width 0.508)
		(layer "F.Cu")
		(net "GND")
	)
	(segment
		(start 334.980534 -20.086066)
		(end 335.0514 -20.0152)
		(width 0.508)
		(layer "F.Cu")
		(net "GND")
	)
	(segment
		(start 365.052102 -76.050902)
		(end 365.052102 -74.920094)
		(width 0.508)
		(layer "F.Cu")
		(net "GND")
	)
	(segment
		(start 453.574912 -67.434968)
		(end 451.854824 -67.434968)
		(width 0.508)
		(layer "F.Cu")
		(net "GND")
	)
	(segment
		(start 70.59422 -297.266868)
		(end 70.59422 -298.450254)
		(width 0.508)
		(layer "F.Cu")
		(net "GND")
	)
	(segment
		(start 457.6699 -74.920094)
		(end 457.6699 -76.113894)
		(width 0.508)
		(layer "F.Cu")
		(net "GND")
	)
	(segment
		(start 392.177778 -42.034968)
		(end 390.474962 -42.034968)
		(width 0.508)
		(layer "F.Cu")
		(net "GND")
	)
	(segment
		(start 268.816582 18.48358)
		(end 268.816582 18.762218)
		(width 0.508)
		(layer "F.Cu")
		(net "GND")
	)
	(segment
		(start 248.106438 -300.482762)
		(end 248.285 -300.3042)
		(width 0.508)
		(layer "F.Cu")
		(net "GND")
	)
	(segment
		(start 262.017002 -217.577162)
		(end 262.017002 -216.523062)
		(width 0.508)
		(layer "F.Cu")
		(net "GND")
	)
	(segment
		(start 88.454992 -165.429946)
		(end 90.261948 -165.429946)
		(width 0.508)
		(layer "F.Cu")
		(net "GND")
	)
	(segment
		(start 102.210362 -300.992794)
		(end 102.210362 -301.831248)
		(width 0.508)
		(layer "F.Cu")
		(net "GND")
	)
	(segment
		(start 327.375012 -45.844968)
		(end 325.654924 -45.844968)
		(width 0.508)
		(layer "F.Cu")
		(net "GND")
	)
	(segment
		(start 334.980534 -21.00707)
		(end 334.980534 -20.086066)
		(width 0.508)
		(layer "F.Cu")
		(net "GND")
	)
	(segment
		(start 213.211156 -386.273802)
		(end 213.743032 -386.805678)
		(width 0.3556)
		(layer "F.Cu")
		(net "GND")
	)
	(segment
		(start 185.950098 -309.785004)
		(end 187.833 -309.785004)
		(width 0.508)
		(layer "F.Cu")
		(net "GND")
	)
	(segment
		(start 473.235274 -287.809432)
		(end 473.849192 -287.195514)
		(width 0.508)
		(layer "F.Cu")
		(net "GND")
	)
	(segment
		(start 344.026998 -21.586952)
		(end 344.026998 -22.063202)
		(width 0.508)
		(layer "F.Cu")
		(net "GND")
	)
	(segment
		(start 243.713 -248.36755)
		(end 244.128036 -247.952514)
		(width 0.508)
		(layer "F.Cu")
		(net "GND")
	)
	(segment
		(start 176.84623 -28.635452)
		(end 177.160682 -28.321)
		(width 0.508)
		(layer "F.Cu")
		(net "GND")
	)
	(segment
		(start 124.674884 -174.814992)
		(end 122.954796 -174.814992)
		(width 0.508)
		(layer "F.Cu")
		(net "GND")
	)
	(segment
		(start 52.631086 -279.494742)
		(end 53.555646 -279.494742)
		(width 0.4064)
		(layer "F.Cu")
		(net "GND")
	)
	(segment
		(start 219.878402 -212.992462)
		(end 219.878402 -211.938362)
		(width 0.508)
		(layer "F.Cu")
		(net "GND")
	)
	(segment
		(start 378.233432 -283.957522)
		(end 378.233432 -284.905196)
		(width 0.508)
		(layer "F.Cu")
		(net "GND")
	)
	(segment
		(start 165.408864 -296.959528)
		(end 165.287706 -297.080686)
		(width 0.508)
		(layer "F.Cu")
		(net "GND")
	)
	(segment
		(start 132.329174 -128.74117)
		(end 132.329174 -130.122676)
		(width 0.508)
		(layer "F.Cu")
		(net "GND")
	)
	(segment
		(start 448.904868 -50.429922)
		(end 450.711824 -50.429922)
		(width 0.508)
		(layer "F.Cu")
		(net "GND")
	)
	(segment
		(start 396.14475 -44.602654)
		(end 396.14475 -43.855894)
		(width 0.4064)
		(layer "F.Cu")
		(net "GND")
	)
	(segment
		(start 47.853346 -282.060142)
		(end 47.853346 -282.923742)
		(width 0.508)
		(layer "F.Cu")
		(net "GND")
	)
	(segment
		(start 120.998742 -309.785004)
		(end 122.849894 -309.785004)
		(width 0.508)
		(layer "F.Cu")
		(net "GND")
	)
	(segment
		(start 154.399996 -194.78498)
		(end 156.282898 -194.78498)
		(width 0.508)
		(layer "F.Cu")
		(net "GND")
	)
	(segment
		(start 87.036148 -70.322694)
		(end 85.766148 -70.322694)
		(width 0.508)
		(layer "F.Cu")
		(net "GND")
	)
	(segment
		(start 356.8954 -42.164)
		(end 357.024432 -42.034968)
		(width 0.508)
		(layer "F.Cu")
		(net "GND")
	)
	(segment
		(start 327.375012 -299.975016)
		(end 325.654924 -299.975016)
		(width 0.508)
		(layer "F.Cu")
		(net "GND")
	)
	(segment
		(start 70.758304 -295.07815)
		(end 70.758558 -295.07815)
		(width 0.508)
		(layer "F.Cu")
		(net "GND")
	)
	(segment
		(start 144.852898 -289.603942)
		(end 144.852898 -291.000942)
		(width 0.508)
		(layer "F.Cu")
		(net "GND")
	)
	(segment
		(start 49.129442 -289.80003)
		(end 50.202846 -290.873434)
		(width 0.508)
		(layer "F.Cu")
		(net "GND")
	)
	(segment
		(start 10.122662 -128.761236)
		(end 10.122662 -130.142742)
		(width 0.508)
		(layer "F.Cu")
		(net "GND")
	)
	(segment
		(start 483.718616 -292.355016)
		(end 485.125014 -292.355016)
		(width 0.508)
		(layer "F.Cu")
		(net "GND")
	)
	(segment
		(start 59.749944 -36.03498)
		(end 61.632846 -36.03498)
		(width 0.508)
		(layer "F.Cu")
		(net "GND")
	)
	(segment
		(start 329.8698 -68.9102)
		(end 329.8698 -69.2912)
		(width 0.508)
		(layer "F.Cu")
		(net "GND")
	)
	(segment
		(start 483.300024 -266.035028)
		(end 485.182926 -266.035028)
		(width 0.508)
		(layer "F.Cu")
		(net "GND")
	)
	(segment
		(start 358.925114 -299.975016)
		(end 357.205026 -299.975016)
		(width 0.508)
		(layer "F.Cu")
		(net "GND")
	)
	(segment
		(start 405.70023 -130.408172)
		(end 405.695404 -130.403346)
		(width 0.508)
		(layer "F.Cu")
		(net "GND")
	)
	(segment
		(start 420.200074 -309.785004)
		(end 422.082976 -309.785004)
		(width 0.508)
		(layer "F.Cu")
		(net "GND")
	)
	(segment
		(start 316.778386 -60.060586)
		(end 316.62624 -59.90844)
		(width 0.381)
		(layer "F.Cu")
		(net "GND")
	)
	(segment
		(start 144.446498 -47.66564)
		(end 144.4498 -47.66564)
		(width 0.4064)
		(layer "F.Cu")
		(net "GND")
	)
	(segment
		(start 25.355042 -52.829968)
		(end 27.161998 -52.829968)
		(width 0.508)
		(layer "F.Cu")
		(net "GND")
	)
	(segment
		(start 135.029956 -137.548874)
		(end 135.173466 -137.692384)
		(width 0.254)
		(layer "F.Cu")
		(net "GND")
	)
	(segment
		(start 379.9078 -176.127918)
		(end 379.593348 -175.813466)
		(width 0.508)
		(layer "F.Cu")
		(net "GND")
	)
	(segment
		(start 330.835 -182.604918)
		(end 329.819 -182.604918)
		(width 0.508)
		(layer "F.Cu")
		(net "GND")
	)
	(segment
		(start 375.5898 -147.0914)
		(end 375.5898 -146.2659)
		(width 0.508)
		(layer "F.Cu")
		(net "GND")
	)
	(segment
		(start 227.550726 -236.936788)
		(end 227.69068 -237.076742)
		(width 0.3556)
		(layer "F.Cu")
		(net "GND")
	)
	(segment
		(start 472.9988 -174.4218)
		(end 473.752926 -175.175926)
		(width 0.508)
		(layer "F.Cu")
		(net "GND")
	)
	(segment
		(start 451.749922 -266.035028)
		(end 453.632824 -266.035028)
		(width 0.508)
		(layer "F.Cu")
		(net "GND")
	)
	(segment
		(start 453.574912 -164.654992)
		(end 451.854824 -164.654992)
		(width 0.508)
		(layer "F.Cu")
		(net "GND")
	)
	(segment
		(start 36.242498 -61.127894)
		(end 36.242498 -60.238894)
		(width 0.508)
		(layer "F.Cu")
		(net "GND")
	)
	(segment
		(start 70.63486 -302.951896)
		(end 70.63486 -304.106834)
		(width 0.508)
		(layer "F.Cu")
		(net "GND")
	)
	(segment
		(start 234.963462 -262.16229)
		(end 234.963462 -262.573262)
		(width 0.508)
		(layer "F.Cu")
		(net "GND")
	)
	(segment
		(start 56.90489 -282.830016)
		(end 58.711846 -282.830016)
		(width 0.508)
		(layer "F.Cu")
		(net "GND")
	)
	(segment
		(start 348.864174 -145.991326)
		(end 348.557088 -145.68424)
		(width 0.508)
		(layer "F.Cu")
		(net "GND")
	)
	(segment
		(start 338.565236 -33.994852)
		(end 338.565236 -34.978848)
		(width 0.508)
		(layer "F.Cu")
		(net "GND")
	)
	(segment
		(start 23.936198 -300.322742)
		(end 22.666198 -300.322742)
		(width 0.508)
		(layer "F.Cu")
		(net "GND")
	)
	(segment
		(start 327.406 -36.9316)
		(end 326.50938 -36.03498)
		(width 0.508)
		(layer "F.Cu")
		(net "GND")
	)
	(segment
		(start 30.025086 -62.354968)
		(end 28.304998 -62.354968)
		(width 0.508)
		(layer "F.Cu")
		(net "GND")
	)
	(segment
		(start 109.450886 -130.261614)
		(end 109.450886 -131.135628)
		(width 0.508)
		(layer "F.Cu")
		(net "GND")
	)
	(segment
		(start 232.859326 -262.176006)
		(end 232.859326 -262.210296)
		(width 0.508)
		(layer "F.Cu")
		(net "GND")
	)
	(segment
		(start 357.430832 -59.814968)
		(end 358.925114 -59.814968)
		(width 0.508)
		(layer "F.Cu")
		(net "GND")
	)
	(segment
		(start 282.796234 20.532852)
		(end 283.21 20.119086)
		(width 0.508)
		(layer "F.Cu")
		(net "GND")
	)
	(segment
		(start 171.5008 -179.683918)
		(end 170.307 -179.683918)
		(width 0.508)
		(layer "F.Cu")
		(net "GND")
	)
	(segment
		(start 59.749944 -309.785004)
		(end 61.632846 -309.785004)
		(width 0.508)
		(layer "F.Cu")
		(net "GND")
	)
	(segment
		(start 324.308724 -50.429922)
		(end 322.704968 -50.429922)
		(width 0.508)
		(layer "F.Cu")
		(net "GND")
	)
	(segment
		(start 471.536014 -280.928064)
		(end 471.534998 -280.928064)
		(width 0.508)
		(layer "F.Cu")
		(net "GND")
	)
	(segment
		(start 237.573312 -252.93828)
		(end 239.17656 -252.93828)
		(width 0.508)
		(layer "F.Cu")
		(net "GND")
	)
	(segment
		(start 453.574912 -49.654968)
		(end 451.854824 -49.654968)
		(width 0.508)
		(layer "F.Cu")
		(net "GND")
	)
	(segment
		(start 346.812616 -285.33471)
		(end 347.70949 -285.33471)
		(width 0.508)
		(layer "F.Cu")
		(net "GND")
	)
	(segment
		(start 232.859326 -262.210296)
		(end 232.777284 -262.292338)
		(width 0.508)
		(layer "F.Cu")
		(net "GND")
	)
	(segment
		(start 324.206362 -52.829968)
		(end 322.704968 -52.829968)
		(width 0.508)
		(layer "F.Cu")
		(net "GND")
	)
	(segment
		(start 185.950098 -79.473044)
		(end 185.950098 -79.784956)
		(width 0.508)
		(layer "F.Cu")
		(net "GND")
	)
	(segment
		(start 424.469052 -190.097918)
		(end 424.469052 -191.113918)
		(width 0.508)
		(layer "F.Cu")
		(net "GND")
	)
	(segment
		(start 232.430828 -389.763)
		(end 233.3752 -389.763)
		(width 0.508)
		(layer "F.Cu")
		(net "GND")
	)
	(segment
		(start 48.322738 -150.238714)
		(end 47.907956 -150.238714)
		(width 0.508)
		(layer "F.Cu")
		(net "GND")
	)
	(segment
		(start 176.403 -174.603918)
		(end 176.403 -176.000918)
		(width 0.508)
		(layer "F.Cu")
		(net "GND")
	)
	(segment
		(start 453.574912 -69.974968)
		(end 451.854824 -69.974968)
		(width 0.508)
		(layer "F.Cu")
		(net "GND")
	)
	(segment
		(start 92.751148 -20.62988)
		(end 92.751148 -19.743674)
		(width 0.508)
		(layer "F.Cu")
		(net "GND")
	)
	(segment
		(start 258.318 -279.146)
		(end 258.318 -277.8633)
		(width 0.508)
		(layer "F.Cu")
		(net "GND")
	)
	(segment
		(start 327.375012 -69.974968)
		(end 324.639432 -69.974968)
		(width 0.508)
		(layer "F.Cu")
		(net "GND")
	)
	(segment
		(start 42.763694 -131.156456)
		(end 42.76471 -131.157472)
		(width 0.508)
		(layer "F.Cu")
		(net "GND")
	)
	(segment
		(start 133.697218 -301.413164)
		(end 133.697218 -300.510194)
		(width 0.508)
		(layer "F.Cu")
		(net "GND")
	)
	(segment
		(start 422.025064 -292.355016)
		(end 420.304976 -292.355016)
		(width 0.508)
		(layer "F.Cu")
		(net "GND")
	)
	(segment
		(start 390.474962 -177.354992)
		(end 388.754874 -177.354992)
		(width 0.508)
		(layer "F.Cu")
		(net "GND")
	)
	(segment
		(start 21.081238 -164.494718)
		(end 22.005798 -164.494718)
		(width 0.4064)
		(layer "F.Cu")
		(net "GND")
	)
	(segment
		(start 443.404244 -245.278656)
		(end 442.519054 -245.278656)
		(width 0.508)
		(layer "F.Cu")
		(net "GND")
	)
	(segment
		(start 349.367602 -291.127942)
		(end 349.367602 -290.238942)
		(width 0.508)
		(layer "F.Cu")
		(net "GND")
	)
	(segment
		(start 260.546596 -252.15596)
		(end 260.546596 -254.390652)
		(width 0.3556)
		(layer "F.Cu")
		(net "GND")
	)
	(segment
		(start 139.516866 -130.386074)
		(end 139.516866 -131.211574)
		(width 0.508)
		(layer "F.Cu")
		(net "GND")
	)
	(segment
		(start 156.224986 -164.654992)
		(end 154.504898 -164.654992)
		(width 0.508)
		(layer "F.Cu")
		(net "GND")
	)
	(segment
		(start 395.45895 -182.223918)
		(end 396.85595 -182.223918)
		(width 0.508)
		(layer "F.Cu")
		(net "GND")
	)
	(segment
		(start 333.502 -189.920118)
		(end 333.502 -191.113918)
		(width 0.508)
		(layer "F.Cu")
		(net "GND")
	)
	(segment
		(start 89.662254 -22.22881)
		(end 89.662254 -20.776946)
		(width 0.3048)
		(layer "F.Cu")
		(net "GND")
	)
	(segment
		(start 459.3844 -279.596342)
		(end 460.239872 -279.596342)
		(width 0.508)
		(layer "F.Cu")
		(net "GND")
	)
	(segment
		(start 364.734602 -164.596318)
		(end 365.661702 -164.596318)
		(width 0.508)
		(layer "F.Cu")
		(net "GND")
	)
	(segment
		(start 144.89938 -47.6504)
		(end 144.934686 -47.615094)
		(width 0.4064)
		(layer "F.Cu")
		(net "GND")
	)
	(segment
		(start 390.474962 -49.654968)
		(end 388.754874 -49.654968)
		(width 0.508)
		(layer "F.Cu")
		(net "GND")
	)
	(segment
		(start 480.45497 -165.429946)
		(end 482.261926 -165.429946)
		(width 0.508)
		(layer "F.Cu")
		(net "GND")
	)
	(segment
		(start 81.752948 -59.603894)
		(end 81.752948 -61.000894)
		(width 0.508)
		(layer "F.Cu")
		(net "GND")
	)
	(segment
		(start 257.683 -292.862)
		(end 257.683 -293.243)
		(width 0.508)
		(layer "F.Cu")
		(net "GND")
	)
	(segment
		(start 93.125036 -42.034968)
		(end 91.404948 -42.034968)
		(width 0.508)
		(layer "F.Cu")
		(net "GND")
	)
	(segment
		(start 181.1909 -278.554942)
		(end 181.1909 -279.443942)
		(width 0.508)
		(layer "F.Cu")
		(net "GND")
	)
	(segment
		(start 388.656068 -60.457334)
		(end 389.298434 -59.814968)
		(width 0.508)
		(layer "F.Cu")
		(net "GND")
	)
	(segment
		(start 46.377352 -131.145026)
		(end 46.3804 -131.148074)
		(width 0.508)
		(layer "F.Cu")
		(net "GND")
	)
	(segment
		(start 30.025086 -59.814968)
		(end 28.304998 -59.814968)
		(width 0.508)
		(layer "F.Cu")
		(net "GND")
	)
	(segment
		(start 441.128912 -285.356046)
		(end 441.128912 -286.49549)
		(width 0.508)
		(layer "F.Cu")
		(net "GND")
	)
	(segment
		(start 120.00484 -170.230038)
		(end 121.811796 -170.230038)
		(width 0.508)
		(layer "F.Cu")
		(net "GND")
	)
	(segment
		(start 101.466396 -296.891202)
		(end 101.466396 -296.363898)
		(width 0.508)
		(layer "F.Cu")
		(net "GND")
	)
	(segment
		(start 338.4804 -15.0368)
		(end 338.03717 -15.48003)
		(width 0.381)
		(layer "F.Cu")
		(net "GND")
	)
	(segment
		(start 13.750798 -64.683894)
		(end 12.556998 -64.683894)
		(width 0.508)
		(layer "F.Cu")
		(net "GND")
	)
	(segment
		(start 258.20116 15.33144)
		(end 258.20116 14.409928)
		(width 0.3048)
		(layer "F.Cu")
		(net "GND")
	)
	(segment
		(start 156.224986 -69.974968)
		(end 154.504898 -69.974968)
		(width 0.508)
		(layer "F.Cu")
		(net "GND")
	)
	(segment
		(start 310.25084 -60.478162)
		(end 309.858918 -60.870084)
		(width 0.508)
		(layer "F.Cu")
		(net "GND")
	)
	(segment
		(start 276.03196 20.25904)
		(end 276.03196 19.667728)
		(width 0.381)
		(layer "F.Cu")
		(net "GND")
	)
	(segment
		(start 425.485052 -182.604918)
		(end 424.469052 -182.604918)
		(width 0.508)
		(layer "F.Cu")
		(net "GND")
	)
	(segment
		(start 480.45497 -52.829968)
		(end 482.261926 -52.829968)
		(width 0.508)
		(layer "F.Cu")
		(net "GND")
	)
	(segment
		(start 468.763604 -130.371342)
		(end 468.763604 -128.709166)
		(width 0.508)
		(layer "F.Cu")
		(net "GND")
	)
	(segment
		(start 389.298434 -59.814968)
		(end 390.474962 -59.814968)
		(width 0.508)
		(layer "F.Cu")
		(net "GND")
	)
	(segment
		(start 395.45895 -67.223894)
		(end 396.85595 -67.223894)
		(width 0.508)
		(layer "F.Cu")
		(net "GND")
	)
	(segment
		(start 425.815252 -275.903182)
		(end 425.815252 -276.649942)
		(width 0.4064)
		(layer "F.Cu")
		(net "GND")
	)
	(segment
		(start 480.45497 -285.230062)
		(end 482.261926 -285.230062)
		(width 0.508)
		(layer "F.Cu")
		(net "GND")
	)
	(segment
		(start 358.925114 -157.034992)
		(end 357.205026 -157.034992)
		(width 0.508)
		(layer "F.Cu")
		(net "GND")
	)
	(segment
		(start 317.615824 -245.36019)
		(end 317.615824 -243.698014)
		(width 0.508)
		(layer "F.Cu")
		(net "GND")
	)
	(segment
		(start 349.565722 -145.991326)
		(end 348.864174 -145.991326)
		(width 0.508)
		(layer "F.Cu")
		(net "GND")
	)
	(segment
		(start 485.125014 -174.814992)
		(end 483.404926 -174.814992)
		(width 0.508)
		(layer "F.Cu")
		(net "GND")
	)
	(segment
		(start 183.105044 -282.830016)
		(end 184.912 -282.830016)
		(width 0.508)
		(layer "F.Cu")
		(net "GND")
	)
	(segment
		(start 422.025064 -160.844992)
		(end 420.304976 -160.844992)
		(width 0.508)
		(layer "F.Cu")
		(net "GND")
	)
	(segment
		(start 257.957828 16.8148)
		(end 257.957828 17.7292)
		(width 0.508)
		(layer "F.Cu")
		(net "GND")
	)
	(segment
		(start 150.440898 -305.224942)
		(end 150.440898 -306.240942)
		(width 0.508)
		(layer "F.Cu")
		(net "GND")
	)
	(segment
		(start 177.419 -292.778942)
		(end 175.95723 -292.778942)
		(width 0.508)
		(layer "F.Cu")
		(net "GND")
	)
	(segment
		(start 238.254286 -251.907802)
		(end 238.254286 -250.78182)
		(width 0.508)
		(layer "F.Cu")
		(net "GND")
	)
	(segment
		(start 361.369102 -75.097894)
		(end 361.369102 -77.143102)
		(width 0.508)
		(layer "F.Cu")
		(net "GND")
	)
	(segment
		(start 183.105044 -285.230062)
		(end 184.912 -285.230062)
		(width 0.508)
		(layer "F.Cu")
		(net "GND")
	)
	(segment
		(start 394.35405 -288.638742)
		(end 394.35405 -289.4838)
		(width 0.508)
		(layer "F.Cu")
		(net "GND")
	)
	(segment
		(start 176.564798 -48.03902)
		(end 176.988724 -47.615094)
		(width 0.4064)
		(layer "F.Cu")
		(net "GND")
	)
	(segment
		(start 392.91895 -305.097942)
		(end 392.91895 -306.026058)
		(width 0.508)
		(layer "F.Cu")
		(net "GND")
	)
	(segment
		(start 467.938104 -179.683918)
		(end 466.744304 -179.683918)
		(width 0.508)
		(layer "F.Cu")
		(net "GND")
	)
	(segment
		(start 326.20966 -62.354968)
		(end 327.375012 -62.354968)
		(width 0.508)
		(layer "F.Cu")
		(net "GND")
	)
	(segment
		(start 51.218846 -292.778942)
		(end 50.202846 -292.778942)
		(width 0.508)
		(layer "F.Cu")
		(net "GND")
	)
	(segment
		(start 417.35502 -50.429922)
		(end 419.161976 -50.429922)
		(width 0.508)
		(layer "F.Cu")
		(net "GND")
	)
	(segment
		(start 131.62153 -61.127894)
		(end 132.046472 -61.552836)
		(width 0.508)
		(layer "F.Cu")
		(net "GND")
	)
	(segment
		(start 437.31434 -130.34391)
		(end 437.309514 -130.339084)
		(width 0.508)
		(layer "F.Cu")
		(net "GND")
	)
	(segment
		(start 142.604998 -53.126894)
		(end 142.604998 -54.207664)
		(width 0.508)
		(layer "F.Cu")
		(net "GND")
	)
	(segment
		(start 19.668998 -292.778942)
		(end 18.652998 -292.778942)
		(width 0.508)
		(layer "F.Cu")
		(net "GND")
	)
	(segment
		(start 51.218846 -177.778918)
		(end 50.202846 -177.778918)
		(width 0.508)
		(layer "F.Cu")
		(net "GND")
	)
	(segment
		(start 121.489724 -50.138076)
		(end 121.197878 -50.429922)
		(width 0.508)
		(layer "F.Cu")
		(net "GND")
	)
	(segment
		(start 102.174294 -302.947324)
		(end 103.133398 -302.947324)
		(width 0.508)
		(layer "F.Cu")
		(net "GND")
	)
	(segment
		(start 327.375012 -174.814992)
		(end 325.654924 -174.814992)
		(width 0.508)
		(layer "F.Cu")
		(net "GND")
	)
	(segment
		(start 365.5822 -76.581)
		(end 365.052102 -76.050902)
		(width 0.508)
		(layer "F.Cu")
		(net "GND")
	)
	(segment
		(start 187.775088 -289.815016)
		(end 186.055 -289.815016)
		(width 0.508)
		(layer "F.Cu")
		(net "GND")
	)
	(segment
		(start 385.804918 -280.42997)
		(end 387.611874 -280.42997)
		(width 0.508)
		(layer "F.Cu")
		(net "GND")
	)
	(segment
		(start 317.502794 -130.419602)
		(end 317.497968 -130.414776)
		(width 0.508)
		(layer "F.Cu")
		(net "GND")
	)
	(segment
		(start 390.474962 -45.844968)
		(end 388.754874 -45.844968)
		(width 0.508)
		(layer "F.Cu")
		(net "GND")
	)
	(segment
		(start 153.743152 -49.654968)
		(end 153.547318 -49.850802)
		(width 0.508)
		(layer "F.Cu")
		(net "GND")
	)
	(segment
		(start 374.144032 -246.290084)
		(end 374.144032 -245.303802)
		(width 0.508)
		(layer "F.Cu")
		(net "GND")
	)
	(segment
		(start 448.783202 -256.34315)
		(end 448.846702 -256.40665)
		(width 0.508)
		(layer "F.Cu")
		(net "GND")
	)
	(segment
		(start 442.519054 -245.278656)
		(end 442.468254 -245.227856)
		(width 0.508)
		(layer "F.Cu")
		(net "GND")
	)
	(segment
		(start 346.827094 -287.44037)
		(end 346.827094 -288.5694)
		(width 0.508)
		(layer "F.Cu")
		(net "GND")
	)
	(segment
		(start 262.141462 9.78535)
		(end 262.141462 8.878062)
		(width 0.508)
		(layer "F.Cu")
		(net "GND")
	)
	(segment
		(start 275.3868 20.9042)
		(end 276.03196 20.25904)
		(width 0.381)
		(layer "F.Cu")
		(net "GND")
	)
	(segment
		(start 39.040054 -184.173114)
		(end 39.040054 -183.080914)
		(width 0.508)
		(layer "F.Cu")
		(net "GND")
	)
	(segment
		(start 453.574912 -174.814992)
		(end 451.854824 -174.814992)
		(width 0.508)
		(layer "F.Cu")
		(net "GND")
	)
	(segment
		(start 154.817826 -67.434968)
		(end 156.224986 -67.434968)
		(width 0.508)
		(layer "F.Cu")
		(net "GND")
	)
	(segment
		(start 220.6244 -376.62104)
		(end 220.6244 -375.659142)
		(width 0.508)
		(layer "F.Cu")
		(net "GND")
	)
	(segment
		(start 341.976202 -130.386836)
		(end 341.971376 -130.38201)
		(width 0.508)
		(layer "F.Cu")
		(net "GND")
	)
	(segment
		(start 156.224986 -275.845016)
		(end 154.504898 -275.845016)
		(width 0.508)
		(layer "F.Cu")
		(net "GND")
	)
	(segment
		(start 475.24162 -272.9992)
		(end 475.24162 -273.54276)
		(width 0.3556)
		(layer "F.Cu")
		(net "GND")
	)
	(segment
		(start 88.454992 -280.42997)
		(end 90.261948 -280.42997)
		(width 0.508)
		(layer "F.Cu")
		(net "GND")
	)
	(segment
		(start 48.54067 -147.503642)
		(end 48.54067 -148.480018)
		(width 0.508)
		(layer "F.Cu")
		(net "GND")
	)
	(segment
		(start 333.0448 -44.602654)
		(end 333.0448 -43.855894)
		(width 0.4064)
		(layer "F.Cu")
		(net "GND")
	)
	(segment
		(start 144.660366 -128.683258)
		(end 144.660366 -127.540258)
		(width 0.508)
		(layer "F.Cu")
		(net "GND")
	)
	(segment
		(start 82.768948 -292.778942)
		(end 81.752948 -292.778942)
		(width 0.508)
		(layer "F.Cu")
		(net "GND")
	)
	(segment
		(start 357.905304 -36.03498)
		(end 357.100124 -36.03498)
		(width 0.508)
		(layer "F.Cu")
		(net "GND")
	)
	(segment
		(start 420.200074 -194.78498)
		(end 422.082976 -194.78498)
		(width 0.508)
		(layer "F.Cu")
		(net "GND")
	)
	(segment
		(start 233.618786 -246.600472)
		(end 232.791 -245.772686)
		(width 0.508)
		(layer "F.Cu")
		(net "GND")
	)
	(segment
		(start 405.695404 -130.403346)
		(end 405.695404 -128.74117)
		(width 0.508)
		(layer "F.Cu")
		(net "GND")
	)
	(segment
		(start 380.94285 -60.11545)
		(end 380.7206 -59.8932)
		(width 0.508)
		(layer "F.Cu")
		(net "GND")
	)
	(segment
		(start 257.5941 -13.7668)
		(end 258.4704 -13.7668)
		(width 0.508)
		(layer "F.Cu")
		(net "GND")
	)
	(segment
		(start 427.694852 -274.602702)
		(end 427.694852 -273.855942)
		(width 0.4064)
		(layer "F.Cu")
		(net "GND")
	)
	(segment
		(start 124.674884 -157.034992)
		(end 122.954796 -157.034992)
		(width 0.508)
		(layer "F.Cu")
		(net "GND")
	)
	(segment
		(start 55.790846 -190.224918)
		(end 55.790846 -191.240918)
		(width 0.508)
		(layer "F.Cu")
		(net "GND")
	)
	(segment
		(start 380.94285 -61.102494)
		(end 380.94285 -60.11545)
		(width 0.508)
		(layer "F.Cu")
		(net "GND")
	)
	(segment
		(start 299.834808 -24.585676)
		(end 300.771814 -24.585676)
		(width 0.508)
		(layer "F.Cu")
		(net "GND")
	)
	(segment
		(start 181.6862 -300.322742)
		(end 180.4162 -300.322742)
		(width 0.508)
		(layer "F.Cu")
		(net "GND")
	)
	(segment
		(start 290.72332 -275.5646)
		(end 290.72332 -273.98472)
		(width 0.3556)
		(layer "F.Cu")
		(net "GND")
	)
	(segment
		(start 224.155 -386.808472)
		(end 224.7011 -386.262372)
		(width 0.508)
		(layer "F.Cu")
		(net "GND")
	)
	(segment
		(start 147.281138 -279.494742)
		(end 148.205698 -279.494742)
		(width 0.4064)
		(layer "F.Cu")
		(net "GND")
	)
	(segment
		(start 315.928756 -290.934902)
		(end 315.928756 -291.29355)
		(width 0.508)
		(layer "F.Cu")
		(net "GND")
	)
	(segment
		(start 184.803796 -36.03498)
		(end 185.950098 -36.03498)
		(width 0.508)
		(layer "F.Cu")
		(net "GND")
	)
	(segment
		(start 225.171 -364.6805)
		(end 225.171 -363.855)
		(width 0.508)
		(layer "F.Cu")
		(net "GND")
	)
	(via
		(at 1.397 -322.958968)
		(size 0.7112)
		(drill 0.4064)
		(layers "F.Cu" "B.Cu")
		(net "GND")
	)
	(via
		(at 1.397 -287.398968)
		(size 0.7112)
		(drill 0.4064)
		(layers "F.Cu" "B.Cu")
		(net "GND")
	)
	(via
		(at 426.664882 -347.802962)
		(size 0.7112)
		(drill 0.4064)
		(layers "F.Cu" "B.Cu")
		(net "GND")
	)
	(via
		(at 232.477056 37.403024)
		(size 0.7112)
		(drill 0.4064)
		(layers "F.Cu" "B.Cu")
		(net "GND")
	)
	(via
		(at 477.617282 -241.386614)
		(size 0.5588)
		(drill 0.3048)
		(layers "F.Cu" "B.Cu")
		(net "GND")
	)
	(via
		(at 312.341514 -291.73932)
		(size 0.5588)
		(drill 0.3048)
		(layers "F.Cu" "B.Cu")
		(net "GND")
	)
	(via
		(at 22.666198 -70.322694)
		(size 0.5588)
		(drill 0.3048)
		(layers "F.Cu" "B.Cu")
		(net "GND")
	)
	(via
		(at 490.053122 -247.361202)
		(size 0.7112)
		(drill 0.4064)
		(layers "F.Cu" "B.Cu")
		(net "GND")
	)
	(via
		(at 387.611874 -167.829992)
		(size 0.5588)
		(drill 0.3048)
		(layers "F.Cu" "B.Cu")
		(net "GND")
	)
	(via
		(at 376.412252 -130.192272)
		(size 0.5588)
		(drill 0.3048)
		(layers "F.Cu" "B.Cu")
		(net "GND")
	)
	(via
		(at 201.397108 -412.232856)
		(size 0.7112)
		(drill 0.4064)
		(layers "F.Cu" "B.Cu")
		(net "GND")
	)
	(via
		(at 473.752926 -59.603894)
		(size 0.5588)
		(drill 0.3048)
		(layers "F.Cu" "B.Cu")
		(net "GND")
	)
	(via
		(at 370.909596 -150.494492)
		(size 0.5588)
		(drill 0.3048)
		(layers "F.Cu" "B.Cu")
		(net "GND")
	)
	(via
		(at 221.651068 34.43605)
		(size 0.7112)
		(drill 0.4064)
		(layers "F.Cu" "B.Cu")
		(net "GND")
	)
	(via
		(at 298.874942 -375.397014)
		(size 0.7112)
		(drill 0.4064)
		(layers "F.Cu" "B.Cu")
		(net "GND")
	)
	(via
		(at 450.794882 -347.802962)
		(size 0.7112)
		(drill 0.4064)
		(layers "F.Cu" "B.Cu")
		(net "GND")
	)
	(via
		(at 25.4 -127)
		(size 0.5588)
		(drill 0.3048)
		(layers "F.Cu" "B.Cu")
		(net "GND")
	)
	(via
		(at 189.992 -198.882)
		(size 0.5588)
		(drill 0.3048)
		(layers "F.Cu" "B.Cu")
		(net "GND")
	)
	(via
		(at 1.397 -90.548968)
		(size 0.7112)
		(drill 0.4064)
		(layers "F.Cu" "B.Cu")
		(net "GND")
	)
	(via
		(at 314.041028 -1.397)
		(size 0.7112)
		(drill 0.4064)
		(layers "F.Cu" "B.Cu")
		(net "GND")
	)
	(via
		(at 397.65097 -9.275318)
		(size 0.7112)
		(drill 0.4064)
		(layers "F.Cu" "B.Cu")
		(net "GND")
	)
	(via
		(at 6.091682 -347.548962)
		(size 0.7112)
		(drill 0.4064)
		(layers "F.Cu" "B.Cu")
		(net "GND")
	)
	(via
		(at 160.528 -237.744)
		(size 0.5588)
		(drill 0.3048)
		(layers "F.Cu" "B.Cu")
		(net "GND")
	)
	(via
		(at 47.853346 -282.923742)
		(size 0.5588)
		(drill 0.3048)
		(layers "F.Cu" "B.Cu")
		(net "GND")
	)
	(via
		(at 249.32132 -236.900212)
		(size 0.5588)
		(drill 0.3048)
		(layers "F.Cu" "B.Cu")
		(net "GND")
	)
	(via
		(at 60.96 -127)
		(size 0.5588)
		(drill 0.3048)
		(layers "F.Cu" "B.Cu")
		(net "GND")
	)
	(via
		(at 269.964916 -21.192236)
		(size 0.5588)
		(drill 0.3048)
		(layers "F.Cu" "B.Cu")
		(net "GND")
	)
	(via
		(at 95.125032 -1.397)
		(size 0.7112)
		(drill 0.4064)
		(layers "F.Cu" "B.Cu")
		(net "GND")
	)
	(via
		(at 46.865032 -1.397)
		(size 0.7112)
		(drill 0.4064)
		(layers "F.Cu" "B.Cu")
		(net "GND")
	)
	(via
		(at 197.612 -251.079)
		(size 0.5588)
		(drill 0.3048)
		(layers "F.Cu" "B.Cu")
		(net "GND")
	)
	(via
		(at 227.397056 37.403024)
		(size 0.7112)
		(drill 0.4064)
		(layers "F.Cu" "B.Cu")
		(net "GND")
	)
	(via
		(at 247.717056 37.403024)
		(size 0.7112)
		(drill 0.4064)
		(layers "F.Cu" "B.Cu")
		(net "GND")
	)
	(via
		(at 69.182996 -347.802962)
		(size 0.7112)
		(drill 0.4064)
		(layers "F.Cu" "B.Cu")
		(net "GND")
	)
	(via
		(at 257.957828 17.7292)
		(size 0.5588)
		(drill 0.3048)
		(layers "F.Cu" "B.Cu")
		(net "GND")
	)
	(via
		(at 192.350898 -352.011742)
		(size 0.7112)
		(drill 0.4064)
		(layers "F.Cu" "B.Cu")
		(net "GND")
	)
	(via
		(at 490.053122 -234.06735)
		(size 0.7112)
		(drill 0.4064)
		(layers "F.Cu" "B.Cu")
		(net "GND")
	)
	(via
		(at 12.556998 -64.683894)
		(size 0.5588)
		(drill 0.3048)
		(layers "F.Cu" "B.Cu")
		(net "GND")
	)
	(via
		(at 304.741072 -17.619472)
		(size 0.5588)
		(drill 0.3048)
		(layers "F.Cu" "B.Cu")
		(net "GND")
	)
	(via
		(at 490.053122 -38.48735)
		(size 0.7112)
		(drill 0.4064)
		(layers "F.Cu" "B.Cu")
		(net "GND")
	)
	(via
		(at 102.235 -198.247)
		(size 0.5588)
		(drill 0.3048)
		(layers "F.Cu" "B.Cu")
		(net "GND")
	)
	(via
		(at 1.397 -169.288968)
		(size 0.7112)
		(drill 0.4064)
		(layers "F.Cu" "B.Cu")
		(net "GND")
	)
	(via
		(at 447.4464 -250.7488)
		(size 0.5588)
		(drill 0.3048)
		(layers "F.Cu" "B.Cu")
		(net "GND")
	)
	(via
		(at 430.474882 -347.802962)
		(size 0.7112)
		(drill 0.4064)
		(layers "F.Cu" "B.Cu")
		(net "GND")
	)
	(via
		(at 428.787052 -49.596294)
		(size 0.5588)
		(drill 0.3048)
		(layers "F.Cu" "B.Cu")
		(net "GND")
	)
	(via
		(at 156.282898 -266.035028)
		(size 0.5588)
		(drill 0.3048)
		(layers "F.Cu" "B.Cu")
		(net "GND")
	)
	(via
		(at 149.733 -250.952)
		(size 0.5588)
		(drill 0.3048)
		(layers "F.Cu" "B.Cu")
		(net "GND")
	)
	(via
		(at 219.964 -80.01)
		(size 0.5588)
		(drill 0.3048)
		(layers "F.Cu" "B.Cu")
		(net "GND")
	)
	(via
		(at 1.397 -159.128968)
		(size 0.7112)
		(drill 0.4064)
		(layers "F.Cu" "B.Cu")
		(net "GND")
	)
	(via
		(at 21.331682 -347.548962)
		(size 0.7112)
		(drill 0.4064)
		(layers "F.Cu" "B.Cu")
		(net "GND")
	)
	(via
		(at 1.397 -15.618968)
		(size 0.7112)
		(drill 0.4064)
		(layers "F.Cu" "B.Cu")
		(net "GND")
	)
	(via
		(at 153.453084 -1.397)
		(size 0.7112)
		(drill 0.4064)
		(layers "F.Cu" "B.Cu")
		(net "GND")
	)
	(via
		(at 470.336118 -45.48505)
		(size 0.5588)
		(drill 0.3048)
		(layers "F.Cu" "B.Cu")
		(net "GND")
	)
	(via
		(at 475.74962 -1.397)
		(size 0.7112)
		(drill 0.4064)
		(layers "F.Cu" "B.Cu")
		(net "GND")
	)
	(via
		(at 490.053122 -272.761202)
		(size 0.7112)
		(drill 0.4064)
		(layers "F.Cu" "B.Cu")
		(net "GND")
	)
	(via
		(at 362.458 -96.52)
		(size 0.5588)
		(drill 0.3048)
		(layers "F.Cu" "B.Cu")
		(net "GND")
	)
	(via
		(at 272.566892 -419.803072)
		(size 0.7112)
		(drill 0.4064)
		(layers "F.Cu" "B.Cu")
		(net "GND")
	)
	(via
		(at 1.397 -292.478968)
		(size 0.7112)
		(drill 0.4064)
		(layers "F.Cu" "B.Cu")
		(net "GND")
	)
	(via
		(at 490.053122 -46.10735)
		(size 0.7112)
		(drill 0.4064)
		(layers "F.Cu" "B.Cu")
		(net "GND")
	)
	(via
		(at 490.053122 -218.82735)
		(size 0.7112)
		(drill 0.4064)
		(layers "F.Cu" "B.Cu")
		(net "GND")
	)
	(via
		(at 1.397 -254.378968)
		(size 0.7112)
		(drill 0.4064)
		(layers "F.Cu" "B.Cu")
		(net "GND")
	)
	(via
		(at 6.35 -254)
		(size 0.5588)
		(drill 0.3048)
		(layers "F.Cu" "B.Cu")
		(net "GND")
	)
	(via
		(at 81.155032 -1.397)
		(size 0.7112)
		(drill 0.4064)
		(layers "F.Cu" "B.Cu")
		(net "GND")
	)
	(via
		(at 57.15 -207.01)
		(size 0.5588)
		(drill 0.3048)
		(layers "F.Cu" "B.Cu")
		(net "GND")
	)
	(via
		(at 478.8662 -161.7472)
		(size 0.5588)
		(drill 0.3048)
		(layers "F.Cu" "B.Cu")
		(net "GND")
	)
	(via
		(at 1.397 -315.338968)
		(size 0.7112)
		(drill 0.4064)
		(layers "F.Cu" "B.Cu")
		(net "GND")
	)
	(via
		(at 473.752926 -62.778894)
		(size 0.5588)
		(drill 0.3048)
		(layers "F.Cu" "B.Cu")
		(net "GND")
	)
	(via
		(at 482.261926 -282.830016)
		(size 0.5588)
		(drill 0.3048)
		(layers "F.Cu" "B.Cu")
		(net "GND")
	)
	(via
		(at 445.262 -330.708)
		(size 0.5588)
		(drill 0.3048)
		(layers "F.Cu" "B.Cu")
		(net "GND")
	)
	(via
		(at 258.4704 -13.7668)
		(size 0.5588)
		(drill 0.3048)
		(layers "F.Cu" "B.Cu")
		(net "GND")
	)
	(via
		(at 110.231682 -347.548962)
		(size 0.7112)
		(drill 0.4064)
		(layers "F.Cu" "B.Cu")
		(net "GND")
	)
	(via
		(at 118.11 -124.714)
		(size 0.5588)
		(drill 0.3048)
		(layers "F.Cu" "B.Cu")
		(net "GND")
	)
	(via
		(at 233.747056 37.403024)
		(size 0.7112)
		(drill 0.4064)
		(layers "F.Cu" "B.Cu")
		(net "GND")
	)
	(via
		(at 30.48 -20.32)
		(size 0.5588)
		(drill 0.3048)
		(layers "F.Cu" "B.Cu")
		(net "GND")
	)
	(via
		(at 1.397 -23.238968)
		(size 0.7112)
		(drill 0.4064)
		(layers "F.Cu" "B.Cu")
		(net "GND")
	)
	(via
		(at 58.711846 -280.42997)
		(size 0.5588)
		(drill 0.3048)
		(layers "F.Cu" "B.Cu")
		(net "GND")
	)
	(via
		(at 474.924882 -347.802962)
		(size 0.7112)
		(drill 0.4064)
		(layers "F.Cu" "B.Cu")
		(net "GND")
	)
	(via
		(at 218.092528 -101.3968)
		(size 0.5588)
		(drill 0.3048)
		(layers "F.Cu" "B.Cu")
		(net "GND")
	)
	(via
		(at 459.7019 -306.113942)
		(size 0.5588)
		(drill 0.3048)
		(layers "F.Cu" "B.Cu")
		(net "GND")
	)
	(via
		(at 457.2 -25.4)
		(size 0.5588)
		(drill 0.3048)
		(layers "F.Cu" "B.Cu")
		(net "GND")
	)
	(via
		(at 257.483102 -247.561354)
		(size 0.5588)
		(drill 0.3048)
		(layers "F.Cu" "B.Cu")
		(net "GND")
	)
	(via
		(at 58.42 -335.28)
		(size 0.5588)
		(drill 0.3048)
		(layers "F.Cu" "B.Cu")
		(net "GND")
	)
	(via
		(at 294.302942 -363.745018)
		(size 0.7112)
		(drill 0.4064)
		(layers "F.Cu" "B.Cu")
		(net "GND")
	)
	(via
		(at 352.298 -315.849)
		(size 0.5588)
		(drill 0.3048)
		(layers "F.Cu" "B.Cu")
		(net "GND")
	)
	(via
		(at 490.053122 -252.441202)
		(size 0.7112)
		(drill 0.4064)
		(layers "F.Cu" "B.Cu")
		(net "GND")
	)
	(via
		(at 72.517 -48.133)
		(size 0.5588)
		(drill 0.3048)
		(layers "F.Cu" "B.Cu")
		(net "GND")
	)
	(via
		(at 180.4162 -300.322742)
		(size 0.5588)
		(drill 0.3048)
		(layers "F.Cu" "B.Cu")
		(net "GND")
	)
	(via
		(at 490.053122 -128.65735)
		(size 0.7112)
		(drill 0.4064)
		(layers "F.Cu" "B.Cu")
		(net "GND")
	)
	(via
		(at 189.992 -93.599)
		(size 0.5588)
		(drill 0.3048)
		(layers "F.Cu" "B.Cu")
		(net "GND")
	)
	(via
		(at 149.640798 -164.443918)
		(size 0.5588)
		(drill 0.3048)
		(layers "F.Cu" "B.Cu")
		(net "GND")
	)
	(via
		(at 1.397 -25.778968)
		(size 0.7112)
		(drill 0.4064)
		(layers "F.Cu" "B.Cu")
		(net "GND")
	)
	(via
		(at 16.385032 -1.397)
		(size 0.7112)
		(drill 0.4064)
		(layers "F.Cu" "B.Cu")
		(net "GND")
	)
	(via
		(at 464.31962 -1.397)
		(size 0.7112)
		(drill 0.4064)
		(layers "F.Cu" "B.Cu")
		(net "GND")
	)
	(via
		(at 490.053122 -192.15735)
		(size 0.7112)
		(drill 0.4064)
		(layers "F.Cu" "B.Cu")
		(net "GND")
	)
	(via
		(at 1.397 -65.148968)
		(size 0.7112)
		(drill 0.4064)
		(layers "F.Cu" "B.Cu")
		(net "GND")
	)
	(via
		(at 357.205026 -160.844992)
		(size 0.5588)
		(drill 0.3048)
		(layers "F.Cu" "B.Cu")
		(net "GND")
	)
	(via
		(at 416.56 -320.04)
		(size 0.5588)
		(drill 0.3048)
		(layers "F.Cu" "B.Cu")
		(net "GND")
	)
	(via
		(at 201.397108 -398.262856)
		(size 0.7112)
		(drill 0.4064)
		(layers "F.Cu" "B.Cu")
		(net "GND")
	)
	(via
		(at 15.115032 -1.397)
		(size 0.7112)
		(drill 0.4064)
		(layers "F.Cu" "B.Cu")
		(net "GND")
	)
	(via
		(at 22.733 -203.835)
		(size 0.5588)
		(drill 0.3048)
		(layers "F.Cu" "B.Cu")
		(net "GND")
	)
	(via
		(at 163.322 -139.573)
		(size 0.5588)
		(drill 0.3048)
		(layers "F.Cu" "B.Cu")
		(net "GND")
	)
	(via
		(at 419.161976 -285.230062)
		(size 0.5588)
		(drill 0.3048)
		(layers "F.Cu" "B.Cu")
		(net "GND")
	)
	(via
		(at 28.304998 -67.434968)
		(size 0.5588)
		(drill 0.3048)
		(layers "F.Cu" "B.Cu")
		(net "GND")
	)
	(via
		(at 490.053122 -301.971202)
		(size 0.7112)
		(drill 0.4064)
		(layers "F.Cu" "B.Cu")
		(net "GND")
	)
	(via
		(at 67.185032 -1.397)
		(size 0.7112)
		(drill 0.4064)
		(layers "F.Cu" "B.Cu")
		(net "GND")
	)
	(via
		(at 165.269672 -183.028082)
		(size 0.5588)
		(drill 0.3048)
		(layers "F.Cu" "B.Cu")
		(net "GND")
	)
	(via
		(at 439.42 -190.5)
		(size 0.5588)
		(drill 0.3048)
		(layers "F.Cu" "B.Cu")
		(net "GND")
	)
	(via
		(at 136.492996 -347.802962)
		(size 0.7112)
		(drill 0.4064)
		(layers "F.Cu" "B.Cu")
		(net "GND")
	)
	(via
		(at 83.82 -170.688)
		(size 0.5588)
		(drill 0.3048)
		(layers "F.Cu" "B.Cu")
		(net "GND")
	)
	(via
		(at 13.208 -301.244)
		(size 0.5588)
		(drill 0.3048)
		(layers "F.Cu" "B.Cu")
		(net "GND")
	)
	(via
		(at 446.53962 -1.397)
		(size 0.7112)
		(drill 0.4064)
		(layers "F.Cu" "B.Cu")
		(net "GND")
	)
	(via
		(at 255.7272 -302.5648)
		(size 0.5588)
		(drill 0.3048)
		(layers "F.Cu" "B.Cu")
		(net "GND")
	)
	(via
		(at 453.334882 -347.802962)
		(size 0.7112)
		(drill 0.4064)
		(layers "F.Cu" "B.Cu")
		(net "GND")
	)
	(via
		(at 258.653788 -138.482578)
		(size 0.5588)
		(drill 0.3048)
		(layers "F.Cu" "B.Cu")
		(net "GND")
	)
	(via
		(at 1.397 -199.768968)
		(size 0.7112)
		(drill 0.4064)
		(layers "F.Cu" "B.Cu")
		(net "GND")
	)
	(via
		(at 431.8 -111.76)
		(size 0.5588)
		(drill 0.3048)
		(layers "F.Cu" "B.Cu")
		(net "GND")
	)
	(via
		(at 414.528 -266.573)
		(size 0.5588)
		(drill 0.3048)
		(layers "F.Cu" "B.Cu")
		(net "GND")
	)
	(via
		(at 426.72 -127)
		(size 0.5588)
		(drill 0.3048)
		(layers "F.Cu" "B.Cu")
		(net "GND")
	)
	(via
		(at 139.319 -87.122)
		(size 0.5588)
		(drill 0.3048)
		(layers "F.Cu" "B.Cu")
		(net "GND")
	)
	(via
		(at 447.04 -25.4)
		(size 0.5588)
		(drill 0.3048)
		(layers "F.Cu" "B.Cu")
		(net "GND")
	)
	(via
		(at 18.925032 -1.397)
		(size 0.7112)
		(drill 0.4064)
		(layers "F.Cu" "B.Cu")
		(net "GND")
	)
	(via
		(at 164.883084 -1.397)
		(size 0.7112)
		(drill 0.4064)
		(layers "F.Cu" "B.Cu")
		(net "GND")
	)
	(via
		(at 462.224882 -347.802962)
		(size 0.7112)
		(drill 0.4064)
		(layers "F.Cu" "B.Cu")
		(net "GND")
	)
	(via
		(at 433.014882 -347.802962)
		(size 0.7112)
		(drill 0.4064)
		(layers "F.Cu" "B.Cu")
		(net "GND")
	)
	(via
		(at 419.1 -241.3)
		(size 0.5588)
		(drill 0.3048)
		(layers "F.Cu" "B.Cu")
		(net "GND")
	)
	(via
		(at 201.397108 -390.642856)
		(size 0.7112)
		(drill 0.4064)
		(layers "F.Cu" "B.Cu")
		(net "GND")
	)
	(via
		(at 1.397 -312.798968)
		(size 0.7112)
		(drill 0.4064)
		(layers "F.Cu" "B.Cu")
		(net "GND")
	)
	(via
		(at 434.893974 -254.394716)
		(size 0.5588)
		(drill 0.3048)
		(layers "F.Cu" "B.Cu")
		(net "GND")
	)
	(via
		(at 40.64 -223.52)
		(size 0.5588)
		(drill 0.3048)
		(layers "F.Cu" "B.Cu")
		(net "GND")
	)
	(via
		(at 162.216084 -131.062476)
		(size 0.5588)
		(drill 0.3048)
		(layers "F.Cu" "B.Cu")
		(net "GND")
	)
	(via
		(at 52.324 -170.688)
		(size 0.5588)
		(drill 0.3048)
		(layers "F.Cu" "B.Cu")
		(net "GND")
	)
	(via
		(at 90.045032 -1.397)
		(size 0.7112)
		(drill 0.4064)
		(layers "F.Cu" "B.Cu")
		(net "GND")
	)
	(via
		(at 490.053122 -161.67735)
		(size 0.7112)
		(drill 0.4064)
		(layers "F.Cu" "B.Cu")
		(net "GND")
	)
	(via
		(at 483.404926 -45.844968)
		(size 0.5588)
		(drill 0.3048)
		(layers "F.Cu" "B.Cu")
		(net "GND")
	)
	(via
		(at 490.053122 -237.87735)
		(size 0.7112)
		(drill 0.4064)
		(layers "F.Cu" "B.Cu")
		(net "GND")
	)
	(via
		(at 3.81 -246.38)
		(size 0.5588)
		(drill 0.3048)
		(layers "F.Cu" "B.Cu")
		(net "GND")
	)
	(via
		(at 439.42 -175.26)
		(size 0.5588)
		(drill 0.3048)
		(layers "F.Cu" "B.Cu")
		(net "GND")
	)
	(via
		(at 146.05 -268.605)
		(size 0.5588)
		(drill 0.3048)
		(layers "F.Cu" "B.Cu")
		(net "GND")
	)
	(via
		(at 192.096898 -369.383056)
		(size 0.7112)
		(drill 0.4064)
		(layers "F.Cu" "B.Cu")
		(net "GND")
	)
	(via
		(at 201.397108 -385.562856)
		(size 0.7112)
		(drill 0.4064)
		(layers "F.Cu" "B.Cu")
		(net "GND")
	)
	(via
		(at 219.878402 -211.938362)
		(size 0.5588)
		(drill 0.3048)
		(layers "F.Cu" "B.Cu")
		(net "GND")
	)
	(via
		(at 457.028804 -182.246524)
		(size 0.5588)
		(drill 0.3048)
		(layers "F.Cu" "B.Cu")
		(net "GND")
	)
	(via
		(at 398.724882 -347.802962)
		(size 0.7112)
		(drill 0.4064)
		(layers "F.Cu" "B.Cu")
		(net "GND")
	)
	(via
		(at 264.227056 37.403024)
		(size 0.7112)
		(drill 0.4064)
		(layers "F.Cu" "B.Cu")
		(net "GND")
	)
	(via
		(at 327.406 -36.9316)
		(size 0.5588)
		(drill 0.3048)
		(layers "F.Cu" "B.Cu")
		(net "GND")
	)
	(via
		(at 67.37985 -151.611584)
		(size 0.5588)
		(drill 0.3048)
		(layers "F.Cu" "B.Cu")
		(net "GND")
	)
	(via
		(at 203.2 -101.6)
		(size 0.5588)
		(drill 0.3048)
		(layers "F.Cu" "B.Cu")
		(net "GND")
	)
	(via
		(at 224.725484 -343.011252)
		(size 0.5588)
		(drill 0.3048)
		(layers "F.Cu" "B.Cu")
		(net "GND")
	)
	(via
		(at 270.383 -278.4221)
		(size 0.5588)
		(drill 0.3048)
		(layers "F.Cu" "B.Cu")
		(net "GND")
	)
	(via
		(at 133.952996 -347.802962)
		(size 0.7112)
		(drill 0.4064)
		(layers "F.Cu" "B.Cu")
		(net "GND")
	)
	(via
		(at 132.046472 -61.552836)
		(size 0.5588)
		(drill 0.3048)
		(layers "F.Cu" "B.Cu")
		(net "GND")
	)
	(via
		(at 265.100562 -26.045922)
		(size 0.5588)
		(drill 0.3048)
		(layers "F.Cu" "B.Cu")
		(net "GND")
	)
	(via
		(at 490.053122 -164.21735)
		(size 0.7112)
		(drill 0.4064)
		(layers "F.Cu" "B.Cu")
		(net "GND")
	)
	(via
		(at 332.105 -156.315918)
		(size 0.5588)
		(drill 0.3048)
		(layers "F.Cu" "B.Cu")
		(net "GND")
	)
	(via
		(at 395.20495 -156.315918)
		(size 0.5588)
		(drill 0.3048)
		(layers "F.Cu" "B.Cu")
		(net "GND")
	)
	(via
		(at 290.897056 37.403024)
		(size 0.7112)
		(drill 0.4064)
		(layers "F.Cu" "B.Cu")
		(net "GND")
	)
	(via
		(at 294.302942 -366.285018)
		(size 0.7112)
		(drill 0.4064)
		(layers "F.Cu" "B.Cu")
		(net "GND")
	)
	(via
		(at 275.657056 37.403024)
		(size 0.7112)
		(drill 0.4064)
		(layers "F.Cu" "B.Cu")
		(net "GND")
	)
	(via
		(at 471.534998 -281.0256)
		(size 0.5588)
		(drill 0.3048)
		(layers "F.Cu" "B.Cu")
		(net "GND")
	)
	(via
		(at 325.654924 -174.814992)
		(size 0.5588)
		(drill 0.3048)
		(layers "F.Cu" "B.Cu")
		(net "GND")
	)
	(via
		(at 28.304998 -275.845016)
		(size 0.5588)
		(drill 0.3048)
		(layers "F.Cu" "B.Cu")
		(net "GND")
	)
	(via
		(at 265.938 -190.754)
		(size 0.5588)
		(drill 0.3048)
		(layers "F.Cu" "B.Cu")
		(net "GND")
	)
	(via
		(at 190.119 -103.886)
		(size 0.5588)
		(drill 0.3048)
		(layers "F.Cu" "B.Cu")
		(net "GND")
	)
	(via
		(at 490.053122 -294.351202)
		(size 0.7112)
		(drill 0.4064)
		(layers "F.Cu" "B.Cu")
		(net "GND")
	)
	(via
		(at 139.065 -111.76)
		(size 0.5588)
		(drill 0.3048)
		(layers "F.Cu" "B.Cu")
		(net "GND")
	)
	(via
		(at 426.755052 -271.315942)
		(size 0.5588)
		(drill 0.3048)
		(layers "F.Cu" "B.Cu")
		(net "GND")
	)
	(via
		(at 28.304998 -62.354968)
		(size 0.5588)
		(drill 0.3048)
		(layers "F.Cu" "B.Cu")
		(net "GND")
	)
	(via
		(at 83.152996 -347.802962)
		(size 0.7112)
		(drill 0.4064)
		(layers "F.Cu" "B.Cu")
		(net "GND")
	)
	(via
		(at 415.798 -185.166)
		(size 0.5588)
		(drill 0.3048)
		(layers "F.Cu" "B.Cu")
		(net "GND")
	)
	(via
		(at 151.650954 -3.225546)
		(size 0.7112)
		(drill 0.4064)
		(layers "F.Cu" "B.Cu")
		(net "GND")
	)
	(via
		(at 91.44 -243.84)
		(size 0.5588)
		(drill 0.3048)
		(layers "F.Cu" "B.Cu")
		(net "GND")
	)
	(via
		(at 457.2 -20.32)
		(size 0.5588)
		(drill 0.3048)
		(layers "F.Cu" "B.Cu")
		(net "GND")
	)
	(via
		(at 490.053122 -338.801202)
		(size 0.7112)
		(drill 0.4064)
		(layers "F.Cu" "B.Cu")
		(net "GND")
	)
	(via
		(at 411.48 -35.56)
		(size 0.5588)
		(drill 0.3048)
		(layers "F.Cu" "B.Cu")
		(net "GND")
	)
	(via
		(at 18.652998 -289.603942)
		(size 0.5588)
		(drill 0.3048)
		(layers "F.Cu" "B.Cu")
		(net "GND")
	)
	(via
		(at 221.651068 35.70605)
		(size 0.7112)
		(drill 0.4064)
		(layers "F.Cu" "B.Cu")
		(net "GND")
	)
	(via
		(at 199.644 -371.729)
		(size 0.7112)
		(drill 0.4064)
		(layers "F.Cu" "B.Cu")
		(net "GND")
	)
	(via
		(at 447.04 -106.68)
		(size 0.5588)
		(drill 0.3048)
		(layers "F.Cu" "B.Cu")
		(net "GND")
	)
	(via
		(at 1.397 -242.948968)
		(size 0.7112)
		(drill 0.4064)
		(layers "F.Cu" "B.Cu")
		(net "GND")
	)
	(via
		(at 416.56 -127)
		(size 0.5588)
		(drill 0.3048)
		(layers "F.Cu" "B.Cu")
		(net "GND")
	)
	(via
		(at 74.803 -154.305)
		(size 0.5588)
		(drill 0.3048)
		(layers "F.Cu" "B.Cu")
		(net "GND")
	)
	(via
		(at 55.790846 -191.240918)
		(size 0.5588)
		(drill 0.3048)
		(layers "F.Cu" "B.Cu")
		(net "GND")
	)
	(via
		(at 45.974 -320.294)
		(size 0.5588)
		(drill 0.3048)
		(layers "F.Cu" "B.Cu")
		(net "GND")
	)
	(via
		(at 438.15 -203.2)
		(size 0.5588)
		(drill 0.3048)
		(layers "F.Cu" "B.Cu")
		(net "GND")
	)
	(via
		(at 164.973 -72.39)
		(size 0.5588)
		(drill 0.3048)
		(layers "F.Cu" "B.Cu")
		(net "GND")
	)
	(via
		(at 111.501682 -347.548962)
		(size 0.7112)
		(drill 0.4064)
		(layers "F.Cu" "B.Cu")
		(net "GND")
	)
	(via
		(at 1.397 -237.868968)
		(size 0.7112)
		(drill 0.4064)
		(layers "F.Cu" "B.Cu")
		(net "GND")
	)
	(via
		(at 334.222852 -47.956216)
		(size 0.5588)
		(drill 0.3048)
		(layers "F.Cu" "B.Cu")
		(net "GND")
	)
	(via
		(at 157.518862 -130.046476)
		(size 0.5588)
		(drill 0.3048)
		(layers "F.Cu" "B.Cu")
		(net "GND")
	)
	(via
		(at 490.053122 -96.90735)
		(size 0.7112)
		(drill 0.4064)
		(layers "F.Cu" "B.Cu")
		(net "GND")
	)
	(via
		(at 420.304976 -174.814992)
		(size 0.5588)
		(drill 0.3048)
		(layers "F.Cu" "B.Cu")
		(net "GND")
	)
	(via
		(at 236.869986 -345.474798)
		(size 0.5588)
		(drill 0.3048)
		(layers "F.Cu" "B.Cu")
		(net "GND")
	)
	(via
		(at 308.602888 -391.831068)
		(size 0.7112)
		(drill 0.4064)
		(layers "F.Cu" "B.Cu")
		(net "GND")
	)
	(via
		(at 265.456924 -142.557246)
		(size 0.5588)
		(drill 0.3048)
		(layers "F.Cu" "B.Cu")
		(net "GND")
	)
	(via
		(at 415.234882 -347.802962)
		(size 0.7112)
		(drill 0.4064)
		(layers "F.Cu" "B.Cu")
		(net "GND")
	)
	(via
		(at 3.551682 -347.548962)
		(size 0.7112)
		(drill 0.4064)
		(layers "F.Cu" "B.Cu")
		(net "GND")
	)
	(via
		(at 35.56 -15.24)
		(size 0.5588)
		(drill 0.3048)
		(layers "F.Cu" "B.Cu")
		(net "GND")
	)
	(via
		(at 472.384882 -347.802962)
		(size 0.7112)
		(drill 0.4064)
		(layers "F.Cu" "B.Cu")
		(net "GND")
	)
	(via
		(at 192.024 -311.277)
		(size 0.5588)
		(drill 0.3048)
		(layers "F.Cu" "B.Cu")
		(net "GND")
	)
	(via
		(at 416.56 -132.08)
		(size 0.5588)
		(drill 0.3048)
		(layers "F.Cu" "B.Cu")
		(net "GND")
	)
	(via
		(at 388.754874 -69.974968)
		(size 0.5588)
		(drill 0.3048)
		(layers "F.Cu" "B.Cu")
		(net "GND")
	)
	(via
		(at 233.299 -380.9238)
		(size 0.5588)
		(drill 0.3048)
		(layers "F.Cu" "B.Cu")
		(net "GND")
	)
	(via
		(at 101.6 -20.32)
		(size 0.5588)
		(drill 0.3048)
		(layers "F.Cu" "B.Cu")
		(net "GND")
	)
	(via
		(at 421.64 -20.32)
		(size 0.5588)
		(drill 0.3048)
		(layers "F.Cu" "B.Cu")
		(net "GND")
	)
	(via
		(at 292.167056 37.403024)
		(size 0.7112)
		(drill 0.4064)
		(layers "F.Cu" "B.Cu")
		(net "GND")
	)
	(via
		(at 368.244882 -347.802962)
		(size 0.7112)
		(drill 0.4064)
		(layers "F.Cu" "B.Cu")
		(net "GND")
	)
	(via
		(at 1.397 -91.818968)
		(size 0.7112)
		(drill 0.4064)
		(layers "F.Cu" "B.Cu")
		(net "GND")
	)
	(via
		(at 436.88 -5.08)
		(size 0.5588)
		(drill 0.3048)
		(layers "F.Cu" "B.Cu")
		(net "GND")
	)
	(via
		(at 370.784882 -347.802962)
		(size 0.7112)
		(drill 0.4064)
		(layers "F.Cu" "B.Cu")
		(net "GND")
	)
	(via
		(at 289.627056 37.403024)
		(size 0.7112)
		(drill 0.4064)
		(layers "F.Cu" "B.Cu")
		(net "GND")
	)
	(via
		(at 156.2354 -130.374898)
		(size 0.5588)
		(drill 0.3048)
		(layers "F.Cu" "B.Cu")
		(net "GND")
	)
	(via
		(at 11.938 -281.305)
		(size 0.5588)
		(drill 0.3048)
		(layers "F.Cu" "B.Cu")
		(net "GND")
	)
	(via
		(at 1.397 -145.158968)
		(size 0.7112)
		(drill 0.4064)
		(layers "F.Cu" "B.Cu")
		(net "GND")
	)
	(via
		(at 490.053122 -257.521202)
		(size 0.7112)
		(drill 0.4064)
		(layers "F.Cu" "B.Cu")
		(net "GND")
	)
	(via
		(at 60.96 -10.16)
		(size 0.5588)
		(drill 0.3048)
		(layers "F.Cu" "B.Cu")
		(net "GND")
	)
	(via
		(at 141.097 -216.408)
		(size 0.5588)
		(drill 0.3048)
		(layers "F.Cu" "B.Cu")
		(net "GND")
	)
	(via
		(at 32.766 -65.786)
		(size 0.5588)
		(drill 0.3048)
		(layers "F.Cu" "B.Cu")
		(net "GND")
	)
	(via
		(at 476.453454 -240.486184)
		(size 0.5588)
		(drill 0.3048)
		(layers "F.Cu" "B.Cu")
		(net "GND")
	)
	(via
		(at 224.9424 -209.3976)
		(size 0.5588)
		(drill 0.3048)
		(layers "F.Cu" "B.Cu")
		(net "GND")
	)
	(via
		(at 172.503084 -1.397)
		(size 0.7112)
		(drill 0.4064)
		(layers "F.Cu" "B.Cu")
		(net "GND")
	)
	(via
		(at 1.397 -272.158968)
		(size 0.7112)
		(drill 0.4064)
		(layers "F.Cu" "B.Cu")
		(net "GND")
	)
	(via
		(at 180.005482 -222.747332)
		(size 0.5588)
		(drill 0.3048)
		(layers "F.Cu" "B.Cu")
		(net "GND")
	)
	(via
		(at 202.74534 -159.11576)
		(size 0.5588)
		(drill 0.3048)
		(layers "F.Cu" "B.Cu")
		(net "GND")
	)
	(via
		(at 198.374 -348.742)
		(size 0.5588)
		(drill 0.3048)
		(layers "F.Cu" "B.Cu")
		(net "GND")
	)
	(via
		(at 182.88 -10.16)
		(size 0.5588)
		(drill 0.3048)
		(layers "F.Cu" "B.Cu")
		(net "GND")
	)
	(via
		(at 8.765032 -1.397)
		(size 0.7112)
		(drill 0.4064)
		(layers "F.Cu" "B.Cu")
		(net "GND")
	)
	(via
		(at 171.45 -19.177)
		(size 0.5588)
		(drill 0.3048)
		(layers "F.Cu" "B.Cu")
		(net "GND")
	)
	(via
		(at 3.81 -241.3)
		(size 0.5588)
		(drill 0.3048)
		(layers "F.Cu" "B.Cu")
		(net "GND")
	)
	(via
		(at 284.4038 -271.0688)
		(size 0.5588)
		(drill 0.3048)
		(layers "F.Cu" "B.Cu")
		(net "GND")
	)
	(via
		(at 288.911284 -314.505086)
		(size 0.6604)
		(drill 0.3556)
		(layers "F.Cu" "B.Cu")
		(net "GND")
	)
	(via
		(at 5.08 -25.4)
		(size 0.5588)
		(drill 0.3048)
		(layers "F.Cu" "B.Cu")
		(net "GND")
	)
	(via
		(at 324.511924 -165.429946)
		(size 0.5588)
		(drill 0.3048)
		(layers "F.Cu" "B.Cu")
		(net "GND")
	)
	(via
		(at 426.339 -81.28)
		(size 0.5588)
		(drill 0.3048)
		(layers "F.Cu" "B.Cu")
		(net "GND")
	)
	(via
		(at 162.343084 -1.397)
		(size 0.7112)
		(drill 0.4064)
		(layers "F.Cu" "B.Cu")
		(net "GND")
	)
	(via
		(at 28.304998 -49.654968)
		(size 0.5588)
		(drill 0.3048)
		(layers "F.Cu" "B.Cu")
		(net "GND")
	)
	(via
		(at 236.802676 -350.51873)
		(size 0.5588)
		(drill 0.3048)
		(layers "F.Cu" "B.Cu")
		(net "GND")
	)
	(via
		(at 1.397 -338.198968)
		(size 0.7112)
		(drill 0.4064)
		(layers "F.Cu" "B.Cu")
		(net "GND")
	)
	(via
		(at 397.65097 -5.465318)
		(size 0.7112)
		(drill 0.4064)
		(layers "F.Cu" "B.Cu")
		(net "GND")
	)
	(via
		(at 60.96 -121.92)
		(size 0.5588)
		(drill 0.3048)
		(layers "F.Cu" "B.Cu")
		(net "GND")
	)
	(via
		(at 324.511924 -167.829992)
		(size 0.5588)
		(drill 0.3048)
		(layers "F.Cu" "B.Cu")
		(net "GND")
	)
	(via
		(at 436.88 -25.4)
		(size 0.5588)
		(drill 0.3048)
		(layers "F.Cu" "B.Cu")
		(net "GND")
	)
	(via
		(at 5.08 -45.72)
		(size 0.5588)
		(drill 0.3048)
		(layers "F.Cu" "B.Cu")
		(net "GND")
	)
	(via
		(at 35.56 -35.56)
		(size 0.5588)
		(drill 0.3048)
		(layers "F.Cu" "B.Cu")
		(net "GND")
	)
	(via
		(at 202.971908 -11.06805)
		(size 0.5588)
		(drill 0.3048)
		(layers "F.Cu" "B.Cu")
		(net "GND")
	)
	(via
		(at 443.174882 -347.802962)
		(size 0.7112)
		(drill 0.4064)
		(layers "F.Cu" "B.Cu")
		(net "GND")
	)
	(via
		(at 490.053122 -261.331202)
		(size 0.7112)
		(drill 0.4064)
		(layers "F.Cu" "B.Cu")
		(net "GND")
	)
	(via
		(at 272.542 -171.704)
		(size 0.5588)
		(drill 0.3048)
		(layers "F.Cu" "B.Cu")
		(net "GND")
	)
	(via
		(at 427.694852 -273.855942)
		(size 0.5588)
		(drill 0.3048)
		(layers "F.Cu" "B.Cu")
		(net "GND")
	)
	(via
		(at 69.662802 -149.66315)
		(size 0.5588)
		(drill 0.3048)
		(layers "F.Cu" "B.Cu")
		(net "GND")
	)
	(via
		(at 298.602908 1.928876)
		(size 0.7112)
		(drill 0.4064)
		(layers "F.Cu" "B.Cu")
		(net "GND")
	)
	(via
		(at 132.329174 -130.122676)
		(size 0.5588)
		(drill 0.3048)
		(layers "F.Cu" "B.Cu")
		(net "GND")
	)
	(via
		(at 5.08 -35.56)
		(size 0.5588)
		(drill 0.3048)
		(layers "F.Cu" "B.Cu")
		(net "GND")
	)
	(via
		(at 144.852898 -59.603894)
		(size 0.5588)
		(drill 0.3048)
		(layers "F.Cu" "B.Cu")
		(net "GND")
	)
	(via
		(at 142.24 -152.4)
		(size 0.5588)
		(drill 0.3048)
		(layers "F.Cu" "B.Cu")
		(net "GND")
	)
	(via
		(at 63.648844 -135.61568)
		(size 0.5588)
		(drill 0.3048)
		(layers "F.Cu" "B.Cu")
		(net "GND")
	)
	(via
		(at 61.632846 -309.785004)
		(size 0.5588)
		(drill 0.3048)
		(layers "F.Cu" "B.Cu")
		(net "GND")
	)
	(via
		(at 483.3874 -292.0238)
		(size 0.5588)
		(drill 0.3048)
		(layers "F.Cu" "B.Cu")
		(net "GND")
	)
	(via
		(at 482.261926 -55.230014)
		(size 0.5588)
		(drill 0.3048)
		(layers "F.Cu" "B.Cu")
		(net "GND")
	)
	(via
		(at 184.752996 -347.802962)
		(size 0.7112)
		(drill 0.4064)
		(layers "F.Cu" "B.Cu")
		(net "GND")
	)
	(via
		(at 281.2034 -278.3967)
		(size 0.5588)
		(drill 0.3048)
		(layers "F.Cu" "B.Cu")
		(net "GND")
	)
	(via
		(at 118.149878 -31.624778)
		(size 0.6604)
		(drill 0.3556)
		(layers "F.Cu" "B.Cu")
		(net "GND")
	)
	(via
		(at 447.4464 -249.7328)
		(size 0.5588)
		(drill 0.3048)
		(layers "F.Cu" "B.Cu")
		(net "GND")
	)
	(via
		(at 326.898 -115.824)
		(size 0.5588)
		(drill 0.3048)
		(layers "F.Cu" "B.Cu")
		(net "GND")
	)
	(via
		(at 83.185 -304.038)
		(size 0.5588)
		(drill 0.3048)
		(layers "F.Cu" "B.Cu")
		(net "GND")
	)
	(via
		(at 30.267402 -243.74475)
		(size 0.5588)
		(drill 0.3048)
		(layers "F.Cu" "B.Cu")
		(net "GND")
	)
	(via
		(at 56.785002 -254.31115)
		(size 0.5588)
		(drill 0.3048)
		(layers "F.Cu" "B.Cu")
		(net "GND")
	)
	(via
		(at 78.615032 -1.397)
		(size 0.7112)
		(drill 0.4064)
		(layers "F.Cu" "B.Cu")
		(net "GND")
	)
	(via
		(at 25.4 -238.76)
		(size 0.5588)
		(drill 0.3048)
		(layers "F.Cu" "B.Cu")
		(net "GND")
	)
	(via
		(at 91.404948 -177.354992)
		(size 0.5588)
		(drill 0.3048)
		(layers "F.Cu" "B.Cu")
		(net "GND")
	)
	(via
		(at 438.576974 -254.394716)
		(size 0.5588)
		(drill 0.3048)
		(layers "F.Cu" "B.Cu")
		(net "GND")
	)
	(via
		(at 490.053122 -135.00735)
		(size 0.7112)
		(drill 0.4064)
		(layers "F.Cu" "B.Cu")
		(net "GND")
	)
	(via
		(at 114.427 -306.959)
		(size 0.5588)
		(drill 0.3048)
		(layers "F.Cu" "B.Cu")
		(net "GND")
	)
	(via
		(at 431.8 -25.4)
		(size 0.5588)
		(drill 0.3048)
		(layers "F.Cu" "B.Cu")
		(net "GND")
	)
	(via
		(at 435.991 -239.649)
		(size 0.5588)
		(drill 0.3048)
		(layers "F.Cu" "B.Cu")
		(net "GND")
	)
	(via
		(at 72.710802 -149.66315)
		(size 0.5588)
		(drill 0.3048)
		(layers "F.Cu" "B.Cu")
		(net "GND")
	)
	(via
		(at 35.56 -20.32)
		(size 0.5588)
		(drill 0.3048)
		(layers "F.Cu" "B.Cu")
		(net "GND")
	)
	(via
		(at 451.854824 -272.035016)
		(size 0.5588)
		(drill 0.3048)
		(layers "F.Cu" "B.Cu")
		(net "GND")
	)
	(via
		(at 357.205026 -292.355016)
		(size 0.5588)
		(drill 0.3048)
		(layers "F.Cu" "B.Cu")
		(net "GND")
	)
	(via
		(at 76.454 -312.674)
		(size 0.5588)
		(drill 0.3048)
		(layers "F.Cu" "B.Cu")
		(net "GND")
	)
	(via
		(at 221.651068 20.46605)
		(size 0.7112)
		(drill 0.4064)
		(layers "F.Cu" "B.Cu")
		(net "GND")
	)
	(via
		(at 459.2447 -158.855918)
		(size 0.5588)
		(drill 0.3048)
		(layers "F.Cu" "B.Cu")
		(net "GND")
	)
	(via
		(at 490.053122 -122.30735)
		(size 0.7112)
		(drill 0.4064)
		(layers "F.Cu" "B.Cu")
		(net "GND")
	)
	(via
		(at 228.092 -68.072)
		(size 0.5588)
		(drill 0.3048)
		(layers "F.Cu" "B.Cu")
		(net "GND")
	)
	(via
		(at 490.053122 -253.711202)
		(size 0.7112)
		(drill 0.4064)
		(layers "F.Cu" "B.Cu")
		(net "GND")
	)
	(via
		(at 288.163 26.289)
		(size 0.5588)
		(drill 0.3048)
		(layers "F.Cu" "B.Cu")
		(net "GND")
	)
	(via
		(at 485.182926 -194.78498)
		(size 0.5588)
		(drill 0.3048)
		(layers "F.Cu" "B.Cu")
		(net "GND")
	)
	(via
		(at 371.1702 -102.6668)
		(size 0.5588)
		(drill 0.3048)
		(layers "F.Cu" "B.Cu")
		(net "GND")
	)
	(via
		(at 4.445 -322.58)
		(size 0.5588)
		(drill 0.3048)
		(layers "F.Cu" "B.Cu")
		(net "GND")
	)
	(via
		(at 483.404926 -157.034992)
		(size 0.5588)
		(drill 0.3048)
		(layers "F.Cu" "B.Cu")
		(net "GND")
	)
	(via
		(at 252.349 -334.518)
		(size 0.5588)
		(drill 0.3048)
		(layers "F.Cu" "B.Cu")
		(net "GND")
	)
	(via
		(at 462.28 -142.24)
		(size 0.5588)
		(drill 0.3048)
		(layers "F.Cu" "B.Cu")
		(net "GND")
	)
	(via
		(at 55.88 -25.4)
		(size 0.5588)
		(drill 0.3048)
		(layers "F.Cu" "B.Cu")
		(net "GND")
	)
	(via
		(at 473.235274 -287.809432)
		(size 0.5588)
		(drill 0.3048)
		(layers "F.Cu" "B.Cu")
		(net "GND")
	)
	(via
		(at 447.04 -10.16)
		(size 0.5588)
		(drill 0.3048)
		(layers "F.Cu" "B.Cu")
		(net "GND")
	)
	(via
		(at 90.17 -198.247)
		(size 0.5588)
		(drill 0.3048)
		(layers "F.Cu" "B.Cu")
		(net "GND")
	)
	(via
		(at 490.053122 -305.781202)
		(size 0.7112)
		(drill 0.4064)
		(layers "F.Cu" "B.Cu")
		(net "GND")
	)
	(via
		(at 1.397 -151.508968)
		(size 0.7112)
		(drill 0.4064)
		(layers "F.Cu" "B.Cu")
		(net "GND")
	)
	(via
		(at 416.05962 -1.397)
		(size 0.7112)
		(drill 0.4064)
		(layers "F.Cu" "B.Cu")
		(net "GND")
	)
	(via
		(at 100.205032 -1.397)
		(size 0.7112)
		(drill 0.4064)
		(layers "F.Cu" "B.Cu")
		(net "GND")
	)
	(via
		(at 148.020532 -70.322694)
		(size 0.5588)
		(drill 0.3048)
		(layers "F.Cu" "B.Cu")
		(net "GND")
	)
	(via
		(at 151.732996 -347.802962)
		(size 0.7112)
		(drill 0.4064)
		(layers "F.Cu" "B.Cu")
		(net "GND")
	)
	(via
		(at 451.854824 -184.974992)
		(size 0.5588)
		(drill 0.3048)
		(layers "F.Cu" "B.Cu")
		(net "GND")
	)
	(via
		(at 396.14475 -273.855942)
		(size 0.5588)
		(drill 0.3048)
		(layers "F.Cu" "B.Cu")
		(net "GND")
	)
	(via
		(at 55.88 -30.48)
		(size 0.5588)
		(drill 0.3048)
		(layers "F.Cu" "B.Cu")
		(net "GND")
	)
	(via
		(at 431.29962 -1.397)
		(size 0.7112)
		(drill 0.4064)
		(layers "F.Cu" "B.Cu")
		(net "GND")
	)
	(via
		(at 83.82 -111.76)
		(size 0.5588)
		(drill 0.3048)
		(layers "F.Cu" "B.Cu")
		(net "GND")
	)
	(via
		(at 240.009934 -384.8608)
		(size 0.5588)
		(drill 0.3048)
		(layers "F.Cu" "B.Cu")
		(net "GND")
	)
	(via
		(at 362.385102 -67.604894)
		(size 0.5588)
		(drill 0.3048)
		(layers "F.Cu" "B.Cu")
		(net "GND")
	)
	(via
		(at 35.56 -81.28)
		(size 0.5588)
		(drill 0.3048)
		(layers "F.Cu" "B.Cu")
		(net "GND")
	)
	(via
		(at 300.506892 -419.803072)
		(size 0.7112)
		(drill 0.4064)
		(layers "F.Cu" "B.Cu")
		(net "GND")
	)
	(via
		(at 84.831682 -347.548962)
		(size 0.7112)
		(drill 0.4064)
		(layers "F.Cu" "B.Cu")
		(net "GND")
	)
	(via
		(at 467.36 -30.48)
		(size 0.5588)
		(drill 0.3048)
		(layers "F.Cu" "B.Cu")
		(net "GND")
	)
	(via
		(at 71.12 -20.32)
		(size 0.5588)
		(drill 0.3048)
		(layers "F.Cu" "B.Cu")
		(net "GND")
	)
	(via
		(at 210.185 -234.315)
		(size 0.5588)
		(drill 0.3048)
		(layers "F.Cu" "B.Cu")
		(net "GND")
	)
	(via
		(at 79.33817 -18.50517)
		(size 0.5588)
		(drill 0.3048)
		(layers "F.Cu" "B.Cu")
		(net "GND")
	)
	(via
		(at 29.4132 -247.7008)
		(size 0.5588)
		(drill 0.3048)
		(layers "F.Cu" "B.Cu")
		(net "GND")
	)
	(via
		(at 252.220476 -255.45796)
		(size 0.5588)
		(drill 0.3048)
		(layers "F.Cu" "B.Cu")
		(net "GND")
	)
	(via
		(at 176.403 -174.603918)
		(size 0.5588)
		(drill 0.3048)
		(layers "F.Cu" "B.Cu")
		(net "GND")
	)
	(via
		(at 1.397 -273.428968)
		(size 0.7112)
		(drill 0.4064)
		(layers "F.Cu" "B.Cu")
		(net "GND")
	)
	(via
		(at 406.344882 -347.802962)
		(size 0.7112)
		(drill 0.4064)
		(layers "F.Cu" "B.Cu")
		(net "GND")
	)
	(via
		(at 309.858918 -60.870084)
		(size 0.5588)
		(drill 0.3048)
		(layers "F.Cu" "B.Cu")
		(net "GND")
	)
	(via
		(at 1.397 -21.968968)
		(size 0.7112)
		(drill 0.4064)
		(layers "F.Cu" "B.Cu")
		(net "GND")
	)
	(via
		(at 267.716 -219.964)
		(size 0.5588)
		(drill 0.3048)
		(layers "F.Cu" "B.Cu")
		(net "GND")
	)
	(via
		(at 3.81 -256.54)
		(size 0.5588)
		(drill 0.3048)
		(layers "F.Cu" "B.Cu")
		(net "GND")
	)
	(via
		(at 36.642802 -145.59915)
		(size 0.5588)
		(drill 0.3048)
		(layers "F.Cu" "B.Cu")
		(net "GND")
	)
	(via
		(at 1.397 -99.438968)
		(size 0.7112)
		(drill 0.4064)
		(layers "F.Cu" "B.Cu")
		(net "GND")
	)
	(via
		(at 463.796634 -257.940048)
		(size 0.5588)
		(drill 0.3048)
		(layers "F.Cu" "B.Cu")
		(net "GND")
	)
	(via
		(at 1.397 -61.338968)
		(size 0.7112)
		(drill 0.4064)
		(layers "F.Cu" "B.Cu")
		(net "GND")
	)
	(via
		(at 61.734954 -151.035004)
		(size 0.5588)
		(drill 0.3048)
		(layers "F.Cu" "B.Cu")
		(net "GND")
	)
	(via
		(at 149.026626 -50.009552)
		(size 0.5588)
		(drill 0.3048)
		(layers "F.Cu" "B.Cu")
		(net "GND")
	)
	(via
		(at 60.96 -332.74)
		(size 0.5588)
		(drill 0.3048)
		(layers "F.Cu" "B.Cu")
		(net "GND")
	)
	(via
		(at 282.3464 -278.8412)
		(size 0.5588)
		(drill 0.3048)
		(layers "F.Cu" "B.Cu")
		(net "GND")
	)
	(via
		(at 298.831 0.127)
		(size 0.7112)
		(drill 0.4064)
		(layers "F.Cu" "B.Cu")
		(net "GND")
	)
	(via
		(at 416.56 -15.24)
		(size 0.5588)
		(drill 0.3048)
		(layers "F.Cu" "B.Cu")
		(net "GND")
	)
	(via
		(at 331.4954 -271.315942)
		(size 0.5588)
		(drill 0.3048)
		(layers "F.Cu" "B.Cu")
		(net "GND")
	)
	(via
		(at 490.053122 -307.051202)
		(size 0.7112)
		(drill 0.4064)
		(layers "F.Cu" "B.Cu")
		(net "GND")
	)
	(via
		(at 1.397 -277.238968)
		(size 0.7112)
		(drill 0.4064)
		(layers "F.Cu" "B.Cu")
		(net "GND")
	)
	(via
		(at 398.27962 -1.397)
		(size 0.7112)
		(drill 0.4064)
		(layers "F.Cu" "B.Cu")
		(net "GND")
	)
	(via
		(at 74.9808 -268.8336)
		(size 0.5588)
		(drill 0.3048)
		(layers "F.Cu" "B.Cu")
		(net "GND")
	)
	(via
		(at 318.9224 -60.2742)
		(size 0.5588)
		(drill 0.3048)
		(layers "F.Cu" "B.Cu")
		(net "GND")
	)
	(via
		(at 27.161998 -52.829968)
		(size 0.5588)
		(drill 0.3048)
		(layers "F.Cu" "B.Cu")
		(net "GND")
	)
	(via
		(at 115.443 -170.688)
		(size 0.5588)
		(drill 0.3048)
		(layers "F.Cu" "B.Cu")
		(net "GND")
	)
	(via
		(at 303.699672 -181.8386)
		(size 0.5588)
		(drill 0.3048)
		(layers "F.Cu" "B.Cu")
		(net "GND")
	)
	(via
		(at 413.964882 -347.802962)
		(size 0.7112)
		(drill 0.4064)
		(layers "F.Cu" "B.Cu")
		(net "GND")
	)
	(via
		(at 355.15423 -194.78498)
		(size 0.5588)
		(drill 0.3048)
		(layers "F.Cu" "B.Cu")
		(net "GND")
	)
	(via
		(at 224.6884 -174.9552)
		(size 0.5588)
		(drill 0.3048)
		(layers "F.Cu" "B.Cu")
		(net "GND")
	)
	(via
		(at 483.404926 -49.654968)
		(size 0.5588)
		(drill 0.3048)
		(layers "F.Cu" "B.Cu")
		(net "GND")
	)
	(via
		(at 356.062026 -52.829968)
		(size 0.5588)
		(drill 0.3048)
		(layers "F.Cu" "B.Cu")
		(net "GND")
	)
	(via
		(at 71.12 -25.4)
		(size 0.5588)
		(drill 0.3048)
		(layers "F.Cu" "B.Cu")
		(net "GND")
	)
	(via
		(at 28.304998 -45.844968)
		(size 0.5588)
		(drill 0.3048)
		(layers "F.Cu" "B.Cu")
		(net "GND")
	)
	(via
		(at 325.12 -109.22)
		(size 0.5588)
		(drill 0.3048)
		(layers "F.Cu" "B.Cu")
		(net "GND")
	)
	(via
		(at 304.741072 -22.699472)
		(size 0.5588)
		(drill 0.3048)
		(layers "F.Cu" "B.Cu")
		(net "GND")
	)
	(via
		(at 405.257 -65.659)
		(size 0.5588)
		(drill 0.3048)
		(layers "F.Cu" "B.Cu")
		(net "GND")
	)
	(via
		(at 357.205026 -174.814992)
		(size 0.5588)
		(drill 0.3048)
		(layers "F.Cu" "B.Cu")
		(net "GND")
	)
	(via
		(at 64.102996 -347.802962)
		(size 0.7112)
		(drill 0.4064)
		(layers "F.Cu" "B.Cu")
		(net "GND")
	)
	(via
		(at 307.281072 -17.619472)
		(size 0.5588)
		(drill 0.3048)
		(layers "F.Cu" "B.Cu")
		(net "GND")
	)
	(via
		(at 339.034882 -347.802962)
		(size 0.7112)
		(drill 0.4064)
		(layers "F.Cu" "B.Cu")
		(net "GND")
	)
	(via
		(at 122.954796 -184.974992)
		(size 0.5588)
		(drill 0.3048)
		(layers "F.Cu" "B.Cu")
		(net "GND")
	)
	(via
		(at 478.5868 -227.33)
		(size 0.5588)
		(drill 0.3048)
		(layers "F.Cu" "B.Cu")
		(net "GND")
	)
	(via
		(at 420.314882 -347.802962)
		(size 0.7112)
		(drill 0.4064)
		(layers "F.Cu" "B.Cu")
		(net "GND")
	)
	(via
		(at 29.4132 -249.7328)
		(size 0.5588)
		(drill 0.3048)
		(layers "F.Cu" "B.Cu")
		(net "GND")
	)
	(via
		(at 487.68 -320.04)
		(size 0.5588)
		(drill 0.3048)
		(layers "F.Cu" "B.Cu")
		(net "GND")
	)
	(via
		(at 224.866454 -345.073478)
		(size 0.5588)
		(drill 0.3048)
		(layers "F.Cu" "B.Cu")
		(net "GND")
	)
	(via
		(at 261.687056 37.403024)
		(size 0.7112)
		(drill 0.4064)
		(layers "F.Cu" "B.Cu")
		(net "GND")
	)
	(via
		(at 25.019 -315.214)
		(size 0.5588)
		(drill 0.3048)
		(layers "F.Cu" "B.Cu")
		(net "GND")
	)
	(via
		(at 365.8362 -47.752)
		(size 0.5588)
		(drill 0.3048)
		(layers "F.Cu" "B.Cu")
		(net "GND")
	)
	(via
		(at 28.304998 -164.654992)
		(size 0.5588)
		(drill 0.3048)
		(layers "F.Cu" "B.Cu")
		(net "GND")
	)
	(via
		(at 490.053122 -265.141202)
		(size 0.7112)
		(drill 0.4064)
		(layers "F.Cu" "B.Cu")
		(net "GND")
	)
	(via
		(at 1.397 -320.418968)
		(size 0.7112)
		(drill 0.4064)
		(layers "F.Cu" "B.Cu")
		(net "GND")
	)
	(via
		(at 467.47303 -256.57048)
		(size 0.5588)
		(drill 0.3048)
		(layers "F.Cu" "B.Cu")
		(net "GND")
	)
	(via
		(at 114.041682 -347.548962)
		(size 0.7112)
		(drill 0.4064)
		(layers "F.Cu" "B.Cu")
		(net "GND")
	)
	(via
		(at 441.12815 -285.355284)
		(size 0.5588)
		(drill 0.3048)
		(layers "F.Cu" "B.Cu")
		(net "GND")
	)
	(via
		(at 235.017056 37.403024)
		(size 0.7112)
		(drill 0.4064)
		(layers "F.Cu" "B.Cu")
		(net "GND")
	)
	(via
		(at 389.834882 -347.802962)
		(size 0.7112)
		(drill 0.4064)
		(layers "F.Cu" "B.Cu")
		(net "GND")
	)
	(via
		(at 483.404926 -62.354968)
		(size 0.5588)
		(drill 0.3048)
		(layers "F.Cu" "B.Cu")
		(net "GND")
	)
	(via
		(at 91.404948 -157.034992)
		(size 0.5588)
		(drill 0.3048)
		(layers "F.Cu" "B.Cu")
		(net "GND")
	)
	(via
		(at 436.824882 -347.802962)
		(size 0.7112)
		(drill 0.4064)
		(layers "F.Cu" "B.Cu")
		(net "GND")
	)
	(via
		(at 44.325032 -1.397)
		(size 0.7112)
		(drill 0.4064)
		(layers "F.Cu" "B.Cu")
		(net "GND")
	)
	(via
		(at 186.473084 -1.397)
		(size 0.7112)
		(drill 0.4064)
		(layers "F.Cu" "B.Cu")
		(net "GND")
	)
	(via
		(at 490.053122 -57.53735)
		(size 0.7112)
		(drill 0.4064)
		(layers "F.Cu" "B.Cu")
		(net "GND")
	)
	(via
		(at 466.31733 -259.096256)
		(size 0.5588)
		(drill 0.3048)
		(layers "F.Cu" "B.Cu")
		(net "GND")
	)
	(via
		(at 153.002996 -347.802962)
		(size 0.7112)
		(drill 0.4064)
		(layers "F.Cu" "B.Cu")
		(net "GND")
	)
	(via
		(at 35.56 -238.76)
		(size 0.5588)
		(drill 0.3048)
		(layers "F.Cu" "B.Cu")
		(net "GND")
	)
	(via
		(at 154.504898 -299.975016)
		(size 0.5588)
		(drill 0.3048)
		(layers "F.Cu" "B.Cu")
		(net "GND")
	)
	(via
		(at 97.917 -79.502)
		(size 0.5588)
		(drill 0.3048)
		(layers "F.Cu" "B.Cu")
		(net "GND")
	)
	(via
		(at 1.397 -71.498968)
		(size 0.7112)
		(drill 0.4064)
		(layers "F.Cu" "B.Cu")
		(net "GND")
	)
	(via
		(at 1.397 -255.648968)
		(size 0.7112)
		(drill 0.4064)
		(layers "F.Cu" "B.Cu")
		(net "GND")
	)
	(via
		(at 490.053122 -328.641202)
		(size 0.7112)
		(drill 0.4064)
		(layers "F.Cu" "B.Cu")
		(net "GND")
	)
	(via
		(at 490.053122 -61.34735)
		(size 0.7112)
		(drill 0.4064)
		(layers "F.Cu" "B.Cu")
		(net "GND")
	)
	(via
		(at 55.88 -327.66)
		(size 0.5588)
		(drill 0.3048)
		(layers "F.Cu" "B.Cu")
		(net "GND")
	)
	(via
		(at 475.869 -55.626)
		(size 0.5588)
		(drill 0.3048)
		(layers "F.Cu" "B.Cu")
		(net "GND")
	)
	(via
		(at 269.307056 37.403024)
		(size 0.7112)
		(drill 0.4064)
		(layers "F.Cu" "B.Cu")
		(net "GND")
	)
	(via
		(at 388.754874 -182.434992)
		(size 0.5588)
		(drill 0.3048)
		(layers "F.Cu" "B.Cu")
		(net "GND")
	)
	(via
		(at 480.06 -106.68)
		(size 0.5588)
		(drill 0.3048)
		(layers "F.Cu" "B.Cu")
		(net "GND")
	)
	(via
		(at 298.602908 4.468876)
		(size 0.7112)
		(drill 0.4064)
		(layers "F.Cu" "B.Cu")
		(net "GND")
	)
	(via
		(at 1.397 -101.978968)
		(size 0.7112)
		(drill 0.4064)
		(layers "F.Cu" "B.Cu")
		(net "GND")
	)
	(via
		(at 58.42 -325.12)
		(size 0.5588)
		(drill 0.3048)
		(layers "F.Cu" "B.Cu")
		(net "GND")
	)
	(via
		(at 490.053122 -27.05735)
		(size 0.7112)
		(drill 0.4064)
		(layers "F.Cu" "B.Cu")
		(net "GND")
	)
	(via
		(at 192.350898 -367.251742)
		(size 0.7112)
		(drill 0.4064)
		(layers "F.Cu" "B.Cu")
		(net "GND")
	)
	(via
		(at 76.2 -5.08)
		(size 0.5588)
		(drill 0.3048)
		(layers "F.Cu" "B.Cu")
		(net "GND")
	)
	(via
		(at 190.724282 -229.537006)
		(size 0.5588)
		(drill 0.3048)
		(layers "F.Cu" "B.Cu")
		(net "GND")
	)
	(via
		(at 243.6876 -243.9162)
		(size 0.5588)
		(drill 0.3048)
		(layers "F.Cu" "B.Cu")
		(net "GND")
	)
	(via
		(at 99.06 -267.97)
		(size 0.5588)
		(drill 0.3048)
		(layers "F.Cu" "B.Cu")
		(net "GND")
	)
	(via
		(at 23.440898 -49.443894)
		(size 0.5588)
		(drill 0.3048)
		(layers "F.Cu" "B.Cu")
		(net "GND")
	)
	(via
		(at 98.552 -154.178)
		(size 0.5588)
		(drill 0.3048)
		(layers "F.Cu" "B.Cu")
		(net "GND")
	)
	(via
		(at 281.456892 -419.803072)
		(size 0.7112)
		(drill 0.4064)
		(layers "F.Cu" "B.Cu")
		(net "GND")
	)
	(via
		(at 383.0066 -136.9314)
		(size 0.5588)
		(drill 0.3048)
		(layers "F.Cu" "B.Cu")
		(net "GND")
	)
	(via
		(at 45.72 -233.68)
		(size 0.5588)
		(drill 0.3048)
		(layers "F.Cu" "B.Cu")
		(net "GND")
	)
	(via
		(at 326.741028 -1.397)
		(size 0.7112)
		(drill 0.4064)
		(layers "F.Cu" "B.Cu")
		(net "GND")
	)
	(via
		(at 64.77 -306.705)
		(size 0.5588)
		(drill 0.3048)
		(layers "F.Cu" "B.Cu")
		(net "GND")
	)
	(via
		(at 131.412996 -347.802962)
		(size 0.7112)
		(drill 0.4064)
		(layers "F.Cu" "B.Cu")
		(net "GND")
	)
	(via
		(at 442.468254 -245.227856)
		(size 0.5588)
		(drill 0.3048)
		(layers "F.Cu" "B.Cu")
		(net "GND")
	)
	(via
		(at 3.81 -261.62)
		(size 0.5588)
		(drill 0.3048)
		(layers "F.Cu" "B.Cu")
		(net "GND")
	)
	(via
		(at 308.602888 -404.531068)
		(size 0.7112)
		(drill 0.4064)
		(layers "F.Cu" "B.Cu")
		(net "GND")
	)
	(via
		(at 25.4 -30.48)
		(size 0.5588)
		(drill 0.3048)
		(layers "F.Cu" "B.Cu")
		(net "GND")
	)
	(via
		(at 363.655102 -41.315894)
		(size 0.5588)
		(drill 0.3048)
		(layers "F.Cu" "B.Cu")
		(net "GND")
	)
	(via
		(at 268.816582 18.48358)
		(size 0.5588)
		(drill 0.3048)
		(layers "F.Cu" "B.Cu")
		(net "GND")
	)
	(via
		(at 406.4 -5.08)
		(size 0.5588)
		(drill 0.3048)
		(layers "F.Cu" "B.Cu")
		(net "GND")
	)
	(via
		(at 102.140766 -189.103762)
		(size 0.5588)
		(drill 0.3048)
		(layers "F.Cu" "B.Cu")
		(net "GND")
	)
	(via
		(at 30.48 -127)
		(size 0.5588)
		(drill 0.3048)
		(layers "F.Cu" "B.Cu")
		(net "GND")
	)
	(via
		(at 76.2 -76.2)
		(size 0.5588)
		(drill 0.3048)
		(layers "F.Cu" "B.Cu")
		(net "GND")
	)
	(via
		(at 380.91745 -290.238942)
		(size 0.5588)
		(drill 0.3048)
		(layers "F.Cu" "B.Cu")
		(net "GND")
	)
	(via
		(at 277.067772 -389.99668)
		(size 0.5588)
		(drill 0.3048)
		(layers "F.Cu" "B.Cu")
		(net "GND")
	)
	(via
		(at 277.603458 -394.992098)
		(size 0.5588)
		(drill 0.3048)
		(layers "F.Cu" "B.Cu")
		(net "GND")
	)
	(via
		(at 201.397108 -414.772856)
		(size 0.7112)
		(drill 0.4064)
		(layers "F.Cu" "B.Cu")
		(net "GND")
	)
	(via
		(at 1.397 -295.018968)
		(size 0.7112)
		(drill 0.4064)
		(layers "F.Cu" "B.Cu")
		(net "GND")
	)
	(via
		(at 70.678802 -149.66315)
		(size 0.5588)
		(drill 0.3048)
		(layers "F.Cu" "B.Cu")
		(net "GND")
	)
	(via
		(at 457.3651 -276.649942)
		(size 0.5588)
		(drill 0.3048)
		(layers "F.Cu" "B.Cu")
		(net "GND")
	)
	(via
		(at 396.60195 -306.113942)
		(size 0.5588)
		(drill 0.3048)
		(layers "F.Cu" "B.Cu")
		(net "GND")
	)
	(via
		(at 334.685894 -27.405584)
		(size 0.5588)
		(drill 0.3048)
		(layers "F.Cu" "B.Cu")
		(net "GND")
	)
	(via
		(at 1.397 -170.558968)
		(size 0.7112)
		(drill 0.4064)
		(layers "F.Cu" "B.Cu")
		(net "GND")
	)
	(via
		(at 416.56 -25.4)
		(size 0.5588)
		(drill 0.3048)
		(layers "F.Cu" "B.Cu")
		(net "GND")
	)
	(via
		(at 156.201618 -34.233358)
		(size 0.5588)
		(drill 0.3048)
		(layers "F.Cu" "B.Cu")
		(net "GND")
	)
	(via
		(at 201.397108 -407.152856)
		(size 0.7112)
		(drill 0.4064)
		(layers "F.Cu" "B.Cu")
		(net "GND")
	)
	(via
		(at 247.777 -2.921)
		(size 0.5588)
		(drill 0.3048)
		(layers "F.Cu" "B.Cu")
		(net "GND")
	)
	(via
		(at 59.7662 -290.2458)
		(size 0.5588)
		(drill 0.3048)
		(layers "F.Cu" "B.Cu")
		(net "GND")
	)
	(via
		(at 1.397 -324.228968)
		(size 0.7112)
		(drill 0.4064)
		(layers "F.Cu" "B.Cu")
		(net "GND")
	)
	(via
		(at 165.408864 -295.668954)
		(size 0.5588)
		(drill 0.3048)
		(layers "F.Cu" "B.Cu")
		(net "GND")
	)
	(via
		(at 467.36 -86.36)
		(size 0.5588)
		(drill 0.3048)
		(layers "F.Cu" "B.Cu")
		(net "GND")
	)
	(via
		(at 236.287056 37.403024)
		(size 0.7112)
		(drill 0.4064)
		(layers "F.Cu" "B.Cu")
		(net "GND")
	)
	(via
		(at 457.96962 -1.397)
		(size 0.7112)
		(drill 0.4064)
		(layers "F.Cu" "B.Cu")
		(net "GND")
	)
	(via
		(at 59.854846 -59.814968)
		(size 0.5588)
		(drill 0.3048)
		(layers "F.Cu" "B.Cu")
		(net "GND")
	)
	(via
		(at 480.004882 -347.802962)
		(size 0.7112)
		(drill 0.4064)
		(layers "F.Cu" "B.Cu")
		(net "GND")
	)
	(via
		(at 298.394882 -347.802962)
		(size 0.7112)
		(drill 0.4064)
		(layers "F.Cu" "B.Cu")
		(net "GND")
	)
	(via
		(at 298.602908 15.898876)
		(size 0.7112)
		(drill 0.4064)
		(layers "F.Cu" "B.Cu")
		(net "GND")
	)
	(via
		(at 457.2 -137.16)
		(size 0.5588)
		(drill 0.3048)
		(layers "F.Cu" "B.Cu")
		(net "GND")
	)
	(via
		(at 218.973146 -15.653004)
		(size 0.5588)
		(drill 0.3048)
		(layers "F.Cu" "B.Cu")
		(net "GND")
	)
	(via
		(at 1.397 -70.228968)
		(size 0.7112)
		(drill 0.4064)
		(layers "F.Cu" "B.Cu")
		(net "GND")
	)
	(via
		(at 47.371 -145.0848)
		(size 0.5588)
		(drill 0.3048)
		(layers "F.Cu" "B.Cu")
		(net "GND")
	)
	(via
		(at 153.361898 -165.429946)
		(size 0.5588)
		(drill 0.3048)
		(layers "F.Cu" "B.Cu")
		(net "GND")
	)
	(via
		(at 49.328324 -239.097312)
		(size 0.5588)
		(drill 0.3048)
		(layers "F.Cu" "B.Cu")
		(net "GND")
	)
	(via
		(at 396.24 -120.65)
		(size 0.5588)
		(drill 0.3048)
		(layers "F.Cu" "B.Cu")
		(net "GND")
	)
	(via
		(at 490.053122 -5.46735)
		(size 0.7112)
		(drill 0.4064)
		(layers "F.Cu" "B.Cu")
		(net "GND")
	)
	(via
		(at 5.08 -71.12)
		(size 0.5588)
		(drill 0.3048)
		(layers "F.Cu" "B.Cu")
		(net "GND")
	)
	(via
		(at 86.101682 -347.548962)
		(size 0.7112)
		(drill 0.4064)
		(layers "F.Cu" "B.Cu")
		(net "GND")
	)
	(via
		(at 91.404948 -299.975016)
		(size 0.5588)
		(drill 0.3048)
		(layers "F.Cu" "B.Cu")
		(net "GND")
	)
	(via
		(at 361.894882 -347.802962)
		(size 0.7112)
		(drill 0.4064)
		(layers "F.Cu" "B.Cu")
		(net "GND")
	)
	(via
		(at 93.98 -137.16)
		(size 0.5588)
		(drill 0.3048)
		(layers "F.Cu" "B.Cu")
		(net "GND")
	)
	(via
		(at 284.266386 -220.50502)
		(size 0.5588)
		(drill 0.3048)
		(layers "F.Cu" "B.Cu")
		(net "GND")
	)
	(via
		(at 288.911284 -260.10235)
		(size 0.6604)
		(drill 0.3556)
		(layers "F.Cu" "B.Cu")
		(net "GND")
	)
	(via
		(at 390.621266 -309.785004)
		(size 0.5588)
		(drill 0.3048)
		(layers "F.Cu" "B.Cu")
		(net "GND")
	)
	(via
		(at 57.025032 -1.397)
		(size 0.7112)
		(drill 0.4064)
		(layers "F.Cu" "B.Cu")
		(net "GND")
	)
	(via
		(at 7.884922 -175.03521)
		(size 0.5588)
		(drill 0.3048)
		(layers "F.Cu" "B.Cu")
		(net "GND")
	)
	(via
		(at 156.270452 -309.613554)
		(size 0.5588)
		(drill 0.3048)
		(layers "F.Cu" "B.Cu")
		(net "GND")
	)
	(via
		(at 339.852 -138.811)
		(size 0.5588)
		(drill 0.3048)
		(layers "F.Cu" "B.Cu")
		(net "GND")
	)
	(via
		(at 177.419 -105.537)
		(size 0.5588)
		(drill 0.3048)
		(layers "F.Cu" "B.Cu")
		(net "GND")
	)
	(via
		(at 1.397 -293.748968)
		(size 0.7112)
		(drill 0.4064)
		(layers "F.Cu" "B.Cu")
		(net "GND")
	)
	(via
		(at 155.542996 -347.802962)
		(size 0.7112)
		(drill 0.4064)
		(layers "F.Cu" "B.Cu")
		(net "GND")
	)
	(via
		(at 257.092196 22.536404)
		(size 0.5588)
		(drill 0.3048)
		(layers "F.Cu" "B.Cu")
		(net "GND")
	)
	(via
		(at 308.961028 -1.397)
		(size 0.7112)
		(drill 0.4064)
		(layers "F.Cu" "B.Cu")
		(net "GND")
	)
	(via
		(at 1.397 -72.768968)
		(size 0.7112)
		(drill 0.4064)
		(layers "F.Cu" "B.Cu")
		(net "GND")
	)
	(via
		(at 113.302796 -174.603918)
		(size 0.5588)
		(drill 0.3048)
		(layers "F.Cu" "B.Cu")
		(net "GND")
	)
	(via
		(at 49.129442 -289.80003)
		(size 0.5588)
		(drill 0.3048)
		(layers "F.Cu" "B.Cu")
		(net "GND")
	)
	(via
		(at 457.699872 -191.158876)
		(size 0.5588)
		(drill 0.3048)
		(layers "F.Cu" "B.Cu")
		(net "GND")
	)
	(via
		(at 309.824882 -347.802962)
		(size 0.7112)
		(drill 0.4064)
		(layers "F.Cu" "B.Cu")
		(net "GND")
	)
	(via
		(at 46.740318 -241.582448)
		(size 0.5588)
		(drill 0.3048)
		(layers "F.Cu" "B.Cu")
		(net "GND")
	)
	(via
		(at 399.542 -143.637)
		(size 0.5588)
		(drill 0.3048)
		(layers "F.Cu" "B.Cu")
		(net "GND")
	)
	(via
		(at 363.655102 -271.315942)
		(size 0.5588)
		(drill 0.3048)
		(layers "F.Cu" "B.Cu")
		(net "GND")
	)
	(via
		(at 394.56995 -76.113894)
		(size 0.5588)
		(drill 0.3048)
		(layers "F.Cu" "B.Cu")
		(net "GND")
	)
	(via
		(at 1.397 -136.268968)
		(size 0.7112)
		(drill 0.4064)
		(layers "F.Cu" "B.Cu")
		(net "GND")
	)
	(via
		(at 490.053122 -9.27735)
		(size 0.7112)
		(drill 0.4064)
		(layers "F.Cu" "B.Cu")
		(net "GND")
	)
	(via
		(at 37.975032 -1.397)
		(size 0.7112)
		(drill 0.4064)
		(layers "F.Cu" "B.Cu")
		(net "GND")
	)
	(via
		(at 490.053122 -80.39735)
		(size 0.7112)
		(drill 0.4064)
		(layers "F.Cu" "B.Cu")
		(net "GND")
	)
	(via
		(at 1.397 -326.768968)
		(size 0.7112)
		(drill 0.4064)
		(layers "F.Cu" "B.Cu")
		(net "GND")
	)
	(via
		(at 4.445 -317.5)
		(size 0.5588)
		(drill 0.3048)
		(layers "F.Cu" "B.Cu")
		(net "GND")
	)
	(via
		(at 151.384 -14.351)
		(size 0.7112)
		(drill 0.4064)
		(layers "F.Cu" "B.Cu")
		(net "GND")
	)
	(via
		(at 39.043864 -298.397422)
		(size 0.5588)
		(drill 0.3048)
		(layers "F.Cu" "B.Cu")
		(net "GND")
	)
	(via
		(at 60.96 -5.08)
		(size 0.5588)
		(drill 0.3048)
		(layers "F.Cu" "B.Cu")
		(net "GND")
	)
	(via
		(at 467.466426 -240.171478)
		(size 0.5588)
		(drill 0.3048)
		(layers "F.Cu" "B.Cu")
		(net "GND")
	)
	(via
		(at 155.993084 -1.397)
		(size 0.7112)
		(drill 0.4064)
		(layers "F.Cu" "B.Cu")
		(net "GND")
	)
	(via
		(at 1.397 -11.808968)
		(size 0.7112)
		(drill 0.4064)
		(layers "F.Cu" "B.Cu")
		(net "GND")
	)
	(via
		(at 30.48 -116.84)
		(size 0.5588)
		(drill 0.3048)
		(layers "F.Cu" "B.Cu")
		(net "GND")
	)
	(via
		(at 422.854882 -347.802962)
		(size 0.7112)
		(drill 0.4064)
		(layers "F.Cu" "B.Cu")
		(net "GND")
	)
	(via
		(at 279.615138 -230.026718)
		(size 0.5588)
		(drill 0.3048)
		(layers "F.Cu" "B.Cu")
		(net "GND")
	)
	(via
		(at 268.859 -93.599)
		(size 0.5588)
		(drill 0.3048)
		(layers "F.Cu" "B.Cu")
		(net "GND")
	)
	(via
		(at 55.88 -101.6)
		(size 0.5588)
		(drill 0.3048)
		(layers "F.Cu" "B.Cu")
		(net "GND")
	)
	(via
		(at 288.911284 -263.702292)
		(size 0.6604)
		(drill 0.3556)
		(layers "F.Cu" "B.Cu")
		(net "GND")
	)
	(via
		(at 67.37985 -153.008584)
		(size 0.5588)
		(drill 0.3048)
		(layers "F.Cu" "B.Cu")
		(net "GND")
	)
	(via
		(at 89.662 -312.674)
		(size 0.5588)
		(drill 0.3048)
		(layers "F.Cu" "B.Cu")
		(net "GND")
	)
	(via
		(at 7.685024 -283.649674)
		(size 0.5588)
		(drill 0.3048)
		(layers "F.Cu" "B.Cu")
		(net "GND")
	)
	(via
		(at 247.396 -132.842)
		(size 0.5588)
		(drill 0.3048)
		(layers "F.Cu" "B.Cu")
		(net "GND")
	)
	(via
		(at 483.404926 -299.975016)
		(size 0.5588)
		(drill 0.3048)
		(layers "F.Cu" "B.Cu")
		(net "GND")
	)
	(via
		(at 132.969 -224.409)
		(size 0.5588)
		(drill 0.3048)
		(layers "F.Cu" "B.Cu")
		(net "GND")
	)
	(via
		(at 41.683178 -130.132074)
		(size 0.5588)
		(drill 0.3048)
		(layers "F.Cu" "B.Cu")
		(net "GND")
	)
	(via
		(at 150.462996 -347.802962)
		(size 0.7112)
		(drill 0.4064)
		(layers "F.Cu" "B.Cu")
		(net "GND")
	)
	(via
		(at 221.651068 14.11605)
		(size 0.7112)
		(drill 0.4064)
		(layers "F.Cu" "B.Cu")
		(net "GND")
	)
	(via
		(at 482.261926 -285.230062)
		(size 0.5588)
		(drill 0.3048)
		(layers "F.Cu" "B.Cu")
		(net "GND")
	)
	(via
		(at 308.602888 -395.641068)
		(size 0.7112)
		(drill 0.4064)
		(layers "F.Cu" "B.Cu")
		(net "GND")
	)
	(via
		(at 74.262996 -347.802962)
		(size 0.7112)
		(drill 0.4064)
		(layers "F.Cu" "B.Cu")
		(net "GND")
	)
	(via
		(at 1.397 -93.088968)
		(size 0.7112)
		(drill 0.4064)
		(layers "F.Cu" "B.Cu")
		(net "GND")
	)
	(via
		(at 1.397 -175.638968)
		(size 0.7112)
		(drill 0.4064)
		(layers "F.Cu" "B.Cu")
		(net "GND")
	)
	(via
		(at 233.3752 -389.763)
		(size 0.5588)
		(drill 0.3048)
		(layers "F.Cu" "B.Cu")
		(net "GND")
	)
	(via
		(at 184.912 -55.230014)
		(size 0.5588)
		(drill 0.3048)
		(layers "F.Cu" "B.Cu")
		(net "GND")
	)
	(via
		(at 222.057976 -11.41349)
		(size 0.5588)
		(drill 0.3048)
		(layers "F.Cu" "B.Cu")
		(net "GND")
	)
	(via
		(at 362.715302 -161.649918)
		(size 0.5588)
		(drill 0.3048)
		(layers "F.Cu" "B.Cu")
		(net "GND")
	)
	(via
		(at 283.504386 -221.14002)
		(size 0.5588)
		(drill 0.3048)
		(layers "F.Cu" "B.Cu")
		(net "GND")
	)
	(via
		(at 478.74809 -271.1196)
		(size 0.5588)
		(drill 0.3048)
		(layers "F.Cu" "B.Cu")
		(net "GND")
	)
	(via
		(at 477.766126 -300.322742)
		(size 0.5588)
		(drill 0.3048)
		(layers "F.Cu" "B.Cu")
		(net "GND")
	)
	(via
		(at 416.56 -30.48)
		(size 0.5588)
		(drill 0.3048)
		(layers "F.Cu" "B.Cu")
		(net "GND")
	)
	(via
		(at 450.711824 -50.429922)
		(size 0.5588)
		(drill 0.3048)
		(layers "F.Cu" "B.Cu")
		(net "GND")
	)
	(via
		(at 1.397 -246.758968)
		(size 0.7112)
		(drill 0.4064)
		(layers "F.Cu" "B.Cu")
		(net "GND")
	)
	(via
		(at 165.263576 -304.047652)
		(size 0.5588)
		(drill 0.3048)
		(layers "F.Cu" "B.Cu")
		(net "GND")
	)
	(via
		(at 91.404948 -62.354968)
		(size 0.5588)
		(drill 0.3048)
		(layers "F.Cu" "B.Cu")
		(net "GND")
	)
	(via
		(at 154.723084 -1.397)
		(size 0.7112)
		(drill 0.4064)
		(layers "F.Cu" "B.Cu")
		(net "GND")
	)
	(via
		(at 363.1692 -76.835)
		(size 0.5588)
		(drill 0.3048)
		(layers "F.Cu" "B.Cu")
		(net "GND")
	)
	(via
		(at 426.755052 -41.315894)
		(size 0.5588)
		(drill 0.3048)
		(layers "F.Cu" "B.Cu")
		(net "GND")
	)
	(via
		(at 66.04 -10.16)
		(size 0.5588)
		(drill 0.3048)
		(layers "F.Cu" "B.Cu")
		(net "GND")
	)
	(via
		(at 185.9534 -50.386742)
		(size 0.5588)
		(drill 0.3048)
		(layers "F.Cu" "B.Cu")
		(net "GND")
	)
	(via
		(at 51.402996 -347.802962)
		(size 0.7112)
		(drill 0.4064)
		(layers "F.Cu" "B.Cu")
		(net "GND")
	)
	(via
		(at 303.699672 -182.753)
		(size 0.5588)
		(drill 0.3048)
		(layers "F.Cu" "B.Cu")
		(net "GND")
	)
	(via
		(at 19.939 -43.053)
		(size 0.5588)
		(drill 0.3048)
		(layers "F.Cu" "B.Cu")
		(net "GND")
	)
	(via
		(at 154.504898 -184.974992)
		(size 0.5588)
		(drill 0.3048)
		(layers "F.Cu" "B.Cu")
		(net "GND")
	)
	(via
		(at 258.826 -299.212)
		(size 0.5588)
		(drill 0.3048)
		(layers "F.Cu" "B.Cu")
		(net "GND")
	)
	(via
		(at 222.8596 -174.9552)
		(size 0.5588)
		(drill 0.3048)
		(layers "F.Cu" "B.Cu")
		(net "GND")
	)
	(via
		(at 469.516714 -209.241898)
		(size 0.5588)
		(drill 0.3048)
		(layers "F.Cu" "B.Cu")
		(net "GND")
	)
	(via
		(at 388.754874 -292.355016)
		(size 0.5588)
		(drill 0.3048)
		(layers "F.Cu" "B.Cu")
		(net "GND")
	)
	(via
		(at 58.42 -330.2)
		(size 0.5588)
		(drill 0.3048)
		(layers "F.Cu" "B.Cu")
		(net "GND")
	)
	(via
		(at 93.98 -132.08)
		(size 0.5588)
		(drill 0.3048)
		(layers "F.Cu" "B.Cu")
		(net "GND")
	)
	(via
		(at 451.854824 -160.844992)
		(size 0.5588)
		(drill 0.3048)
		(layers "F.Cu" "B.Cu")
		(net "GND")
	)
	(via
		(at 70.59422 -298.450254)
		(size 0.5588)
		(drill 0.3048)
		(layers "F.Cu" "B.Cu")
		(net "GND")
	)
	(via
		(at 160.622996 -347.802962)
		(size 0.7112)
		(drill 0.4064)
		(layers "F.Cu" "B.Cu")
		(net "GND")
	)
	(via
		(at 490.053122 -113.41735)
		(size 0.7112)
		(drill 0.4064)
		(layers "F.Cu" "B.Cu")
		(net "GND")
	)
	(via
		(at 439.42 -196.85)
		(size 0.5588)
		(drill 0.3048)
		(layers "F.Cu" "B.Cu")
		(net "GND")
	)
	(via
		(at 13.845032 -1.397)
		(size 0.7112)
		(drill 0.4064)
		(layers "F.Cu" "B.Cu")
		(net "GND")
	)
	(via
		(at 250.317 -155.829)
		(size 0.5588)
		(drill 0.3048)
		(layers "F.Cu" "B.Cu")
		(net "GND")
	)
	(via
		(at 1.397 -180.718968)
		(size 0.7112)
		(drill 0.4064)
		(layers "F.Cu" "B.Cu")
		(net "GND")
	)
	(via
		(at 490.053122 -285.461202)
		(size 0.7112)
		(drill 0.4064)
		(layers "F.Cu" "B.Cu")
		(net "GND")
	)
	(via
		(at 485.084882 -347.802962)
		(size 0.7112)
		(drill 0.4064)
		(layers "F.Cu" "B.Cu")
		(net "GND")
	)
	(via
		(at 1.397 -296.288968)
		(size 0.7112)
		(drill 0.4064)
		(layers "F.Cu" "B.Cu")
		(net "GND")
	)
	(via
		(at 426.72 -325.12)
		(size 0.5588)
		(drill 0.3048)
		(layers "F.Cu" "B.Cu")
		(net "GND")
	)
	(via
		(at 55.88 -106.68)
		(size 0.5588)
		(drill 0.3048)
		(layers "F.Cu" "B.Cu")
		(net "GND")
	)
	(via
		(at 388.656068 -60.457334)
		(size 0.5588)
		(drill 0.3048)
		(layers "F.Cu" "B.Cu")
		(net "GND")
	)
	(via
		(at 100.34905 -4.734306)
		(size 0.7112)
		(drill 0.4064)
		(layers "F.Cu" "B.Cu")
		(net "GND")
	)
	(via
		(at 81.752948 -174.603918)
		(size 0.5588)
		(drill 0.3048)
		(layers "F.Cu" "B.Cu")
		(net "GND")
	)
	(via
		(at 199.136 -366.522)
		(size 0.5588)
		(drill 0.3048)
		(layers "F.Cu" "B.Cu")
		(net "GND")
	)
	(via
		(at 176.313084 -1.397)
		(size 0.7112)
		(drill 0.4064)
		(layers "F.Cu" "B.Cu")
		(net "GND")
	)
	(via
		(at 288.911284 -318.105282)
		(size 0.6604)
		(drill 0.3556)
		(layers "F.Cu" "B.Cu")
		(net "GND")
	)
	(via
		(at 128.011682 -347.548962)
		(size 0.7112)
		(drill 0.4064)
		(layers "F.Cu" "B.Cu")
		(net "GND")
	)
	(via
		(at 59.854846 -160.844992)
		(size 0.5588)
		(drill 0.3048)
		(layers "F.Cu" "B.Cu")
		(net "GND")
	)
	(via
		(at 260.874002 -216.078562)
		(size 0.5588)
		(drill 0.3048)
		(layers "F.Cu" "B.Cu")
		(net "GND")
	)
	(via
		(at 1.397 -330.578968)
		(size 0.7112)
		(drill 0.4064)
		(layers "F.Cu" "B.Cu")
		(net "GND")
	)
	(via
		(at 421.64 -116.84)
		(size 0.5588)
		(drill 0.3048)
		(layers "F.Cu" "B.Cu")
		(net "GND")
	)
	(via
		(at 473.20962 -1.397)
		(size 0.7112)
		(drill 0.4064)
		(layers "F.Cu" "B.Cu")
		(net "GND")
	)
	(via
		(at 18.796 -272.796)
		(size 0.5588)
		(drill 0.3048)
		(layers "F.Cu" "B.Cu")
		(net "GND")
	)
	(via
		(at 420.304976 -59.814968)
		(size 0.5588)
		(drill 0.3048)
		(layers "F.Cu" "B.Cu")
		(net "GND")
	)
	(via
		(at 50.8 -15.24)
		(size 0.5588)
		(drill 0.3048)
		(layers "F.Cu" "B.Cu")
		(net "GND")
	)
	(via
		(at 78.072996 -347.802962)
		(size 0.7112)
		(drill 0.4064)
		(layers "F.Cu" "B.Cu")
		(net "GND")
	)
	(via
		(at 185.203084 -1.397)
		(size 0.7112)
		(drill 0.4064)
		(layers "F.Cu" "B.Cu")
		(net "GND")
	)
	(via
		(at 294.894 -374.523)
		(size 0.7112)
		(drill 0.4064)
		(layers "F.Cu" "B.Cu")
		(net "GND")
	)
	(via
		(at 472.510104 -231.662986)
		(size 0.5588)
		(drill 0.3048)
		(layers "F.Cu" "B.Cu")
		(net "GND")
	)
	(via
		(at 490.053122 -103.25735)
		(size 0.7112)
		(drill 0.4064)
		(layers "F.Cu" "B.Cu")
		(net "GND")
	)
	(via
		(at 331.359002 -21.414486)
		(size 0.5588)
		(drill 0.3048)
		(layers "F.Cu" "B.Cu")
		(net "GND")
	)
	(via
		(at 434.34 -195.58)
		(size 0.5588)
		(drill 0.3048)
		(layers "F.Cu" "B.Cu")
		(net "GND")
	)
	(via
		(at 133.410706 -131.148074)
		(size 0.5588)
		(drill 0.3048)
		(layers "F.Cu" "B.Cu")
		(net "GND")
	)
	(via
		(at 135.605266 -143.771874)
		(size 0.5588)
		(drill 0.3048)
		(layers "F.Cu" "B.Cu")
		(net "GND")
	)
	(via
		(at 163.613084 -1.397)
		(size 0.7112)
		(drill 0.4064)
		(layers "F.Cu" "B.Cu")
		(net "GND")
	)
	(via
		(at 324.511924 -285.230062)
		(size 0.5588)
		(drill 0.3048)
		(layers "F.Cu" "B.Cu")
		(net "GND")
	)
	(via
		(at 176.403 -62.778894)
		(size 0.5588)
		(drill 0.3048)
		(layers "F.Cu" "B.Cu")
		(net "GND")
	)
	(via
		(at 396.24 -133.35)
		(size 0.5588)
		(drill 0.3048)
		(layers "F.Cu" "B.Cu")
		(net "GND")
	)
	(via
		(at 230.124 -392.0998)
		(size 0.5588)
		(drill 0.3048)
		(layers "F.Cu" "B.Cu")
		(net "GND")
	)
	(via
		(at 383.159 -261.239)
		(size 0.5588)
		(drill 0.3048)
		(layers "F.Cu" "B.Cu")
		(net "GND")
	)
	(via
		(at 28.304998 -289.815016)
		(size 0.5588)
		(drill 0.3048)
		(layers "F.Cu" "B.Cu")
		(net "GND")
	)
	(via
		(at 121.960386 -51.11623)
		(size 0.5588)
		(drill 0.3048)
		(layers "F.Cu" "B.Cu")
		(net "GND")
	)
	(via
		(at 490.053122 -256.251202)
		(size 0.7112)
		(drill 0.4064)
		(layers "F.Cu" "B.Cu")
		(net "GND")
	)
	(via
		(at 436.798974 -254.394716)
		(size 0.5588)
		(drill 0.3048)
		(layers "F.Cu" "B.Cu")
		(net "GND")
	)
	(via
		(at 1.397 -107.058968)
		(size 0.7112)
		(drill 0.4064)
		(layers "F.Cu" "B.Cu")
		(net "GND")
	)
	(via
		(at 420.304976 -184.974992)
		(size 0.5588)
		(drill 0.3048)
		(layers "F.Cu" "B.Cu")
		(net "GND")
	)
	(via
		(at 122.954796 -62.354968)
		(size 0.5588)
		(drill 0.3048)
		(layers "F.Cu" "B.Cu")
		(net "GND")
	)
	(via
		(at 490.053122 -146.43735)
		(size 0.7112)
		(drill 0.4064)
		(layers "F.Cu" "B.Cu")
		(net "GND")
	)
	(via
		(at 10.16 -251.46)
		(size 0.5588)
		(drill 0.3048)
		(layers "F.Cu" "B.Cu")
		(net "GND")
	)
	(via
		(at 91.404948 -279.655016)
		(size 0.5588)
		(drill 0.3048)
		(layers "F.Cu" "B.Cu")
		(net "GND")
	)
	(via
		(at 131.444746 -146.540474)
		(size 0.5588)
		(drill 0.3048)
		(layers "F.Cu" "B.Cu")
		(net "GND")
	)
	(via
		(at 333.0448 -158.855918)
		(size 0.5588)
		(drill 0.3048)
		(layers "F.Cu" "B.Cu")
		(net "GND")
	)
	(via
		(at 259.147056 37.403024)
		(size 0.7112)
		(drill 0.4064)
		(layers "F.Cu" "B.Cu")
		(net "GND")
	)
	(via
		(at 308.602888 -409.611068)
		(size 0.7112)
		(drill 0.4064)
		(layers "F.Cu" "B.Cu")
		(net "GND")
	)
	(via
		(at 220.672914 -375.610628)
		(size 0.5588)
		(drill 0.3048)
		(layers "F.Cu" "B.Cu")
		(net "GND")
	)
	(via
		(at 128.199896 -283.990542)
		(size 0.5588)
		(drill 0.3048)
		(layers "F.Cu" "B.Cu")
		(net "GND")
	)
	(via
		(at 134.239 -272.669)
		(size 0.5588)
		(drill 0.3048)
		(layers "F.Cu" "B.Cu")
		(net "GND")
	)
	(via
		(at 296.334942 -375.397014)
		(size 0.7112)
		(drill 0.4064)
		(layers "F.Cu" "B.Cu")
		(net "GND")
	)
	(via
		(at 382.149858 -31.624778)
		(size 0.6604)
		(drill 0.3556)
		(layers "F.Cu" "B.Cu")
		(net "GND")
	)
	(via
		(at 10.16 -10.16)
		(size 0.5588)
		(drill 0.3048)
		(layers "F.Cu" "B.Cu")
		(net "GND")
	)
	(via
		(at 100.33 -160.274)
		(size 0.5588)
		(drill 0.3048)
		(layers "F.Cu" "B.Cu")
		(net "GND")
	)
	(via
		(at 441.904882 -347.802962)
		(size 0.7112)
		(drill 0.4064)
		(layers "F.Cu" "B.Cu")
		(net "GND")
	)
	(via
		(at 490.053122 -206.12735)
		(size 0.7112)
		(drill 0.4064)
		(layers "F.Cu" "B.Cu")
		(net "GND")
	)
	(via
		(at 325.654924 -289.815016)
		(size 0.5588)
		(drill 0.3048)
		(layers "F.Cu" "B.Cu")
		(net "GND")
	)
	(via
		(at 66.802 -265.938)
		(size 0.5588)
		(drill 0.3048)
		(layers "F.Cu" "B.Cu")
		(net "GND")
	)
	(via
		(at 370.713 -202.311)
		(size 0.5588)
		(drill 0.3048)
		(layers "F.Cu" "B.Cu")
		(net "GND")
	)
	(via
		(at 325.654924 -160.844992)
		(size 0.5588)
		(drill 0.3048)
		(layers "F.Cu" "B.Cu")
		(net "GND")
	)
	(via
		(at 463.79003 -241.541046)
		(size 0.5588)
		(drill 0.3048)
		(layers "F.Cu" "B.Cu")
		(net "GND")
	)
	(via
		(at 48.862996 -347.802962)
		(size 0.7112)
		(drill 0.4064)
		(layers "F.Cu" "B.Cu")
		(net "GND")
	)
	(via
		(at 356.062026 -165.429946)
		(size 0.5588)
		(drill 0.3048)
		(layers "F.Cu" "B.Cu")
		(net "GND")
	)
	(via
		(at 1.397 -278.508968)
		(size 0.7112)
		(drill 0.4064)
		(layers "F.Cu" "B.Cu")
		(net "GND")
	)
	(via
		(at 490.053122 -215.01735)
		(size 0.7112)
		(drill 0.4064)
		(layers "F.Cu" "B.Cu")
		(net "GND")
	)
	(via
		(at 169.5958 -294.683942)
		(size 0.5588)
		(drill 0.3048)
		(layers "F.Cu" "B.Cu")
		(net "GND")
	)
	(via
		(at 10.16 -81.28)
		(size 0.5588)
		(drill 0.3048)
		(layers "F.Cu" "B.Cu")
		(net "GND")
	)
	(via
		(at 366.26038 -102.61346)
		(size 0.5588)
		(drill 0.3048)
		(layers "F.Cu" "B.Cu")
		(net "GND")
	)
	(via
		(at 406.4 -86.36)
		(size 0.5588)
		(drill 0.3048)
		(layers "F.Cu" "B.Cu")
		(net "GND")
	)
	(via
		(at 45.72 -15.24)
		(size 0.5588)
		(drill 0.3048)
		(layers "F.Cu" "B.Cu")
		(net "GND")
	)
	(via
		(at 264.879582 -110.339886)
		(size 0.5588)
		(drill 0.3048)
		(layers "F.Cu" "B.Cu")
		(net "GND")
	)
	(via
		(at 63.747396 -153.113232)
		(size 0.5588)
		(drill 0.3048)
		(layers "F.Cu" "B.Cu")
		(net "GND")
	)
	(via
		(at 480.06 -101.6)
		(size 0.5588)
		(drill 0.3048)
		(layers "F.Cu" "B.Cu")
		(net "GND")
	)
	(via
		(at 24.240998 -76.240894)
		(size 0.5588)
		(drill 0.3048)
		(layers "F.Cu" "B.Cu")
		(net "GND")
	)
	(via
		(at 47.892208 -258.868164)
		(size 0.5588)
		(drill 0.3048)
		(layers "F.Cu" "B.Cu")
		(net "GND")
	)
	(via
		(at 486.354882 -347.802962)
		(size 0.7112)
		(drill 0.4064)
		(layers "F.Cu" "B.Cu")
		(net "GND")
	)
	(via
		(at 55.88 -325.12)
		(size 0.5588)
		(drill 0.3048)
		(layers "F.Cu" "B.Cu")
		(net "GND")
	)
	(via
		(at 45.595032 -1.397)
		(size 0.7112)
		(drill 0.4064)
		(layers "F.Cu" "B.Cu")
		(net "GND")
	)
	(via
		(at 252.73 -115.57)
		(size 0.5588)
		(drill 0.3048)
		(layers "F.Cu" "B.Cu")
		(net "GND")
	)
	(via
		(at 421.64 -330.2)
		(size 0.5588)
		(drill 0.3048)
		(layers "F.Cu" "B.Cu")
		(net "GND")
	)
	(via
		(at 452.12 -132.08)
		(size 0.5588)
		(drill 0.3048)
		(layers "F.Cu" "B.Cu")
		(net "GND")
	)
	(via
		(at 111.76 -142.24)
		(size 0.5588)
		(drill 0.3048)
		(layers "F.Cu" "B.Cu")
		(net "GND")
	)
	(via
		(at 416.56 -20.32)
		(size 0.5588)
		(drill 0.3048)
		(layers "F.Cu" "B.Cu")
		(net "GND")
	)
	(via
		(at 407.16962 -1.397)
		(size 0.7112)
		(drill 0.4064)
		(layers "F.Cu" "B.Cu")
		(net "GND")
	)
	(via
		(at 319.121028 -1.397)
		(size 0.7112)
		(drill 0.4064)
		(layers "F.Cu" "B.Cu")
		(net "GND")
	)
	(via
		(at 133.674358 -180.486812)
		(size 0.5588)
		(drill 0.3048)
		(layers "F.Cu" "B.Cu")
		(net "GND")
	)
	(via
		(at 477.550988 -242.331748)
		(size 0.5588)
		(drill 0.3048)
		(layers "F.Cu" "B.Cu")
		(net "GND")
	)
	(via
		(at 186.055 -45.844968)
		(size 0.5588)
		(drill 0.3048)
		(layers "F.Cu" "B.Cu")
		(net "GND")
	)
	(via
		(at 8.631682 -347.548962)
		(size 0.7112)
		(drill 0.4064)
		(layers "F.Cu" "B.Cu")
		(net "GND")
	)
	(via
		(at 50.202846 -292.778942)
		(size 0.5588)
		(drill 0.3048)
		(layers "F.Cu" "B.Cu")
		(net "GND")
	)
	(via
		(at 468.12962 -1.397)
		(size 0.7112)
		(drill 0.4064)
		(layers "F.Cu" "B.Cu")
		(net "GND")
	)
	(via
		(at 55.88 -332.74)
		(size 0.5588)
		(drill 0.3048)
		(layers "F.Cu" "B.Cu")
		(net "GND")
	)
	(via
		(at 420.304976 -42.034968)
		(size 0.5588)
		(drill 0.3048)
		(layers "F.Cu" "B.Cu")
		(net "GND")
	)
	(via
		(at 447.04 -15.24)
		(size 0.5588)
		(drill 0.3048)
		(layers "F.Cu" "B.Cu")
		(net "GND")
	)
	(via
		(at 436.88 -86.36)
		(size 0.5588)
		(drill 0.3048)
		(layers "F.Cu" "B.Cu")
		(net "GND")
	)
	(via
		(at 231.394 -77.597)
		(size 0.5588)
		(drill 0.3048)
		(layers "F.Cu" "B.Cu")
		(net "GND")
	)
	(via
		(at 63.375032 -1.397)
		(size 0.7112)
		(drill 0.4064)
		(layers "F.Cu" "B.Cu")
		(net "GND")
	)
	(via
		(at 360.624882 -347.802962)
		(size 0.7112)
		(drill 0.4064)
		(layers "F.Cu" "B.Cu")
		(net "GND")
	)
	(via
		(at 459.9559 -67.223894)
		(size 0.5588)
		(drill 0.3048)
		(layers "F.Cu" "B.Cu")
		(net "GND")
	)
	(via
		(at 333.091028 -1.397)
		(size 0.7112)
		(drill 0.4064)
		(layers "F.Cu" "B.Cu")
		(net "GND")
	)
	(via
		(at 372.0338 -148.7424)
		(size 0.5588)
		(drill 0.3048)
		(layers "F.Cu" "B.Cu")
		(net "GND")
	)
	(via
		(at 221.651068 9.03605)
		(size 0.7112)
		(drill 0.4064)
		(layers "F.Cu" "B.Cu")
		(net "GND")
	)
	(via
		(at 150.440898 -191.240918)
		(size 0.5588)
		(drill 0.3048)
		(layers "F.Cu" "B.Cu")
		(net "GND")
	)
	(via
		(at 134.112 -155.194)
		(size 0.5588)
		(drill 0.3048)
		(layers "F.Cu" "B.Cu")
		(net "GND")
	)
	(via
		(at 457.144882 -347.802962)
		(size 0.7112)
		(drill 0.4064)
		(layers "F.Cu" "B.Cu")
		(net "GND")
	)
	(via
		(at 178.917346 -158.140146)
		(size 0.7112)
		(drill 0.4064)
		(layers "F.Cu" "B.Cu")
		(net "GND")
	)
	(via
		(at 319.984882 -347.802962)
		(size 0.7112)
		(drill 0.4064)
		(layers "F.Cu" "B.Cu")
		(net "GND")
	)
	(via
		(at 99.06 -137.16)
		(size 0.5588)
		(drill 0.3048)
		(layers "F.Cu" "B.Cu")
		(net "GND")
	)
	(via
		(at 483.404926 -177.354992)
		(size 0.5588)
		(drill 0.3048)
		(layers "F.Cu" "B.Cu")
		(net "GND")
	)
	(via
		(at 135.97128 -292.803834)
		(size 0.5588)
		(drill 0.3048)
		(layers "F.Cu" "B.Cu")
		(net "GND")
	)
	(via
		(at 122.954796 -299.975016)
		(size 0.5588)
		(drill 0.3048)
		(layers "F.Cu" "B.Cu")
		(net "GND")
	)
	(via
		(at 490.053122 -58.80735)
		(size 0.7112)
		(drill 0.4064)
		(layers "F.Cu" "B.Cu")
		(net "GND")
	)
	(via
		(at 29.4132 -248.7168)
		(size 0.5588)
		(drill 0.3048)
		(layers "F.Cu" "B.Cu")
		(net "GND")
	)
	(via
		(at 462.28 -116.84)
		(size 0.5588)
		(drill 0.3048)
		(layers "F.Cu" "B.Cu")
		(net "GND")
	)
	(via
		(at 308.602888 -405.801068)
		(size 0.7112)
		(drill 0.4064)
		(layers "F.Cu" "B.Cu")
		(net "GND")
	)
	(via
		(at 1.397 -334.388968)
		(size 0.7112)
		(drill 0.4064)
		(layers "F.Cu" "B.Cu")
		(net "GND")
	)
	(via
		(at 1.397 -289.938968)
		(size 0.7112)
		(drill 0.4064)
		(layers "F.Cu" "B.Cu")
		(net "GND")
	)
	(via
		(at 413.401002 -287.54705)
		(size 0.5588)
		(drill 0.3048)
		(layers "F.Cu" "B.Cu")
		(net "GND")
	)
	(via
		(at 441.45962 -1.397)
		(size 0.7112)
		(drill 0.4064)
		(layers "F.Cu" "B.Cu")
		(net "GND")
	)
	(via
		(at 476.194882 -347.802962)
		(size 0.7112)
		(drill 0.4064)
		(layers "F.Cu" "B.Cu")
		(net "GND")
	)
	(via
		(at 132.08 -152.4)
		(size 0.5588)
		(drill 0.3048)
		(layers "F.Cu" "B.Cu")
		(net "GND")
	)
	(via
		(at 346.349066 -6.304534)
		(size 0.7112)
		(drill 0.4064)
		(layers "F.Cu" "B.Cu")
		(net "GND")
	)
	(via
		(at 221.651068 26.81605)
		(size 0.7112)
		(drill 0.4064)
		(layers "F.Cu" "B.Cu")
		(net "GND")
	)
	(via
		(at 39.208202 -295.07815)
		(size 0.5588)
		(drill 0.3048)
		(layers "F.Cu" "B.Cu")
		(net "GND")
	)
	(via
		(at 328.011028 -1.397)
		(size 0.7112)
		(drill 0.4064)
		(layers "F.Cu" "B.Cu")
		(net "GND")
	)
	(via
		(at 325.700898 -61.846206)
		(size 0.5588)
		(drill 0.3048)
		(layers "F.Cu" "B.Cu")
		(net "GND")
	)
	(via
		(at 29.4132 -250.7488)
		(size 0.5588)
		(drill 0.3048)
		(layers "F.Cu" "B.Cu")
		(net "GND")
	)
	(via
		(at 365.306102 -297.223942)
		(size 0.5588)
		(drill 0.3048)
		(layers "F.Cu" "B.Cu")
		(net "GND")
	)
	(via
		(at 59.854846 -182.434992)
		(size 0.5588)
		(drill 0.3048)
		(layers "F.Cu" "B.Cu")
		(net "GND")
	)
	(via
		(at 480.06 -96.52)
		(size 0.5588)
		(drill 0.3048)
		(layers "F.Cu" "B.Cu")
		(net "GND")
	)
	(via
		(at 158.533084 -1.397)
		(size 0.7112)
		(drill 0.4064)
		(layers "F.Cu" "B.Cu")
		(net "GND")
	)
	(via
		(at 268.732 -156.464)
		(size 0.5588)
		(drill 0.3048)
		(layers "F.Cu" "B.Cu")
		(net "GND")
	)
	(via
		(at 105.151682 -347.548962)
		(size 0.7112)
		(drill 0.4064)
		(layers "F.Cu" "B.Cu")
		(net "GND")
	)
	(via
		(at 93.98 -127)
		(size 0.5588)
		(drill 0.3048)
		(layers "F.Cu" "B.Cu")
		(net "GND")
	)
	(via
		(at 444.0174 -290.238942)
		(size 0.5588)
		(drill 0.3048)
		(layers "F.Cu" "B.Cu")
		(net "GND")
	)
	(via
		(at 483.404926 -67.434968)
		(size 0.5588)
		(drill 0.3048)
		(layers "F.Cu" "B.Cu")
		(net "GND")
	)
	(via
		(at 45.72 -86.36)
		(size 0.5588)
		(drill 0.3048)
		(layers "F.Cu" "B.Cu")
		(net "GND")
	)
	(via
		(at 79.885032 -1.397)
		(size 0.7112)
		(drill 0.4064)
		(layers "F.Cu" "B.Cu")
		(net "GND")
	)
	(via
		(at 111.125 -188.976)
		(size 0.5588)
		(drill 0.3048)
		(layers "F.Cu" "B.Cu")
		(net "GND")
	)
	(via
		(at 387.611874 -55.230014)
		(size 0.5588)
		(drill 0.3048)
		(layers "F.Cu" "B.Cu")
		(net "GND")
	)
	(via
		(at 447.04 -86.36)
		(size 0.5588)
		(drill 0.3048)
		(layers "F.Cu" "B.Cu")
		(net "GND")
	)
	(via
		(at 35.65779 -145.46072)
		(size 0.6096)
		(drill 0.3048)
		(layers "F.Cu" "B.Cu")
		(net "GND")
	)
	(via
		(at 490.053122 -204.85735)
		(size 0.7112)
		(drill 0.4064)
		(layers "F.Cu" "B.Cu")
		(net "GND")
	)
	(via
		(at 53.34 -163.576)
		(size 0.5588)
		(drill 0.3048)
		(layers "F.Cu" "B.Cu")
		(net "GND")
	)
	(via
		(at 392.91895 -76.113894)
		(size 0.5588)
		(drill 0.3048)
		(layers "F.Cu" "B.Cu")
		(net "GND")
	)
	(via
		(at 228.32568 -259.08)
		(size 0.5588)
		(drill 0.3048)
		(layers "F.Cu" "B.Cu")
		(net "GND")
	)
	(via
		(at 50.409602 -241.56035)
		(size 0.5588)
		(drill 0.3048)
		(layers "F.Cu" "B.Cu")
		(net "GND")
	)
	(via
		(at 90.261948 -282.830016)
		(size 0.5588)
		(drill 0.3048)
		(layers "F.Cu" "B.Cu")
		(net "GND")
	)
	(via
		(at 53.555646 -279.494742)
		(size 0.5588)
		(drill 0.3048)
		(layers "F.Cu" "B.Cu")
		(net "GND")
	)
	(via
		(at 62.105032 -1.397)
		(size 0.7112)
		(drill 0.4064)
		(layers "F.Cu" "B.Cu")
		(net "GND")
	)
	(via
		(at 459.7019 -76.113894)
		(size 0.5588)
		(drill 0.3048)
		(layers "F.Cu" "B.Cu")
		(net "GND")
	)
	(via
		(at 228.667056 37.403024)
		(size 0.7112)
		(drill 0.4064)
		(layers "F.Cu" "B.Cu")
		(net "GND")
	)
	(via
		(at 298.602908 36.218876)
		(size 0.7112)
		(drill 0.4064)
		(layers "F.Cu" "B.Cu")
		(net "GND")
	)
	(via
		(at 482.6 -325.12)
		(size 0.5588)
		(drill 0.3048)
		(layers "F.Cu" "B.Cu")
		(net "GND")
	)
	(via
		(at 148.971 -269.621)
		(size 0.5588)
		(drill 0.3048)
		(layers "F.Cu" "B.Cu")
		(net "GND")
	)
	(via
		(at 426.72 -116.84)
		(size 0.5588)
		(drill 0.3048)
		(layers "F.Cu" "B.Cu")
		(net "GND")
	)
	(via
		(at 490.053122 -254.981202)
		(size 0.7112)
		(drill 0.4064)
		(layers "F.Cu" "B.Cu")
		(net "GND")
	)
	(via
		(at 28.304998 -272.035016)
		(size 0.5588)
		(drill 0.3048)
		(layers "F.Cu" "B.Cu")
		(net "GND")
	)
	(via
		(at 1.397 -185.798968)
		(size 0.7112)
		(drill 0.4064)
		(layers "F.Cu" "B.Cu")
		(net "GND")
	)
	(via
		(at 283.277056 37.403024)
		(size 0.7112)
		(drill 0.4064)
		(layers "F.Cu" "B.Cu")
		(net "GND")
	)
	(via
		(at 331.414882 -347.802962)
		(size 0.7112)
		(drill 0.4064)
		(layers "F.Cu" "B.Cu")
		(net "GND")
	)
	(via
		(at 490.053122 -152.78735)
		(size 0.7112)
		(drill 0.4064)
		(layers "F.Cu" "B.Cu")
		(net "GND")
	)
	(via
		(at 383.159 -266.827)
		(size 0.5588)
		(drill 0.3048)
		(layers "F.Cu" "B.Cu")
		(net "GND")
	)
	(via
		(at 329.819 -191.113918)
		(size 0.5588)
		(drill 0.3048)
		(layers "F.Cu" "B.Cu")
		(net "GND")
	)
	(via
		(at 6.35 -269.24)
		(size 0.5588)
		(drill 0.3048)
		(layers "F.Cu" "B.Cu")
		(net "GND")
	)
	(via
		(at 490.053122 -203.58735)
		(size 0.7112)
		(drill 0.4064)
		(layers "F.Cu" "B.Cu")
		(net "GND")
	)
	(via
		(at 1.397 -240.408968)
		(size 0.7112)
		(drill 0.4064)
		(layers "F.Cu" "B.Cu")
		(net "GND")
	)
	(via
		(at 201.397108 -380.482856)
		(size 0.7112)
		(drill 0.4064)
		(layers "F.Cu" "B.Cu")
		(net "GND")
	)
	(via
		(at 283.85389 29.249878)
		(size 0.5588)
		(drill 0.3048)
		(layers "F.Cu" "B.Cu")
		(net "GND")
	)
	(via
		(at 150.876 -15.621)
		(size 0.7112)
		(drill 0.4064)
		(layers "F.Cu" "B.Cu")
		(net "GND")
	)
	(via
		(at 431.744882 -347.802962)
		(size 0.7112)
		(drill 0.4064)
		(layers "F.Cu" "B.Cu")
		(net "GND")
	)
	(via
		(at 122.954796 -275.845016)
		(size 0.5588)
		(drill 0.3048)
		(layers "F.Cu" "B.Cu")
		(net "GND")
	)
	(via
		(at 484.631746 -214.977472)
		(size 0.5588)
		(drill 0.3048)
		(layers "F.Cu" "B.Cu")
		(net "GND")
	)
	(via
		(at 482.6 -25.4)
		(size 0.5588)
		(drill 0.3048)
		(layers "F.Cu" "B.Cu")
		(net "GND")
	)
	(via
		(at 96.395032 -1.397)
		(size 0.7112)
		(drill 0.4064)
		(layers "F.Cu" "B.Cu")
		(net "GND")
	)
	(via
		(at 305.586892 -419.803072)
		(size 0.7112)
		(drill 0.4064)
		(layers "F.Cu" "B.Cu")
		(net "GND")
	)
	(via
		(at 298.602908 19.708876)
		(size 0.7112)
		(drill 0.4064)
		(layers "F.Cu" "B.Cu")
		(net "GND")
	)
	(via
		(at 58.42 -327.66)
		(size 0.5588)
		(drill 0.3048)
		(layers "F.Cu" "B.Cu")
		(net "GND")
	)
	(via
		(at 316.581028 -1.397)
		(size 0.7112)
		(drill 0.4064)
		(layers "F.Cu" "B.Cu")
		(net "GND")
	)
	(via
		(at 1.397 -192.148968)
		(size 0.7112)
		(drill 0.4064)
		(layers "F.Cu" "B.Cu")
		(net "GND")
	)
	(via
		(at 186.022996 -347.802962)
		(size 0.7112)
		(drill 0.4064)
		(layers "F.Cu" "B.Cu")
		(net "GND")
	)
	(via
		(at 122.954796 -297.435016)
		(size 0.5588)
		(drill 0.3048)
		(layers "F.Cu" "B.Cu")
		(net "GND")
	)
	(via
		(at 162.179 -265.811)
		(size 0.5588)
		(drill 0.3048)
		(layers "F.Cu" "B.Cu")
		(net "GND")
	)
	(via
		(at 66.27114 -154.389582)
		(size 0.5588)
		(drill 0.3048)
		(layers "F.Cu" "B.Cu")
		(net "GND")
	)
	(via
		(at 331.47 -306.113942)
		(size 0.5588)
		(drill 0.3048)
		(layers "F.Cu" "B.Cu")
		(net "GND")
	)
	(via
		(at 490.053122 -10.54735)
		(size 0.7112)
		(drill 0.4064)
		(layers "F.Cu" "B.Cu")
		(net "GND")
	)
	(via
		(at 346.349066 -3.764534)
		(size 0.7112)
		(drill 0.4064)
		(layers "F.Cu" "B.Cu")
		(net "GND")
	)
	(via
		(at 402.534882 -347.802962)
		(size 0.7112)
		(drill 0.4064)
		(layers "F.Cu" "B.Cu")
		(net "GND")
	)
	(via
		(at 426.120052 -76.113894)
		(size 0.5588)
		(drill 0.3048)
		(layers "F.Cu" "B.Cu")
		(net "GND")
	)
	(via
		(at 28.304998 -160.844992)
		(size 0.5588)
		(drill 0.3048)
		(layers "F.Cu" "B.Cu")
		(net "GND")
	)
	(via
		(at 10.16 -86.36)
		(size 0.5588)
		(drill 0.3048)
		(layers "F.Cu" "B.Cu")
		(net "GND")
	)
	(via
		(at 265.34872 -234.0356)
		(size 0.5588)
		(drill 0.3048)
		(layers "F.Cu" "B.Cu")
		(net "GND")
	)
	(via
		(at 183.274208 -241.634518)
		(size 0.7112)
		(drill 0.4064)
		(layers "F.Cu" "B.Cu")
		(net "GND")
	)
	(via
		(at 482.6 -30.48)
		(size 0.5588)
		(drill 0.3048)
		(layers "F.Cu" "B.Cu")
		(net "GND")
	)
	(via
		(at 59.854846 -174.814992)
		(size 0.5588)
		(drill 0.3048)
		(layers "F.Cu" "B.Cu")
		(net "GND")
	)
	(via
		(at 308.602888 -386.751068)
		(size 0.7112)
		(drill 0.4064)
		(layers "F.Cu" "B.Cu")
		(net "GND")
	)
	(via
		(at 22.098 -137.414)
		(size 0.5588)
		(drill 0.3048)
		(layers "F.Cu" "B.Cu")
		(net "GND")
	)
	(via
		(at 153.361898 -167.829992)
		(size 0.5588)
		(drill 0.3048)
		(layers "F.Cu" "B.Cu")
		(net "GND")
	)
	(via
		(at 132.682996 -347.802962)
		(size 0.7112)
		(drill 0.4064)
		(layers "F.Cu" "B.Cu")
		(net "GND")
	)
	(via
		(at 122.954796 -59.814968)
		(size 0.5588)
		(drill 0.3048)
		(layers "F.Cu" "B.Cu")
		(net "GND")
	)
	(via
		(at 325.654924 -164.654992)
		(size 0.5588)
		(drill 0.3048)
		(layers "F.Cu" "B.Cu")
		(net "GND")
	)
	(via
		(at 60.96 -30.48)
		(size 0.5588)
		(drill 0.3048)
		(layers "F.Cu" "B.Cu")
		(net "GND")
	)
	(via
		(at 1.397 -189.608968)
		(size 0.7112)
		(drill 0.4064)
		(layers "F.Cu" "B.Cu")
		(net "GND")
	)
	(via
		(at 306.011072 -22.699472)
		(size 0.5588)
		(drill 0.3048)
		(layers "F.Cu" "B.Cu")
		(net "GND")
	)
	(via
		(at 25.4 -137.541)
		(size 0.5588)
		(drill 0.3048)
		(layers "F.Cu" "B.Cu")
		(net "GND")
	)
	(via
		(at 1.397 -20.698968)
		(size 0.7112)
		(drill 0.4064)
		(layers "F.Cu" "B.Cu")
		(net "GND")
	)
	(via
		(at 54.216046 -70.322694)
		(size 0.5588)
		(drill 0.3048)
		(layers "F.Cu" "B.Cu")
		(net "GND")
	)
	(via
		(at 490.053122 -288.001202)
		(size 0.7112)
		(drill 0.4064)
		(layers "F.Cu" "B.Cu")
		(net "GND")
	)
	(via
		(at 205.74 -302.641)
		(size 0.5588)
		(drill 0.3048)
		(layers "F.Cu" "B.Cu")
		(net "GND")
	)
	(via
		(at 7.797038 -172.606462)
		(size 0.5588)
		(drill 0.3048)
		(layers "F.Cu" "B.Cu")
		(net "GND")
	)
	(via
		(at 325.3232 -42.4688)
		(size 0.5588)
		(drill 0.3048)
		(layers "F.Cu" "B.Cu")
		(net "GND")
	)
	(via
		(at 426.72 -335.28)
		(size 0.5588)
		(drill 0.3048)
		(layers "F.Cu" "B.Cu")
		(net "GND")
	)
	(via
		(at 397.383 -236.474)
		(size 0.5588)
		(drill 0.3048)
		(layers "F.Cu" "B.Cu")
		(net "GND")
	)
	(via
		(at 221.651068 24.27605)
		(size 0.7112)
		(drill 0.4064)
		(layers "F.Cu" "B.Cu")
		(net "GND")
	)
	(via
		(at 441.96 -81.28)
		(size 0.5588)
		(drill 0.3048)
		(layers "F.Cu" "B.Cu")
		(net "GND")
	)
	(via
		(at 298.602908 5.738876)
		(size 0.7112)
		(drill 0.4064)
		(layers "F.Cu" "B.Cu")
		(net "GND")
	)
	(via
		(at 20.828 -55.626)
		(size 0.5588)
		(drill 0.3048)
		(layers "F.Cu" "B.Cu")
		(net "GND")
	)
	(via
		(at 327.432924 -151.035004)
		(size 0.5588)
		(drill 0.3048)
		(layers "F.Cu" "B.Cu")
		(net "GND")
	)
	(via
		(at 439.42 -180.34)
		(size 0.5588)
		(drill 0.3048)
		(layers "F.Cu" "B.Cu")
		(net "GND")
	)
	(via
		(at 410.154882 -347.802962)
		(size 0.7112)
		(drill 0.4064)
		(layers "F.Cu" "B.Cu")
		(net "GND")
	)
	(via
		(at 232.378504 -228.861366)
		(size 0.5588)
		(drill 0.3048)
		(layers "F.Cu" "B.Cu")
		(net "GND")
	)
	(via
		(at 60.96 -111.76)
		(size 0.5588)
		(drill 0.3048)
		(layers "F.Cu" "B.Cu")
		(net "GND")
	)
	(via
		(at 178.853084 -1.397)
		(size 0.7112)
		(drill 0.4064)
		(layers "F.Cu" "B.Cu")
		(net "GND")
	)
	(via
		(at 1.397 -84.198968)
		(size 0.7112)
		(drill 0.4064)
		(layers "F.Cu" "B.Cu")
		(net "GND")
	)
	(via
		(at 425.394882 -347.802962)
		(size 0.7112)
		(drill 0.4064)
		(layers "F.Cu" "B.Cu")
		(net "GND")
	)
	(via
		(at 475.234 -272.6182)
		(size 0.5588)
		(drill 0.3048)
		(layers "F.Cu" "B.Cu")
		(net "GND")
	)
	(via
		(at 54.216046 -300.322742)
		(size 0.5588)
		(drill 0.3048)
		(layers "F.Cu" "B.Cu")
		(net "GND")
	)
	(via
		(at 317.62065 -246.188992)
		(size 0.5588)
		(drill 0.3048)
		(layers "F.Cu" "B.Cu")
		(net "GND")
	)
	(via
		(at 10.16 -71.12)
		(size 0.5588)
		(drill 0.3048)
		(layers "F.Cu" "B.Cu")
		(net "GND")
	)
	(via
		(at 360.68 -335.28)
		(size 0.5588)
		(drill 0.3048)
		(layers "F.Cu" "B.Cu")
		(net "GND")
	)
	(via
		(at 45.339 -146.1008)
		(size 0.5588)
		(drill 0.3048)
		(layers "F.Cu" "B.Cu")
		(net "GND")
	)
	(via
		(at 1.397 -42.288968)
		(size 0.7112)
		(drill 0.4064)
		(layers "F.Cu" "B.Cu")
		(net "GND")
	)
	(via
		(at 4.445 -342.9)
		(size 0.5588)
		(drill 0.3048)
		(layers "F.Cu" "B.Cu")
		(net "GND")
	)
	(via
		(at 1.397 -265.808968)
		(size 0.7112)
		(drill 0.4064)
		(layers "F.Cu" "B.Cu")
		(net "GND")
	)
	(via
		(at 384.175 -241.046)
		(size 0.5588)
		(drill 0.3048)
		(layers "F.Cu" "B.Cu")
		(net "GND")
	)
	(via
		(at 407.614882 -347.802962)
		(size 0.7112)
		(drill 0.4064)
		(layers "F.Cu" "B.Cu")
		(net "GND")
	)
	(via
		(at 248.2596 -294.1066)
		(size 0.5588)
		(drill 0.3048)
		(layers "F.Cu" "B.Cu")
		(net "GND")
	)
	(via
		(at 276.927056 37.403024)
		(size 0.7112)
		(drill 0.4064)
		(layers "F.Cu" "B.Cu")
		(net "GND")
	)
	(via
		(at 121.661682 -347.548962)
		(size 0.7112)
		(drill 0.4064)
		(layers "F.Cu" "B.Cu")
		(net "GND")
	)
	(via
		(at 186.055 -160.844992)
		(size 0.5588)
		(drill 0.3048)
		(layers "F.Cu" "B.Cu")
		(net "GND")
	)
	(via
		(at 154.504898 -289.815016)
		(size 0.5588)
		(drill 0.3048)
		(layers "F.Cu" "B.Cu")
		(net "GND")
	)
	(via
		(at 30.48 -25.4)
		(size 0.5588)
		(drill 0.3048)
		(layers "F.Cu" "B.Cu")
		(net "GND")
	)
	(via
		(at 99.342448 -290.238942)
		(size 0.5588)
		(drill 0.3048)
		(layers "F.Cu" "B.Cu")
		(net "GND")
	)
	(via
		(at 2.281682 -347.548962)
		(size 0.7112)
		(drill 0.4064)
		(layers "F.Cu" "B.Cu")
		(net "GND")
	)
	(via
		(at 196.633084 -1.397)
		(size 0.7112)
		(drill 0.4064)
		(layers "F.Cu" "B.Cu")
		(net "GND")
	)
	(via
		(at 416.56 -5.08)
		(size 0.5588)
		(drill 0.3048)
		(layers "F.Cu" "B.Cu")
		(net "GND")
	)
	(via
		(at 210.058 -296.672)
		(size 0.5588)
		(drill 0.3048)
		(layers "F.Cu" "B.Cu")
		(net "GND")
	)
	(via
		(at 186.055 -289.815016)
		(size 0.5588)
		(drill 0.3048)
		(layers "F.Cu" "B.Cu")
		(net "GND")
	)
	(via
		(at 380.873 -211.074)
		(size 0.5588)
		(drill 0.3048)
		(layers "F.Cu" "B.Cu")
		(net "GND")
	)
	(via
		(at 91.404948 -49.654968)
		(size 0.5588)
		(drill 0.3048)
		(layers "F.Cu" "B.Cu")
		(net "GND")
	)
	(via
		(at 422.082976 -266.035028)
		(size 0.5588)
		(drill 0.3048)
		(layers "F.Cu" "B.Cu")
		(net "GND")
	)
	(via
		(at 61.562996 -347.802962)
		(size 0.7112)
		(drill 0.4064)
		(layers "F.Cu" "B.Cu")
		(net "GND")
	)
	(via
		(at 308.602888 -399.451068)
		(size 0.7112)
		(drill 0.4064)
		(layers "F.Cu" "B.Cu")
		(net "GND")
	)
	(via
		(at 343.205054 -22.885146)
		(size 0.5588)
		(drill 0.3048)
		(layers "F.Cu" "B.Cu")
		(net "GND")
	)
	(via
		(at 490.053122 -81.66735)
		(size 0.7112)
		(drill 0.4064)
		(layers "F.Cu" "B.Cu")
		(net "GND")
	)
	(via
		(at 45.72 -35.56)
		(size 0.5588)
		(drill 0.3048)
		(layers "F.Cu" "B.Cu")
		(net "GND")
	)
	(via
		(at 35.56 -116.84)
		(size 0.5588)
		(drill 0.3048)
		(layers "F.Cu" "B.Cu")
		(net "GND")
	)
	(via
		(at 64.897 -168.783)
		(size 0.5588)
		(drill 0.3048)
		(layers "F.Cu" "B.Cu")
		(net "GND")
	)
	(via
		(at 116.581682 -347.548962)
		(size 0.7112)
		(drill 0.4064)
		(layers "F.Cu" "B.Cu")
		(net "GND")
	)
	(via
		(at 370.205 -250.825)
		(size 0.5588)
		(drill 0.3048)
		(layers "F.Cu" "B.Cu")
		(net "GND")
	)
	(via
		(at 396.60195 -76.113894)
		(size 0.5588)
		(drill 0.3048)
		(layers "F.Cu" "B.Cu")
		(net "GND")
	)
	(via
		(at 201.397108 -413.502856)
		(size 0.7112)
		(drill 0.4064)
		(layers "F.Cu" "B.Cu")
		(net "GND")
	)
	(via
		(at 490.053122 -94.36735)
		(size 0.7112)
		(drill 0.4064)
		(layers "F.Cu" "B.Cu")
		(net "GND")
	)
	(via
		(at 490.053122 -54.99735)
		(size 0.7112)
		(drill 0.4064)
		(layers "F.Cu" "B.Cu")
		(net "GND")
	)
	(via
		(at 1.397 -336.928968)
		(size 0.7112)
		(drill 0.4064)
		(layers "F.Cu" "B.Cu")
		(net "GND")
	)
	(via
		(at 61.632846 -266.035028)
		(size 0.5588)
		(drill 0.3048)
		(layers "F.Cu" "B.Cu")
		(net "GND")
	)
	(via
		(at 132.5499 -31.624778)
		(size 0.6604)
		(drill 0.3556)
		(layers "F.Cu" "B.Cu")
		(net "GND")
	)
	(via
		(at 5.08 -15.24)
		(size 0.5588)
		(drill 0.3048)
		(layers "F.Cu" "B.Cu")
		(net "GND")
	)
	(via
		(at 178.430682 -240.281206)
		(size 0.7112)
		(drill 0.4064)
		(layers "F.Cu" "B.Cu")
		(net "GND")
	)
	(via
		(at 469.9 -189.23)
		(size 0.5588)
		(drill 0.3048)
		(layers "F.Cu" "B.Cu")
		(net "GND")
	)
	(via
		(at 490.053122 -341.341202)
		(size 0.7112)
		(drill 0.4064)
		(layers "F.Cu" "B.Cu")
		(net "GND")
	)
	(via
		(at 39.054278 -180.505862)
		(size 0.5588)
		(drill 0.3048)
		(layers "F.Cu" "B.Cu")
		(net "GND")
	)
	(via
		(at 490.053122 -171.83735)
		(size 0.7112)
		(drill 0.4064)
		(layers "F.Cu" "B.Cu")
		(net "GND")
	)
	(via
		(at 191.008 -304.165)
		(size 0.5588)
		(drill 0.3048)
		(layers "F.Cu" "B.Cu")
		(net "GND")
	)
	(via
		(at 387.611874 -50.429922)
		(size 0.5588)
		(drill 0.3048)
		(layers "F.Cu" "B.Cu")
		(net "GND")
	)
	(via
		(at 431.8 -330.2)
		(size 0.5588)
		(drill 0.3048)
		(layers "F.Cu" "B.Cu")
		(net "GND")
	)
	(via
		(at 490.053122 -267.681202)
		(size 0.7112)
		(drill 0.4064)
		(layers "F.Cu" "B.Cu")
		(net "GND")
	)
	(via
		(at 431.8 -20.32)
		(size 0.5588)
		(drill 0.3048)
		(layers "F.Cu" "B.Cu")
		(net "GND")
	)
	(via
		(at 298.602908 23.518876)
		(size 0.7112)
		(drill 0.4064)
		(layers "F.Cu" "B.Cu")
		(net "GND")
	)
	(via
		(at 40.64 -35.56)
		(size 0.5588)
		(drill 0.3048)
		(layers "F.Cu" "B.Cu")
		(net "GND")
	)
	(via
		(at 1.397 -227.708968)
		(size 0.7112)
		(drill 0.4064)
		(layers "F.Cu" "B.Cu")
		(net "GND")
	)
	(via
		(at 459.23962 -1.397)
		(size 0.7112)
		(drill 0.4064)
		(layers "F.Cu" "B.Cu")
		(net "GND")
	)
	(via
		(at 126.43739 -45.220636)
		(size 0.5588)
		(drill 0.3048)
		(layers "F.Cu" "B.Cu")
		(net "GND")
	)
	(via
		(at 147.32 -152.4)
		(size 0.5588)
		(drill 0.3048)
		(layers "F.Cu" "B.Cu")
		(net "GND")
	)
	(via
		(at 392.43 -120.65)
		(size 0.5588)
		(drill 0.3048)
		(layers "F.Cu" "B.Cu")
		(net "GND")
	)
	(via
		(at 100.584 -14.097)
		(size 0.7112)
		(drill 0.4064)
		(layers "F.Cu" "B.Cu")
		(net "GND")
	)
	(via
		(at 450.711824 -52.829968)
		(size 0.5588)
		(drill 0.3048)
		(layers "F.Cu" "B.Cu")
		(net "GND")
	)
	(via
		(at 11.6332 -331.7494)
		(size 0.5588)
		(drill 0.3048)
		(layers "F.Cu" "B.Cu")
		(net "GND")
	)
	(via
		(at 213.233 -142.24)
		(size 0.5588)
		(drill 0.3048)
		(layers "F.Cu" "B.Cu")
		(net "GND")
	)
	(via
		(at 34.165032 -1.397)
		(size 0.7112)
		(drill 0.4064)
		(layers "F.Cu" "B.Cu")
		(net "GND")
	)
	(via
		(at 218.719654 -16.93672)
		(size 0.5588)
		(drill 0.3048)
		(layers "F.Cu" "B.Cu")
		(net "GND")
	)
	(via
		(at 361.369102 -191.113918)
		(size 0.5588)
		(drill 0.3048)
		(layers "F.Cu" "B.Cu")
		(net "GND")
	)
	(via
		(at 90.261948 -167.829992)
		(size 0.5588)
		(drill 0.3048)
		(layers "F.Cu" "B.Cu")
		(net "GND")
	)
	(via
		(at 480.06 -91.44)
		(size 0.5588)
		(drill 0.3048)
		(layers "F.Cu" "B.Cu")
		(net "GND")
	)
	(via
		(at 1.397 -166.748968)
		(size 0.7112)
		(drill 0.4064)
		(layers "F.Cu" "B.Cu")
		(net "GND")
	)
	(via
		(at 397.65097 -10.545318)
		(size 0.7112)
		(drill 0.4064)
		(layers "F.Cu" "B.Cu")
		(net "GND")
	)
	(via
		(at 308.602888 -398.181068)
		(size 0.7112)
		(drill 0.4064)
		(layers "F.Cu" "B.Cu")
		(net "GND")
	)
	(via
		(at 490.053122 -170.56735)
		(size 0.7112)
		(drill 0.4064)
		(layers "F.Cu" "B.Cu")
		(net "GND")
	)
	(via
		(at 490.053122 -72.77735)
		(size 0.7112)
		(drill 0.4064)
		(layers "F.Cu" "B.Cu")
		(net "GND")
	)
	(via
		(at 191.897 -349.123)
		(size 0.7112)
		(drill 0.4064)
		(layers "F.Cu" "B.Cu")
		(net "GND")
	)
	(via
		(at 47.592996 -347.802962)
		(size 0.7112)
		(drill 0.4064)
		(layers "F.Cu" "B.Cu")
		(net "GND")
	)
	(via
		(at 79.479648 -169.015918)
		(size 0.5588)
		(drill 0.3048)
		(layers "F.Cu" "B.Cu")
		(net "GND")
	)
	(via
		(at 50.480214 -257.780028)
		(size 0.5588)
		(drill 0.3048)
		(layers "F.Cu" "B.Cu")
		(net "GND")
	)
	(via
		(at 91.063572 -297.462956)
		(size 0.5588)
		(drill 0.3048)
		(layers "F.Cu" "B.Cu")
		(net "GND")
	)
	(via
		(at 1.397 -215.008968)
		(size 0.7112)
		(drill 0.4064)
		(layers "F.Cu" "B.Cu")
		(net "GND")
	)
	(via
		(at 484.89362 -1.397)
		(size 0.7112)
		(drill 0.4064)
		(layers "F.Cu" "B.Cu")
		(net "GND")
	)
	(via
		(at 216.619328 -102.3112)
		(size 0.5588)
		(drill 0.3048)
		(layers "F.Cu" "B.Cu")
		(net "GND")
	)
	(via
		(at 83.312 -38.227)
		(size 0.5588)
		(drill 0.3048)
		(layers "F.Cu" "B.Cu")
		(net "GND")
	)
	(via
		(at 445.4144 -252.7808)
		(size 0.5588)
		(drill 0.3048)
		(layers "F.Cu" "B.Cu")
		(net "GND")
	)
	(via
		(at 490.053122 -137.54735)
		(size 0.7112)
		(drill 0.4064)
		(layers "F.Cu" "B.Cu")
		(net "GND")
	)
	(via
		(at 12.446 -205.994)
		(size 0.5588)
		(drill 0.3048)
		(layers "F.Cu" "B.Cu")
		(net "GND")
	)
	(via
		(at 93.721682 -347.548962)
		(size 0.7112)
		(drill 0.4064)
		(layers "F.Cu" "B.Cu")
		(net "GND")
	)
	(via
		(at 416.306 -81.28)
		(size 0.5588)
		(drill 0.3048)
		(layers "F.Cu" "B.Cu")
		(net "GND")
	)
	(via
		(at 222.057976 -9.404604)
		(size 0.5588)
		(drill 0.3048)
		(layers "F.Cu" "B.Cu")
		(net "GND")
	)
	(via
		(at 351.802954 -55.545736)
		(size 0.5588)
		(drill 0.3048)
		(layers "F.Cu" "B.Cu")
		(net "GND")
	)
	(via
		(at 74.805032 -1.397)
		(size 0.7112)
		(drill 0.4064)
		(layers "F.Cu" "B.Cu")
		(net "GND")
	)
	(via
		(at 272.8976 20.574)
		(size 0.5588)
		(drill 0.3048)
		(layers "F.Cu" "B.Cu")
		(net "GND")
	)
	(via
		(at 265.100562 -28.585922)
		(size 0.5588)
		(drill 0.3048)
		(layers "F.Cu" "B.Cu")
		(net "GND")
	)
	(via
		(at 490.053122 -216.28735)
		(size 0.7112)
		(drill 0.4064)
		(layers "F.Cu" "B.Cu")
		(net "GND")
	)
	(via
		(at 1.397 -302.638968)
		(size 0.7112)
		(drill 0.4064)
		(layers "F.Cu" "B.Cu")
		(net "GND")
	)
	(via
		(at 50.202846 -59.603894)
		(size 0.5588)
		(drill 0.3048)
		(layers "F.Cu" "B.Cu")
		(net "GND")
	)
	(via
		(at 119.38 -109.22)
		(size 0.5588)
		(drill 0.3048)
		(layers "F.Cu" "B.Cu")
		(net "GND")
	)
	(via
		(at 153.361898 -282.830016)
		(size 0.5588)
		(drill 0.3048)
		(layers "F.Cu" "B.Cu")
		(net "GND")
	)
	(via
		(at 287.087056 37.403024)
		(size 0.7112)
		(drill 0.4064)
		(layers "F.Cu" "B.Cu")
		(net "GND")
	)
	(via
		(at 1.397 -152.778968)
		(size 0.7112)
		(drill 0.4064)
		(layers "F.Cu" "B.Cu")
		(net "GND")
	)
	(via
		(at 272.288 -262.89)
		(size 0.5588)
		(drill 0.3048)
		(layers "F.Cu" "B.Cu")
		(net "GND")
	)
	(via
		(at 113.03 -198.12)
		(size 0.5588)
		(drill 0.3048)
		(layers "F.Cu" "B.Cu")
		(net "GND")
	)
	(via
		(at 124.732796 -151.035004)
		(size 0.5588)
		(drill 0.3048)
		(layers "F.Cu" "B.Cu")
		(net "GND")
	)
	(via
		(at 222.317056 37.403024)
		(size 0.7112)
		(drill 0.4064)
		(layers "F.Cu" "B.Cu")
		(net "GND")
	)
	(via
		(at 272.8976 9.9314)
		(size 0.5588)
		(drill 0.3048)
		(layers "F.Cu" "B.Cu")
		(net "GND")
	)
	(via
		(at 346.637102 -290.522914)
		(size 0.5588)
		(drill 0.3048)
		(layers "F.Cu" "B.Cu")
		(net "GND")
	)
	(via
		(at 186.055 -62.354968)
		(size 0.5588)
		(drill 0.3048)
		(layers "F.Cu" "B.Cu")
		(net "GND")
	)
	(via
		(at 14.224 -60.198)
		(size 0.5588)
		(drill 0.3048)
		(layers "F.Cu" "B.Cu")
		(net "GND")
	)
	(via
		(at 217.178128 -101.3968)
		(size 0.5588)
		(drill 0.3048)
		(layers "F.Cu" "B.Cu")
		(net "GND")
	)
	(via
		(at 267.73632 -273.73072)
		(size 0.5588)
		(drill 0.3048)
		(layers "F.Cu" "B.Cu")
		(net "GND")
	)
	(via
		(at 420.304976 -292.355016)
		(size 0.5588)
		(drill 0.3048)
		(layers "F.Cu" "B.Cu")
		(net "GND")
	)
	(via
		(at 1.397 -10.538968)
		(size 0.7112)
		(drill 0.4064)
		(layers "F.Cu" "B.Cu")
		(net "GND")
	)
	(via
		(at 317.502794 -131.243578)
		(size 0.5588)
		(drill 0.3048)
		(layers "F.Cu" "B.Cu")
		(net "GND")
	)
	(via
		(at 117.315996 -70.322694)
		(size 0.5588)
		(drill 0.3048)
		(layers "F.Cu" "B.Cu")
		(net "GND")
	)
	(via
		(at 490.053122 -93.09735)
		(size 0.7112)
		(drill 0.4064)
		(layers "F.Cu" "B.Cu")
		(net "GND")
	)
	(via
		(at 75.532996 -347.802962)
		(size 0.7112)
		(drill 0.4064)
		(layers "F.Cu" "B.Cu")
		(net "GND")
	)
	(via
		(at 27.161998 -170.230038)
		(size 0.5588)
		(drill 0.3048)
		(layers "F.Cu" "B.Cu")
		(net "GND")
	)
	(via
		(at 305.224942 -375.397014)
		(size 0.7112)
		(drill 0.4064)
		(layers "F.Cu" "B.Cu")
		(net "GND")
	)
	(via
		(at 314.904882 -347.802962)
		(size 0.7112)
		(drill 0.4064)
		(layers "F.Cu" "B.Cu")
		(net "GND")
	)
	(via
		(at 107.206796 -179.683918)
		(size 0.5588)
		(drill 0.3048)
		(layers "F.Cu" "B.Cu")
		(net "GND")
	)
	(via
		(at 50.202846 -174.603918)
		(size 0.5588)
		(drill 0.3048)
		(layers "F.Cu" "B.Cu")
		(net "GND")
	)
	(via
		(at 121.92 -243.84)
		(size 0.5588)
		(drill 0.3048)
		(layers "F.Cu" "B.Cu")
		(net "GND")
	)
	(via
		(at 111.054896 -169.015918)
		(size 0.5588)
		(drill 0.3048)
		(layers "F.Cu" "B.Cu")
		(net "GND")
	)
	(via
		(at 28.304998 -297.435016)
		(size 0.5588)
		(drill 0.3048)
		(layers "F.Cu" "B.Cu")
		(net "GND")
	)
	(via
		(at 154.504898 -297.435016)
		(size 0.5588)
		(drill 0.3048)
		(layers "F.Cu" "B.Cu")
		(net "GND")
	)
	(via
		(at 391.104882 -347.802962)
		(size 0.7112)
		(drill 0.4064)
		(layers "F.Cu" "B.Cu")
		(net "GND")
	)
	(via
		(at 239.50295 -347.72854)
		(size 0.5588)
		(drill 0.3048)
		(layers "F.Cu" "B.Cu")
		(net "GND")
	)
	(via
		(at 70.604888 -189.12205)
		(size 0.5588)
		(drill 0.3048)
		(layers "F.Cu" "B.Cu")
		(net "GND")
	)
	(via
		(at 88.9 -116.84)
		(size 0.5588)
		(drill 0.3048)
		(layers "F.Cu" "B.Cu")
		(net "GND")
	)
	(via
		(at 161.892996 -347.802962)
		(size 0.7112)
		(drill 0.4064)
		(layers "F.Cu" "B.Cu")
		(net "GND")
	)
	(via
		(at 71.12 -15.24)
		(size 0.5588)
		(drill 0.3048)
		(layers "F.Cu" "B.Cu")
		(net "GND")
	)
	(via
		(at 419.86962 -1.397)
		(size 0.7112)
		(drill 0.4064)
		(layers "F.Cu" "B.Cu")
		(net "GND")
	)
	(via
		(at 357.205026 -279.655016)
		(size 0.5588)
		(drill 0.3048)
		(layers "F.Cu" "B.Cu")
		(net "GND")
	)
	(via
		(at 122.954796 -69.974968)
		(size 0.5588)
		(drill 0.3048)
		(layers "F.Cu" "B.Cu")
		(net "GND")
	)
	(via
		(at 27.559 -145.288)
		(size 0.5588)
		(drill 0.3048)
		(layers "F.Cu" "B.Cu")
		(net "GND")
	)
	(via
		(at 388.754874 -275.845016)
		(size 0.5588)
		(drill 0.3048)
		(layers "F.Cu" "B.Cu")
		(net "GND")
	)
	(via
		(at 46.355 -142.0368)
		(size 0.5588)
		(drill 0.3048)
		(layers "F.Cu" "B.Cu")
		(net "GND")
	)
	(via
		(at 386.08 -107.061)
		(size 0.5588)
		(drill 0.3048)
		(layers "F.Cu" "B.Cu")
		(net "GND")
	)
	(via
		(at 250.94438 -255.055878)
		(size 0.5588)
		(drill 0.3048)
		(layers "F.Cu" "B.Cu")
		(net "GND")
	)
	(via
		(at 4.445 -332.74)
		(size 0.5588)
		(drill 0.3048)
		(layers "F.Cu" "B.Cu")
		(net "GND")
	)
	(via
		(at 469.844882 -347.802962)
		(size 0.7112)
		(drill 0.4064)
		(layers "F.Cu" "B.Cu")
		(net "GND")
	)
	(via
		(at 327.434956 -266.350496)
		(size 0.5588)
		(drill 0.3048)
		(layers "F.Cu" "B.Cu")
		(net "GND")
	)
	(via
		(at 60.96 -96.52)
		(size 0.5588)
		(drill 0.3048)
		(layers "F.Cu" "B.Cu")
		(net "GND")
	)
	(via
		(at 354.25507 -49.634902)
		(size 0.5588)
		(drill 0.3048)
		(layers "F.Cu" "B.Cu")
		(net "GND")
	)
	(via
		(at 468.307674 -237.760764)
		(size 0.5588)
		(drill 0.3048)
		(layers "F.Cu" "B.Cu")
		(net "GND")
	)
	(via
		(at 1.397 -108.328968)
		(size 0.7112)
		(drill 0.4064)
		(layers "F.Cu" "B.Cu")
		(net "GND")
	)
	(via
		(at 278.916892 -419.803072)
		(size 0.7112)
		(drill 0.4064)
		(layers "F.Cu" "B.Cu")
		(net "GND")
	)
	(via
		(at 22.005798 -164.494718)
		(size 0.5588)
		(drill 0.3048)
		(layers "F.Cu" "B.Cu")
		(net "GND")
	)
	(via
		(at 16.379698 -54.041294)
		(size 0.5588)
		(drill 0.3048)
		(layers "F.Cu" "B.Cu")
		(net "GND")
	)
	(via
		(at 153.339038 -46.251114)
		(size 0.5588)
		(drill 0.3048)
		(layers "F.Cu" "B.Cu")
		(net "GND")
	)
	(via
		(at 1.397 -179.448968)
		(size 0.7112)
		(drill 0.4064)
		(layers "F.Cu" "B.Cu")
		(net "GND")
	)
	(via
		(at 346.349066 -10.114534)
		(size 0.7112)
		(drill 0.4064)
		(layers "F.Cu" "B.Cu")
		(net "GND")
	)
	(via
		(at 294.302942 -353.585018)
		(size 0.7112)
		(drill 0.4064)
		(layers "F.Cu" "B.Cu")
		(net "GND")
	)
	(via
		(at 221.107 -193.675)
		(size 0.5588)
		(drill 0.3048)
		(layers "F.Cu" "B.Cu")
		(net "GND")
	)
	(via
		(at 221.651068 29.35605)
		(size 0.7112)
		(drill 0.4064)
		(layers "F.Cu" "B.Cu")
		(net "GND")
	)
	(via
		(at 19.9644 -250.1392)
		(size 0.7112)
		(drill 0.4064)
		(layers "F.Cu" "B.Cu")
		(net "GND")
	)
	(via
		(at 119.38 -101.6)
		(size 0.5588)
		(drill 0.3048)
		(layers "F.Cu" "B.Cu")
		(net "GND")
	)
	(via
		(at 67.409568 -136.96315)
		(size 0.5588)
		(drill 0.3048)
		(layers "F.Cu" "B.Cu")
		(net "GND")
	)
	(via
		(at 490.053122 -2.92735)
		(size 0.7112)
		(drill 0.4064)
		(layers "F.Cu" "B.Cu")
		(net "GND")
	)
	(via
		(at 149.86 -86.868)
		(size 0.5588)
		(drill 0.3048)
		(layers "F.Cu" "B.Cu")
		(net "GND")
	)
	(via
		(at 324.511924 -282.830016)
		(size 0.5588)
		(drill 0.3048)
		(layers "F.Cu" "B.Cu")
		(net "GND")
	)
	(via
		(at 121.489724 -49.680622)
		(size 0.5588)
		(drill 0.3048)
		(layers "F.Cu" "B.Cu")
		(net "GND")
	)
	(via
		(at 6.35 -233.68)
		(size 0.5588)
		(drill 0.3048)
		(layers "F.Cu" "B.Cu")
		(net "GND")
	)
	(via
		(at 421.64 -25.4)
		(size 0.5588)
		(drill 0.3048)
		(layers "F.Cu" "B.Cu")
		(net "GND")
	)
	(via
		(at 453.632824 -151.035004)
		(size 0.5588)
		(drill 0.3048)
		(layers "F.Cu" "B.Cu")
		(net "GND")
	)
	(via
		(at 230.886 -22.606)
		(size 0.5588)
		(drill 0.3048)
		(layers "F.Cu" "B.Cu")
		(net "GND")
	)
	(via
		(at 271.847056 37.403024)
		(size 0.7112)
		(drill 0.4064)
		(layers "F.Cu" "B.Cu")
		(net "GND")
	)
	(via
		(at 345.384882 -347.802962)
		(size 0.7112)
		(drill 0.4064)
		(layers "F.Cu" "B.Cu")
		(net "GND")
	)
	(via
		(at 299.085 -38.989)
		(size 0.5588)
		(drill 0.3048)
		(layers "F.Cu" "B.Cu")
		(net "GND")
	)
	(via
		(at 490.053122 -326.101202)
		(size 0.7112)
		(drill 0.4064)
		(layers "F.Cu" "B.Cu")
		(net "GND")
	)
	(via
		(at 12.954 -191.897)
		(size 0.5588)
		(drill 0.3048)
		(layers "F.Cu" "B.Cu")
		(net "GND")
	)
	(via
		(at 457.3651 -161.649918)
		(size 0.5588)
		(drill 0.3048)
		(layers "F.Cu" "B.Cu")
		(net "GND")
	)
	(via
		(at 277.067772 -389.03148)
		(size 0.5588)
		(drill 0.3048)
		(layers "F.Cu" "B.Cu")
		(net "GND")
	)
	(via
		(at 30.082998 -194.78498)
		(size 0.5588)
		(drill 0.3048)
		(layers "F.Cu" "B.Cu")
		(net "GND")
	)
	(via
		(at 135.857996 -289.502596)
		(size 0.5588)
		(drill 0.3048)
		(layers "F.Cu" "B.Cu")
		(net "GND")
	)
	(via
		(at 462.28 -81.28)
		(size 0.5588)
		(drill 0.3048)
		(layers "F.Cu" "B.Cu")
		(net "GND")
	)
	(via
		(at 12.556998 -179.683918)
		(size 0.5588)
		(drill 0.3048)
		(layers "F.Cu" "B.Cu")
		(net "GND")
	)
	(via
		(at 490.053122 -107.06735)
		(size 0.7112)
		(drill 0.4064)
		(layers "F.Cu" "B.Cu")
		(net "GND")
	)
	(via
		(at 111.76 -155.702)
		(size 0.5588)
		(drill 0.3048)
		(layers "F.Cu" "B.Cu")
		(net "GND")
	)
	(via
		(at 92.751148 -19.743674)
		(size 0.5588)
		(drill 0.3048)
		(layers "F.Cu" "B.Cu")
		(net "GND")
	)
	(via
		(at 50.132996 -347.802962)
		(size 0.7112)
		(drill 0.4064)
		(layers "F.Cu" "B.Cu")
		(net "GND")
	)
	(via
		(at 307.281072 -22.699472)
		(size 0.5588)
		(drill 0.3048)
		(layers "F.Cu" "B.Cu")
		(net "GND")
	)
	(via
		(at 280.885138 -230.026718)
		(size 0.5588)
		(drill 0.3048)
		(layers "F.Cu" "B.Cu")
		(net "GND")
	)
	(via
		(at 349.367602 -290.238942)
		(size 0.5588)
		(drill 0.3048)
		(layers "F.Cu" "B.Cu")
		(net "GND")
	)
	(via
		(at 27.815032 -1.397)
		(size 0.7112)
		(drill 0.4064)
		(layers "F.Cu" "B.Cu")
		(net "GND")
	)
	(via
		(at 477.464882 -347.802962)
		(size 0.7112)
		(drill 0.4064)
		(layers "F.Cu" "B.Cu")
		(net "GND")
	)
	(via
		(at 487.68 -20.32)
		(size 0.5588)
		(drill 0.3048)
		(layers "F.Cu" "B.Cu")
		(net "GND")
	)
	(via
		(at 308.602888 -414.691068)
		(size 0.7112)
		(drill 0.4064)
		(layers "F.Cu" "B.Cu")
		(net "GND")
	)
	(via
		(at 28.304998 -182.434992)
		(size 0.5588)
		(drill 0.3048)
		(layers "F.Cu" "B.Cu")
		(net "GND")
	)
	(via
		(at 451.854824 -182.434992)
		(size 0.5588)
		(drill 0.3048)
		(layers "F.Cu" "B.Cu")
		(net "GND")
	)
	(via
		(at 50.8 -30.48)
		(size 0.5588)
		(drill 0.3048)
		(layers "F.Cu" "B.Cu")
		(net "GND")
	)
	(via
		(at 122.954796 -289.815016)
		(size 0.5588)
		(drill 0.3048)
		(layers "F.Cu" "B.Cu")
		(net "GND")
	)
	(via
		(at 121.92 -238.76)
		(size 0.5588)
		(drill 0.3048)
		(layers "F.Cu" "B.Cu")
		(net "GND")
	)
	(via
		(at 1.397 -46.098968)
		(size 0.7112)
		(drill 0.4064)
		(layers "F.Cu" "B.Cu")
		(net "GND")
	)
	(via
		(at 25.4 -116.84)
		(size 0.5588)
		(drill 0.3048)
		(layers "F.Cu" "B.Cu")
		(net "GND")
	)
	(via
		(at 88.9 -142.24)
		(size 0.5588)
		(drill 0.3048)
		(layers "F.Cu" "B.Cu")
		(net "GND")
	)
	(via
		(at 39.043356 -183.068214)
		(size 0.5588)
		(drill 0.3048)
		(layers "F.Cu" "B.Cu")
		(net "GND")
	)
	(via
		(at 477.766126 -185.322718)
		(size 0.5588)
		(drill 0.3048)
		(layers "F.Cu" "B.Cu")
		(net "GND")
	)
	(via
		(at 490.053122 -115.95735)
		(size 0.7112)
		(drill 0.4064)
		(layers "F.Cu" "B.Cu")
		(net "GND")
	)
	(via
		(at 138.756898 -179.683918)
		(size 0.5588)
		(drill 0.3048)
		(layers "F.Cu" "B.Cu")
		(net "GND")
	)
	(via
		(at 36.162996 -347.802962)
		(size 0.7112)
		(drill 0.4064)
		(layers "F.Cu" "B.Cu")
		(net "GND")
	)
	(via
		(at 26.545032 -1.397)
		(size 0.7112)
		(drill 0.4064)
		(layers "F.Cu" "B.Cu")
		(net "GND")
	)
	(via
		(at 358.084882 -347.802962)
		(size 0.7112)
		(drill 0.4064)
		(layers "F.Cu" "B.Cu")
		(net "GND")
	)
	(via
		(at 45.72 -25.4)
		(size 0.5588)
		(drill 0.3048)
		(layers "F.Cu" "B.Cu")
		(net "GND")
	)
	(via
		(at 100.34905 -3.464306)
		(size 0.7112)
		(drill 0.4064)
		(layers "F.Cu" "B.Cu")
		(net "GND")
	)
	(via
		(at 66.548 -53.086)
		(size 0.5588)
		(drill 0.3048)
		(layers "F.Cu" "B.Cu")
		(net "GND")
	)
	(via
		(at 170.307 -64.683894)
		(size 0.5588)
		(drill 0.3048)
		(layers "F.Cu" "B.Cu")
		(net "GND")
	)
	(via
		(at 45.298868 -130.122676)
		(size 0.5588)
		(drill 0.3048)
		(layers "F.Cu" "B.Cu")
		(net "GND")
	)
	(via
		(at 1.397 -32.128968)
		(size 0.7112)
		(drill 0.4064)
		(layers "F.Cu" "B.Cu")
		(net "GND")
	)
	(via
		(at 10.16 -233.68)
		(size 0.5588)
		(drill 0.3048)
		(layers "F.Cu" "B.Cu")
		(net "GND")
	)
	(via
		(at 475.558104 -233.694986)
		(size 0.5588)
		(drill 0.3048)
		(layers "F.Cu" "B.Cu")
		(net "GND")
	)
	(via
		(at 468.795354 -210.316064)
		(size 0.5588)
		(drill 0.3048)
		(layers "F.Cu" "B.Cu")
		(net "GND")
	)
	(via
		(at 122.954796 -272.035016)
		(size 0.5588)
		(drill 0.3048)
		(layers "F.Cu" "B.Cu")
		(net "GND")
	)
	(via
		(at 490.053122 -245.49735)
		(size 0.7112)
		(drill 0.4064)
		(layers "F.Cu" "B.Cu")
		(net "GND")
	)
	(via
		(at 30.082998 -309.785004)
		(size 0.5588)
		(drill 0.3048)
		(layers "F.Cu" "B.Cu")
		(net "GND")
	)
	(via
		(at 265.3284 -103.505)
		(size 0.5588)
		(drill 0.3048)
		(layers "F.Cu" "B.Cu")
		(net "GND")
	)
	(via
		(at 462.28 -137.16)
		(size 0.5588)
		(drill 0.3048)
		(layers "F.Cu" "B.Cu")
		(net "GND")
	)
	(via
		(at 55.88 -111.76)
		(size 0.5588)
		(drill 0.3048)
		(layers "F.Cu" "B.Cu")
		(net "GND")
	)
	(via
		(at 97.665032 -1.397)
		(size 0.7112)
		(drill 0.4064)
		(layers "F.Cu" "B.Cu")
		(net "GND")
	)
	(via
		(at 266.767056 37.403024)
		(size 0.7112)
		(drill 0.4064)
		(layers "F.Cu" "B.Cu")
		(net "GND")
	)
	(via
		(at 37.465 -153.797)
		(size 0.5588)
		(drill 0.3048)
		(layers "F.Cu" "B.Cu")
		(net "GND")
	)
	(via
		(at 311.0992 -57.2008)
		(size 0.5588)
		(drill 0.3048)
		(layers "F.Cu" "B.Cu")
		(net "GND")
	)
	(via
		(at 294.259 -372.999)
		(size 0.7112)
		(drill 0.4064)
		(layers "F.Cu" "B.Cu")
		(net "GND")
	)
	(via
		(at 464.92033 -259.096256)
		(size 0.5588)
		(drill 0.3048)
		(layers "F.Cu" "B.Cu")
		(net "GND")
	)
	(via
		(at 490.053122 -51.18735)
		(size 0.7112)
		(drill 0.4064)
		(layers "F.Cu" "B.Cu")
		(net "GND")
	)
	(via
		(at 221.651068 31.89605)
		(size 0.7112)
		(drill 0.4064)
		(layers "F.Cu" "B.Cu")
		(net "GND")
	)
	(via
		(at 370.332 -321.437)
		(size 0.5588)
		(drill 0.3048)
		(layers "F.Cu" "B.Cu")
		(net "GND")
	)
	(via
		(at 426.72 -5.08)
		(size 0.5588)
		(drill 0.3048)
		(layers "F.Cu" "B.Cu")
		(net "GND")
	)
	(via
		(at 1.397 -54.988968)
		(size 0.7112)
		(drill 0.4064)
		(layers "F.Cu" "B.Cu")
		(net "GND")
	)
	(via
		(at 422.082976 -194.78498)
		(size 0.5588)
		(drill 0.3048)
		(layers "F.Cu" "B.Cu")
		(net "GND")
	)
	(via
		(at 182.88 -15.24)
		(size 0.5588)
		(drill 0.3048)
		(layers "F.Cu" "B.Cu")
		(net "GND")
	)
	(via
		(at 1.397 -235.328968)
		(size 0.7112)
		(drill 0.4064)
		(layers "F.Cu" "B.Cu")
		(net "GND")
	)
	(via
		(at 5.08 -60.96)
		(size 0.5588)
		(drill 0.3048)
		(layers "F.Cu" "B.Cu")
		(net "GND")
	)
	(via
		(at 304.258472 -183.6674)
		(size 0.5588)
		(drill 0.3048)
		(layers "F.Cu" "B.Cu")
		(net "GND")
	)
	(via
		(at 490.053122 -270.221202)
		(size 0.7112)
		(drill 0.4064)
		(layers "F.Cu" "B.Cu")
		(net "GND")
	)
	(via
		(at 187.833 -151.035004)
		(size 0.5588)
		(drill 0.3048)
		(layers "F.Cu" "B.Cu")
		(net "GND")
	)
	(via
		(at 184.785 -120.904)
		(size 0.5588)
		(drill 0.3048)
		(layers "F.Cu" "B.Cu")
		(net "GND")
	)
	(via
		(at 325.501 -26.289)
		(size 0.5588)
		(drill 0.3048)
		(layers "F.Cu" "B.Cu")
		(net "GND")
	)
	(via
		(at 414.02 -193.04)
		(size 0.5588)
		(drill 0.3048)
		(layers "F.Cu" "B.Cu")
		(net "GND")
	)
	(via
		(at 485.787954 -213.853776)
		(size 0.5588)
		(drill 0.3048)
		(layers "F.Cu" "B.Cu")
		(net "GND")
	)
	(via
		(at 28.542996 -347.802962)
		(size 0.7112)
		(drill 0.4064)
		(layers "F.Cu" "B.Cu")
		(net "GND")
	)
	(via
		(at 294.156892 -419.803072)
		(size 0.7112)
		(drill 0.4064)
		(layers "F.Cu" "B.Cu")
		(net "GND")
	)
	(via
		(at 48.26 -335.28)
		(size 0.5588)
		(drill 0.3048)
		(layers "F.Cu" "B.Cu")
		(net "GND")
	)
	(via
		(at 298.602908 3.198876)
		(size 0.7112)
		(drill 0.4064)
		(layers "F.Cu" "B.Cu")
		(net "GND")
	)
	(via
		(at 40.515032 -1.397)
		(size 0.7112)
		(drill 0.4064)
		(layers "F.Cu" "B.Cu")
		(net "GND")
	)
	(via
		(at 203.835 -303.403)
		(size 0.5588)
		(drill 0.3048)
		(layers "F.Cu" "B.Cu")
		(net "GND")
	)
	(via
		(at 490.053122 -71.50735)
		(size 0.7112)
		(drill 0.4064)
		(layers "F.Cu" "B.Cu")
		(net "GND")
	)
	(via
		(at 59.854846 -67.434968)
		(size 0.5588)
		(drill 0.3048)
		(layers "F.Cu" "B.Cu")
		(net "GND")
	)
	(via
		(at 490.053122 -98.17735)
		(size 0.7112)
		(drill 0.4064)
		(layers "F.Cu" "B.Cu")
		(net "GND")
	)
	(via
		(at 67.792346 -175.238918)
		(size 0.5588)
		(drill 0.3048)
		(layers "F.Cu" "B.Cu")
		(net "GND")
	)
	(via
		(at 490.053122 -195.96735)
		(size 0.7112)
		(drill 0.4064)
		(layers "F.Cu" "B.Cu")
		(net "GND")
	)
	(via
		(at 5.08 -86.36)
		(size 0.5588)
		(drill 0.3048)
		(layers "F.Cu" "B.Cu")
		(net "GND")
	)
	(via
		(at 403.35962 -1.397)
		(size 0.7112)
		(drill 0.4064)
		(layers "F.Cu" "B.Cu")
		(net "GND")
	)
	(via
		(at 490.053122 -332.451202)
		(size 0.7112)
		(drill 0.4064)
		(layers "F.Cu" "B.Cu")
		(net "GND")
	)
	(via
		(at 190.9445 -174.0662)
		(size 0.5588)
		(drill 0.3048)
		(layers "F.Cu" "B.Cu")
		(net "GND")
	)
	(via
		(at 308.602888 -393.101068)
		(size 0.7112)
		(drill 0.4064)
		(layers "F.Cu" "B.Cu")
		(net "GND")
	)
	(via
		(at 1.397 -165.478968)
		(size 0.7112)
		(drill 0.4064)
		(layers "F.Cu" "B.Cu")
		(net "GND")
	)
	(via
		(at 216.027 -67.564)
		(size 0.5588)
		(drill 0.3048)
		(layers "F.Cu" "B.Cu")
		(net "GND")
	)
	(via
		(at 490.053122 -282.921202)
		(size 0.7112)
		(drill 0.4064)
		(layers "F.Cu" "B.Cu")
		(net "GND")
	)
	(via
		(at 422.082976 -309.785004)
		(size 0.5588)
		(drill 0.3048)
		(layers "F.Cu" "B.Cu")
		(net "GND")
	)
	(via
		(at 59.854846 -299.975016)
		(size 0.5588)
		(drill 0.3048)
		(layers "F.Cu" "B.Cu")
		(net "GND")
	)
	(via
		(at 91.44 -5.08)
		(size 0.5588)
		(drill 0.3048)
		(layers "F.Cu" "B.Cu")
		(net "GND")
	)
	(via
		(at 22.735032 -1.397)
		(size 0.7112)
		(drill 0.4064)
		(layers "F.Cu" "B.Cu")
		(net "GND")
	)
	(via
		(at 1.397 -228.978968)
		(size 0.7112)
		(drill 0.4064)
		(layers "F.Cu" "B.Cu")
		(net "GND")
	)
	(via
		(at 401.32 -20.32)
		(size 0.5588)
		(drill 0.3048)
		(layers "F.Cu" "B.Cu")
		(net "GND")
	)
	(via
		(at 120.391682 -347.548962)
		(size 0.7112)
		(drill 0.4064)
		(layers "F.Cu" "B.Cu")
		(net "GND")
	)
	(via
		(at 1.397 -183.258968)
		(size 0.7112)
		(drill 0.4064)
		(layers "F.Cu" "B.Cu")
		(net "GND")
	)
	(via
		(at 388.754874 -177.354992)
		(size 0.5588)
		(drill 0.3048)
		(layers "F.Cu" "B.Cu")
		(net "GND")
	)
	(via
		(at 214.874094 -13.401548)
		(size 0.5588)
		(drill 0.3048)
		(layers "F.Cu" "B.Cu")
		(net "GND")
	)
	(via
		(at 452.12 -137.16)
		(size 0.5588)
		(drill 0.3048)
		(layers "F.Cu" "B.Cu")
		(net "GND")
	)
	(via
		(at 1.397 -67.688968)
		(size 0.7112)
		(drill 0.4064)
		(layers "F.Cu" "B.Cu")
		(net "GND")
	)
	(via
		(at 81.28 -10.16)
		(size 0.5588)
		(drill 0.3048)
		(layers "F.Cu" "B.Cu")
		(net "GND")
	)
	(via
		(at 490.053122 -49.91735)
		(size 0.7112)
		(drill 0.4064)
		(layers "F.Cu" "B.Cu")
		(net "GND")
	)
	(via
		(at 166.116 -231.394)
		(size 0.5588)
		(drill 0.3048)
		(layers "F.Cu" "B.Cu")
		(net "GND")
	)
	(via
		(at 292.862 -379.984)
		(size 0.5588)
		(drill 0.3048)
		(layers "F.Cu" "B.Cu")
		(net "GND")
	)
	(via
		(at 439.42 -170.18)
		(size 0.5588)
		(drill 0.3048)
		(layers "F.Cu" "B.Cu")
		(net "GND")
	)
	(via
		(at 294.302942 -365.015018)
		(size 0.7112)
		(drill 0.4064)
		(layers "F.Cu" "B.Cu")
		(net "GND")
	)
	(via
		(at 93.98 -142.24)
		(size 0.5588)
		(drill 0.3048)
		(layers "F.Cu" "B.Cu")
		(net "GND")
	)
	(via
		(at 490.053122 -70.23735)
		(size 0.7112)
		(drill 0.4064)
		(layers "F.Cu" "B.Cu")
		(net "GND")
	)
	(via
		(at 476.574104 -233.694986)
		(size 0.5588)
		(drill 0.3048)
		(layers "F.Cu" "B.Cu")
		(net "GND")
	)
	(via
		(at 451.854824 -174.814992)
		(size 0.5588)
		(drill 0.3048)
		(layers "F.Cu" "B.Cu")
		(net "GND")
	)
	(via
		(at 397.65097 -6.735318)
		(size 0.7112)
		(drill 0.4064)
		(layers "F.Cu" "B.Cu")
		(net "GND")
	)
	(via
		(at 441.96 -30.48)
		(size 0.5588)
		(drill 0.3048)
		(layers "F.Cu" "B.Cu")
		(net "GND")
	)
	(via
		(at 169.512996 -347.802962)
		(size 0.7112)
		(drill 0.4064)
		(layers "F.Cu" "B.Cu")
		(net "GND")
	)
	(via
		(at 340.304882 -347.802962)
		(size 0.7112)
		(drill 0.4064)
		(layers "F.Cu" "B.Cu")
		(net "GND")
	)
	(via
		(at 490.053122 -333.721202)
		(size 0.7112)
		(drill 0.4064)
		(layers "F.Cu" "B.Cu")
		(net "GND")
	)
	(via
		(at 250.257056 37.403024)
		(size 0.7112)
		(drill 0.4064)
		(layers "F.Cu" "B.Cu")
		(net "GND")
	)
	(via
		(at 90.261948 -55.230014)
		(size 0.5588)
		(drill 0.3048)
		(layers "F.Cu" "B.Cu")
		(net "GND")
	)
	(via
		(at 405.694134 -246.271288)
		(size 0.5588)
		(drill 0.3048)
		(layers "F.Cu" "B.Cu")
		(net "GND")
	)
	(via
		(at 35.56 -111.76)
		(size 0.5588)
		(drill 0.3048)
		(layers "F.Cu" "B.Cu")
		(net "GND")
	)
	(via
		(at 280.737056 37.403024)
		(size 0.7112)
		(drill 0.4064)
		(layers "F.Cu" "B.Cu")
		(net "GND")
	)
	(via
		(at 490.053122 -279.111202)
		(size 0.7112)
		(drill 0.4064)
		(layers "F.Cu" "B.Cu")
		(net "GND")
	)
	(via
		(at 266.7254 -99.7204)
		(size 0.5588)
		(drill 0.3048)
		(layers "F.Cu" "B.Cu")
		(net "GND")
	)
	(via
		(at 122.954796 -292.355016)
		(size 0.5588)
		(drill 0.3048)
		(layers "F.Cu" "B.Cu")
		(net "GND")
	)
	(via
		(at 472.786202 -254.66675)
		(size 0.5588)
		(drill 0.3048)
		(layers "F.Cu" "B.Cu")
		(net "GND")
	)
	(via
		(at 439.42 -185.42)
		(size 0.5588)
		(drill 0.3048)
		(layers "F.Cu" "B.Cu")
		(net "GND")
	)
	(via
		(at 67.243706 -185.956956)
		(size 0.5588)
		(drill 0.3048)
		(layers "F.Cu" "B.Cu")
		(net "GND")
	)
	(via
		(at 10.16 -236.22)
		(size 0.5588)
		(drill 0.3048)
		(layers "F.Cu" "B.Cu")
		(net "GND")
	)
	(via
		(at 420.304976 -49.654968)
		(size 0.5588)
		(drill 0.3048)
		(layers "F.Cu" "B.Cu")
		(net "GND")
	)
	(via
		(at 21.59 -259.08)
		(size 0.5588)
		(drill 0.3048)
		(layers "F.Cu" "B.Cu")
		(net "GND")
	)
	(via
		(at 1.397 -137.538968)
		(size 0.7112)
		(drill 0.4064)
		(layers "F.Cu" "B.Cu")
		(net "GND")
	)
	(via
		(at 308.602888 -385.481068)
		(size 0.7112)
		(drill 0.4064)
		(layers "F.Cu" "B.Cu")
		(net "GND")
	)
	(via
		(at 308.602888 -379.131068)
		(size 0.7112)
		(drill 0.4064)
		(layers "F.Cu" "B.Cu")
		(net "GND")
	)
	(via
		(at 84.965032 -1.397)
		(size 0.7112)
		(drill 0.4064)
		(layers "F.Cu" "B.Cu")
		(net "GND")
	)
	(via
		(at 1.397 -279.778968)
		(size 0.7112)
		(drill 0.4064)
		(layers "F.Cu" "B.Cu")
		(net "GND")
	)
	(via
		(at 178.943 -201.93)
		(size 0.5588)
		(drill 0.3048)
		(layers "F.Cu" "B.Cu")
		(net "GND")
	)
	(via
		(at 344.805 -11.049)
		(size 0.5588)
		(drill 0.3048)
		(layers "F.Cu" "B.Cu")
		(net "GND")
	)
	(via
		(at 490.053122 -44.83735)
		(size 0.7112)
		(drill 0.4064)
		(layers "F.Cu" "B.Cu")
		(net "GND")
	)
	(via
		(at 302.768 -220.726)
		(size 0.5588)
		(drill 0.3048)
		(layers "F.Cu" "B.Cu")
		(net "GND")
	)
	(via
		(at 5.08 -91.44)
		(size 0.5588)
		(drill 0.3048)
		(layers "F.Cu" "B.Cu")
		(net "GND")
	)
	(via
		(at 294.302942 -371.365018)
		(size 0.7112)
		(drill 0.4064)
		(layers "F.Cu" "B.Cu")
		(net "GND")
	)
	(via
		(at 154.504898 -275.845016)
		(size 0.5588)
		(drill 0.3048)
		(layers "F.Cu" "B.Cu")
		(net "GND")
	)
	(via
		(at 151.003 -117.348)
		(size 0.5588)
		(drill 0.3048)
		(layers "F.Cu" "B.Cu")
		(net "GND")
	)
	(via
		(at 1.397 -60.068968)
		(size 0.7112)
		(drill 0.4064)
		(layers "F.Cu" "B.Cu")
		(net "GND")
	)
	(via
		(at 490.053122 -198.50735)
		(size 0.7112)
		(drill 0.4064)
		(layers "F.Cu" "B.Cu")
		(net "GND")
	)
	(via
		(at 365.052102 -306.113942)
		(size 0.5588)
		(drill 0.3048)
		(layers "F.Cu" "B.Cu")
		(net "GND")
	)
	(via
		(at 379.674882 -347.802962)
		(size 0.7112)
		(drill 0.4064)
		(layers "F.Cu" "B.Cu")
		(net "GND")
	)
	(via
		(at 294.302942 -349.775018)
		(size 0.7112)
		(drill 0.4064)
		(layers "F.Cu" "B.Cu")
		(net "GND")
	)
	(via
		(at 275.106892 -419.803072)
		(size 0.7112)
		(drill 0.4064)
		(layers "F.Cu" "B.Cu")
		(net "GND")
	)
	(via
		(at 428.152052 -76.113894)
		(size 0.5588)
		(drill 0.3048)
		(layers "F.Cu" "B.Cu")
		(net "GND")
	)
	(via
		(at 224.8662 -348.2467)
		(size 0.5588)
		(drill 0.3048)
		(layers "F.Cu" "B.Cu")
		(net "GND")
	)
	(via
		(at 439.039 -63.373)
		(size 0.5588)
		(drill 0.3048)
		(layers "F.Cu" "B.Cu")
		(net "GND")
	)
	(via
		(at 467.36 -25.4)
		(size 0.5588)
		(drill 0.3048)
		(layers "F.Cu" "B.Cu")
		(net "GND")
	)
	(via
		(at 482.6 -335.28)
		(size 0.5588)
		(drill 0.3048)
		(layers "F.Cu" "B.Cu")
		(net "GND")
	)
	(via
		(at 411.48 -20.32)
		(size 0.5588)
		(drill 0.3048)
		(layers "F.Cu" "B.Cu")
		(net "GND")
	)
	(via
		(at 447.04 -132.08)
		(size 0.5588)
		(drill 0.3048)
		(layers "F.Cu" "B.Cu")
		(net "GND")
	)
	(via
		(at 400.431 -235.839)
		(size 0.5588)
		(drill 0.3048)
		(layers "F.Cu" "B.Cu")
		(net "GND")
	)
	(via
		(at 490.053122 -193.42735)
		(size 0.7112)
		(drill 0.4064)
		(layers "F.Cu" "B.Cu")
		(net "GND")
	)
	(via
		(at 201.397108 -404.612856)
		(size 0.7112)
		(drill 0.4064)
		(layers "F.Cu" "B.Cu")
		(net "GND")
	)
	(via
		(at 96.52 -238.76)
		(size 0.5588)
		(drill 0.3048)
		(layers "F.Cu" "B.Cu")
		(net "GND")
	)
	(via
		(at 421.584882 -347.802962)
		(size 0.7112)
		(drill 0.4064)
		(layers "F.Cu" "B.Cu")
		(net "GND")
	)
	(via
		(at 191.553084 -1.397)
		(size 0.7112)
		(drill 0.4064)
		(layers "F.Cu" "B.Cu")
		(net "GND")
	)
	(via
		(at 7.890256 -179.045616)
		(size 0.5588)
		(drill 0.3048)
		(layers "F.Cu" "B.Cu")
		(net "GND")
	)
	(via
		(at 477.52 -30.48)
		(size 0.5588)
		(drill 0.3048)
		(layers "F.Cu" "B.Cu")
		(net "GND")
	)
	(via
		(at 402.12772 -246.243094)
		(size 0.5588)
		(drill 0.3048)
		(layers "F.Cu" "B.Cu")
		(net "GND")
	)
	(via
		(at 472.215718 -157.513274)
		(size 0.5588)
		(drill 0.3048)
		(layers "F.Cu" "B.Cu")
		(net "GND")
	)
	(via
		(at 343.251028 -1.397)
		(size 0.7112)
		(drill 0.4064)
		(layers "F.Cu" "B.Cu")
		(net "GND")
	)
	(via
		(at 88.9 -132.08)
		(size 0.5588)
		(drill 0.3048)
		(layers "F.Cu" "B.Cu")
		(net "GND")
	)
	(via
		(at 450.34962 -1.397)
		(size 0.7112)
		(drill 0.4064)
		(layers "F.Cu" "B.Cu")
		(net "GND")
	)
	(via
		(at 490.053122 -123.57735)
		(size 0.7112)
		(drill 0.4064)
		(layers "F.Cu" "B.Cu")
		(net "GND")
	)
	(via
		(at 361.369102 -306.113942)
		(size 0.5588)
		(drill 0.3048)
		(layers "F.Cu" "B.Cu")
		(net "GND")
	)
	(via
		(at 451.854824 -289.815016)
		(size 0.5588)
		(drill 0.3048)
		(layers "F.Cu" "B.Cu")
		(net "GND")
	)
	(via
		(at 35.654488 -186.02198)
		(size 0.5588)
		(drill 0.3048)
		(layers "F.Cu" "B.Cu")
		(net "GND")
	)
	(via
		(at 413.453326 -281.949398)
		(size 0.5588)
		(drill 0.3048)
		(layers "F.Cu" "B.Cu")
		(net "GND")
	)
	(via
		(at 19.033998 -47.615094)
		(size 0.5588)
		(drill 0.3048)
		(layers "F.Cu" "B.Cu")
		(net "GND")
	)
	(via
		(at 265.146028 -228.998272)
		(size 0.5588)
		(drill 0.3048)
		(layers "F.Cu" "B.Cu")
		(net "GND")
	)
	(via
		(at 457.704952 -46.711616)
		(size 0.5588)
		(drill 0.3048)
		(layers "F.Cu" "B.Cu")
		(net "GND")
	)
	(via
		(at 467.656926 -64.683894)
		(size 0.5588)
		(drill 0.3048)
		(layers "F.Cu" "B.Cu")
		(net "GND")
	)
	(via
		(at 52.324 -55.626)
		(size 0.5588)
		(drill 0.3048)
		(layers "F.Cu" "B.Cu")
		(net "GND")
	)
	(via
		(at 388.754874 -272.035016)
		(size 0.5588)
		(drill 0.3048)
		(layers "F.Cu" "B.Cu")
		(net "GND")
	)
	(via
		(at 201.397108 -376.672856)
		(size 0.7112)
		(drill 0.4064)
		(layers "F.Cu" "B.Cu")
		(net "GND")
	)
	(via
		(at 490.053122 -41.02735)
		(size 0.7112)
		(drill 0.4064)
		(layers "F.Cu" "B.Cu")
		(net "GND")
	)
	(via
		(at 124.732796 -266.035028)
		(size 0.5588)
		(drill 0.3048)
		(layers "F.Cu" "B.Cu")
		(net "GND")
	)
	(via
		(at 100.34905 -7.274306)
		(size 0.7112)
		(drill 0.4064)
		(layers "F.Cu" "B.Cu")
		(net "GND")
	)
	(via
		(at 221.651068 21.73605)
		(size 0.7112)
		(drill 0.4064)
		(layers "F.Cu" "B.Cu")
		(net "GND")
	)
	(via
		(at 457.2 -111.76)
		(size 0.5588)
		(drill 0.3048)
		(layers "F.Cu" "B.Cu")
		(net "GND")
	)
	(via
		(at 178.917346 -157.073346)
		(size 0.7112)
		(drill 0.4064)
		(layers "F.Cu" "B.Cu")
		(net "GND")
	)
	(via
		(at 4.445 -337.82)
		(size 0.5588)
		(drill 0.3048)
		(layers "F.Cu" "B.Cu")
		(net "GND")
	)
	(via
		(at 1.397 -37.208968)
		(size 0.7112)
		(drill 0.4064)
		(layers "F.Cu" "B.Cu")
		(net "GND")
	)
	(via
		(at 53.942996 -347.802962)
		(size 0.7112)
		(drill 0.4064)
		(layers "F.Cu" "B.Cu")
		(net "GND")
	)
	(via
		(at 280.186892 -419.803072)
		(size 0.7112)
		(drill 0.4064)
		(layers "F.Cu" "B.Cu")
		(net "GND")
	)
	(via
		(at 262.957056 37.403024)
		(size 0.7112)
		(drill 0.4064)
		(layers "F.Cu" "B.Cu")
		(net "GND")
	)
	(via
		(at 490.053122 -281.651202)
		(size 0.7112)
		(drill 0.4064)
		(layers "F.Cu" "B.Cu")
		(net "GND")
	)
	(via
		(at 318.516 -26.67)
		(size 0.5588)
		(drill 0.3048)
		(layers "F.Cu" "B.Cu")
		(net "GND")
	)
	(via
		(at 411.48 -10.16)
		(size 0.5588)
		(drill 0.3048)
		(layers "F.Cu" "B.Cu")
		(net "GND")
	)
	(via
		(at 383.484882 -347.802962)
		(size 0.7112)
		(drill 0.4064)
		(layers "F.Cu" "B.Cu")
		(net "GND")
	)
	(via
		(at 441.96 -20.32)
		(size 0.5588)
		(drill 0.3048)
		(layers "F.Cu" "B.Cu")
		(net "GND")
	)
	(via
		(at 1.397 -58.798968)
		(size 0.7112)
		(drill 0.4064)
		(layers "F.Cu" "B.Cu")
		(net "GND")
	)
	(via
		(at 146.652996 -347.802962)
		(size 0.7112)
		(drill 0.4064)
		(layers "F.Cu" "B.Cu")
		(net "GND")
	)
	(via
		(at 295.148 -348.361)
		(size 0.7112)
		(drill 0.4064)
		(layers "F.Cu" "B.Cu")
		(net "GND")
	)
	(via
		(at 444.444882 -347.802962)
		(size 0.7112)
		(drill 0.4064)
		(layers "F.Cu" "B.Cu")
		(net "GND")
	)
	(via
		(at 29.4132 -246.6848)
		(size 0.5588)
		(drill 0.3048)
		(layers "F.Cu" "B.Cu")
		(net "GND")
	)
	(via
		(at 472.44 -335.28)
		(size 0.5588)
		(drill 0.3048)
		(layers "F.Cu" "B.Cu")
		(net "GND")
	)
	(via
		(at 476.574104 -231.662986)
		(size 0.5588)
		(drill 0.3048)
		(layers "F.Cu" "B.Cu")
		(net "GND")
	)
	(via
		(at 341.981028 -1.397)
		(size 0.7112)
		(drill 0.4064)
		(layers "F.Cu" "B.Cu")
		(net "GND")
	)
	(via
		(at 201.397108 -416.042856)
		(size 0.7112)
		(drill 0.4064)
		(layers "F.Cu" "B.Cu")
		(net "GND")
	)
	(via
		(at 301.341028 -1.397)
		(size 0.7112)
		(drill 0.4064)
		(layers "F.Cu" "B.Cu")
		(net "GND")
	)
	(via
		(at 1.397 -241.678968)
		(size 0.7112)
		(drill 0.4064)
		(layers "F.Cu" "B.Cu")
		(net "GND")
	)
	(via
		(at 451.854824 -279.655016)
		(size 0.5588)
		(drill 0.3048)
		(layers "F.Cu" "B.Cu")
		(net "GND")
	)
	(via
		(at 487.68 -325.12)
		(size 0.5588)
		(drill 0.3048)
		(layers "F.Cu" "B.Cu")
		(net "GND")
	)
	(via
		(at 86.540848 -49.443894)
		(size 0.5588)
		(drill 0.3048)
		(layers "F.Cu" "B.Cu")
		(net "GND")
	)
	(via
		(at 490.053122 -299.431202)
		(size 0.7112)
		(drill 0.4064)
		(layers "F.Cu" "B.Cu")
		(net "GND")
	)
	(via
		(at 293.751 -206.502)
		(size 0.5588)
		(drill 0.3048)
		(layers "F.Cu" "B.Cu")
		(net "GND")
	)
	(via
		(at 10.16 -246.38)
		(size 0.5588)
		(drill 0.3048)
		(layers "F.Cu" "B.Cu")
		(net "GND")
	)
	(via
		(at 39.245032 -1.397)
		(size 0.7112)
		(drill 0.4064)
		(layers "F.Cu" "B.Cu")
		(net "GND")
	)
	(via
		(at 149.86 -316.738)
		(size 0.5588)
		(drill 0.3048)
		(layers "F.Cu" "B.Cu")
		(net "GND")
	)
	(via
		(at 77.5208 -271.3736)
		(size 0.5588)
		(drill 0.3048)
		(layers "F.Cu" "B.Cu")
		(net "GND")
	)
	(via
		(at 364.434882 -347.802962)
		(size 0.7112)
		(drill 0.4064)
		(layers "F.Cu" "B.Cu")
		(net "GND")
	)
	(via
		(at 203.733908 -10.43305)
		(size 0.5588)
		(drill 0.3048)
		(layers "F.Cu" "B.Cu")
		(net "GND")
	)
	(via
		(at 184.912 -170.230038)
		(size 0.5588)
		(drill 0.3048)
		(layers "F.Cu" "B.Cu")
		(net "GND")
	)
	(via
		(at 363.164882 -347.802962)
		(size 0.7112)
		(drill 0.4064)
		(layers "F.Cu" "B.Cu")
		(net "GND")
	)
	(via
		(at 490.053122 -79.12735)
		(size 0.7112)
		(drill 0.4064)
		(layers "F.Cu" "B.Cu")
		(net "GND")
	)
	(via
		(at 177.897282 -238.808006)
		(size 0.6096)
		(drill 0.3048)
		(layers "F.Cu" "B.Cu")
		(net "GND")
	)
	(via
		(at 490.053122 -155.32735)
		(size 0.7112)
		(drill 0.4064)
		(layers "F.Cu" "B.Cu")
		(net "GND")
	)
	(via
		(at 345.948 -250.698)
		(size 0.5588)
		(drill 0.3048)
		(layers "F.Cu" "B.Cu")
		(net "GND")
	)
	(via
		(at 258.4704 -16.1544)
		(size 0.5588)
		(drill 0.3048)
		(layers "F.Cu" "B.Cu")
		(net "GND")
	)
	(via
		(at 262.89 16.9672)
		(size 0.5588)
		(drill 0.3048)
		(layers "F.Cu" "B.Cu")
		(net "GND")
	)
	(via
		(at 462.28 -198.12)
		(size 0.5588)
		(drill 0.3048)
		(layers "F.Cu" "B.Cu")
		(net "GND")
	)
	(via
		(at 68.646802 -149.66315)
		(size 0.5588)
		(drill 0.3048)
		(layers "F.Cu" "B.Cu")
		(net "GND")
	)
	(via
		(at 162.442398 -60.238894)
		(size 0.5588)
		(drill 0.3048)
		(layers "F.Cu" "B.Cu")
		(net "GND")
	)
	(via
		(at 55.88 -132.08)
		(size 0.5588)
		(drill 0.3048)
		(layers "F.Cu" "B.Cu")
		(net "GND")
	)
	(via
		(at 1.397 -225.168968)
		(size 0.7112)
		(drill 0.4064)
		(layers "F.Cu" "B.Cu")
		(net "GND")
	)
	(via
		(at 201.397108 -418.582856)
		(size 0.7112)
		(drill 0.4064)
		(layers "F.Cu" "B.Cu")
		(net "GND")
	)
	(via
		(at 1.397 -35.938968)
		(size 0.7112)
		(drill 0.4064)
		(layers "F.Cu" "B.Cu")
		(net "GND")
	)
	(via
		(at 39.624 -262.128)
		(size 0.5588)
		(drill 0.3048)
		(layers "F.Cu" "B.Cu")
		(net "GND")
	)
	(via
		(at 92.751148 -22.537674)
		(size 0.5588)
		(drill 0.3048)
		(layers "F.Cu" "B.Cu")
		(net "GND")
	)
	(via
		(at 462.28 -25.4)
		(size 0.5588)
		(drill 0.3048)
		(layers "F.Cu" "B.Cu")
		(net "GND")
	)
	(via
		(at 292.886892 -419.803072)
		(size 0.7112)
		(drill 0.4064)
		(layers "F.Cu" "B.Cu")
		(net "GND")
	)
	(via
		(at 238.155734 -232.492296)
		(size 0.5588)
		(drill 0.3048)
		(layers "F.Cu" "B.Cu")
		(net "GND")
	)
	(via
		(at 82.133948 -47.615094)
		(size 0.5588)
		(drill 0.3048)
		(layers "F.Cu" "B.Cu")
		(net "GND")
	)
	(via
		(at 462.28 -35.56)
		(size 0.5588)
		(drill 0.3048)
		(layers "F.Cu" "B.Cu")
		(net "GND")
	)
	(via
		(at 447.04 -121.92)
		(size 0.5588)
		(drill 0.3048)
		(layers "F.Cu" "B.Cu")
		(net "GND")
	)
	(via
		(at 130.274568 -186.00293)
		(size 0.5588)
		(drill 0.3048)
		(layers "F.Cu" "B.Cu")
		(net "GND")
	)
	(via
		(at 55.88 -127)
		(size 0.5588)
		(drill 0.3048)
		(layers "F.Cu" "B.Cu")
		(net "GND")
	)
	(via
		(at 388.754874 -62.354968)
		(size 0.5588)
		(drill 0.3048)
		(layers "F.Cu" "B.Cu")
		(net "GND")
	)
	(via
		(at 301.776892 -419.803072)
		(size 0.7112)
		(drill 0.4064)
		(layers "F.Cu" "B.Cu")
		(net "GND")
	)
	(via
		(at 426.120052 -306.113942)
		(size 0.5588)
		(drill 0.3048)
		(layers "F.Cu" "B.Cu")
		(net "GND")
	)
	(via
		(at 76.2 -81.28)
		(size 0.5588)
		(drill 0.3048)
		(layers "F.Cu" "B.Cu")
		(net "GND")
	)
	(via
		(at 55.88 -322.58)
		(size 0.5588)
		(drill 0.3048)
		(layers "F.Cu" "B.Cu")
		(net "GND")
	)
	(via
		(at 477.52 -15.24)
		(size 0.5588)
		(drill 0.3048)
		(layers "F.Cu" "B.Cu")
		(net "GND")
	)
	(via
		(at 436.290974 -255.537716)
		(size 0.5588)
		(drill 0.3048)
		(layers "F.Cu" "B.Cu")
		(net "GND")
	)
	(via
		(at 456.048872 -191.158876)
		(size 0.5588)
		(drill 0.3048)
		(layers "F.Cu" "B.Cu")
		(net "GND")
	)
	(via
		(at 286.536892 -419.803072)
		(size 0.7112)
		(drill 0.4064)
		(layers "F.Cu" "B.Cu")
		(net "GND")
	)
	(via
		(at 148.205698 -164.494718)
		(size 0.5588)
		(drill 0.3048)
		(layers "F.Cu" "B.Cu")
		(net "GND")
	)
	(via
		(at 1.397 -331.848968)
		(size 0.7112)
		(drill 0.4064)
		(layers "F.Cu" "B.Cu")
		(net "GND")
	)
	(via
		(at 338.455 -14.351)
		(size 0.5588)
		(drill 0.3048)
		(layers "F.Cu" "B.Cu")
		(net "GND")
	)
	(via
		(at 100.838 -231.394)
		(size 0.5588)
		(drill 0.3048)
		(layers "F.Cu" "B.Cu")
		(net "GND")
	)
	(via
		(at 38.862 -280.67)
		(size 0.5588)
		(drill 0.3048)
		(layers "F.Cu" "B.Cu")
		(net "GND")
	)
	(via
		(at 384.754882 -347.802962)
		(size 0.7112)
		(drill 0.4064)
		(layers "F.Cu" "B.Cu")
		(net "GND")
	)
	(via
		(at 400.81962 -1.397)
		(size 0.7112)
		(drill 0.4064)
		(layers "F.Cu" "B.Cu")
		(net "GND")
	)
	(via
		(at 147.066 -170.688)
		(size 0.5588)
		(drill 0.3048)
		(layers "F.Cu" "B.Cu")
		(net "GND")
	)
	(via
		(at 201.397108 -402.072856)
		(size 0.7112)
		(drill 0.4064)
		(layers "F.Cu" "B.Cu")
		(net "GND")
	)
	(via
		(at 340.233 -201.676)
		(size 0.5588)
		(drill 0.3048)
		(layers "F.Cu" "B.Cu")
		(net "GND")
	)
	(via
		(at 136.906 -332.486)
		(size 0.5588)
		(drill 0.3048)
		(layers "F.Cu" "B.Cu")
		(net "GND")
	)
	(via
		(at 490.053122 -37.21735)
		(size 0.7112)
		(drill 0.4064)
		(layers "F.Cu" "B.Cu")
		(net "GND")
	)
	(via
		(at 144.660366 -127.540258)
		(size 0.5588)
		(drill 0.3048)
		(layers "F.Cu" "B.Cu")
		(net "GND")
	)
	(via
		(at 1.397 -231.518968)
		(size 0.7112)
		(drill 0.4064)
		(layers "F.Cu" "B.Cu")
		(net "GND")
	)
	(via
		(at 359.354882 -347.802962)
		(size 0.7112)
		(drill 0.4064)
		(layers "F.Cu" "B.Cu")
		(net "GND")
	)
	(via
		(at 144.852898 -289.603942)
		(size 0.5588)
		(drill 0.3048)
		(layers "F.Cu" "B.Cu")
		(net "GND")
	)
	(via
		(at 308.602888 -381.671068)
		(size 0.7112)
		(drill 0.4064)
		(layers "F.Cu" "B.Cu")
		(net "GND")
	)
	(via
		(at 278.7904 20.945348)
		(size 0.5588)
		(drill 0.3048)
		(layers "F.Cu" "B.Cu")
		(net "GND")
	)
	(via
		(at 25.4 -228.6)
		(size 0.5588)
		(drill 0.3048)
		(layers "F.Cu" "B.Cu")
		(net "GND")
	)
	(via
		(at 27.161998 -282.830016)
		(size 0.5588)
		(drill 0.3048)
		(layers "F.Cu" "B.Cu")
		(net "GND")
	)
	(via
		(at 77.343 -290.195)
		(size 0.5588)
		(drill 0.3048)
		(layers "F.Cu" "B.Cu")
		(net "GND")
	)
	(via
		(at 281.520138 -229.264718)
		(size 0.5588)
		(drill 0.3048)
		(layers "F.Cu" "B.Cu")
		(net "GND")
	)
	(via
		(at 186.055 -67.434968)
		(size 0.5588)
		(drill 0.3048)
		(layers "F.Cu" "B.Cu")
		(net "GND")
	)
	(via
		(at 357.205026 -297.435016)
		(size 0.5588)
		(drill 0.3048)
		(layers "F.Cu" "B.Cu")
		(net "GND")
	)
	(via
		(at 234.839002 -244.58803)
		(size 0.5588)
		(drill 0.3048)
		(layers "F.Cu" "B.Cu")
		(net "GND")
	)
	(via
		(at 10.16 -241.3)
		(size 0.5588)
		(drill 0.3048)
		(layers "F.Cu" "B.Cu")
		(net "GND")
	)
	(via
		(at 44.106846 -64.683894)
		(size 0.5588)
		(drill 0.3048)
		(layers "F.Cu" "B.Cu")
		(net "GND")
	)
	(via
		(at 43.055032 -1.397)
		(size 0.7112)
		(drill 0.4064)
		(layers "F.Cu" "B.Cu")
		(net "GND")
	)
	(via
		(at 121.811796 -280.42997)
		(size 0.5588)
		(drill 0.3048)
		(layers "F.Cu" "B.Cu")
		(net "GND")
	)
	(via
		(at 428.406052 -297.223942)
		(size 0.5588)
		(drill 0.3048)
		(layers "F.Cu" "B.Cu")
		(net "GND")
	)
	(via
		(at 458.3049 -156.315918)
		(size 0.5588)
		(drill 0.3048)
		(layers "F.Cu" "B.Cu")
		(net "GND")
	)
	(via
		(at 1.397 -230.248968)
		(size 0.7112)
		(drill 0.4064)
		(layers "F.Cu" "B.Cu")
		(net "GND")
	)
	(via
		(at 12.573 -185.166)
		(size 0.5588)
		(drill 0.3048)
		(layers "F.Cu" "B.Cu")
		(net "GND")
	)
	(via
		(at 15.24 -30.48)
		(size 0.5588)
		(drill 0.3048)
		(layers "F.Cu" "B.Cu")
		(net "GND")
	)
	(via
		(at 490.053122 -11.81735)
		(size 0.7112)
		(drill 0.4064)
		(layers "F.Cu" "B.Cu")
		(net "GND")
	)
	(via
		(at 351.915476 -282.830016)
		(size 0.5588)
		(drill 0.3048)
		(layers "F.Cu" "B.Cu")
		(net "GND")
	)
	(via
		(at 9.779 -203.327)
		(size 0.5588)
		(drill 0.3048)
		(layers "F.Cu" "B.Cu")
		(net "GND")
	)
	(via
		(at 217.619326 -19.039078)
		(size 0.5588)
		(drill 0.3048)
		(layers "F.Cu" "B.Cu")
		(net "GND")
	)
	(via
		(at 201.397108 -375.402856)
		(size 0.7112)
		(drill 0.4064)
		(layers "F.Cu" "B.Cu")
		(net "GND")
	)
	(via
		(at 15.24 -81.28)
		(size 0.5588)
		(drill 0.3048)
		(layers "F.Cu" "B.Cu")
		(net "GND")
	)
	(via
		(at 89.154 -17.9578)
		(size 0.5588)
		(drill 0.3048)
		(layers "F.Cu" "B.Cu")
		(net "GND")
	)
	(via
		(at 7.778242 -290.088828)
		(size 0.5588)
		(drill 0.3048)
		(layers "F.Cu" "B.Cu")
		(net "GND")
	)
	(via
		(at 419.161976 -50.429922)
		(size 0.5588)
		(drill 0.3048)
		(layers "F.Cu" "B.Cu")
		(net "GND")
	)
	(via
		(at 426.72 -106.68)
		(size 0.5588)
		(drill 0.3048)
		(layers "F.Cu" "B.Cu")
		(net "GND")
	)
	(via
		(at 150.368 -228.727)
		(size 0.5588)
		(drill 0.3048)
		(layers "F.Cu" "B.Cu")
		(net "GND")
	)
	(via
		(at 1.397 -134.998968)
		(size 0.7112)
		(drill 0.4064)
		(layers "F.Cu" "B.Cu")
		(net "GND")
	)
	(via
		(at 292.1 16.002)
		(size 0.5588)
		(drill 0.3048)
		(layers "F.Cu" "B.Cu")
		(net "GND")
	)
	(via
		(at 253.365 -302.895)
		(size 0.5588)
		(drill 0.3048)
		(layers "F.Cu" "B.Cu")
		(net "GND")
	)
	(via
		(at 370.577618 -246.26189)
		(size 0.5588)
		(drill 0.3048)
		(layers "F.Cu" "B.Cu")
		(net "GND")
	)
	(via
		(at 24.240998 -191.240918)
		(size 0.5588)
		(drill 0.3048)
		(layers "F.Cu" "B.Cu")
		(net "GND")
	)
	(via
		(at 1.397 -105.788968)
		(size 0.7112)
		(drill 0.4064)
		(layers "F.Cu" "B.Cu")
		(net "GND")
	)
	(via
		(at 15.748 -70.231)
		(size 0.5588)
		(drill 0.3048)
		(layers "F.Cu" "B.Cu")
		(net "GND")
	)
	(via
		(at 490.053122 -34.67735)
		(size 0.7112)
		(drill 0.4064)
		(layers "F.Cu" "B.Cu")
		(net "GND")
	)
	(via
		(at 149.192996 -347.802962)
		(size 0.7112)
		(drill 0.4064)
		(layers "F.Cu" "B.Cu")
		(net "GND")
	)
	(via
		(at 487.68 -335.28)
		(size 0.5588)
		(drill 0.3048)
		(layers "F.Cu" "B.Cu")
		(net "GND")
	)
	(via
		(at 447.4464 -251.7648)
		(size 0.5588)
		(drill 0.3048)
		(layers "F.Cu" "B.Cu")
		(net "GND")
	)
	(via
		(at 452.12 -30.48)
		(size 0.5588)
		(drill 0.3048)
		(layers "F.Cu" "B.Cu")
		(net "GND")
	)
	(via
		(at 226.862132 -385.201668)
		(size 0.5588)
		(drill 0.3048)
		(layers "F.Cu" "B.Cu")
		(net "GND")
	)
	(via
		(at 101.466396 -296.363898)
		(size 0.5588)
		(drill 0.3048)
		(layers "F.Cu" "B.Cu")
		(net "GND")
	)
	(via
		(at 174.1297 -169.015918)
		(size 0.5588)
		(drill 0.3048)
		(layers "F.Cu" "B.Cu")
		(net "GND")
	)
	(via
		(at 10.16 -15.24)
		(size 0.5588)
		(drill 0.3048)
		(layers "F.Cu" "B.Cu")
		(net "GND")
	)
	(via
		(at 69.725032 -1.397)
		(size 0.7112)
		(drill 0.4064)
		(layers "F.Cu" "B.Cu")
		(net "GND")
	)
	(via
		(at 186.055 -279.655016)
		(size 0.5588)
		(drill 0.3048)
		(layers "F.Cu" "B.Cu")
		(net "GND")
	)
	(via
		(at 171.069 -191.008)
		(size 0.5588)
		(drill 0.3048)
		(layers "F.Cu" "B.Cu")
		(net "GND")
	)
	(via
		(at 198.004938 -371.603016)
		(size 0.7112)
		(drill 0.4064)
		(layers "F.Cu" "B.Cu")
		(net "GND")
	)
	(via
		(at 1.397 -66.418968)
		(size 0.7112)
		(drill 0.4064)
		(layers "F.Cu" "B.Cu")
		(net "GND")
	)
	(via
		(at 129.281682 -347.548962)
		(size 0.7112)
		(drill 0.4064)
		(layers "F.Cu" "B.Cu")
		(net "GND")
	)
	(via
		(at 35.56 -30.48)
		(size 0.5588)
		(drill 0.3048)
		(layers "F.Cu" "B.Cu")
		(net "GND")
	)
	(via
		(at 421.64 -335.28)
		(size 0.5588)
		(drill 0.3048)
		(layers "F.Cu" "B.Cu")
		(net "GND")
	)
	(via
		(at 70.649084 -300.46676)
		(size 0.5588)
		(drill 0.3048)
		(layers "F.Cu" "B.Cu")
		(net "GND")
	)
	(via
		(at 1.397 -154.048968)
		(size 0.7112)
		(drill 0.4064)
		(layers "F.Cu" "B.Cu")
		(net "GND")
	)
	(via
		(at 490.053122 -60.07735)
		(size 0.7112)
		(drill 0.4064)
		(layers "F.Cu" "B.Cu")
		(net "GND")
	)
	(via
		(at 490.053122 -19.43735)
		(size 0.7112)
		(drill 0.4064)
		(layers "F.Cu" "B.Cu")
		(net "GND")
	)
	(via
		(at 117.010942 -272.281904)
		(size 0.5588)
		(drill 0.3048)
		(layers "F.Cu" "B.Cu")
		(net "GND")
	)
	(via
		(at 186.055 -184.974992)
		(size 0.5588)
		(drill 0.3048)
		(layers "F.Cu" "B.Cu")
		(net "GND")
	)
	(via
		(at 490.053122 -63.88735)
		(size 0.7112)
		(drill 0.4064)
		(layers "F.Cu" "B.Cu")
		(net "GND")
	)
	(via
		(at 297.247056 37.403024)
		(size 0.7112)
		(drill 0.4064)
		(layers "F.Cu" "B.Cu")
		(net "GND")
	)
	(via
		(at 297.124882 -347.802962)
		(size 0.7112)
		(drill 0.4064)
		(layers "F.Cu" "B.Cu")
		(net "GND")
	)
	(via
		(at 325.064882 -347.802962)
		(size 0.7112)
		(drill 0.4064)
		(layers "F.Cu" "B.Cu")
		(net "GND")
	)
	(via
		(at 462.28 -30.48)
		(size 0.5588)
		(drill 0.3048)
		(layers "F.Cu" "B.Cu")
		(net "GND")
	)
	(via
		(at 50.8 -20.32)
		(size 0.5588)
		(drill 0.3048)
		(layers "F.Cu" "B.Cu")
		(net "GND")
	)
	(via
		(at 71.12 -30.48)
		(size 0.5588)
		(drill 0.3048)
		(layers "F.Cu" "B.Cu")
		(net "GND")
	)
	(via
		(at 16.379698 -169.015918)
		(size 0.5588)
		(drill 0.3048)
		(layers "F.Cu" "B.Cu")
		(net "GND")
	)
	(via
		(at 22.601682 -347.548962)
		(size 0.7112)
		(drill 0.4064)
		(layers "F.Cu" "B.Cu")
		(net "GND")
	)
	(via
		(at 397.256 -241.046)
		(size 0.5588)
		(drill 0.3048)
		(layers "F.Cu" "B.Cu")
		(net "GND")
	)
	(via
		(at 278.197056 37.403024)
		(size 0.7112)
		(drill 0.4064)
		(layers "F.Cu" "B.Cu")
		(net "GND")
	)
	(via
		(at 362.715302 -276.649942)
		(size 0.5588)
		(drill 0.3048)
		(layers "F.Cu" "B.Cu")
		(net "GND")
	)
	(via
		(at 457.2 -121.92)
		(size 0.5588)
		(drill 0.3048)
		(layers "F.Cu" "B.Cu")
		(net "GND")
	)
	(via
		(at 150.440898 -76.240894)
		(size 0.5588)
		(drill 0.3048)
		(layers "F.Cu" "B.Cu")
		(net "GND")
	)
	(via
		(at 125.471682 -347.548962)
		(size 0.7112)
		(drill 0.4064)
		(layers "F.Cu" "B.Cu")
		(net "GND")
	)
	(via
		(at 18.652998 -177.778918)
		(size 0.5588)
		(drill 0.3048)
		(layers "F.Cu" "B.Cu")
		(net "GND")
	)
	(via
		(at 179.7558 -164.875718)
		(size 0.5588)
		(drill 0.3048)
		(layers "F.Cu" "B.Cu")
		(net "GND")
	)
	(via
		(at 302.785272 -181.8386)
		(size 0.5588)
		(drill 0.3048)
		(layers "F.Cu" "B.Cu")
		(net "GND")
	)
	(via
		(at 201.397108 -396.992856)
		(size 0.7112)
		(drill 0.4064)
		(layers "F.Cu" "B.Cu")
		(net "GND")
	)
	(via
		(at 259.744972 9.3726)
		(size 0.5588)
		(drill 0.3048)
		(layers "F.Cu" "B.Cu")
		(net "GND")
	)
	(via
		(at 117.221 -195.453)
		(size 0.5588)
		(drill 0.3048)
		(layers "F.Cu" "B.Cu")
		(net "GND")
	)
	(via
		(at 35.56 -76.2)
		(size 0.5588)
		(drill 0.3048)
		(layers "F.Cu" "B.Cu")
		(net "GND")
	)
	(via
		(at 230.124 -310.388)
		(size 0.5588)
		(drill 0.3048)
		(layers "F.Cu" "B.Cu")
		(net "GND")
	)
	(via
		(at 490.053122 -231.52735)
		(size 0.7112)
		(drill 0.4064)
		(layers "F.Cu" "B.Cu")
		(net "GND")
	)
	(via
		(at 54.485032 -1.397)
		(size 0.7112)
		(drill 0.4064)
		(layers "F.Cu" "B.Cu")
		(net "GND")
	)
	(via
		(at 20.574 -285.623)
		(size 0.5588)
		(drill 0.3048)
		(layers "F.Cu" "B.Cu")
		(net "GND")
	)
	(via
		(at 5.08 -76.2)
		(size 0.5588)
		(drill 0.3048)
		(layers "F.Cu" "B.Cu")
		(net "GND")
	)
	(via
		(at 490.053122 -190.88735)
		(size 0.7112)
		(drill 0.4064)
		(layers "F.Cu" "B.Cu")
		(net "GND")
	)
	(via
		(at 404.62962 -1.397)
		(size 0.7112)
		(drill 0.4064)
		(layers "F.Cu" "B.Cu")
		(net "GND")
	)
	(via
		(at 35.56 -127)
		(size 0.5588)
		(drill 0.3048)
		(layers "F.Cu" "B.Cu")
		(net "GND")
	)
	(via
		(at 154.504898 -62.354968)
		(size 0.5588)
		(drill 0.3048)
		(layers "F.Cu" "B.Cu")
		(net "GND")
	)
	(via
		(at 39.972996 -347.802962)
		(size 0.7112)
		(drill 0.4064)
		(layers "F.Cu" "B.Cu")
		(net "GND")
	)
	(via
		(at 201.397108 -399.532856)
		(size 0.7112)
		(drill 0.4064)
		(layers "F.Cu" "B.Cu")
		(net "GND")
	)
	(via
		(at 1.397 -95.628968)
		(size 0.7112)
		(drill 0.4064)
		(layers "F.Cu" "B.Cu")
		(net "GND")
	)
	(via
		(at 66.04 -25.4)
		(size 0.5588)
		(drill 0.3048)
		(layers "F.Cu" "B.Cu")
		(net "GND")
	)
	(via
		(at 116.84 -335.28)
		(size 0.5588)
		(drill 0.3048)
		(layers "F.Cu" "B.Cu")
		(net "GND")
	)
	(via
		(at 350.464882 -347.802962)
		(size 0.7112)
		(drill 0.4064)
		(layers "F.Cu" "B.Cu")
		(net "GND")
	)
	(via
		(at 326.334882 -347.802962)
		(size 0.7112)
		(drill 0.4064)
		(layers "F.Cu" "B.Cu")
		(net "GND")
	)
	(via
		(at 221.021402 -212.382862)
		(size 0.5588)
		(drill 0.3048)
		(layers "F.Cu" "B.Cu")
		(net "GND")
	)
	(via
		(at 202.667108 -419.852856)
		(size 0.7112)
		(drill 0.4064)
		(layers "F.Cu" "B.Cu")
		(net "GND")
	)
	(via
		(at 288.911284 -357.705152)
		(size 0.6604)
		(drill 0.3556)
		(layers "F.Cu" "B.Cu")
		(net "GND")
	)
	(via
		(at 55.212996 -347.802962)
		(size 0.7112)
		(drill 0.4064)
		(layers "F.Cu" "B.Cu")
		(net "GND")
	)
	(via
		(at 47.929546 -53.990494)
		(size 0.5588)
		(drill 0.3048)
		(layers "F.Cu" "B.Cu")
		(net "GND")
	)
	(via
		(at 40.64 -81.28)
		(size 0.5588)
		(drill 0.3048)
		(layers "F.Cu" "B.Cu")
		(net "GND")
	)
	(via
		(at 490.053122 -310.861202)
		(size 0.7112)
		(drill 0.4064)
		(layers "F.Cu" "B.Cu")
		(net "GND")
	)
	(via
		(at 100.457 -40.767)
		(size 0.5588)
		(drill 0.3048)
		(layers "F.Cu" "B.Cu")
		(net "GND")
	)
	(via
		(at 374.144032 -246.290084)
		(size 0.5588)
		(drill 0.3048)
		(layers "F.Cu" "B.Cu")
		(net "GND")
	)
	(via
		(at 221.651068 19.19605)
		(size 0.7112)
		(drill 0.4064)
		(layers "F.Cu" "B.Cu")
		(net "GND")
	)
	(via
		(at 216.603326 -17.007078)
		(size 0.5588)
		(drill 0.3048)
		(layers "F.Cu" "B.Cu")
		(net "GND")
	)
	(via
		(at 436.372 -222.504)
		(size 0.5588)
		(drill 0.3048)
		(layers "F.Cu" "B.Cu")
		(net "GND")
	)
	(via
		(at 144.852898 -177.778918)
		(size 0.5588)
		(drill 0.3048)
		(layers "F.Cu" "B.Cu")
		(net "GND")
	)
	(via
		(at 1.397 -156.588968)
		(size 0.7112)
		(drill 0.4064)
		(layers "F.Cu" "B.Cu")
		(net "GND")
	)
	(via
		(at 118.890796 -76.240894)
		(size 0.5588)
		(drill 0.3048)
		(layers "F.Cu" "B.Cu")
		(net "GND")
	)
	(via
		(at 11.305032 -1.397)
		(size 0.7112)
		(drill 0.4064)
		(layers "F.Cu" "B.Cu")
		(net "GND")
	)
	(via
		(at 490.053122 -323.561202)
		(size 0.7112)
		(drill 0.4064)
		(layers "F.Cu" "B.Cu")
		(net "GND")
	)
	(via
		(at 176.657 -117.475)
		(size 0.5588)
		(drill 0.3048)
		(layers "F.Cu" "B.Cu")
		(net "GND")
	)
	(via
		(at 1.397 -63.878968)
		(size 0.7112)
		(drill 0.4064)
		(layers "F.Cu" "B.Cu")
		(net "GND")
	)
	(via
		(at 324.201028 -1.397)
		(size 0.7112)
		(drill 0.4064)
		(layers "F.Cu" "B.Cu")
		(net "GND")
	)
	(via
		(at 181.923182 -220.527626)
		(size 0.5588)
		(drill 0.3048)
		(layers "F.Cu" "B.Cu")
		(net "GND")
	)
	(via
		(at 356.87 -121.92)
		(size 0.5588)
		(drill 0.3048)
		(layers "F.Cu" "B.Cu")
		(net "GND")
	)
	(via
		(at 222.3262 -174.1424)
		(size 0.5588)
		(drill 0.3048)
		(layers "F.Cu" "B.Cu")
		(net "GND")
	)
	(via
		(at 57.752996 -347.802962)
		(size 0.7112)
		(drill 0.4064)
		(layers "F.Cu" "B.Cu")
		(net "GND")
	)
	(via
		(at 150.368 -151.13)
		(size 0.5588)
		(drill 0.3048)
		(layers "F.Cu" "B.Cu")
		(net "GND")
	)
	(via
		(at 288.911284 -328.905108)
		(size 0.6604)
		(drill 0.3556)
		(layers "F.Cu" "B.Cu")
		(net "GND")
	)
	(via
		(at 490.053122 -75.31735)
		(size 0.7112)
		(drill 0.4064)
		(layers "F.Cu" "B.Cu")
		(net "GND")
	)
	(via
		(at 490.053122 -197.23735)
		(size 0.7112)
		(drill 0.4064)
		(layers "F.Cu" "B.Cu")
		(net "GND")
	)
	(via
		(at 490.053122 -235.33735)
		(size 0.7112)
		(drill 0.4064)
		(layers "F.Cu" "B.Cu")
		(net "GND")
	)
	(via
		(at 482.261926 -170.230038)
		(size 0.5588)
		(drill 0.3048)
		(layers "F.Cu" "B.Cu")
		(net "GND")
	)
	(via
		(at 192.350898 -360.901742)
		(size 0.7112)
		(drill 0.4064)
		(layers "F.Cu" "B.Cu")
		(net "GND")
	)
	(via
		(at 201.397108 -394.452856)
		(size 0.7112)
		(drill 0.4064)
		(layers "F.Cu" "B.Cu")
		(net "GND")
	)
	(via
		(at 5.08 -111.76)
		(size 0.5588)
		(drill 0.3048)
		(layers "F.Cu" "B.Cu")
		(net "GND")
	)
	(via
		(at 274.066 -121.158)
		(size 0.5588)
		(drill 0.3048)
		(layers "F.Cu" "B.Cu")
		(net "GND")
	)
	(via
		(at 1.397 -187.068968)
		(size 0.7112)
		(drill 0.4064)
		(layers "F.Cu" "B.Cu")
		(net "GND")
	)
	(via
		(at 77.345032 -1.397)
		(size 0.7112)
		(drill 0.4064)
		(layers "F.Cu" "B.Cu")
		(net "GND")
	)
	(via
		(at 13.738352 -130.133344)
		(size 0.5588)
		(drill 0.3048)
		(layers "F.Cu" "B.Cu")
		(net "GND")
	)
	(via
		(at 193.675 -251.079)
		(size 0.5588)
		(drill 0.3048)
		(layers "F.Cu" "B.Cu")
		(net "GND")
	)
	(via
		(at 490.053122 -300.701202)
		(size 0.7112)
		(drill 0.4064)
		(layers "F.Cu" "B.Cu")
		(net "GND")
	)
	(via
		(at 221.4118 -174.1424)
		(size 0.5588)
		(drill 0.3048)
		(layers "F.Cu" "B.Cu")
		(net "GND")
	)
	(via
		(at 175.641 -197.612)
		(size 0.5588)
		(drill 0.3048)
		(layers "F.Cu" "B.Cu")
		(net "GND")
	)
	(via
		(at 6.35 -276.86)
		(size 0.5588)
		(drill 0.3048)
		(layers "F.Cu" "B.Cu")
		(net "GND")
	)
	(via
		(at 490.053122 -35.94735)
		(size 0.7112)
		(drill 0.4064)
		(layers "F.Cu" "B.Cu")
		(net "GND")
	)
	(via
		(at 490.053122 -242.95735)
		(size 0.7112)
		(drill 0.4064)
		(layers "F.Cu" "B.Cu")
		(net "GND")
	)
	(via
		(at 6.35 -259.08)
		(size 0.5588)
		(drill 0.3048)
		(layers "F.Cu" "B.Cu")
		(net "GND")
	)
	(via
		(at 50.675032 -1.397)
		(size 0.7112)
		(drill 0.4064)
		(layers "F.Cu" "B.Cu")
		(net "GND")
	)
	(via
		(at 36.242498 -60.238894)
		(size 0.5588)
		(drill 0.3048)
		(layers "F.Cu" "B.Cu")
		(net "GND")
	)
	(via
		(at 490.053122 -112.14735)
		(size 0.7112)
		(drill 0.4064)
		(layers "F.Cu" "B.Cu")
		(net "GND")
	)
	(via
		(at 285.817056 37.403024)
		(size 0.7112)
		(drill 0.4064)
		(layers "F.Cu" "B.Cu")
		(net "GND")
	)
	(via
		(at 354.33 -201.041)
		(size 0.5588)
		(drill 0.3048)
		(layers "F.Cu" "B.Cu")
		(net "GND")
	)
	(via
		(at 198.12 -10.16)
		(size 0.5588)
		(drill 0.3048)
		(layers "F.Cu" "B.Cu")
		(net "GND")
	)
	(via
		(at 441.96 -25.4)
		(size 0.5588)
		(drill 0.3048)
		(layers "F.Cu" "B.Cu")
		(net "GND")
	)
	(via
		(at 256.3114 12.3444)
		(size 0.5588)
		(drill 0.3048)
		(layers "F.Cu" "B.Cu")
		(net "GND")
	)
	(via
		(at 265.938 -124.968)
		(size 0.5588)
		(drill 0.3048)
		(layers "F.Cu" "B.Cu")
		(net "GND")
	)
	(via
		(at 303.276 -380.746)
		(size 0.5588)
		(drill 0.3048)
		(layers "F.Cu" "B.Cu")
		(net "GND")
	)
	(via
		(at 121.811796 -282.830016)
		(size 0.5588)
		(drill 0.3048)
		(layers "F.Cu" "B.Cu")
		(net "GND")
	)
	(via
		(at 294.302942 -357.395018)
		(size 0.7112)
		(drill 0.4064)
		(layers "F.Cu" "B.Cu")
		(net "GND")
	)
	(via
		(at 70.452996 -347.802962)
		(size 0.7112)
		(drill 0.4064)
		(layers "F.Cu" "B.Cu")
		(net "GND")
	)
	(via
		(at 164.432996 -347.802962)
		(size 0.7112)
		(drill 0.4064)
		(layers "F.Cu" "B.Cu")
		(net "GND")
	)
	(via
		(at 30.48 -233.68)
		(size 0.5588)
		(drill 0.3048)
		(layers "F.Cu" "B.Cu")
		(net "GND")
	)
	(via
		(at 320.929 -334.899)
		(size 0.5588)
		(drill 0.3048)
		(layers "F.Cu" "B.Cu")
		(net "GND")
	)
	(via
		(at 413.51962 -1.397)
		(size 0.7112)
		(drill 0.4064)
		(layers "F.Cu" "B.Cu")
		(net "GND")
	)
	(via
		(at 151.650954 -10.845546)
		(size 0.7112)
		(drill 0.4064)
		(layers "F.Cu" "B.Cu")
		(net "GND")
	)
	(via
		(at 87.340948 -191.240918)
		(size 0.5588)
		(drill 0.3048)
		(layers "F.Cu" "B.Cu")
		(net "GND")
	)
	(via
		(at 99.06 -142.24)
		(size 0.5588)
		(drill 0.3048)
		(layers "F.Cu" "B.Cu")
		(net "GND")
	)
	(via
		(at 365.274098 -181.294024)
		(size 0.5588)
		(drill 0.3048)
		(layers "F.Cu" "B.Cu")
		(net "GND")
	)
	(via
		(at 218.092528 -99.568)
		(size 0.5588)
		(drill 0.3048)
		(layers "F.Cu" "B.Cu")
		(net "GND")
	)
	(via
		(at 423.67962 -1.397)
		(size 0.7112)
		(drill 0.4064)
		(layers "F.Cu" "B.Cu")
		(net "GND")
	)
	(via
		(at 333.73441 -66.939414)
		(size 0.5588)
		(drill 0.3048)
		(layers "F.Cu" "B.Cu")
		(net "GND")
	)
	(via
		(at 490.053122 -18.16735)
		(size 0.7112)
		(drill 0.4064)
		(layers "F.Cu" "B.Cu")
		(net "GND")
	)
	(via
		(at 70.607174 -183.00319)
		(size 0.5588)
		(drill 0.3048)
		(layers "F.Cu" "B.Cu")
		(net "GND")
	)
	(via
		(at 18.652998 -59.603894)
		(size 0.5588)
		(drill 0.3048)
		(layers "F.Cu" "B.Cu")
		(net "GND")
	)
	(via
		(at 79.581248 -25.07107)
		(size 0.5588)
		(drill 0.3048)
		(layers "F.Cu" "B.Cu")
		(net "GND")
	)
	(via
		(at 154.106372 -42.81932)
		(size 0.5588)
		(drill 0.3048)
		(layers "F.Cu" "B.Cu")
		(net "GND")
	)
	(via
		(at 263.144762 -23.759922)
		(size 0.5588)
		(drill 0.3048)
		(layers "F.Cu" "B.Cu")
		(net "GND")
	)
	(via
		(at 297.831256 -284.066742)
		(size 0.5588)
		(drill 0.3048)
		(layers "F.Cu" "B.Cu")
		(net "GND")
	)
	(via
		(at 457.3905 -271.265142)
		(size 0.5588)
		(drill 0.3048)
		(layers "F.Cu" "B.Cu")
		(net "GND")
	)
	(via
		(at 472.44 -20.32)
		(size 0.5588)
		(drill 0.3048)
		(layers "F.Cu" "B.Cu")
		(net "GND")
	)
	(via
		(at 201.397108 -377.942856)
		(size 0.7112)
		(drill 0.4064)
		(layers "F.Cu" "B.Cu")
		(net "GND")
	)
	(via
		(at 298.602908 18.438876)
		(size 0.7112)
		(drill 0.4064)
		(layers "F.Cu" "B.Cu")
		(net "GND")
	)
	(via
		(at 431.8 -325.12)
		(size 0.5588)
		(drill 0.3048)
		(layers "F.Cu" "B.Cu")
		(net "GND")
	)
	(via
		(at 273.485102 29.35478)
		(size 0.5588)
		(drill 0.3048)
		(layers "F.Cu" "B.Cu")
		(net "GND")
	)
	(via
		(at 267.208 -267.716)
		(size 0.5588)
		(drill 0.3048)
		(layers "F.Cu" "B.Cu")
		(net "GND")
	)
	(via
		(at 199.898 -130.556)
		(size 0.5588)
		(drill 0.3048)
		(layers "F.Cu" "B.Cu")
		(net "GND")
	)
	(via
		(at 124.201682 -347.548962)
		(size 0.7112)
		(drill 0.4064)
		(layers "F.Cu" "B.Cu")
		(net "GND")
	)
	(via
		(at 370.84 -330.2)
		(size 0.5588)
		(drill 0.3048)
		(layers "F.Cu" "B.Cu")
		(net "GND")
	)
	(via
		(at 201.397108 -405.882856)
		(size 0.7112)
		(drill 0.4064)
		(layers "F.Cu" "B.Cu")
		(net "GND")
	)
	(via
		(at 490.053122 -136.27735)
		(size 0.7112)
		(drill 0.4064)
		(layers "F.Cu" "B.Cu")
		(net "GND")
	)
	(via
		(at 421.64 -137.16)
		(size 0.5588)
		(drill 0.3048)
		(layers "F.Cu" "B.Cu")
		(net "GND")
	)
	(via
		(at 35.245802 -144.45615)
		(size 0.5588)
		(drill 0.3048)
		(layers "F.Cu" "B.Cu")
		(net "GND")
	)
	(via
		(at 135.128 -158.242)
		(size 0.5588)
		(drill 0.3048)
		(layers "F.Cu" "B.Cu")
		(net "GND")
	)
	(via
		(at 192.350898 -364.711742)
		(size 0.7112)
		(drill 0.4064)
		(layers "F.Cu" "B.Cu")
		(net "GND")
	)
	(via
		(at 329.819 -76.9366)
		(size 0.5588)
		(drill 0.3048)
		(layers "F.Cu" "B.Cu")
		(net "GND")
	)
	(via
		(at 1.397 -244.218968)
		(size 0.7112)
		(drill 0.4064)
		(layers "F.Cu" "B.Cu")
		(net "GND")
	)
	(via
		(at 447.929 -73.152)
		(size 0.5588)
		(drill 0.3048)
		(layers "F.Cu" "B.Cu")
		(net "GND")
	)
	(via
		(at 258.6482 -139.7)
		(size 0.5588)
		(drill 0.3048)
		(layers "F.Cu" "B.Cu")
		(net "GND")
	)
	(via
		(at 337.764882 -347.802962)
		(size 0.7112)
		(drill 0.4064)
		(layers "F.Cu" "B.Cu")
		(net "GND")
	)
	(via
		(at 81.28 -5.08)
		(size 0.5588)
		(drill 0.3048)
		(layers "F.Cu" "B.Cu")
		(net "GND")
	)
	(via
		(at 290.346892 -419.803072)
		(size 0.7112)
		(drill 0.4064)
		(layers "F.Cu" "B.Cu")
		(net "GND")
	)
	(via
		(at 1.397 -308.988968)
		(size 0.7112)
		(drill 0.4064)
		(layers "F.Cu" "B.Cu")
		(net "GND")
	)
	(via
		(at 394.35405 -289.4838)
		(size 0.5588)
		(drill 0.3048)
		(layers "F.Cu" "B.Cu")
		(net "GND")
	)
	(via
		(at 356.8954 -42.164)
		(size 0.5588)
		(drill 0.3048)
		(layers "F.Cu" "B.Cu")
		(net "GND")
	)
	(via
		(at 447.04 -20.32)
		(size 0.5588)
		(drill 0.3048)
		(layers "F.Cu" "B.Cu")
		(net "GND")
	)
	(via
		(at 365.633 -107.061)
		(size 0.5588)
		(drill 0.3048)
		(layers "F.Cu" "B.Cu")
		(net "GND")
	)
	(via
		(at 373.38 -147.32)
		(size 0.5588)
		(drill 0.3048)
		(layers "F.Cu" "B.Cu")
		(net "GND")
	)
	(via
		(at 1.397 -103.248968)
		(size 0.7112)
		(drill 0.4064)
		(layers "F.Cu" "B.Cu")
		(net "GND")
	)
	(via
		(at 213.211156 -386.273802)
		(size 0.5588)
		(drill 0.3048)
		(layers "F.Cu" "B.Cu")
		(net "GND")
	)
	(via
		(at 370.84 -335.28)
		(size 0.5588)
		(drill 0.3048)
		(layers "F.Cu" "B.Cu")
		(net "GND")
	)
	(via
		(at 342.844882 -347.802962)
		(size 0.7112)
		(drill 0.4064)
		(layers "F.Cu" "B.Cu")
		(net "GND")
	)
	(via
		(at 148.844 -155.194)
		(size 0.5588)
		(drill 0.3048)
		(layers "F.Cu" "B.Cu")
		(net "GND")
	)
	(via
		(at 52.721002 -254.31115)
		(size 0.5588)
		(drill 0.3048)
		(layers "F.Cu" "B.Cu")
		(net "GND")
	)
	(via
		(at 383.667 -223.012)
		(size 0.5588)
		(drill 0.3048)
		(layers "F.Cu" "B.Cu")
		(net "GND")
	)
	(via
		(at 1.397 -282.318968)
		(size 0.7112)
		(drill 0.4064)
		(layers "F.Cu" "B.Cu")
		(net "GND")
	)
	(via
		(at 443.23 -170.18)
		(size 0.5588)
		(drill 0.3048)
		(layers "F.Cu" "B.Cu")
		(net "GND")
	)
	(via
		(at 60.292996 -347.802962)
		(size 0.7112)
		(drill 0.4064)
		(layers "F.Cu" "B.Cu")
		(net "GND")
	)
	(via
		(at 1.397 -157.858968)
		(size 0.7112)
		(drill 0.4064)
		(layers "F.Cu" "B.Cu")
		(net "GND")
	)
	(via
		(at 86.36 -10.16)
		(size 0.5588)
		(drill 0.3048)
		(layers "F.Cu" "B.Cu")
		(net "GND")
	)
	(via
		(at 358.902 -315.341)
		(size 0.5588)
		(drill 0.3048)
		(layers "F.Cu" "B.Cu")
		(net "GND")
	)
	(via
		(at 425.485052 -182.604918)
		(size 0.5588)
		(drill 0.3048)
		(layers "F.Cu" "B.Cu")
		(net "GND")
	)
	(via
		(at 170.782996 -347.802962)
		(size 0.7112)
		(drill 0.4064)
		(layers "F.Cu" "B.Cu")
		(net "GND")
	)
	(via
		(at 10.16 -157.48)
		(size 0.5588)
		(drill 0.3048)
		(layers "F.Cu" "B.Cu")
		(net "GND")
	)
	(via
		(at 362.385102 -297.604942)
		(size 0.5588)
		(drill 0.3048)
		(layers "F.Cu" "B.Cu")
		(net "GND")
	)
	(via
		(at 221.651068 12.84605)
		(size 0.7112)
		(drill 0.4064)
		(layers "F.Cu" "B.Cu")
		(net "GND")
	)
	(via
		(at 419.706298 -70.445122)
		(size 0.5588)
		(drill 0.3048)
		(layers "F.Cu" "B.Cu")
		(net "GND")
	)
	(via
		(at 46.740318 -240.185448)
		(size 0.5588)
		(drill 0.3048)
		(layers "F.Cu" "B.Cu")
		(net "GND")
	)
	(via
		(at 1.397 -43.558968)
		(size 0.7112)
		(drill 0.4064)
		(layers "F.Cu" "B.Cu")
		(net "GND")
	)
	(via
		(at 1.397 -184.528968)
		(size 0.7112)
		(drill 0.4064)
		(layers "F.Cu" "B.Cu")
		(net "GND")
	)
	(via
		(at 91.44 -10.16)
		(size 0.5588)
		(drill 0.3048)
		(layers "F.Cu" "B.Cu")
		(net "GND")
	)
	(via
		(at 77.724 -300.355)
		(size 0.5588)
		(drill 0.3048)
		(layers "F.Cu" "B.Cu")
		(net "GND")
	)
	(via
		(at 490.053122 -176.91735)
		(size 0.7112)
		(drill 0.4064)
		(layers "F.Cu" "B.Cu")
		(net "GND")
	)
	(via
		(at 91.404948 -42.034968)
		(size 0.5588)
		(drill 0.3048)
		(layers "F.Cu" "B.Cu")
		(net "GND")
	)
	(via
		(at 272.669 -271.0434)
		(size 0.5588)
		(drill 0.3048)
		(layers "F.Cu" "B.Cu")
		(net "GND")
	)
	(via
		(at 1.397 -274.698968)
		(size 0.7112)
		(drill 0.4064)
		(layers "F.Cu" "B.Cu")
		(net "GND")
	)
	(via
		(at 184.404 -93.726)
		(size 0.5588)
		(drill 0.3048)
		(layers "F.Cu" "B.Cu")
		(net "GND")
	)
	(via
		(at 420.304976 -182.434992)
		(size 0.5588)
		(drill 0.3048)
		(layers "F.Cu" "B.Cu")
		(net "GND")
	)
	(via
		(at 58.711846 -167.829992)
		(size 0.5588)
		(drill 0.3048)
		(layers "F.Cu" "B.Cu")
		(net "GND")
	)
	(via
		(at 200.787 -372.491)
		(size 0.7112)
		(drill 0.4064)
		(layers "F.Cu" "B.Cu")
		(net "GND")
	)
	(via
		(at 294.302942 -351.045018)
		(size 0.7112)
		(drill 0.4064)
		(layers "F.Cu" "B.Cu")
		(net "GND")
	)
	(via
		(at 462.28 -121.92)
		(size 0.5588)
		(drill 0.3048)
		(layers "F.Cu" "B.Cu")
		(net "GND")
	)
	(via
		(at 126.746 -140.462)
		(size 0.5588)
		(drill 0.3048)
		(layers "F.Cu" "B.Cu")
		(net "GND")
	)
	(via
		(at 271.4498 -278.5364)
		(size 0.5588)
		(drill 0.3048)
		(layers "F.Cu" "B.Cu")
		(net "GND")
	)
	(via
		(at 1.397 -39.748968)
		(size 0.7112)
		(drill 0.4064)
		(layers "F.Cu" "B.Cu")
		(net "GND")
	)
	(via
		(at 100.34905 -11.084306)
		(size 0.7112)
		(drill 0.4064)
		(layers "F.Cu" "B.Cu")
		(net "GND")
	)
	(via
		(at 1.397 -24.508968)
		(size 0.7112)
		(drill 0.4064)
		(layers "F.Cu" "B.Cu")
		(net "GND")
	)
	(via
		(at 91.404948 -69.974968)
		(size 0.5588)
		(drill 0.3048)
		(layers "F.Cu" "B.Cu")
		(net "GND")
	)
	(via
		(at 399.54962 -1.397)
		(size 0.7112)
		(drill 0.4064)
		(layers "F.Cu" "B.Cu")
		(net "GND")
	)
	(via
		(at 490.053122 -280.381202)
		(size 0.7112)
		(drill 0.4064)
		(layers "F.Cu" "B.Cu")
		(net "GND")
	)
	(via
		(at 482.6 -20.32)
		(size 0.5588)
		(drill 0.3048)
		(layers "F.Cu" "B.Cu")
		(net "GND")
	)
	(via
		(at 59.854846 -49.654968)
		(size 0.5588)
		(drill 0.3048)
		(layers "F.Cu" "B.Cu")
		(net "GND")
	)
	(via
		(at 142.842996 -347.802962)
		(size 0.7112)
		(drill 0.4064)
		(layers "F.Cu" "B.Cu")
		(net "GND")
	)
	(via
		(at 311.094882 -347.802962)
		(size 0.7112)
		(drill 0.4064)
		(layers "F.Cu" "B.Cu")
		(net "GND")
	)
	(via
		(at 155.829 -16.764)
		(size 0.5588)
		(drill 0.3048)
		(layers "F.Cu" "B.Cu")
		(net "GND")
	)
	(via
		(at 81.752948 -289.603942)
		(size 0.5588)
		(drill 0.3048)
		(layers "F.Cu" "B.Cu")
		(net "GND")
	)
	(via
		(at 429.204882 -347.802962)
		(size 0.7112)
		(drill 0.4064)
		(layers "F.Cu" "B.Cu")
		(net "GND")
	)
	(via
		(at 358.983026 -309.785004)
		(size 0.5588)
		(drill 0.3048)
		(layers "F.Cu" "B.Cu")
		(net "GND")
	)
	(via
		(at 161.036 -250.952)
		(size 0.5588)
		(drill 0.3048)
		(layers "F.Cu" "B.Cu")
		(net "GND")
	)
	(via
		(at 474.542104 -232.678986)
		(size 0.5588)
		(drill 0.3048)
		(layers "F.Cu" "B.Cu")
		(net "GND")
	)
	(via
		(at 397.454882 -347.802962)
		(size 0.7112)
		(drill 0.4064)
		(layers "F.Cu" "B.Cu")
		(net "GND")
	)
	(via
		(at 305.757072 -15.384272)
		(size 0.5588)
		(drill 0.3048)
		(layers "F.Cu" "B.Cu")
		(net "GND")
	)
	(via
		(at 21.971 -40.005)
		(size 0.5588)
		(drill 0.3048)
		(layers "F.Cu" "B.Cu")
		(net "GND")
	)
	(via
		(at 91.404948 -292.355016)
		(size 0.5588)
		(drill 0.3048)
		(layers "F.Cu" "B.Cu")
		(net "GND")
	)
	(via
		(at 191.2493 -54.2163)
		(size 0.5588)
		(drill 0.3048)
		(layers "F.Cu" "B.Cu")
		(net "GND")
	)
	(via
		(at 447.04 -116.84)
		(size 0.5588)
		(drill 0.3048)
		(layers "F.Cu" "B.Cu")
		(net "GND")
	)
	(via
		(at 139.032996 -347.802962)
		(size 0.7112)
		(drill 0.4064)
		(layers "F.Cu" "B.Cu")
		(net "GND")
	)
	(via
		(at 405.70023 -131.232148)
		(size 0.5588)
		(drill 0.3048)
		(layers "F.Cu" "B.Cu")
		(net "GND")
	)
	(via
		(at 76.075032 -1.397)
		(size 0.7112)
		(drill 0.4064)
		(layers "F.Cu" "B.Cu")
		(net "GND")
	)
	(via
		(at 259.3848 -277.9522)
		(size 0.5588)
		(drill 0.3048)
		(layers "F.Cu" "B.Cu")
		(net "GND")
	)
	(via
		(at 406.4 -20.32)
		(size 0.5588)
		(drill 0.3048)
		(layers "F.Cu" "B.Cu")
		(net "GND")
	)
	(via
		(at 353.187 -266.192)
		(size 0.5588)
		(drill 0.3048)
		(layers "F.Cu" "B.Cu")
		(net "GND")
	)
	(via
		(at 63.648844 -137.01268)
		(size 0.5588)
		(drill 0.3048)
		(layers "F.Cu" "B.Cu")
		(net "GND")
	)
	(via
		(at 298.602908 14.628876)
		(size 0.7112)
		(drill 0.4064)
		(layers "F.Cu" "B.Cu")
		(net "GND")
	)
	(via
		(at 133.66115 -189.168024)
		(size 0.5588)
		(drill 0.3048)
		(layers "F.Cu" "B.Cu")
		(net "GND")
	)
	(via
		(at 47.371 -142.0368)
		(size 0.5588)
		(drill 0.3048)
		(layers "F.Cu" "B.Cu")
		(net "GND")
	)
	(via
		(at 408.432 -65.024)
		(size 0.5588)
		(drill 0.3048)
		(layers "F.Cu" "B.Cu")
		(net "GND")
	)
	(via
		(at 421.64 -5.08)
		(size 0.5588)
		(drill 0.3048)
		(layers "F.Cu" "B.Cu")
		(net "GND")
	)
	(via
		(at 89.408 -84.074)
		(size 0.5588)
		(drill 0.3048)
		(layers "F.Cu" "B.Cu")
		(net "GND")
	)
	(via
		(at 239.17656 -252.93828)
		(size 0.5588)
		(drill 0.3048)
		(layers "F.Cu" "B.Cu")
		(net "GND")
	)
	(via
		(at 416.504882 -347.802962)
		(size 0.7112)
		(drill 0.4064)
		(layers "F.Cu" "B.Cu")
		(net "GND")
	)
	(via
		(at 450.116194 -313.10453)
		(size 0.5588)
		(drill 0.3048)
		(layers "F.Cu" "B.Cu")
		(net "GND")
	)
	(via
		(at 244.475 -329.819)
		(size 0.5588)
		(drill 0.3048)
		(layers "F.Cu" "B.Cu")
		(net "GND")
	)
	(via
		(at 490.053122 -162.94735)
		(size 0.7112)
		(drill 0.4064)
		(layers "F.Cu" "B.Cu")
		(net "GND")
	)
	(via
		(at 490.053122 -140.08735)
		(size 0.7112)
		(drill 0.4064)
		(layers "F.Cu" "B.Cu")
		(net "GND")
	)
	(via
		(at 1.397 -81.658968)
		(size 0.7112)
		(drill 0.4064)
		(layers "F.Cu" "B.Cu")
		(net "GND")
	)
	(via
		(at 474.47962 -1.397)
		(size 0.7112)
		(drill 0.4064)
		(layers "F.Cu" "B.Cu")
		(net "GND")
	)
	(via
		(at 451.854824 -49.654968)
		(size 0.5588)
		(drill 0.3048)
		(layers "F.Cu" "B.Cu")
		(net "GND")
	)
	(via
		(at 140.081 -225.552)
		(size 0.5588)
		(drill 0.3048)
		(layers "F.Cu" "B.Cu")
		(net "GND")
	)
	(via
		(at 159.803084 -1.397)
		(size 0.7112)
		(drill 0.4064)
		(layers "F.Cu" "B.Cu")
		(net "GND")
	)
	(via
		(at 416.56 -10.16)
		(size 0.5588)
		(drill 0.3048)
		(layers "F.Cu" "B.Cu")
		(net "GND")
	)
	(via
		(at 151.650954 -9.575546)
		(size 0.7112)
		(drill 0.4064)
		(layers "F.Cu" "B.Cu")
		(net "GND")
	)
	(via
		(at 462.28 -147.32)
		(size 0.5588)
		(drill 0.3048)
		(layers "F.Cu" "B.Cu")
		(net "GND")
	)
	(via
		(at 485.182926 -36.03498)
		(size 0.5588)
		(drill 0.3048)
		(layers "F.Cu" "B.Cu")
		(net "GND")
	)
	(via
		(at 41.785032 -1.397)
		(size 0.7112)
		(drill 0.4064)
		(layers "F.Cu" "B.Cu")
		(net "GND")
	)
	(via
		(at 490.053122 -91.82735)
		(size 0.7112)
		(drill 0.4064)
		(layers "F.Cu" "B.Cu")
		(net "GND")
	)
	(via
		(at 53.215032 -1.397)
		(size 0.7112)
		(drill 0.4064)
		(layers "F.Cu" "B.Cu")
		(net "GND")
	)
	(via
		(at 308.602888 -388.021068)
		(size 0.7112)
		(drill 0.4064)
		(layers "F.Cu" "B.Cu")
		(net "GND")
	)
	(via
		(at 74.304144 -131.157472)
		(size 0.5588)
		(drill 0.3048)
		(layers "F.Cu" "B.Cu")
		(net "GND")
	)
	(via
		(at 490.053122 -324.831202)
		(size 0.7112)
		(drill 0.4064)
		(layers "F.Cu" "B.Cu")
		(net "GND")
	)
	(via
		(at 253.492 -96.012)
		(size 0.5588)
		(drill 0.3048)
		(layers "F.Cu" "B.Cu")
		(net "GND")
	)
	(via
		(at 1.397 -234.058968)
		(size 0.7112)
		(drill 0.4064)
		(layers "F.Cu" "B.Cu")
		(net "GND")
	)
	(via
		(at 23.622 -335.026)
		(size 0.5588)
		(drill 0.3048)
		(layers "F.Cu" "B.Cu")
		(net "GND")
	)
	(via
		(at 357.205026 -45.844968)
		(size 0.5588)
		(drill 0.3048)
		(layers "F.Cu" "B.Cu")
		(net "GND")
	)
	(via
		(at 416.56 -116.84)
		(size 0.5588)
		(drill 0.3048)
		(layers "F.Cu" "B.Cu")
		(net "GND")
	)
	(via
		(at 490.053122 -322.291202)
		(size 0.7112)
		(drill 0.4064)
		(layers "F.Cu" "B.Cu")
		(net "GND")
	)
	(via
		(at 1.397 -307.718968)
		(size 0.7112)
		(drill 0.4064)
		(layers "F.Cu" "B.Cu")
		(net "GND")
	)
	(via
		(at 265.100562 -24.775922)
		(size 0.5588)
		(drill 0.3048)
		(layers "F.Cu" "B.Cu")
		(net "GND")
	)
	(via
		(at 241.367056 37.403024)
		(size 0.7112)
		(drill 0.4064)
		(layers "F.Cu" "B.Cu")
		(net "GND")
	)
	(via
		(at 303.699672 -180.9242)
		(size 0.5588)
		(drill 0.3048)
		(layers "F.Cu" "B.Cu")
		(net "GND")
	)
	(via
		(at 308.602888 -380.401068)
		(size 0.7112)
		(drill 0.4064)
		(layers "F.Cu" "B.Cu")
		(net "GND")
	)
	(via
		(at 490.053122 -334.991202)
		(size 0.7112)
		(drill 0.4064)
		(layers "F.Cu" "B.Cu")
		(net "GND")
	)
	(via
		(at 153.547318 -49.850802)
		(size 0.5588)
		(drill 0.3048)
		(layers "F.Cu" "B.Cu")
		(net "GND")
	)
	(via
		(at 308.602888 -417.231068)
		(size 0.7112)
		(drill 0.4064)
		(layers "F.Cu" "B.Cu")
		(net "GND")
	)
	(via
		(at 168.242996 -347.802962)
		(size 0.7112)
		(drill 0.4064)
		(layers "F.Cu" "B.Cu")
		(net "GND")
	)
	(via
		(at 185.928 -95.123)
		(size 0.5588)
		(drill 0.3048)
		(layers "F.Cu" "B.Cu")
		(net "GND")
	)
	(via
		(at 183.896 -85.979)
		(size 0.5588)
		(drill 0.3048)
		(layers "F.Cu" "B.Cu")
		(net "GND")
	)
	(via
		(at 1.397 -328.038968)
		(size 0.7112)
		(drill 0.4064)
		(layers "F.Cu" "B.Cu")
		(net "GND")
	)
	(via
		(at 132.227066 -140.520674)
		(size 0.5588)
		(drill 0.3048)
		(layers "F.Cu" "B.Cu")
		(net "GND")
	)
	(via
		(at 53.34 -335.28)
		(size 0.5588)
		(drill 0.3048)
		(layers "F.Cu" "B.Cu")
		(net "GND")
	)
	(via
		(at 214.884 -29.591)
		(size 0.5588)
		(drill 0.3048)
		(layers "F.Cu" "B.Cu")
		(net "GND")
	)
	(via
		(at 66.04 -335.28)
		(size 0.5588)
		(drill 0.3048)
		(layers "F.Cu" "B.Cu")
		(net "GND")
	)
	(via
		(at 317.851028 -1.397)
		(size 0.7112)
		(drill 0.4064)
		(layers "F.Cu" "B.Cu")
		(net "GND")
	)
	(via
		(at 62.23 -223.52)
		(size 0.5588)
		(drill 0.3048)
		(layers "F.Cu" "B.Cu")
		(net "GND")
	)
	(via
		(at 225.679 -66.167)
		(size 0.5588)
		(drill 0.3048)
		(layers "F.Cu" "B.Cu")
		(net "GND")
	)
	(via
		(at 1.397 -239.138968)
		(size 0.7112)
		(drill 0.4064)
		(layers "F.Cu" "B.Cu")
		(net "GND")
	)
	(via
		(at 107.691682 -347.548962)
		(size 0.7112)
		(drill 0.4064)
		(layers "F.Cu" "B.Cu")
		(net "GND")
	)
	(via
		(at 187.743084 -1.397)
		(size 0.7112)
		(drill 0.4064)
		(layers "F.Cu" "B.Cu")
		(net "GND")
	)
	(via
		(at 346.349066 -11.384534)
		(size 0.7112)
		(drill 0.4064)
		(layers "F.Cu" "B.Cu")
		(net "GND")
	)
	(via
		(at 365.299244 -66.366898)
		(size 0.5588)
		(drill 0.3048)
		(layers "F.Cu" "B.Cu")
		(net "GND")
	)
	(via
		(at 122.218196 -67.434968)
		(size 0.5588)
		(drill 0.3048)
		(layers "F.Cu" "B.Cu")
		(net "GND")
	)
	(via
		(at 372.491 -85.8774)
		(size 0.5588)
		(drill 0.3048)
		(layers "F.Cu" "B.Cu")
		(net "GND")
	)
	(via
		(at 151.650954 -1.955546)
		(size 0.7112)
		(drill 0.4064)
		(layers "F.Cu" "B.Cu")
		(net "GND")
	)
	(via
		(at 220.4974 -174.1424)
		(size 0.5588)
		(drill 0.3048)
		(layers "F.Cu" "B.Cu")
		(net "GND")
	)
	(via
		(at 397.39697 -13.239496)
		(size 0.7112)
		(drill 0.4064)
		(layers "F.Cu" "B.Cu")
		(net "GND")
	)
	(via
		(at 414.02 -198.12)
		(size 0.5588)
		(drill 0.3048)
		(layers "F.Cu" "B.Cu")
		(net "GND")
	)
	(via
		(at 87.505032 -1.397)
		(size 0.7112)
		(drill 0.4064)
		(layers "F.Cu" "B.Cu")
		(net "GND")
	)
	(via
		(at 27.272996 -347.802962)
		(size 0.7112)
		(drill 0.4064)
		(layers "F.Cu" "B.Cu")
		(net "GND")
	)
	(via
		(at 144.446498 -47.66564)
		(size 0.5588)
		(drill 0.3048)
		(layers "F.Cu" "B.Cu")
		(net "GND")
	)
	(via
		(at 53.555646 -49.494694)
		(size 0.5588)
		(drill 0.3048)
		(layers "F.Cu" "B.Cu")
		(net "GND")
	)
	(via
		(at 71.12 -35.56)
		(size 0.5588)
		(drill 0.3048)
		(layers "F.Cu" "B.Cu")
		(net "GND")
	)
	(via
		(at 216.8906 -22.784054)
		(size 0.5588)
		(drill 0.3048)
		(layers "F.Cu" "B.Cu")
		(net "GND")
	)
	(via
		(at 386.08 -197.104)
		(size 0.5588)
		(drill 0.3048)
		(layers "F.Cu" "B.Cu")
		(net "GND")
	)
	(via
		(at 50.480214 -256.383028)
		(size 0.5588)
		(drill 0.3048)
		(layers "F.Cu" "B.Cu")
		(net "GND")
	)
	(via
		(at 1.397 -256.918968)
		(size 0.7112)
		(drill 0.4064)
		(layers "F.Cu" "B.Cu")
		(net "GND")
	)
	(via
		(at 420.304976 -164.654992)
		(size 0.5588)
		(drill 0.3048)
		(layers "F.Cu" "B.Cu")
		(net "GND")
	)
	(via
		(at 190.119 -327.025)
		(size 0.5588)
		(drill 0.3048)
		(layers "F.Cu" "B.Cu")
		(net "GND")
	)
	(via
		(at 81.882996 -347.802962)
		(size 0.7112)
		(drill 0.4064)
		(layers "F.Cu" "B.Cu")
		(net "GND")
	)
	(via
		(at 306.421028 -1.397)
		(size 0.7112)
		(drill 0.4064)
		(layers "F.Cu" "B.Cu")
		(net "GND")
	)
	(via
		(at 221.651068 5.22605)
		(size 0.7112)
		(drill 0.4064)
		(layers "F.Cu" "B.Cu")
		(net "GND")
	)
	(via
		(at 180.848 -265.684)
		(size 0.5588)
		(drill 0.3048)
		(layers "F.Cu" "B.Cu")
		(net "GND")
	)
	(via
		(at 362.385102 -182.604918)
		(size 0.5588)
		(drill 0.3048)
		(layers "F.Cu" "B.Cu")
		(net "GND")
	)
	(via
		(at 159.772096 -27.338782)
		(size 0.5588)
		(drill 0.3048)
		(layers "F.Cu" "B.Cu")
		(net "GND")
	)
	(via
		(at 1.397 -48.638968)
		(size 0.7112)
		(drill 0.4064)
		(layers "F.Cu" "B.Cu")
		(net "GND")
	)
	(via
		(at 448.254882 -347.802962)
		(size 0.7112)
		(drill 0.4064)
		(layers "F.Cu" "B.Cu")
		(net "GND")
	)
	(via
		(at 456.69962 -1.397)
		(size 0.7112)
		(drill 0.4064)
		(layers "F.Cu" "B.Cu")
		(net "GND")
	)
	(via
		(at 244.128036 -247.952514)
		(size 0.5588)
		(drill 0.3048)
		(layers "F.Cu" "B.Cu")
		(net "GND")
	)
	(via
		(at 324.886574 -272.05559)
		(size 0.5588)
		(drill 0.3048)
		(layers "F.Cu" "B.Cu")
		(net "GND")
	)
	(via
		(at 327.604882 -347.802962)
		(size 0.7112)
		(drill 0.4064)
		(layers "F.Cu" "B.Cu")
		(net "GND")
	)
	(via
		(at 98.679 -38.989)
		(size 0.5588)
		(drill 0.3048)
		(layers "F.Cu" "B.Cu")
		(net "GND")
	)
	(via
		(at 333.502 -76.9366)
		(size 0.5588)
		(drill 0.3048)
		(layers "F.Cu" "B.Cu")
		(net "GND")
	)
	(via
		(at 402.08962 -1.397)
		(size 0.7112)
		(drill 0.4064)
		(layers "F.Cu" "B.Cu")
		(net "GND")
	)
	(via
		(at 1.397 -188.338968)
		(size 0.7112)
		(drill 0.4064)
		(layers "F.Cu" "B.Cu")
		(net "GND")
	)
	(via
		(at 30.966156 -254.886714)
		(size 0.5588)
		(drill 0.3048)
		(layers "F.Cu" "B.Cu")
		(net "GND")
	)
	(via
		(at 239.234472 -241.833654)
		(size 0.5588)
		(drill 0.3048)
		(layers "F.Cu" "B.Cu")
		(net "GND")
	)
	(via
		(at 416.56 -142.24)
		(size 0.5588)
		(drill 0.3048)
		(layers "F.Cu" "B.Cu")
		(net "GND")
	)
	(via
		(at 201.397108 -403.342856)
		(size 0.7112)
		(drill 0.4064)
		(layers "F.Cu" "B.Cu")
		(net "GND")
	)
	(via
		(at 469.944958 -213.041484)
		(size 0.5588)
		(drill 0.3048)
		(layers "F.Cu" "B.Cu")
		(net "GND")
	)
	(via
		(at 378.290582 -291.506656)
		(size 0.5588)
		(drill 0.3048)
		(layers "F.Cu" "B.Cu")
		(net "GND")
	)
	(via
		(at 294.302942 -370.095018)
		(size 0.7112)
		(drill 0.4064)
		(layers "F.Cu" "B.Cu")
		(net "GND")
	)
	(via
		(at 21.59 -269.24)
		(size 0.5588)
		(drill 0.3048)
		(layers "F.Cu" "B.Cu")
		(net "GND")
	)
	(via
		(at 467.36 -81.28)
		(size 0.5588)
		(drill 0.3048)
		(layers "F.Cu" "B.Cu")
		(net "GND")
	)
	(via
		(at 490.053122 -303.241202)
		(size 0.7112)
		(drill 0.4064)
		(layers "F.Cu" "B.Cu")
		(net "GND")
	)
	(via
		(at 313.634882 -347.802962)
		(size 0.7112)
		(drill 0.4064)
		(layers "F.Cu" "B.Cu")
		(net "GND")
	)
	(via
		(at 71.12 -10.16)
		(size 0.5588)
		(drill 0.3048)
		(layers "F.Cu" "B.Cu")
		(net "GND")
	)
	(via
		(at 424.124882 -347.802962)
		(size 0.7112)
		(drill 0.4064)
		(layers "F.Cu" "B.Cu")
		(net "GND")
	)
	(via
		(at 29.085032 -1.397)
		(size 0.7112)
		(drill 0.4064)
		(layers "F.Cu" "B.Cu")
		(net "GND")
	)
	(via
		(at 452.12 -121.92)
		(size 0.5588)
		(drill 0.3048)
		(layers "F.Cu" "B.Cu")
		(net "GND")
	)
	(via
		(at 177.583084 -1.397)
		(size 0.7112)
		(drill 0.4064)
		(layers "F.Cu" "B.Cu")
		(net "GND")
	)
	(via
		(at 414.78962 -1.397)
		(size 0.7112)
		(drill 0.4064)
		(layers "F.Cu" "B.Cu")
		(net "GND")
	)
	(via
		(at 61.632846 -194.78498)
		(size 0.5588)
		(drill 0.3048)
		(layers "F.Cu" "B.Cu")
		(net "GND")
	)
	(via
		(at 175.862996 -347.802962)
		(size 0.7112)
		(drill 0.4064)
		(layers "F.Cu" "B.Cu")
		(net "GND")
	)
	(via
		(at 356.606602 -62.354968)
		(size 0.5588)
		(drill 0.3048)
		(layers "F.Cu" "B.Cu")
		(net "GND")
	)
	(via
		(at 113.302796 -177.778918)
		(size 0.5588)
		(drill 0.3048)
		(layers "F.Cu" "B.Cu")
		(net "GND")
	)
	(via
		(at 218.730068 -18.040604)
		(size 0.5588)
		(drill 0.3048)
		(layers "F.Cu" "B.Cu")
		(net "GND")
	)
	(via
		(at 36.705032 -1.397)
		(size 0.7112)
		(drill 0.4064)
		(layers "F.Cu" "B.Cu")
		(net "GND")
	)
	(via
		(at 71.722996 -347.802962)
		(size 0.7112)
		(drill 0.4064)
		(layers "F.Cu" "B.Cu")
		(net "GND")
	)
	(via
		(at 418.59962 -1.397)
		(size 0.7112)
		(drill 0.4064)
		(layers "F.Cu" "B.Cu")
		(net "GND")
	)
	(via
		(at 1.397 -38.478968)
		(size 0.7112)
		(drill 0.4064)
		(layers "F.Cu" "B.Cu")
		(net "GND")
	)
	(via
		(at 353.004882 -347.802962)
		(size 0.7112)
		(drill 0.4064)
		(layers "F.Cu" "B.Cu")
		(net "GND")
	)
	(via
		(at 63.5 -327.66)
		(size 0.5588)
		(drill 0.3048)
		(layers "F.Cu" "B.Cu")
		(net "GND")
	)
	(via
		(at 237.557056 37.403024)
		(size 0.7112)
		(drill 0.4064)
		(layers "F.Cu" "B.Cu")
		(net "GND")
	)
	(via
		(at 388.754874 -164.654992)
		(size 0.5588)
		(drill 0.3048)
		(layers "F.Cu" "B.Cu")
		(net "GND")
	)
	(via
		(at 68.455032 -1.397)
		(size 0.7112)
		(drill 0.4064)
		(layers "F.Cu" "B.Cu")
		(net "GND")
	)
	(via
		(at 85.766148 -300.322742)
		(size 0.5588)
		(drill 0.3048)
		(layers "F.Cu" "B.Cu")
		(net "GND")
	)
	(via
		(at 308.602888 -394.371068)
		(size 0.7112)
		(drill 0.4064)
		(layers "F.Cu" "B.Cu")
		(net "GND")
	)
	(via
		(at 308.602888 -407.071068)
		(size 0.7112)
		(drill 0.4064)
		(layers "F.Cu" "B.Cu")
		(net "GND")
	)
	(via
		(at 31.625032 -1.397)
		(size 0.7112)
		(drill 0.4064)
		(layers "F.Cu" "B.Cu")
		(net "GND")
	)
	(via
		(at 1.397 -306.448968)
		(size 0.7112)
		(drill 0.4064)
		(layers "F.Cu" "B.Cu")
		(net "GND")
	)
	(via
		(at 28.304998 -177.354992)
		(size 0.5588)
		(drill 0.3048)
		(layers "F.Cu" "B.Cu")
		(net "GND")
	)
	(via
		(at 268.037056 37.403024)
		(size 0.7112)
		(drill 0.4064)
		(layers "F.Cu" "B.Cu")
		(net "GND")
	)
	(via
		(at 411.424882 -347.802962)
		(size 0.7112)
		(drill 0.4064)
		(layers "F.Cu" "B.Cu")
		(net "GND")
	)
	(via
		(at 317.8175 -289.9918)
		(size 0.5588)
		(drill 0.3048)
		(layers "F.Cu" "B.Cu")
		(net "GND")
	)
	(via
		(at 72.644 -205.867)
		(size 0.5588)
		(drill 0.3048)
		(layers "F.Cu" "B.Cu")
		(net "GND")
	)
	(via
		(at 454.604882 -347.802962)
		(size 0.7112)
		(drill 0.4064)
		(layers "F.Cu" "B.Cu")
		(net "GND")
	)
	(via
		(at 483.262178 -211.301076)
		(size 0.5588)
		(drill 0.3048)
		(layers "F.Cu" "B.Cu")
		(net "GND")
	)
	(via
		(at 34.29 -149.352)
		(size 0.5588)
		(drill 0.3048)
		(layers "F.Cu" "B.Cu")
		(net "GND")
	)
	(via
		(at 329.281028 -1.397)
		(size 0.7112)
		(drill 0.4064)
		(layers "F.Cu" "B.Cu")
		(net "GND")
	)
	(via
		(at 412.694882 -347.802962)
		(size 0.7112)
		(drill 0.4064)
		(layers "F.Cu" "B.Cu")
		(net "GND")
	)
	(via
		(at 1.397 -155.318968)
		(size 0.7112)
		(drill 0.4064)
		(layers "F.Cu" "B.Cu")
		(net "GND")
	)
	(via
		(at 45.847 -60.198)
		(size 0.5588)
		(drill 0.3048)
		(layers "F.Cu" "B.Cu")
		(net "GND")
	)
	(via
		(at 91.404948 -59.814968)
		(size 0.5588)
		(drill 0.3048)
		(layers "F.Cu" "B.Cu")
		(net "GND")
	)
	(via
		(at 477.52 -86.36)
		(size 0.5588)
		(drill 0.3048)
		(layers "F.Cu" "B.Cu")
		(net "GND")
	)
	(via
		(at 269.57655 10.256012)
		(size 0.5588)
		(drill 0.3048)
		(layers "F.Cu" "B.Cu")
		(net "GND")
	)
	(via
		(at 38.1 -133.731)
		(size 0.5588)
		(drill 0.3048)
		(layers "F.Cu" "B.Cu")
		(net "GND")
	)
	(via
		(at 485.182926 -266.035028)
		(size 0.5588)
		(drill 0.3048)
		(layers "F.Cu" "B.Cu")
		(net "GND")
	)
	(via
		(at 425.815252 -46.649894)
		(size 0.5588)
		(drill 0.3048)
		(layers "F.Cu" "B.Cu")
		(net "GND")
	)
	(via
		(at 427.99 -195.58)
		(size 0.5588)
		(drill 0.3048)
		(layers "F.Cu" "B.Cu")
		(net "GND")
	)
	(via
		(at 44.106846 -179.683918)
		(size 0.5588)
		(drill 0.3048)
		(layers "F.Cu" "B.Cu")
		(net "GND")
	)
	(via
		(at 433.70373 -131.356608)
		(size 0.5588)
		(drill 0.3048)
		(layers "F.Cu" "B.Cu")
		(net "GND")
	)
	(via
		(at 282.7782 11.2014)
		(size 0.5588)
		(drill 0.3048)
		(layers "F.Cu" "B.Cu")
		(net "GND")
	)
	(via
		(at 323.3928 -66.9798)
		(size 0.5588)
		(drill 0.3048)
		(layers "F.Cu" "B.Cu")
		(net "GND")
	)
	(via
		(at 5.08 -81.28)
		(size 0.5588)
		(drill 0.3048)
		(layers "F.Cu" "B.Cu")
		(net "GND")
	)
	(via
		(at 467.36 -142.24)
		(size 0.5588)
		(drill 0.3048)
		(layers "F.Cu" "B.Cu")
		(net "GND")
	)
	(via
		(at 457.0349 -297.604942)
		(size 0.5588)
		(drill 0.3048)
		(layers "F.Cu" "B.Cu")
		(net "GND")
	)
	(via
		(at 483.404926 -289.815016)
		(size 0.5588)
		(drill 0.3048)
		(layers "F.Cu" "B.Cu")
		(net "GND")
	)
	(via
		(at 40.64 -238.76)
		(size 0.5588)
		(drill 0.3048)
		(layers "F.Cu" "B.Cu")
		(net "GND")
	)
	(via
		(at 1.397 -115.948968)
		(size 0.7112)
		(drill 0.4064)
		(layers "F.Cu" "B.Cu")
		(net "GND")
	)
	(via
		(at 477.796352 -75.230736)
		(size 0.5588)
		(drill 0.3048)
		(layers "F.Cu" "B.Cu")
		(net "GND")
	)
	(via
		(at 221.651068 15.38605)
		(size 0.7112)
		(drill 0.4064)
		(layers "F.Cu" "B.Cu")
		(net "GND")
	)
	(via
		(at 304.258472 -184.5818)
		(size 0.5588)
		(drill 0.3048)
		(layers "F.Cu" "B.Cu")
		(net "GND")
	)
	(via
		(at 366.974882 -347.802962)
		(size 0.7112)
		(drill 0.4064)
		(layers "F.Cu" "B.Cu")
		(net "GND")
	)
	(via
		(at 490.053122 -314.671202)
		(size 0.7112)
		(drill 0.4064)
		(layers "F.Cu" "B.Cu")
		(net "GND")
	)
	(via
		(at 260.417056 37.403024)
		(size 0.7112)
		(drill 0.4064)
		(layers "F.Cu" "B.Cu")
		(net "GND")
	)
	(via
		(at 162.442398 -175.238918)
		(size 0.5588)
		(drill 0.3048)
		(layers "F.Cu" "B.Cu")
		(net "GND")
	)
	(via
		(at 184.912 -280.42997)
		(size 0.5588)
		(drill 0.3048)
		(layers "F.Cu" "B.Cu")
		(net "GND")
	)
	(via
		(at 66.04 -330.2)
		(size 0.5588)
		(drill 0.3048)
		(layers "F.Cu" "B.Cu")
		(net "GND")
	)
	(via
		(at 190.283084 -1.397)
		(size 0.7112)
		(drill 0.4064)
		(layers "F.Cu" "B.Cu")
		(net "GND")
	)
	(via
		(at 354.274882 -347.802962)
		(size 0.7112)
		(drill 0.4064)
		(layers "F.Cu" "B.Cu")
		(net "GND")
	)
	(via
		(at 127.046736 -50.883312)
		(size 0.5588)
		(drill 0.3048)
		(layers "F.Cu" "B.Cu")
		(net "GND")
	)
	(via
		(at 300.144942 -375.397014)
		(size 0.7112)
		(drill 0.4064)
		(layers "F.Cu" "B.Cu")
		(net "GND")
	)
	(via
		(at 452.88962 -1.397)
		(size 0.7112)
		(drill 0.4064)
		(layers "F.Cu" "B.Cu")
		(net "GND")
	)
	(via
		(at 364.109 -265.176)
		(size 0.5588)
		(drill 0.3048)
		(layers "F.Cu" "B.Cu")
		(net "GND")
	)
	(via
		(at 342.265 -5.334)
		(size 0.5588)
		(drill 0.3048)
		(layers "F.Cu" "B.Cu")
		(net "GND")
	)
	(via
		(at 490.053122 -84.20735)
		(size 0.7112)
		(drill 0.4064)
		(layers "F.Cu" "B.Cu")
		(net "GND")
	)
	(via
		(at 421.64 -111.76)
		(size 0.5588)
		(drill 0.3048)
		(layers "F.Cu" "B.Cu")
		(net "GND")
	)
	(via
		(at 392.91895 -191.113918)
		(size 0.5588)
		(drill 0.3048)
		(layers "F.Cu" "B.Cu")
		(net "GND")
	)
	(via
		(at 1.397 -193.418968)
		(size 0.7112)
		(drill 0.4064)
		(layers "F.Cu" "B.Cu")
		(net "GND")
	)
	(via
		(at 435.325266 -255.309624)
		(size 0.6096)
		(drill 0.3048)
		(layers "F.Cu" "B.Cu")
		(net "GND")
	)
	(via
		(at 282.007056 37.403024)
		(size 0.7112)
		(drill 0.4064)
		(layers "F.Cu" "B.Cu")
		(net "GND")
	)
	(via
		(at 173.322996 -347.802962)
		(size 0.7112)
		(drill 0.4064)
		(layers "F.Cu" "B.Cu")
		(net "GND")
	)
	(via
		(at 45.052996 -347.802962)
		(size 0.7112)
		(drill 0.4064)
		(layers "F.Cu" "B.Cu")
		(net "GND")
	)
	(via
		(at 490.053122 -346.421202)
		(size 0.7112)
		(drill 0.4064)
		(layers "F.Cu" "B.Cu")
		(net "GND")
	)
	(via
		(at 303.344072 -184.5818)
		(size 0.5588)
		(drill 0.3048)
		(layers "F.Cu" "B.Cu")
		(net "GND")
	)
	(via
		(at 191.994282 -230.553006)
		(size 0.5588)
		(drill 0.3048)
		(layers "F.Cu" "B.Cu")
		(net "GND")
	)
	(via
		(at 265.3284 -100.965)
		(size 0.5588)
		(drill 0.3048)
		(layers "F.Cu" "B.Cu")
		(net "GND")
	)
	(via
		(at 203.733908 -12.97305)
		(size 0.5588)
		(drill 0.3048)
		(layers "F.Cu" "B.Cu")
		(net "GND")
	)
	(via
		(at 420.304976 -272.035016)
		(size 0.5588)
		(drill 0.3048)
		(layers "F.Cu" "B.Cu")
		(net "GND")
	)
	(via
		(at 15.24 -5.08)
		(size 0.5588)
		(drill 0.3048)
		(layers "F.Cu" "B.Cu")
		(net "GND")
	)
	(via
		(at 490.053122 -66.42735)
		(size 0.7112)
		(drill 0.4064)
		(layers "F.Cu" "B.Cu")
		(net "GND")
	)
	(via
		(at 3.81 -259.08)
		(size 0.5588)
		(drill 0.3048)
		(layers "F.Cu" "B.Cu")
		(net "GND")
	)
	(via
		(at 63.5 -330.2)
		(size 0.5588)
		(drill 0.3048)
		(layers "F.Cu" "B.Cu")
		(net "GND")
	)
	(via
		(at 229.108 14.732)
		(size 0.5588)
		(drill 0.3048)
		(layers "F.Cu" "B.Cu")
		(net "GND")
	)
	(via
		(at 204.055218 -158.0896)
		(size 0.5588)
		(drill 0.3048)
		(layers "F.Cu" "B.Cu")
		(net "GND")
	)
	(via
		(at 201.397108 -383.022856)
		(size 0.7112)
		(drill 0.4064)
		(layers "F.Cu" "B.Cu")
		(net "GND")
	)
	(via
		(at 66.04 -20.32)
		(size 0.5588)
		(drill 0.3048)
		(layers "F.Cu" "B.Cu")
		(net "GND")
	)
	(via
		(at 148.205698 -49.494694)
		(size 0.5588)
		(drill 0.3048)
		(layers "F.Cu" "B.Cu")
		(net "GND")
	)
	(via
		(at 73.726802 -149.66315)
		(size 0.5588)
		(drill 0.3048)
		(layers "F.Cu" "B.Cu")
		(net "GND")
	)
	(via
		(at 55.88 -15.24)
		(size 0.5588)
		(drill 0.3048)
		(layers "F.Cu" "B.Cu")
		(net "GND")
	)
	(via
		(at 132.842 -265.43)
		(size 0.5588)
		(drill 0.3048)
		(layers "F.Cu" "B.Cu")
		(net "GND")
	)
	(via
		(at 468.327994 -238.777018)
		(size 0.5588)
		(drill 0.3048)
		(layers "F.Cu" "B.Cu")
		(net "GND")
	)
	(via
		(at 186.055 -69.974968)
		(size 0.5588)
		(drill 0.3048)
		(layers "F.Cu" "B.Cu")
		(net "GND")
	)
	(via
		(at 490.053122 -47.37735)
		(size 0.7112)
		(drill 0.4064)
		(layers "F.Cu" "B.Cu")
		(net "GND")
	)
	(via
		(at 411.48 -25.4)
		(size 0.5588)
		(drill 0.3048)
		(layers "F.Cu" "B.Cu")
		(net "GND")
	)
	(via
		(at 60.96 -330.2)
		(size 0.5588)
		(drill 0.3048)
		(layers "F.Cu" "B.Cu")
		(net "GND")
	)
	(via
		(at 186.055 -272.035016)
		(size 0.5588)
		(drill 0.3048)
		(layers "F.Cu" "B.Cu")
		(net "GND")
	)
	(via
		(at 490.053122 -336.261202)
		(size 0.7112)
		(drill 0.4064)
		(layers "F.Cu" "B.Cu")
		(net "GND")
	)
	(via
		(at 428.406052 -67.223894)
		(size 0.5588)
		(drill 0.3048)
		(layers "F.Cu" "B.Cu")
		(net "GND")
	)
	(via
		(at 468.76843 -131.200144)
		(size 0.5588)
		(drill 0.3048)
		(layers "F.Cu" "B.Cu")
		(net "GND")
	)
	(via
		(at 490.053122 -309.591202)
		(size 0.7112)
		(drill 0.4064)
		(layers "F.Cu" "B.Cu")
		(net "GND")
	)
	(via
		(at 411.48 -81.28)
		(size 0.5588)
		(drill 0.3048)
		(layers "F.Cu" "B.Cu")
		(net "GND")
	)
	(via
		(at 1.397 -268.348968)
		(size 0.7112)
		(drill 0.4064)
		(layers "F.Cu" "B.Cu")
		(net "GND")
	)
	(via
		(at 419.044882 -347.802962)
		(size 0.7112)
		(drill 0.4064)
		(layers "F.Cu" "B.Cu")
		(net "GND")
	)
	(via
		(at 473.752926 -177.778918)
		(size 0.5588)
		(drill 0.3048)
		(layers "F.Cu" "B.Cu")
		(net "GND")
	)
	(via
		(at 490.053122 -82.93735)
		(size 0.7112)
		(drill 0.4064)
		(layers "F.Cu" "B.Cu")
		(net "GND")
	)
	(via
		(at 191.135 -348.107)
		(size 0.7112)
		(drill 0.4064)
		(layers "F.Cu" "B.Cu")
		(net "GND")
	)
	(via
		(at 28.304998 -292.355016)
		(size 0.5588)
		(drill 0.3048)
		(layers "F.Cu" "B.Cu")
		(net "GND")
	)
	(via
		(at 388.564882 -347.802962)
		(size 0.7112)
		(drill 0.4064)
		(layers "F.Cu" "B.Cu")
		(net "GND")
	)
	(via
		(at 66.04 -332.74)
		(size 0.5588)
		(drill 0.3048)
		(layers "F.Cu" "B.Cu")
		(net "GND")
	)
	(via
		(at 367.58118 -85.82406)
		(size 0.5588)
		(drill 0.3048)
		(layers "F.Cu" "B.Cu")
		(net "GND")
	)
	(via
		(at 426.755052 -156.315918)
		(size 0.5588)
		(drill 0.3048)
		(layers "F.Cu" "B.Cu")
		(net "GND")
	)
	(via
		(at 411.48 -86.36)
		(size 0.5588)
		(drill 0.3048)
		(layers "F.Cu" "B.Cu")
		(net "GND")
	)
	(via
		(at 176.983898 -147.480782)
		(size 0.5588)
		(drill 0.3048)
		(layers "F.Cu" "B.Cu")
		(net "GND")
	)
	(via
		(at 1.397 -250.568968)
		(size 0.7112)
		(drill 0.4064)
		(layers "F.Cu" "B.Cu")
		(net "GND")
	)
	(via
		(at 357.205026 -299.975016)
		(size 0.5588)
		(drill 0.3048)
		(layers "F.Cu" "B.Cu")
		(net "GND")
	)
	(via
		(at 466.930994 -210.289394)
		(size 0.5588)
		(drill 0.3048)
		(layers "F.Cu" "B.Cu")
		(net "GND")
	)
	(via
		(at 351.79 -121.92)
		(size 0.5588)
		(drill 0.3048)
		(layers "F.Cu" "B.Cu")
		(net "GND")
	)
	(via
		(at 472.44 -15.24)
		(size 0.5588)
		(drill 0.3048)
		(layers "F.Cu" "B.Cu")
		(net "GND")
	)
	(via
		(at 55.755032 -1.397)
		(size 0.7112)
		(drill 0.4064)
		(layers "F.Cu" "B.Cu")
		(net "GND")
	)
	(via
		(at 76.802996 -347.802962)
		(size 0.7112)
		(drill 0.4064)
		(layers "F.Cu" "B.Cu")
		(net "GND")
	)
	(via
		(at 107.696 -280.67)
		(size 0.5588)
		(drill 0.3048)
		(layers "F.Cu" "B.Cu")
		(net "GND")
	)
	(via
		(at 331.1652 -161.649918)
		(size 0.5588)
		(drill 0.3048)
		(layers "F.Cu" "B.Cu")
		(net "GND")
	)
	(via
		(at 107.2642 -64.683894)
		(size 0.5588)
		(drill 0.3048)
		(layers "F.Cu" "B.Cu")
		(net "GND")
	)
	(via
		(at 84.582 -147.32)
		(size 0.5588)
		(drill 0.3048)
		(layers "F.Cu" "B.Cu")
		(net "GND")
	)
	(via
		(at 356.062026 -167.829992)
		(size 0.5588)
		(drill 0.3048)
		(layers "F.Cu" "B.Cu")
		(net "GND")
	)
	(via
		(at 490.053122 -32.13735)
		(size 0.7112)
		(drill 0.4064)
		(layers "F.Cu" "B.Cu")
		(net "GND")
	)
	(via
		(at 477.52 -25.4)
		(size 0.5588)
		(drill 0.3048)
		(layers "F.Cu" "B.Cu")
		(net "GND")
	)
	(via
		(at 9.906 -211.963)
		(size 0.5588)
		(drill 0.3048)
		(layers "F.Cu" "B.Cu")
		(net "GND")
	)
	(via
		(at 81.28 -86.36)
		(size 0.5588)
		(drill 0.3048)
		(layers "F.Cu" "B.Cu")
		(net "GND")
	)
	(via
		(at 99.949 -251.079)
		(size 0.5588)
		(drill 0.3048)
		(layers "F.Cu" "B.Cu")
		(net "GND")
	)
	(via
		(at 99.06 -127)
		(size 0.5588)
		(drill 0.3048)
		(layers "F.Cu" "B.Cu")
		(net "GND")
	)
	(via
		(at 428.75962 -1.397)
		(size 0.7112)
		(drill 0.4064)
		(layers "F.Cu" "B.Cu")
		(net "GND")
	)
	(via
		(at 438.91962 -1.397)
		(size 0.7112)
		(drill 0.4064)
		(layers "F.Cu" "B.Cu")
		(net "GND")
	)
	(via
		(at 288.911284 -350.505268)
		(size 0.6604)
		(drill 0.3556)
		(layers "F.Cu" "B.Cu")
		(net "GND")
	)
	(via
		(at 450.88556 -42.094912)
		(size 0.5588)
		(drill 0.3048)
		(layers "F.Cu" "B.Cu")
		(net "GND")
	)
	(via
		(at 490.053122 -258.791202)
		(size 0.7112)
		(drill 0.4064)
		(layers "F.Cu" "B.Cu")
		(net "GND")
	)
	(via
		(at 18.652998 -292.778942)
		(size 0.5588)
		(drill 0.3048)
		(layers "F.Cu" "B.Cu")
		(net "GND")
	)
	(via
		(at 35.56 -10.16)
		(size 0.5588)
		(drill 0.3048)
		(layers "F.Cu" "B.Cu")
		(net "GND")
	)
	(via
		(at 390.532874 -266.035028)
		(size 0.5588)
		(drill 0.3048)
		(layers "F.Cu" "B.Cu")
		(net "GND")
	)
	(via
		(at 6.35 -248.92)
		(size 0.5588)
		(drill 0.3048)
		(layers "F.Cu" "B.Cu")
		(net "GND")
	)
	(via
		(at 1.397 -220.088968)
		(size 0.7112)
		(drill 0.4064)
		(layers "F.Cu" "B.Cu")
		(net "GND")
	)
	(via
		(at 406.4 -15.24)
		(size 0.5588)
		(drill 0.3048)
		(layers "F.Cu" "B.Cu")
		(net "GND")
	)
	(via
		(at 32.512 -73.279)
		(size 0.5588)
		(drill 0.3048)
		(layers "F.Cu" "B.Cu")
		(net "GND")
	)
	(via
		(at 108.372402 -130.113278)
		(size 0.5588)
		(drill 0.3048)
		(layers "F.Cu" "B.Cu")
		(net "GND")
	)
	(via
		(at 296.291 -210.693)
		(size 0.5588)
		(drill 0.3048)
		(layers "F.Cu" "B.Cu")
		(net "GND")
	)
	(via
		(at 368.878866 -143.1544)
		(size 0.5588)
		(drill 0.3048)
		(layers "F.Cu" "B.Cu")
		(net "GND")
	)
	(via
		(at 40.64 -30.48)
		(size 0.5588)
		(drill 0.3048)
		(layers "F.Cu" "B.Cu")
		(net "GND")
	)
	(via
		(at 118.890796 -306.240942)
		(size 0.5588)
		(drill 0.3048)
		(layers "F.Cu" "B.Cu")
		(net "GND")
	)
	(via
		(at 406.4 -81.28)
		(size 0.5588)
		(drill 0.3048)
		(layers "F.Cu" "B.Cu")
		(net "GND")
	)
	(via
		(at 308.602888 -396.911068)
		(size 0.7112)
		(drill 0.4064)
		(layers "F.Cu" "B.Cu")
		(net "GND")
	)
	(via
		(at 487.43362 -1.397)
		(size 0.7112)
		(drill 0.4064)
		(layers "F.Cu" "B.Cu")
		(net "GND")
	)
	(via
		(at 330.835 -297.604942)
		(size 0.5588)
		(drill 0.3048)
		(layers "F.Cu" "B.Cu")
		(net "GND")
	)
	(via
		(at 1.397 -204.848968)
		(size 0.7112)
		(drill 0.4064)
		(layers "F.Cu" "B.Cu")
		(net "GND")
	)
	(via
		(at 359.0036 -146.05)
		(size 0.5588)
		(drill 0.3048)
		(layers "F.Cu" "B.Cu")
		(net "GND")
	)
	(via
		(at 329.8698 -69.2912)
		(size 0.5588)
		(drill 0.3048)
		(layers "F.Cu" "B.Cu")
		(net "GND")
	)
	(via
		(at 48.26 -332.74)
		(size 0.5588)
		(drill 0.3048)
		(layers "F.Cu" "B.Cu")
		(net "GND")
	)
	(via
		(at 490.053122 -23.24735)
		(size 0.7112)
		(drill 0.4064)
		(layers "F.Cu" "B.Cu")
		(net "GND")
	)
	(via
		(at 490.053122 -157.86735)
		(size 0.7112)
		(drill 0.4064)
		(layers "F.Cu" "B.Cu")
		(net "GND")
	)
	(via
		(at 181.1909 -49.443894)
		(size 0.5588)
		(drill 0.3048)
		(layers "F.Cu" "B.Cu")
		(net "GND")
	)
	(via
		(at 7.495032 -1.397)
		(size 0.7112)
		(drill 0.4064)
		(layers "F.Cu" "B.Cu")
		(net "GND")
	)
	(via
		(at 1.397 -275.968968)
		(size 0.7112)
		(drill 0.4064)
		(layers "F.Cu" "B.Cu")
		(net "GND")
	)
	(via
		(at 25.4 -121.92)
		(size 0.5588)
		(drill 0.3048)
		(layers "F.Cu" "B.Cu")
		(net "GND")
	)
	(via
		(at 390.532874 -151.035004)
		(size 0.5588)
		(drill 0.3048)
		(layers "F.Cu" "B.Cu")
		(net "GND")
	)
	(via
		(at 447.04 -127)
		(size 0.5588)
		(drill 0.3048)
		(layers "F.Cu" "B.Cu")
		(net "GND")
	)
	(via
		(at 5.08 -20.32)
		(size 0.5588)
		(drill 0.3048)
		(layers "F.Cu" "B.Cu")
		(net "GND")
	)
	(via
		(at 91.404948 -182.434992)
		(size 0.5588)
		(drill 0.3048)
		(layers "F.Cu" "B.Cu")
		(net "GND")
	)
	(via
		(at 469.516714 -206.193898)
		(size 0.5588)
		(drill 0.3048)
		(layers "F.Cu" "B.Cu")
		(net "GND")
	)
	(via
		(at 466.912706 -211.233004)
		(size 0.5588)
		(drill 0.3048)
		(layers "F.Cu" "B.Cu")
		(net "GND")
	)
	(via
		(at 34.892996 -347.802962)
		(size 0.7112)
		(drill 0.4064)
		(layers "F.Cu" "B.Cu")
		(net "GND")
	)
	(via
		(at 64.77 -71.12)
		(size 0.5588)
		(drill 0.3048)
		(layers "F.Cu" "B.Cu")
		(net "GND")
	)
	(via
		(at 307.764942 -375.397014)
		(size 0.7112)
		(drill 0.4064)
		(layers "F.Cu" "B.Cu")
		(net "GND")
	)
	(via
		(at 1.397 -207.388968)
		(size 0.7112)
		(drill 0.4064)
		(layers "F.Cu" "B.Cu")
		(net "GND")
	)
	(via
		(at 404.622 -265.049)
		(size 0.5588)
		(drill 0.3048)
		(layers "F.Cu" "B.Cu")
		(net "GND")
	)
	(via
		(at 344.114882 -347.802962)
		(size 0.7112)
		(drill 0.4064)
		(layers "F.Cu" "B.Cu")
		(net "GND")
	)
	(via
		(at 221.651068 33.16605)
		(size 0.7112)
		(drill 0.4064)
		(layers "F.Cu" "B.Cu")
		(net "GND")
	)
	(via
		(at 297.604942 -375.397014)
		(size 0.7112)
		(drill 0.4064)
		(layers "F.Cu" "B.Cu")
		(net "GND")
	)
	(via
		(at 259.585714 -289.947604)
		(size 0.5588)
		(drill 0.3048)
		(layers "F.Cu" "B.Cu")
		(net "GND")
	)
	(via
		(at 484.659178 -211.301076)
		(size 0.5588)
		(drill 0.3048)
		(layers "F.Cu" "B.Cu")
		(net "GND")
	)
	(via
		(at 363.655102 -156.315918)
		(size 0.5588)
		(drill 0.3048)
		(layers "F.Cu" "B.Cu")
		(net "GND")
	)
	(via
		(at 1.397 -57.528968)
		(size 0.7112)
		(drill 0.4064)
		(layers "F.Cu" "B.Cu")
		(net "GND")
	)
	(via
		(at 45.72 -81.28)
		(size 0.5588)
		(drill 0.3048)
		(layers "F.Cu" "B.Cu")
		(net "GND")
	)
	(via
		(at 1.397 -41.018968)
		(size 0.7112)
		(drill 0.4064)
		(layers "F.Cu" "B.Cu")
		(net "GND")
	)
	(via
		(at 325.654924 -45.844968)
		(size 0.5588)
		(drill 0.3048)
		(layers "F.Cu" "B.Cu")
		(net "GND")
	)
	(via
		(at 1.397 -147.698968)
		(size 0.7112)
		(drill 0.4064)
		(layers "F.Cu" "B.Cu")
		(net "GND")
	)
	(via
		(at 99.949 -258.318)
		(size 0.5588)
		(drill 0.3048)
		(layers "F.Cu" "B.Cu")
		(net "GND")
	)
	(via
		(at 169.672 -303.53)
		(size 0.5588)
		(drill 0.3048)
		(layers "F.Cu" "B.Cu")
		(net "GND")
	)
	(via
		(at 257.7592 15.7734)
		(size 0.5588)
		(drill 0.3048)
		(layers "F.Cu" "B.Cu")
		(net "GND")
	)
	(via
		(at 367.749836 -31.624778)
		(size 0.6604)
		(drill 0.3556)
		(layers "F.Cu" "B.Cu")
		(net "GND")
	)
	(via
		(at 490.053122 -108.33735)
		(size 0.7112)
		(drill 0.4064)
		(layers "F.Cu" "B.Cu")
		(net "GND")
	)
	(via
		(at 116.655596 -164.494718)
		(size 0.5588)
		(drill 0.3048)
		(layers "F.Cu" "B.Cu")
		(net "GND")
	)
	(via
		(at 490.053122 -16.89735)
		(size 0.7112)
		(drill 0.4064)
		(layers "F.Cu" "B.Cu")
		(net "GND")
	)
	(via
		(at 145.233898 -162.615118)
		(size 0.5588)
		(drill 0.3048)
		(layers "F.Cu" "B.Cu")
		(net "GND")
	)
	(via
		(at 1.397 -13.078968)
		(size 0.7112)
		(drill 0.4064)
		(layers "F.Cu" "B.Cu")
		(net "GND")
	)
	(via
		(at 90.261948 -285.230062)
		(size 0.5588)
		(drill 0.3048)
		(layers "F.Cu" "B.Cu")
		(net "GND")
	)
	(via
		(at 146.05 -265.684)
		(size 0.5588)
		(drill 0.3048)
		(layers "F.Cu" "B.Cu")
		(net "GND")
	)
	(via
		(at 15.24 -15.24)
		(size 0.5588)
		(drill 0.3048)
		(layers "F.Cu" "B.Cu")
		(net "GND")
	)
	(via
		(at 459.9559 -297.223942)
		(size 0.5588)
		(drill 0.3048)
		(layers "F.Cu" "B.Cu")
		(net "GND")
	)
	(via
		(at 393.93495 -182.604918)
		(size 0.5588)
		(drill 0.3048)
		(layers "F.Cu" "B.Cu")
		(net "GND")
	)
	(via
		(at 96.266 -168.656)
		(size 0.5588)
		(drill 0.3048)
		(layers "F.Cu" "B.Cu")
		(net "GND")
	)
	(via
		(at 177.132996 -347.802962)
		(size 0.7112)
		(drill 0.4064)
		(layers "F.Cu" "B.Cu")
		(net "GND")
	)
	(via
		(at 10.16 -30.48)
		(size 0.5588)
		(drill 0.3048)
		(layers "F.Cu" "B.Cu")
		(net "GND")
	)
	(via
		(at 428.787052 -164.596318)
		(size 0.5588)
		(drill 0.3048)
		(layers "F.Cu" "B.Cu")
		(net "GND")
	)
	(via
		(at 83.82 -116.84)
		(size 0.5588)
		(drill 0.3048)
		(layers "F.Cu" "B.Cu")
		(net "GND")
	)
	(via
		(at 202.176126 0.348996)
		(size 0.7112)
		(drill 0.4064)
		(layers "F.Cu" "B.Cu")
		(net "GND")
	)
	(via
		(at 122.954796 -177.354992)
		(size 0.5588)
		(drill 0.3048)
		(layers "F.Cu" "B.Cu")
		(net "GND")
	)
	(via
		(at 298.602908 34.948876)
		(size 0.7112)
		(drill 0.4064)
		(layers "F.Cu" "B.Cu")
		(net "GND")
	)
	(via
		(at 143.002 -55.2704)
		(size 0.5588)
		(drill 0.3048)
		(layers "F.Cu" "B.Cu")
		(net "GND")
	)
	(via
		(at 387.611874 -282.830016)
		(size 0.5588)
		(drill 0.3048)
		(layers "F.Cu" "B.Cu")
		(net "GND")
	)
	(via
		(at 287.806892 -419.803072)
		(size 0.7112)
		(drill 0.4064)
		(layers "F.Cu" "B.Cu")
		(net "GND")
	)
	(via
		(at 102.153974 -180.42255)
		(size 0.5588)
		(drill 0.3048)
		(layers "F.Cu" "B.Cu")
		(net "GND")
	)
	(via
		(at 457.6699 -76.113894)
		(size 0.5588)
		(drill 0.3048)
		(layers "F.Cu" "B.Cu")
		(net "GND")
	)
	(via
		(at 71.12 -5.08)
		(size 0.5588)
		(drill 0.3048)
		(layers "F.Cu" "B.Cu")
		(net "GND")
	)
	(via
		(at 150.440898 -306.240942)
		(size 0.5588)
		(drill 0.3048)
		(layers "F.Cu" "B.Cu")
		(net "GND")
	)
	(via
		(at 182.212996 -347.802962)
		(size 0.7112)
		(drill 0.4064)
		(layers "F.Cu" "B.Cu")
		(net "GND")
	)
	(via
		(at 483.404926 -184.974992)
		(size 0.5588)
		(drill 0.3048)
		(layers "F.Cu" "B.Cu")
		(net "GND")
	)
	(via
		(at 365.76 -116.84)
		(size 0.5588)
		(drill 0.3048)
		(layers "F.Cu" "B.Cu")
		(net "GND")
	)
	(via
		(at 336.494882 -347.802962)
		(size 0.7112)
		(drill 0.4064)
		(layers "F.Cu" "B.Cu")
		(net "GND")
	)
	(via
		(at 356.062026 -285.230062)
		(size 0.5588)
		(drill 0.3048)
		(layers "F.Cu" "B.Cu")
		(net "GND")
	)
	(via
		(at 427.934882 -347.802962)
		(size 0.7112)
		(drill 0.4064)
		(layers "F.Cu" "B.Cu")
		(net "GND")
	)
	(via
		(at 86.235032 -1.397)
		(size 0.7112)
		(drill 0.4064)
		(layers "F.Cu" "B.Cu")
		(net "GND")
	)
	(via
		(at 58.925714 -50.429922)
		(size 0.5588)
		(drill 0.3048)
		(layers "F.Cu" "B.Cu")
		(net "GND")
	)
	(via
		(at 490.053122 -345.151202)
		(size 0.7112)
		(drill 0.4064)
		(layers "F.Cu" "B.Cu")
		(net "GND")
	)
	(via
		(at 441.165234 -294.177212)
		(size 0.5588)
		(drill 0.3048)
		(layers "F.Cu" "B.Cu")
		(net "GND")
	)
	(via
		(at 91.181682 -347.548962)
		(size 0.7112)
		(drill 0.4064)
		(layers "F.Cu" "B.Cu")
		(net "GND")
	)
	(via
		(at 253.414276 -247.63476)
		(size 0.5588)
		(drill 0.3048)
		(layers "F.Cu" "B.Cu")
		(net "GND")
	)
	(via
		(at 300.758352 -25.74544)
		(size 0.5588)
		(drill 0.3048)
		(layers "F.Cu" "B.Cu")
		(net "GND")
	)
	(via
		(at 279.467056 37.403024)
		(size 0.7112)
		(drill 0.4064)
		(layers "F.Cu" "B.Cu")
		(net "GND")
	)
	(via
		(at 388.295642 -289.285172)
		(size 0.5588)
		(drill 0.3048)
		(layers "F.Cu" "B.Cu")
		(net "GND")
	)
	(via
		(at 45.72 -223.52)
		(size 0.5588)
		(drill 0.3048)
		(layers "F.Cu" "B.Cu")
		(net "GND")
	)
	(via
		(at 37.785802 -146.36115)
		(size 0.5588)
		(drill 0.3048)
		(layers "F.Cu" "B.Cu")
		(net "GND")
	)
	(via
		(at 347.924882 -347.802962)
		(size 0.7112)
		(drill 0.4064)
		(layers "F.Cu" "B.Cu")
		(net "GND")
	)
	(via
		(at 446.4304 -250.7488)
		(size 0.5588)
		(drill 0.3048)
		(layers "F.Cu" "B.Cu")
		(net "GND")
	)
	(via
		(at 55.790846 -76.240894)
		(size 0.5588)
		(drill 0.3048)
		(layers "F.Cu" "B.Cu")
		(net "GND")
	)
	(via
		(at 425.815252 -276.649942)
		(size 0.5588)
		(drill 0.3048)
		(layers "F.Cu" "B.Cu")
		(net "GND")
	)
	(via
		(at 194.056 -111.633)
		(size 0.5588)
		(drill 0.3048)
		(layers "F.Cu" "B.Cu")
		(net "GND")
	)
	(via
		(at 50.202846 -177.778918)
		(size 0.5588)
		(drill 0.3048)
		(layers "F.Cu" "B.Cu")
		(net "GND")
	)
	(via
		(at 431.8 -91.44)
		(size 0.5588)
		(drill 0.3048)
		(layers "F.Cu" "B.Cu")
		(net "GND")
	)
	(via
		(at 366.20958 -92.91066)
		(size 0.5588)
		(drill 0.3048)
		(layers "F.Cu" "B.Cu")
		(net "GND")
	)
	(via
		(at 221.651068 7.76605)
		(size 0.7112)
		(drill 0.4064)
		(layers "F.Cu" "B.Cu")
		(net "GND")
	)
	(via
		(at 58.711846 -165.429946)
		(size 0.5588)
		(drill 0.3048)
		(layers "F.Cu" "B.Cu")
		(net "GND")
	)
	(via
		(at 262.509762 -24.775922)
		(size 0.5588)
		(drill 0.3048)
		(layers "F.Cu" "B.Cu")
		(net "GND")
	)
	(via
		(at 41.242996 -347.802962)
		(size 0.7112)
		(drill 0.4064)
		(layers "F.Cu" "B.Cu")
		(net "GND")
	)
	(via
		(at 306.494942 -375.397014)
		(size 0.7112)
		(drill 0.4064)
		(layers "F.Cu" "B.Cu")
		(net "GND")
	)
	(via
		(at 102.611682 -347.548962)
		(size 0.7112)
		(drill 0.4064)
		(layers "F.Cu" "B.Cu")
		(net "GND")
	)
	(via
		(at 53.34 -332.74)
		(size 0.5588)
		(drill 0.3048)
		(layers "F.Cu" "B.Cu")
		(net "GND")
	)
	(via
		(at 241.76101 -378.830586)
		(size 0.5588)
		(drill 0.3048)
		(layers "F.Cu" "B.Cu")
		(net "GND")
	)
	(via
		(at 224.028 26.797)
		(size 0.5588)
		(drill 0.3048)
		(layers "F.Cu" "B.Cu")
		(net "GND")
	)
	(via
		(at 22.666198 -300.322742)
		(size 0.5588)
		(drill 0.3048)
		(layers "F.Cu" "B.Cu")
		(net "GND")
	)
	(via
		(at 1.397 -329.308968)
		(size 0.7112)
		(drill 0.4064)
		(layers "F.Cu" "B.Cu")
		(net "GND")
	)
	(via
		(at 192.350898 -350.741742)
		(size 0.7112)
		(drill 0.4064)
		(layers "F.Cu" "B.Cu")
		(net "GND")
	)
	(via
		(at 346.827094 -288.5694)
		(size 0.5588)
		(drill 0.3048)
		(layers "F.Cu" "B.Cu")
		(net "GND")
	)
	(via
		(at 21.465032 -1.397)
		(size 0.7112)
		(drill 0.4064)
		(layers "F.Cu" "B.Cu")
		(net "GND")
	)
	(via
		(at 322.524882 -347.802962)
		(size 0.7112)
		(drill 0.4064)
		(layers "F.Cu" "B.Cu")
		(net "GND")
	)
	(via
		(at 1.397 -316.608968)
		(size 0.7112)
		(drill 0.4064)
		(layers "F.Cu" "B.Cu")
		(net "GND")
	)
	(via
		(at 184.912 -165.429946)
		(size 0.5588)
		(drill 0.3048)
		(layers "F.Cu" "B.Cu")
		(net "GND")
	)
	(via
		(at 43.18 -302.387)
		(size 0.5588)
		(drill 0.3048)
		(layers "F.Cu" "B.Cu")
		(net "GND")
	)
	(via
		(at 62.23 -218.44)
		(size 0.5588)
		(drill 0.3048)
		(layers "F.Cu" "B.Cu")
		(net "GND")
	)
	(via
		(at 62.23 -228.6)
		(size 0.5588)
		(drill 0.3048)
		(layers "F.Cu" "B.Cu")
		(net "GND")
	)
	(via
		(at 298.602908 12.088876)
		(size 0.7112)
		(drill 0.4064)
		(layers "F.Cu" "B.Cu")
		(net "GND")
	)
	(via
		(at 90.261948 -170.230038)
		(size 0.5588)
		(drill 0.3048)
		(layers "F.Cu" "B.Cu")
		(net "GND")
	)
	(via
		(at 443.99962 -1.397)
		(size 0.7112)
		(drill 0.4064)
		(layers "F.Cu" "B.Cu")
		(net "GND")
	)
	(via
		(at 4.445 -335.28)
		(size 0.5588)
		(drill 0.3048)
		(layers "F.Cu" "B.Cu")
		(net "GND")
	)
	(via
		(at 483.404926 -279.655016)
		(size 0.5588)
		(drill 0.3048)
		(layers "F.Cu" "B.Cu")
		(net "GND")
	)
	(via
		(at 490.053122 -240.41735)
		(size 0.7112)
		(drill 0.4064)
		(layers "F.Cu" "B.Cu")
		(net "GND")
	)
	(via
		(at 308.602888 -403.261068)
		(size 0.7112)
		(drill 0.4064)
		(layers "F.Cu" "B.Cu")
		(net "GND")
	)
	(via
		(at 487.68 -30.48)
		(size 0.5588)
		(drill 0.3048)
		(layers "F.Cu" "B.Cu")
		(net "GND")
	)
	(via
		(at 303.046892 -419.803072)
		(size 0.7112)
		(drill 0.4064)
		(layers "F.Cu" "B.Cu")
		(net "GND")
	)
	(via
		(at 180.123084 -1.397)
		(size 0.7112)
		(drill 0.4064)
		(layers "F.Cu" "B.Cu")
		(net "GND")
	)
	(via
		(at 469.516714 -205.177898)
		(size 0.5588)
		(drill 0.3048)
		(layers "F.Cu" "B.Cu")
		(net "GND")
	)
	(via
		(at 1.397 -164.208968)
		(size 0.7112)
		(drill 0.4064)
		(layers "F.Cu" "B.Cu")
		(net "GND")
	)
	(via
		(at 490.053122 -1.65735)
		(size 0.7112)
		(drill 0.4064)
		(layers "F.Cu" "B.Cu")
		(net "GND")
	)
	(via
		(at 35.56 -233.68)
		(size 0.5588)
		(drill 0.3048)
		(layers "F.Cu" "B.Cu")
		(net "GND")
	)
	(via
		(at 365.76 -250.571)
		(size 0.5588)
		(drill 0.3048)
		(layers "F.Cu" "B.Cu")
		(net "GND")
	)
	(via
		(at 22.666198 -185.322718)
		(size 0.5588)
		(drill 0.3048)
		(layers "F.Cu" "B.Cu")
		(net "GND")
	)
	(via
		(at 490.053122 -217.55735)
		(size 0.7112)
		(drill 0.4064)
		(layers "F.Cu" "B.Cu")
		(net "GND")
	)
	(via
		(at 217.533728 -103.2256)
		(size 0.5588)
		(drill 0.3048)
		(layers "F.Cu" "B.Cu")
		(net "GND")
	)
	(via
		(at 419.161976 -282.830016)
		(size 0.5588)
		(drill 0.3048)
		(layers "F.Cu" "B.Cu")
		(net "GND")
	)
	(via
		(at 184.912 -52.829968)
		(size 0.5588)
		(drill 0.3048)
		(layers "F.Cu" "B.Cu")
		(net "GND")
	)
	(via
		(at 19.033998 -162.615118)
		(size 0.5588)
		(drill 0.3048)
		(layers "F.Cu" "B.Cu")
		(net "GND")
	)
	(via
		(at 184.366408 -241.571018)
		(size 0.7112)
		(drill 0.4064)
		(layers "F.Cu" "B.Cu")
		(net "GND")
	)
	(via
		(at 50.8 -5.08)
		(size 0.5588)
		(drill 0.3048)
		(layers "F.Cu" "B.Cu")
		(net "GND")
	)
	(via
		(at 1.397 -201.038968)
		(size 0.7112)
		(drill 0.4064)
		(layers "F.Cu" "B.Cu")
		(net "GND")
	)
	(via
		(at 160.401 -196.596)
		(size 0.5588)
		(drill 0.3048)
		(layers "F.Cu" "B.Cu")
		(net "GND")
	)
	(via
		(at 58.711846 -52.829968)
		(size 0.5588)
		(drill 0.3048)
		(layers "F.Cu" "B.Cu")
		(net "GND")
	)
	(via
		(at 205.105 -303.403)
		(size 0.5588)
		(drill 0.3048)
		(layers "F.Cu" "B.Cu")
		(net "GND")
	)
	(via
		(at 273.939 -25.146)
		(size 0.5588)
		(drill 0.3048)
		(layers "F.Cu" "B.Cu")
		(net "GND")
	)
	(via
		(at 426.593 -36.576)
		(size 0.5588)
		(drill 0.3048)
		(layers "F.Cu" "B.Cu")
		(net "GND")
	)
	(via
		(at 15.24 -35.56)
		(size 0.5588)
		(drill 0.3048)
		(layers "F.Cu" "B.Cu")
		(net "GND")
	)
	(via
		(at 298.602908 31.138876)
		(size 0.7112)
		(drill 0.4064)
		(layers "F.Cu" "B.Cu")
		(net "GND")
	)
	(via
		(at 334.0862 -279.596342)
		(size 0.5588)
		(drill 0.3048)
		(layers "F.Cu" "B.Cu")
		(net "GND")
	)
	(via
		(at 25.275032 -1.397)
		(size 0.7112)
		(drill 0.4064)
		(layers "F.Cu" "B.Cu")
		(net "GND")
	)
	(via
		(at 375.5898 -147.0914)
		(size 0.5588)
		(drill 0.3048)
		(layers "F.Cu" "B.Cu")
		(net "GND")
	)
	(via
		(at 201.397108 -419.852856)
		(size 0.7112)
		(drill 0.4064)
		(layers "F.Cu" "B.Cu")
		(net "GND")
	)
	(via
		(at 10.16 -243.84)
		(size 0.5588)
		(drill 0.3048)
		(layers "F.Cu" "B.Cu")
		(net "GND")
	)
	(via
		(at 490.053122 -28.32735)
		(size 0.7112)
		(drill 0.4064)
		(layers "F.Cu" "B.Cu")
		(net "GND")
	)
	(via
		(at 163.068 -225.933)
		(size 0.5588)
		(drill 0.3048)
		(layers "F.Cu" "B.Cu")
		(net "GND")
	)
	(via
		(at 1.397 -33.398968)
		(size 0.7112)
		(drill 0.4064)
		(layers "F.Cu" "B.Cu")
		(net "GND")
	)
	(via
		(at 149.399752 -54.99608)
		(size 0.5588)
		(drill 0.3048)
		(layers "F.Cu" "B.Cu")
		(net "GND")
	)
	(via
		(at 24.384 -85.471)
		(size 0.5588)
		(drill 0.3048)
		(layers "F.Cu" "B.Cu")
		(net "GND")
	)
	(via
		(at 265.497056 37.403024)
		(size 0.7112)
		(drill 0.4064)
		(layers "F.Cu" "B.Cu")
		(net "GND")
	)
	(via
		(at 1.397 -86.738968)
		(size 0.7112)
		(drill 0.4064)
		(layers "F.Cu" "B.Cu")
		(net "GND")
	)
	(via
		(at 293.751 -118.618)
		(size 0.5588)
		(drill 0.3048)
		(layers "F.Cu" "B.Cu")
		(net "GND")
	)
	(via
		(at 490.053122 -13.08735)
		(size 0.7112)
		(drill 0.4064)
		(layers "F.Cu" "B.Cu")
		(net "GND")
	)
	(via
		(at 153.361898 -280.42997)
		(size 0.5588)
		(drill 0.3048)
		(layers "F.Cu" "B.Cu")
		(net "GND")
	)
	(via
		(at 17.521682 -347.548962)
		(size 0.7112)
		(drill 0.4064)
		(layers "F.Cu" "B.Cu")
		(net "GND")
	)
	(via
		(at 1.397 -221.358968)
		(size 0.7112)
		(drill 0.4064)
		(layers "F.Cu" "B.Cu")
		(net "GND")
	)
	(via
		(at 40.64 -20.32)
		(size 0.5588)
		(drill 0.3048)
		(layers "F.Cu" "B.Cu")
		(net "GND")
	)
	(via
		(at 240.56975 -347.72854)
		(size 0.5588)
		(drill 0.3048)
		(layers "F.Cu" "B.Cu")
		(net "GND")
	)
	(via
		(at 478.841816 -46.82363)
		(size 0.5588)
		(drill 0.3048)
		(layers "F.Cu" "B.Cu")
		(net "GND")
	)
	(via
		(at 57.15 -213.36)
		(size 0.5588)
		(drill 0.3048)
		(layers "F.Cu" "B.Cu")
		(net "GND")
	)
	(via
		(at 148.205698 -279.494742)
		(size 0.5588)
		(drill 0.3048)
		(layers "F.Cu" "B.Cu")
		(net "GND")
	)
	(via
		(at 291.616892 -419.803072)
		(size 0.7112)
		(drill 0.4064)
		(layers "F.Cu" "B.Cu")
		(net "GND")
	)
	(via
		(at 195.873624 -371.349016)
		(size 0.7112)
		(drill 0.4064)
		(layers "F.Cu" "B.Cu")
		(net "GND")
	)
	(via
		(at 298.602908 8.278876)
		(size 0.7112)
		(drill 0.4064)
		(layers "F.Cu" "B.Cu")
		(net "GND")
	)
	(via
		(at 451.854824 -45.844968)
		(size 0.5588)
		(drill 0.3048)
		(layers "F.Cu" "B.Cu")
		(net "GND")
	)
	(via
		(at 22.352 -146.685)
		(size 0.5588)
		(drill 0.3048)
		(layers "F.Cu" "B.Cu")
		(net "GND")
	)
	(via
		(at 490.053122 -21.97735)
		(size 0.7112)
		(drill 0.4064)
		(layers "F.Cu" "B.Cu")
		(net "GND")
	)
	(via
		(at 33.528 -283.718)
		(size 0.5588)
		(drill 0.3048)
		(layers "F.Cu" "B.Cu")
		(net "GND")
	)
	(via
		(at 83.312 -269.494)
		(size 0.5588)
		(drill 0.3048)
		(layers "F.Cu" "B.Cu")
		(net "GND")
	)
	(via
		(at 240.097056 37.403024)
		(size 0.7112)
		(drill 0.4064)
		(layers "F.Cu" "B.Cu")
		(net "GND")
	)
	(via
		(at 388.754874 -157.034992)
		(size 0.5588)
		(drill 0.3048)
		(layers "F.Cu" "B.Cu")
		(net "GND")
	)
	(via
		(at 392.912092 -306.026058)
		(size 0.5588)
		(drill 0.3048)
		(layers "F.Cu" "B.Cu")
		(net "GND")
	)
	(via
		(at 490.053122 -321.021202)
		(size 0.7112)
		(drill 0.4064)
		(layers "F.Cu" "B.Cu")
		(net "GND")
	)
	(via
		(at 57.15 -228.6)
		(size 0.5588)
		(drill 0.3048)
		(layers "F.Cu" "B.Cu")
		(net "GND")
	)
	(via
		(at 76.838302 -130.122676)
		(size 0.5588)
		(drill 0.3048)
		(layers "F.Cu" "B.Cu")
		(net "GND")
	)
	(via
		(at 440.18962 -1.397)
		(size 0.7112)
		(drill 0.4064)
		(layers "F.Cu" "B.Cu")
		(net "GND")
	)
	(via
		(at 365.5822 -76.581)
		(size 0.5588)
		(drill 0.3048)
		(layers "F.Cu" "B.Cu")
		(net "GND")
	)
	(via
		(at 154.422094 -67.039236)
		(size 0.5588)
		(drill 0.3048)
		(layers "F.Cu" "B.Cu")
		(net "GND")
	)
	(via
		(at 124.732796 -79.784956)
		(size 0.5588)
		(drill 0.3048)
		(layers "F.Cu" "B.Cu")
		(net "GND")
	)
	(via
		(at 74.93 -116.84)
		(size 0.5588)
		(drill 0.3048)
		(layers "F.Cu" "B.Cu")
		(net "GND")
	)
	(via
		(at 490.053122 -221.36735)
		(size 0.7112)
		(drill 0.4064)
		(layers "F.Cu" "B.Cu")
		(net "GND")
	)
	(via
		(at 397.23695 -49.596294)
		(size 0.5588)
		(drill 0.3048)
		(layers "F.Cu" "B.Cu")
		(net "GND")
	)
	(via
		(at 472.44 -81.28)
		(size 0.5588)
		(drill 0.3048)
		(layers "F.Cu" "B.Cu")
		(net "GND")
	)
	(via
		(at 187.96 -15.24)
		(size 0.5588)
		(drill 0.3048)
		(layers "F.Cu" "B.Cu")
		(net "GND")
	)
	(via
		(at 234.823 -313.944)
		(size 0.5588)
		(drill 0.3048)
		(layers "F.Cu" "B.Cu")
		(net "GND")
	)
	(via
		(at 460.3369 -49.596294)
		(size 0.5588)
		(drill 0.3048)
		(layers "F.Cu" "B.Cu")
		(net "GND")
	)
	(via
		(at 220.599 -168.91)
		(size 0.5588)
		(drill 0.3048)
		(layers "F.Cu" "B.Cu")
		(net "GND")
	)
	(via
		(at 389.349996 -31.624778)
		(size 0.6604)
		(drill 0.3556)
		(layers "F.Cu" "B.Cu")
		(net "GND")
	)
	(via
		(at 409.321 -273.812)
		(size 0.5588)
		(drill 0.3048)
		(layers "F.Cu" "B.Cu")
		(net "GND")
	)
	(via
		(at 33.622996 -347.802962)
		(size 0.7112)
		(drill 0.4064)
		(layers "F.Cu" "B.Cu")
		(net "GND")
	)
	(via
		(at 1.397 -27.048968)
		(size 0.7112)
		(drill 0.4064)
		(layers "F.Cu" "B.Cu")
		(net "GND")
	)
	(via
		(at 388.754874 -184.974992)
		(size 0.5588)
		(drill 0.3048)
		(layers "F.Cu" "B.Cu")
		(net "GND")
	)
	(via
		(at 316.174882 -347.802962)
		(size 0.7112)
		(drill 0.4064)
		(layers "F.Cu" "B.Cu")
		(net "GND")
	)
	(via
		(at 387.435344 -37.939726)
		(size 0.5588)
		(drill 0.3048)
		(layers "F.Cu" "B.Cu")
		(net "GND")
	)
	(via
		(at 273.836892 -419.803072)
		(size 0.7112)
		(drill 0.4064)
		(layers "F.Cu" "B.Cu")
		(net "GND")
	)
	(via
		(at 357.205026 -184.974992)
		(size 0.5588)
		(drill 0.3048)
		(layers "F.Cu" "B.Cu")
		(net "GND")
	)
	(via
		(at 25.4 -25.4)
		(size 0.5588)
		(drill 0.3048)
		(layers "F.Cu" "B.Cu")
		(net "GND")
	)
	(via
		(at 307.281072 -16.349472)
		(size 0.5588)
		(drill 0.3048)
		(layers "F.Cu" "B.Cu")
		(net "GND")
	)
	(via
		(at 488.70362 -1.397)
		(size 0.7112)
		(drill 0.4064)
		(layers "F.Cu" "B.Cu")
		(net "GND")
	)
	(via
		(at 86.566248 -279.469342)
		(size 0.5588)
		(drill 0.3048)
		(layers "F.Cu" "B.Cu")
		(net "GND")
	)
	(via
		(at 278.522938 -394.992098)
		(size 0.5588)
		(drill 0.3048)
		(layers "F.Cu" "B.Cu")
		(net "GND")
	)
	(via
		(at 187.833 -194.78498)
		(size 0.5588)
		(drill 0.3048)
		(layers "F.Cu" "B.Cu")
		(net "GND")
	)
	(via
		(at 170.307 -179.683918)
		(size 0.5588)
		(drill 0.3048)
		(layers "F.Cu" "B.Cu")
		(net "GND")
	)
	(via
		(at 441.183014 -290.035234)
		(size 0.5588)
		(drill 0.3048)
		(layers "F.Cu" "B.Cu")
		(net "GND")
	)
	(via
		(at 59.854846 -279.655016)
		(size 0.5588)
		(drill 0.3048)
		(layers "F.Cu" "B.Cu")
		(net "GND")
	)
	(via
		(at 466.034882 -347.802962)
		(size 0.7112)
		(drill 0.4064)
		(layers "F.Cu" "B.Cu")
		(net "GND")
	)
	(via
		(at 45.72 -5.08)
		(size 0.5588)
		(drill 0.3048)
		(layers "F.Cu" "B.Cu")
		(net "GND")
	)
	(via
		(at 6.985 -345.44)
		(size 0.5588)
		(drill 0.3048)
		(layers "F.Cu" "B.Cu")
		(net "GND")
	)
	(via
		(at 70.631304 -304.12817)
		(size 0.5588)
		(drill 0.3048)
		(layers "F.Cu" "B.Cu")
		(net "GND")
	)
	(via
		(at 426.72 -10.16)
		(size 0.5588)
		(drill 0.3048)
		(layers "F.Cu" "B.Cu")
		(net "GND")
	)
	(via
		(at 171.233084 -1.397)
		(size 0.7112)
		(drill 0.4064)
		(layers "F.Cu" "B.Cu")
		(net "GND")
	)
	(via
		(at 299.974 -206.756)
		(size 0.5588)
		(drill 0.3048)
		(layers "F.Cu" "B.Cu")
		(net "GND")
	)
	(via
		(at 490.053122 -337.531202)
		(size 0.7112)
		(drill 0.4064)
		(layers "F.Cu" "B.Cu")
		(net "GND")
	)
	(via
		(at 324.1548 -70.4596)
		(size 0.5588)
		(drill 0.3048)
		(layers "F.Cu" "B.Cu")
		(net "GND")
	)
	(via
		(at 490.053122 -249.901202)
		(size 0.7112)
		(drill 0.4064)
		(layers "F.Cu" "B.Cu")
		(net "GND")
	)
	(via
		(at 294.707056 37.403024)
		(size 0.7112)
		(drill 0.4064)
		(layers "F.Cu" "B.Cu")
		(net "GND")
	)
	(via
		(at 1.397 -311.528968)
		(size 0.7112)
		(drill 0.4064)
		(layers "F.Cu" "B.Cu")
		(net "GND")
	)
	(via
		(at 52.672996 -347.802962)
		(size 0.7112)
		(drill 0.4064)
		(layers "F.Cu" "B.Cu")
		(net "GND")
	)
	(via
		(at 246.815102 29.35478)
		(size 0.5588)
		(drill 0.3048)
		(layers "F.Cu" "B.Cu")
		(net "GND")
	)
	(via
		(at 40.64 -15.24)
		(size 0.5588)
		(drill 0.3048)
		(layers "F.Cu" "B.Cu")
		(net "GND")
	)
	(via
		(at 7.79018 -287.647888)
		(size 0.5588)
		(drill 0.3048)
		(layers "F.Cu" "B.Cu")
		(net "GND")
	)
	(via
		(at 387.611874 -170.230038)
		(size 0.5588)
		(drill 0.3048)
		(layers "F.Cu" "B.Cu")
		(net "GND")
	)
	(via
		(at 63.747396 -151.716232)
		(size 0.5588)
		(drill 0.3048)
		(layers "F.Cu" "B.Cu")
		(net "GND")
	)
	(via
		(at 21.971 -132.588)
		(size 0.5588)
		(drill 0.3048)
		(layers "F.Cu" "B.Cu")
		(net "GND")
	)
	(via
		(at 255.090676 -288.9504)
		(size 0.5588)
		(drill 0.3048)
		(layers "F.Cu" "B.Cu")
		(net "GND")
	)
	(via
		(at 67.792346 -289.857942)
		(size 0.5588)
		(drill 0.3048)
		(layers "F.Cu" "B.Cu")
		(net "GND")
	)
	(via
		(at 82.133948 -277.615142)
		(size 0.5588)
		(drill 0.3048)
		(layers "F.Cu" "B.Cu")
		(net "GND")
	)
	(via
		(at 434.34 -199.39)
		(size 0.5588)
		(drill 0.3048)
		(layers "F.Cu" "B.Cu")
		(net "GND")
	)
	(via
		(at 353.06 -242.697)
		(size 0.5588)
		(drill 0.3048)
		(layers "F.Cu" "B.Cu")
		(net "GND")
	)
	(via
		(at 308.602888 -401.991068)
		(size 0.7112)
		(drill 0.4064)
		(layers "F.Cu" "B.Cu")
		(net "GND")
	)
	(via
		(at 12.954 -214.884)
		(size 0.5588)
		(drill 0.3048)
		(layers "F.Cu" "B.Cu")
		(net "GND")
	)
	(via
		(at 447.4464 -253.7968)
		(size 0.5588)
		(drill 0.3048)
		(layers "F.Cu" "B.Cu")
		(net "GND")
	)
	(via
		(at 490.053122 -236.60735)
		(size 0.7112)
		(drill 0.4064)
		(layers "F.Cu" "B.Cu")
		(net "GND")
	)
	(via
		(at 257.4036 -288.925)
		(size 0.5588)
		(drill 0.3048)
		(layers "F.Cu" "B.Cu")
		(net "GND")
	)
	(via
		(at 472.510104 -232.678986)
		(size 0.5588)
		(drill 0.3048)
		(layers "F.Cu" "B.Cu")
		(net "GND")
	)
	(via
		(at 90.2208 -14.8336)
		(size 0.5588)
		(drill 0.3048)
		(layers "F.Cu" "B.Cu")
		(net "GND")
	)
	(via
		(at 339.725 -146.431)
		(size 0.5588)
		(drill 0.3048)
		(layers "F.Cu" "B.Cu")
		(net "GND")
	)
	(via
		(at 473.3798 -275.59)
		(size 0.5588)
		(drill 0.3048)
		(layers "F.Cu" "B.Cu")
		(net "GND")
	)
	(via
		(at 19.033998 -277.615142)
		(size 0.5588)
		(drill 0.3048)
		(layers "F.Cu" "B.Cu")
		(net "GND")
	)
	(via
		(at 11.171682 -347.548962)
		(size 0.7112)
		(drill 0.4064)
		(layers "F.Cu" "B.Cu")
		(net "GND")
	)
	(via
		(at 460.954882 -347.802962)
		(size 0.7112)
		(drill 0.4064)
		(layers "F.Cu" "B.Cu")
		(net "GND")
	)
	(via
		(at 174.12843 -54.052724)
		(size 0.5588)
		(drill 0.3048)
		(layers "F.Cu" "B.Cu")
		(net "GND")
	)
	(via
		(at 452.12 -15.24)
		(size 0.5588)
		(drill 0.3048)
		(layers "F.Cu" "B.Cu")
		(net "GND")
	)
	(via
		(at 206.121 -94.488)
		(size 0.5588)
		(drill 0.3048)
		(layers "F.Cu" "B.Cu")
		(net "GND")
	)
	(via
		(at 490.053122 -226.44735)
		(size 0.7112)
		(drill 0.4064)
		(layers "F.Cu" "B.Cu")
		(net "GND")
	)
	(via
		(at 1.397 -213.738968)
		(size 0.7112)
		(drill 0.4064)
		(layers "F.Cu" "B.Cu")
		(net "GND")
	)
	(via
		(at 32.895032 -1.397)
		(size 0.7112)
		(drill 0.4064)
		(layers "F.Cu" "B.Cu")
		(net "GND")
	)
	(via
		(at 468.574882 -347.802962)
		(size 0.7112)
		(drill 0.4064)
		(layers "F.Cu" "B.Cu")
		(net "GND")
	)
	(via
		(at 117.348 -251.079)
		(size 0.5588)
		(drill 0.3048)
		(layers "F.Cu" "B.Cu")
		(net "GND")
	)
	(via
		(at 308.602888 -382.941068)
		(size 0.7112)
		(drill 0.4064)
		(layers "F.Cu" "B.Cu")
		(net "GND")
	)
	(via
		(at 278.368252 -389.03148)
		(size 0.5588)
		(drill 0.3048)
		(layers "F.Cu" "B.Cu")
		(net "GND")
	)
	(via
		(at 118.890796 -191.240918)
		(size 0.5588)
		(drill 0.3048)
		(layers "F.Cu" "B.Cu")
		(net "GND")
	)
	(via
		(at 490.053122 -308.321202)
		(size 0.7112)
		(drill 0.4064)
		(layers "F.Cu" "B.Cu")
		(net "GND")
	)
	(via
		(at 133.731254 -296.302684)
		(size 0.5588)
		(drill 0.3048)
		(layers "F.Cu" "B.Cu")
		(net "GND")
	)
	(via
		(at 154.504898 -174.814992)
		(size 0.5588)
		(drill 0.3048)
		(layers "F.Cu" "B.Cu")
		(net "GND")
	)
	(via
		(at 1.397 -208.658968)
		(size 0.7112)
		(drill 0.4064)
		(layers "F.Cu" "B.Cu")
		(net "GND")
	)
	(via
		(at 229.937056 37.403024)
		(size 0.7112)
		(drill 0.4064)
		(layers "F.Cu" "B.Cu")
		(net "GND")
	)
	(via
		(at 355.6 -335.28)
		(size 0.5588)
		(drill 0.3048)
		(layers "F.Cu" "B.Cu")
		(net "GND")
	)
	(via
		(at 419.161976 -165.429946)
		(size 0.5588)
		(drill 0.3048)
		(layers "F.Cu" "B.Cu")
		(net "GND")
	)
	(via
		(at 165.1 -81.915)
		(size 0.5588)
		(drill 0.3048)
		(layers "F.Cu" "B.Cu")
		(net "GND")
	)
	(via
		(at 275.3868 20.9042)
		(size 0.5588)
		(drill 0.3048)
		(layers "F.Cu" "B.Cu")
		(net "GND")
	)
	(via
		(at 490.053122 -124.84735)
		(size 0.7112)
		(drill 0.4064)
		(layers "F.Cu" "B.Cu")
		(net "GND")
	)
	(via
		(at 431.8 -137.16)
		(size 0.5588)
		(drill 0.3048)
		(layers "F.Cu" "B.Cu")
		(net "GND")
	)
	(via
		(at 348.557088 -145.68424)
		(size 0.5588)
		(drill 0.3048)
		(layers "F.Cu" "B.Cu")
		(net "GND")
	)
	(via
		(at 388.754874 -174.814992)
		(size 0.5588)
		(drill 0.3048)
		(layers "F.Cu" "B.Cu")
		(net "GND")
	)
	(via
		(at 358.983026 -151.035004)
		(size 0.5588)
		(drill 0.3048)
		(layers "F.Cu" "B.Cu")
		(net "GND")
	)
	(via
		(at 438.912 -305.943)
		(size 0.5588)
		(drill 0.3048)
		(layers "F.Cu" "B.Cu")
		(net "GND")
	)
	(via
		(at 222.8342 -363.8296)
		(size 0.5588)
		(drill 0.3048)
		(layers "F.Cu" "B.Cu")
		(net "GND")
	)
	(via
		(at 128.7018 -290.061142)
		(size 0.5588)
		(drill 0.3048)
		(layers "F.Cu" "B.Cu")
		(net "GND")
	)
	(via
		(at 70.358 -157.099)
		(size 0.5588)
		(drill 0.3048)
		(layers "F.Cu" "B.Cu")
		(net "GND")
	)
	(via
		(at 1.397 -236.598968)
		(size 0.7112)
		(drill 0.4064)
		(layers "F.Cu" "B.Cu")
		(net "GND")
	)
	(via
		(at 252.222 -161.29)
		(size 0.5588)
		(drill 0.3048)
		(layers "F.Cu" "B.Cu")
		(net "GND")
	)
	(via
		(at 25.4 -223.52)
		(size 0.5588)
		(drill 0.3048)
		(layers "F.Cu" "B.Cu")
		(net "GND")
	)
	(via
		(at 443.23 -167.64)
		(size 0.5588)
		(drill 0.3048)
		(layers "F.Cu" "B.Cu")
		(net "GND")
	)
	(via
		(at 294.302942 -354.855018)
		(size 0.7112)
		(drill 0.4064)
		(layers "F.Cu" "B.Cu")
		(net "GND")
	)
	(via
		(at 288.911284 -346.905326)
		(size 0.6604)
		(drill 0.3556)
		(layers "F.Cu" "B.Cu")
		(net "GND")
	)
	(via
		(at 333.756 -182.223918)
		(size 0.5588)
		(drill 0.3048)
		(layers "F.Cu" "B.Cu")
		(net "GND")
	)
	(via
		(at 12.441682 -347.548962)
		(size 0.7112)
		(drill 0.4064)
		(layers "F.Cu" "B.Cu")
		(net "GND")
	)
	(via
		(at 274.828 -207.137)
		(size 0.5588)
		(drill 0.3048)
		(layers "F.Cu" "B.Cu")
		(net "GND")
	)
	(via
		(at 5.08 -55.88)
		(size 0.5588)
		(drill 0.3048)
		(layers "F.Cu" "B.Cu")
		(net "GND")
	)
	(via
		(at 83.82 -137.16)
		(size 0.5588)
		(drill 0.3048)
		(layers "F.Cu" "B.Cu")
		(net "GND")
	)
	(via
		(at 148.866098 -300.322742)
		(size 0.5588)
		(drill 0.3048)
		(layers "F.Cu" "B.Cu")
		(net "GND")
	)
	(via
		(at 478.28962 -1.397)
		(size 0.7112)
		(drill 0.4064)
		(layers "F.Cu" "B.Cu")
		(net "GND")
	)
	(via
		(at 256.607056 37.403024)
		(size 0.7112)
		(drill 0.4064)
		(layers "F.Cu" "B.Cu")
		(net "GND")
	)
	(via
		(at 490.053122 -129.92735)
		(size 0.7112)
		(drill 0.4064)
		(layers "F.Cu" "B.Cu")
		(net "GND")
	)
	(via
		(at 483.404926 -59.814968)
		(size 0.5588)
		(drill 0.3048)
		(layers "F.Cu" "B.Cu")
		(net "GND")
	)
	(via
		(at 262.509762 -27.315922)
		(size 0.5588)
		(drill 0.3048)
		(layers "F.Cu" "B.Cu")
		(net "GND")
	)
	(via
		(at 490.053122 -289.271202)
		(size 0.7112)
		(drill 0.4064)
		(layers "F.Cu" "B.Cu")
		(net "GND")
	)
	(via
		(at 203.420218 -157.3276)
		(size 0.5588)
		(drill 0.3048)
		(layers "F.Cu" "B.Cu")
		(net "GND")
	)
	(via
		(at 483.404926 -174.814992)
		(size 0.5588)
		(drill 0.3048)
		(layers "F.Cu" "B.Cu")
		(net "GND")
	)
	(via
		(at 294.302942 -352.315018)
		(size 0.7112)
		(drill 0.4064)
		(layers "F.Cu" "B.Cu")
		(net "GND")
	)
	(via
		(at 357.205026 -67.434968)
		(size 0.5588)
		(drill 0.3048)
		(layers "F.Cu" "B.Cu")
		(net "GND")
	)
	(via
		(at 97.531682 -347.548962)
		(size 0.7112)
		(drill 0.4064)
		(layers "F.Cu" "B.Cu")
		(net "GND")
	)
	(via
		(at 226.127056 37.403024)
		(size 0.7112)
		(drill 0.4064)
		(layers "F.Cu" "B.Cu")
		(net "GND")
	)
	(via
		(at 490.053122 -223.90735)
		(size 0.7112)
		(drill 0.4064)
		(layers "F.Cu" "B.Cu")
		(net "GND")
	)
	(via
		(at 111.024416 -294.816784)
		(size 0.5588)
		(drill 0.3048)
		(layers "F.Cu" "B.Cu")
		(net "GND")
	)
	(via
		(at 1.397 -16.888968)
		(size 0.7112)
		(drill 0.4064)
		(layers "F.Cu" "B.Cu")
		(net "GND")
	)
	(via
		(at 141.986 -188.214)
		(size 0.5588)
		(drill 0.3048)
		(layers "F.Cu" "B.Cu")
		(net "GND")
	)
	(via
		(at 467.36 -147.32)
		(size 0.5588)
		(drill 0.3048)
		(layers "F.Cu" "B.Cu")
		(net "GND")
	)
	(via
		(at 43.782996 -347.802962)
		(size 0.7112)
		(drill 0.4064)
		(layers "F.Cu" "B.Cu")
		(net "GND")
	)
	(via
		(at 176.403 -177.778918)
		(size 0.5588)
		(drill 0.3048)
		(layers "F.Cu" "B.Cu")
		(net "GND")
	)
	(via
		(at 59.854846 -184.974992)
		(size 0.5588)
		(drill 0.3048)
		(layers "F.Cu" "B.Cu")
		(net "GND")
	)
	(via
		(at 298.069 -100.838)
		(size 0.5588)
		(drill 0.3048)
		(layers "F.Cu" "B.Cu")
		(net "GND")
	)
	(via
		(at 474.4974 -268.07414)
		(size 0.5588)
		(drill 0.3048)
		(layers "F.Cu" "B.Cu")
		(net "GND")
	)
	(via
		(at 288.911284 -325.305166)
		(size 0.6604)
		(drill 0.3556)
		(layers "F.Cu" "B.Cu")
		(net "GND")
	)
	(via
		(at 419.989 -258.191)
		(size 0.5588)
		(drill 0.3048)
		(layers "F.Cu" "B.Cu")
		(net "GND")
	)
	(via
		(at 242.7478 -261.7978)
		(size 0.5588)
		(drill 0.3048)
		(layers "F.Cu" "B.Cu")
		(net "GND")
	)
	(via
		(at 370.713 -206.756)
		(size 0.5588)
		(drill 0.3048)
		(layers "F.Cu" "B.Cu")
		(net "GND")
	)
	(via
		(at 490.053122 -290.541202)
		(size 0.7112)
		(drill 0.4064)
		(layers "F.Cu" "B.Cu")
		(net "GND")
	)
	(via
		(at 166.153084 -1.397)
		(size 0.7112)
		(drill 0.4064)
		(layers "F.Cu" "B.Cu")
		(net "GND")
	)
	(via
		(at 144.852898 -292.778942)
		(size 0.5588)
		(drill 0.3048)
		(layers "F.Cu" "B.Cu")
		(net "GND")
	)
	(via
		(at 115.311682 -347.548962)
		(size 0.7112)
		(drill 0.4064)
		(layers "F.Cu" "B.Cu")
		(net "GND")
	)
	(via
		(at 216.619328 -103.2256)
		(size 0.5588)
		(drill 0.3048)
		(layers "F.Cu" "B.Cu")
		(net "GND")
	)
	(via
		(at 331.1652 -276.649942)
		(size 0.5588)
		(drill 0.3048)
		(layers "F.Cu" "B.Cu")
		(net "GND")
	)
	(via
		(at 427.694852 -43.855894)
		(size 0.5588)
		(drill 0.3048)
		(layers "F.Cu" "B.Cu")
		(net "GND")
	)
	(via
		(at 288.911284 -256.502408)
		(size 0.6604)
		(drill 0.3556)
		(layers "F.Cu" "B.Cu")
		(net "GND")
	)
	(via
		(at 335.0514 -20.0152)
		(size 0.5588)
		(drill 0.3048)
		(layers "F.Cu" "B.Cu")
		(net "GND")
	)
	(via
		(at 462.28 -111.76)
		(size 0.5588)
		(drill 0.3048)
		(layers "F.Cu" "B.Cu")
		(net "GND")
	)
	(via
		(at 90.261948 -280.42997)
		(size 0.5588)
		(drill 0.3048)
		(layers "F.Cu" "B.Cu")
		(net "GND")
	)
	(via
		(at 294.259 -220.599)
		(size 0.5588)
		(drill 0.3048)
		(layers "F.Cu" "B.Cu")
		(net "GND")
	)
	(via
		(at 490.053122 -315.941202)
		(size 0.7112)
		(drill 0.4064)
		(layers "F.Cu" "B.Cu")
		(net "GND")
	)
	(via
		(at 330.726796 -46.679866)
		(size 0.5588)
		(drill 0.3048)
		(layers "F.Cu" "B.Cu")
		(net "GND")
	)
	(via
		(at 40.64 -45.72)
		(size 0.5588)
		(drill 0.3048)
		(layers "F.Cu" "B.Cu")
		(net "GND")
	)
	(via
		(at 15.24 -86.36)
		(size 0.5588)
		(drill 0.3048)
		(layers "F.Cu" "B.Cu")
		(net "GND")
	)
	(via
		(at 427.48962 -1.397)
		(size 0.7112)
		(drill 0.4064)
		(layers "F.Cu" "B.Cu")
		(net "GND")
	)
	(via
		(at 217.533728 -102.3112)
		(size 0.5588)
		(drill 0.3048)
		(layers "F.Cu" "B.Cu")
		(net "GND")
	)
	(via
		(at 483.404926 -275.845016)
		(size 0.5588)
		(drill 0.3048)
		(layers "F.Cu" "B.Cu")
		(net "GND")
	)
	(via
		(at 224.801684 -5.177536)
		(size 0.5588)
		(drill 0.3048)
		(layers "F.Cu" "B.Cu")
		(net "GND")
	)
	(via
		(at 221.651068 30.62605)
		(size 0.7112)
		(drill 0.4064)
		(layers "F.Cu" "B.Cu")
		(net "GND")
	)
	(via
		(at 379.593348 -175.813466)
		(size 0.5588)
		(drill 0.3048)
		(layers "F.Cu" "B.Cu")
		(net "GND")
	)
	(via
		(at 221.651068 17.92605)
		(size 0.7112)
		(drill 0.4064)
		(layers "F.Cu" "B.Cu")
		(net "GND")
	)
	(via
		(at 490.053122 -43.56735)
		(size 0.7112)
		(drill 0.4064)
		(layers "F.Cu" "B.Cu")
		(net "GND")
	)
	(via
		(at 29.812996 -347.802962)
		(size 0.7112)
		(drill 0.4064)
		(layers "F.Cu" "B.Cu")
		(net "GND")
	)
	(via
		(at 416.56 -335.28)
		(size 0.5588)
		(drill 0.3048)
		(layers "F.Cu" "B.Cu")
		(net "GND")
	)
	(via
		(at 100.34905 -6.004306)
		(size 0.7112)
		(drill 0.4064)
		(layers "F.Cu" "B.Cu")
		(net "GND")
	)
	(via
		(at 486.16362 -1.397)
		(size 0.7112)
		(drill 0.4064)
		(layers "F.Cu" "B.Cu")
		(net "GND")
	)
	(via
		(at 227.550726 -236.936788)
		(size 0.5588)
		(drill 0.3048)
		(layers "F.Cu" "B.Cu")
		(net "GND")
	)
	(via
		(at 1.397 -195.958968)
		(size 0.7112)
		(drill 0.4064)
		(layers "F.Cu" "B.Cu")
		(net "GND")
	)
	(via
		(at 50.8 -10.16)
		(size 0.5588)
		(drill 0.3048)
		(layers "F.Cu" "B.Cu")
		(net "GND")
	)
	(via
		(at 278.368252 -389.99668)
		(size 0.5588)
		(drill 0.3048)
		(layers "F.Cu" "B.Cu")
		(net "GND")
	)
	(via
		(at 179.7558 -279.494742)
		(size 0.5588)
		(drill 0.3048)
		(layers "F.Cu" "B.Cu")
		(net "GND")
	)
	(via
		(at 3.81 -243.84)
		(size 0.5588)
		(drill 0.3048)
		(layers "F.Cu" "B.Cu")
		(net "GND")
	)
	(via
		(at 401.193 -84.074)
		(size 0.5588)
		(drill 0.3048)
		(layers "F.Cu" "B.Cu")
		(net "GND")
	)
	(via
		(at 456.958954 -244.689884)
		(size 0.5588)
		(drill 0.3048)
		(layers "F.Cu" "B.Cu")
		(net "GND")
	)
	(via
		(at 397.764 -151.13)
		(size 0.5588)
		(drill 0.3048)
		(layers "F.Cu" "B.Cu")
		(net "GND")
	)
	(via
		(at 252.222 -39.878)
		(size 0.5588)
		(drill 0.3048)
		(layers "F.Cu" "B.Cu")
		(net "GND")
	)
	(via
		(at 283.504386 -222.41002)
		(size 0.5588)
		(drill 0.3048)
		(layers "F.Cu" "B.Cu")
		(net "GND")
	)
	(via
		(at 424.94962 -1.397)
		(size 0.7112)
		(drill 0.4064)
		(layers "F.Cu" "B.Cu")
		(net "GND")
	)
	(via
		(at 270.667734 21.610828)
		(size 0.5588)
		(drill 0.3048)
		(layers "F.Cu" "B.Cu")
		(net "GND")
	)
	(via
		(at 84.709 -55.626)
		(size 0.5588)
		(drill 0.3048)
		(layers "F.Cu" "B.Cu")
		(net "GND")
	)
	(via
		(at 490.053122 -276.571202)
		(size 0.7112)
		(drill 0.4064)
		(layers "F.Cu" "B.Cu")
		(net "GND")
	)
	(via
		(at 187.292996 -347.802962)
		(size 0.7112)
		(drill 0.4064)
		(layers "F.Cu" "B.Cu")
		(net "GND")
	)
	(via
		(at 144.145 -302.133)
		(size 0.5588)
		(drill 0.3048)
		(layers "F.Cu" "B.Cu")
		(net "GND")
	)
	(via
		(at 273.939 -34.417)
		(size 0.5588)
		(drill 0.3048)
		(layers "F.Cu" "B.Cu")
		(net "GND")
	)
	(via
		(at 308.126892 -419.803072)
		(size 0.7112)
		(drill 0.4064)
		(layers "F.Cu" "B.Cu")
		(net "GND")
	)
	(via
		(at 333.0448 -43.855894)
		(size 0.5588)
		(drill 0.3048)
		(layers "F.Cu" "B.Cu")
		(net "GND")
	)
	(via
		(at 91.315032 -1.397)
		(size 0.7112)
		(drill 0.4064)
		(layers "F.Cu" "B.Cu")
		(net "GND")
	)
	(via
		(at 1.397 -342.008968)
		(size 0.7112)
		(drill 0.4064)
		(layers "F.Cu" "B.Cu")
		(net "GND")
	)
	(via
		(at 424.469052 -191.113918)
		(size 0.5588)
		(drill 0.3048)
		(layers "F.Cu" "B.Cu")
		(net "GND")
	)
	(via
		(at 214.874094 -15.687548)
		(size 0.5588)
		(drill 0.3048)
		(layers "F.Cu" "B.Cu")
		(net "GND")
	)
	(via
		(at 1.397 -206.118968)
		(size 0.7112)
		(drill 0.4064)
		(layers "F.Cu" "B.Cu")
		(net "GND")
	)
	(via
		(at 81.752948 -59.603894)
		(size 0.5588)
		(drill 0.3048)
		(layers "F.Cu" "B.Cu")
		(net "GND")
	)
	(via
		(at 124.732796 -194.78498)
		(size 0.5588)
		(drill 0.3048)
		(layers "F.Cu" "B.Cu")
		(net "GND")
	)
	(via
		(at 1.397 -173.098968)
		(size 0.7112)
		(drill 0.4064)
		(layers "F.Cu" "B.Cu")
		(net "GND")
	)
	(via
		(at 20.32 -81.28)
		(size 0.5588)
		(drill 0.3048)
		(layers "F.Cu" "B.Cu")
		(net "GND")
	)
	(via
		(at 1.397 -305.178968)
		(size 0.7112)
		(drill 0.4064)
		(layers "F.Cu" "B.Cu")
		(net "GND")
	)
	(via
		(at 333.954882 -347.802962)
		(size 0.7112)
		(drill 0.4064)
		(layers "F.Cu" "B.Cu")
		(net "GND")
	)
	(via
		(at 472.9988 -174.4218)
		(size 0.5588)
		(drill 0.3048)
		(layers "F.Cu" "B.Cu")
		(net "GND")
	)
	(via
		(at 364.109 -219.583)
		(size 0.5588)
		(drill 0.3048)
		(layers "F.Cu" "B.Cu")
		(net "GND")
	)
	(via
		(at 301.752 -191.262)
		(size 0.5588)
		(drill 0.3048)
		(layers "F.Cu" "B.Cu")
		(net "GND")
	)
	(via
		(at 62.832996 -347.802962)
		(size 0.7112)
		(drill 0.4064)
		(layers "F.Cu" "B.Cu")
		(net "GND")
	)
	(via
		(at 331.821028 -1.397)
		(size 0.7112)
		(drill 0.4064)
		(layers "F.Cu" "B.Cu")
		(net "GND")
	)
	(via
		(at 394.56995 -191.113918)
		(size 0.5588)
		(drill 0.3048)
		(layers "F.Cu" "B.Cu")
		(net "GND")
	)
	(via
		(at 172.339 -197.231)
		(size 0.5588)
		(drill 0.3048)
		(layers "F.Cu" "B.Cu")
		(net "GND")
	)
	(via
		(at 1.397 -226.438968)
		(size 0.7112)
		(drill 0.4064)
		(layers "F.Cu" "B.Cu")
		(net "GND")
	)
	(via
		(at 16.251682 -347.548962)
		(size 0.7112)
		(drill 0.4064)
		(layers "F.Cu" "B.Cu")
		(net "GND")
	)
	(via
		(at 189.013084 -1.397)
		(size 0.7112)
		(drill 0.4064)
		(layers "F.Cu" "B.Cu")
		(net "GND")
	)
	(via
		(at 257.173476 -262.59536)
		(size 0.5588)
		(drill 0.3048)
		(layers "F.Cu" "B.Cu")
		(net "GND")
	)
	(via
		(at 100.60305 -12.762992)
		(size 0.7112)
		(drill 0.4064)
		(layers "F.Cu" "B.Cu")
		(net "GND")
	)
	(via
		(at 1.397 -29.588968)
		(size 0.7112)
		(drill 0.4064)
		(layers "F.Cu" "B.Cu")
		(net "GND")
	)
	(via
		(at 158.082996 -347.802962)
		(size 0.7112)
		(drill 0.4064)
		(layers "F.Cu" "B.Cu")
		(net "GND")
	)
	(via
		(at 346.349066 -8.844534)
		(size 0.7112)
		(drill 0.4064)
		(layers "F.Cu" "B.Cu")
		(net "GND")
	)
	(via
		(at 178.943 -170.688)
		(size 0.5588)
		(drill 0.3048)
		(layers "F.Cu" "B.Cu")
		(net "GND")
	)
	(via
		(at 357.205026 -182.434992)
		(size 0.5588)
		(drill 0.3048)
		(layers "F.Cu" "B.Cu")
		(net "GND")
	)
	(via
		(at 375.864882 -347.802962)
		(size 0.7112)
		(drill 0.4064)
		(layers "F.Cu" "B.Cu")
		(net "GND")
	)
	(via
		(at 378.079 -278.384)
		(size 0.5588)
		(drill 0.3048)
		(layers "F.Cu" "B.Cu")
		(net "GND")
	)
	(via
		(at 70.995032 -1.397)
		(size 0.7112)
		(drill 0.4064)
		(layers "F.Cu" "B.Cu")
		(net "GND")
	)
	(via
		(at 308.602888 -413.421068)
		(size 0.7112)
		(drill 0.4064)
		(layers "F.Cu" "B.Cu")
		(net "GND")
	)
	(via
		(at 161.134552 -130.037078)
		(size 0.5588)
		(drill 0.3048)
		(layers "F.Cu" "B.Cu")
		(net "GND")
	)
	(via
		(at 154.504898 -160.844992)
		(size 0.5588)
		(drill 0.3048)
		(layers "F.Cu" "B.Cu")
		(net "GND")
	)
	(via
		(at 176.784 -277.615142)
		(size 0.5588)
		(drill 0.3048)
		(layers "F.Cu" "B.Cu")
		(net "GND")
	)
	(via
		(at 118.872 -265.938)
		(size 0.5588)
		(drill 0.3048)
		(layers "F.Cu" "B.Cu")
		(net "GND")
	)
	(via
		(at 151.650954 -5.765546)
		(size 0.7112)
		(drill 0.4064)
		(layers "F.Cu" "B.Cu")
		(net "GND")
	)
	(via
		(at 483.404926 -182.434992)
		(size 0.5588)
		(drill 0.3048)
		(layers "F.Cu" "B.Cu")
		(net "GND")
	)
	(via
		(at 1.397 -298.828968)
		(size 0.7112)
		(drill 0.4064)
		(layers "F.Cu" "B.Cu")
		(net "GND")
	)
	(via
		(at 1.397 -261.998968)
		(size 0.7112)
		(drill 0.4064)
		(layers "F.Cu" "B.Cu")
		(net "GND")
	)
	(via
		(at 217.551 -94.742)
		(size 0.5588)
		(drill 0.3048)
		(layers "F.Cu" "B.Cu")
		(net "GND")
	)
	(via
		(at 447.80962 -1.397)
		(size 0.7112)
		(drill 0.4064)
		(layers "F.Cu" "B.Cu")
		(net "GND")
	)
	(via
		(at 37.150802 -144.45615)
		(size 0.5588)
		(drill 0.3048)
		(layers "F.Cu" "B.Cu")
		(net "GND")
	)
	(via
		(at 324.718934 -52.317396)
		(size 0.5588)
		(drill 0.3048)
		(layers "F.Cu" "B.Cu")
		(net "GND")
	)
	(via
		(at 263.832848 8.842248)
		(size 0.5588)
		(drill 0.3048)
		(layers "F.Cu" "B.Cu")
		(net "GND")
	)
	(via
		(at 248.987056 37.403024)
		(size 0.7112)
		(drill 0.4064)
		(layers "F.Cu" "B.Cu")
		(net "GND")
	)
	(via
		(at 457.2 -30.48)
		(size 0.5588)
		(drill 0.3048)
		(layers "F.Cu" "B.Cu")
		(net "GND")
	)
	(via
		(at 490.053122 -110.87735)
		(size 0.7112)
		(drill 0.4064)
		(layers "F.Cu" "B.Cu")
		(net "GND")
	)
	(via
		(at 330.21651 -306.326032)
		(size 0.5588)
		(drill 0.3048)
		(layers "F.Cu" "B.Cu")
		(net "GND")
	)
	(via
		(at 490.053122 -169.29735)
		(size 0.7112)
		(drill 0.4064)
		(layers "F.Cu" "B.Cu")
		(net "GND")
	)
	(via
		(at 401.32 -5.08)
		(size 0.5588)
		(drill 0.3048)
		(layers "F.Cu" "B.Cu")
		(net "GND")
	)
	(via
		(at 91.404948 -272.035016)
		(size 0.5588)
		(drill 0.3048)
		(layers "F.Cu" "B.Cu")
		(net "GND")
	)
	(via
		(at 54.991 -49.468024)
		(size 0.5588)
		(drill 0.3048)
		(layers "F.Cu" "B.Cu")
		(net "GND")
	)
	(via
		(at 463.796634 -256.543048)
		(size 0.5588)
		(drill 0.3048)
		(layers "F.Cu" "B.Cu")
		(net "GND")
	)
	(via
		(at 490.053122 -228.98735)
		(size 0.7112)
		(drill 0.4064)
		(layers "F.Cu" "B.Cu")
		(net "GND")
	)
	(via
		(at 332.74 -151.638)
		(size 0.5588)
		(drill 0.3048)
		(layers "F.Cu" "B.Cu")
		(net "GND")
	)
	(via
		(at 45.72 -20.32)
		(size 0.5588)
		(drill 0.3048)
		(layers "F.Cu" "B.Cu")
		(net "GND")
	)
	(via
		(at 217.193368 -390.098534)
		(size 0.5588)
		(drill 0.3048)
		(layers "F.Cu" "B.Cu")
		(net "GND")
	)
	(via
		(at 477.52 -81.28)
		(size 0.5588)
		(drill 0.3048)
		(layers "F.Cu" "B.Cu")
		(net "GND")
	)
	(via
		(at 1.397 -100.708968)
		(size 0.7112)
		(drill 0.4064)
		(layers "F.Cu" "B.Cu")
		(net "GND")
	)
	(via
		(at 236.855 -379.2728)
		(size 0.5588)
		(drill 0.3048)
		(layers "F.Cu" "B.Cu")
		(net "GND")
	)
	(via
		(at 490.053122 -199.77735)
		(size 0.7112)
		(drill 0.4064)
		(layers "F.Cu" "B.Cu")
		(net "GND")
	)
	(via
		(at 104.14 -175.895)
		(size 0.5588)
		(drill 0.3048)
		(layers "F.Cu" "B.Cu")
		(net "GND")
	)
	(via
		(at 188.562996 -347.802962)
		(size 0.7112)
		(drill 0.4064)
		(layers "F.Cu" "B.Cu")
		(net "GND")
	)
	(via
		(at 482.6 -320.04)
		(size 0.5588)
		(drill 0.3048)
		(layers "F.Cu" "B.Cu")
		(net "GND")
	)
	(via
		(at 355.6 -103.124)
		(size 0.5588)
		(drill 0.3048)
		(layers "F.Cu" "B.Cu")
		(net "GND")
	)
	(via
		(at 50.202846 -62.778894)
		(size 0.5588)
		(drill 0.3048)
		(layers "F.Cu" "B.Cu")
		(net "GND")
	)
	(via
		(at 91.404948 -289.815016)
		(size 0.5588)
		(drill 0.3048)
		(layers "F.Cu" "B.Cu")
		(net "GND")
	)
	(via
		(at 339.441028 -1.397)
		(size 0.7112)
		(drill 0.4064)
		(layers "F.Cu" "B.Cu")
		(net "GND")
	)
	(via
		(at 490.053122 -260.061202)
		(size 0.7112)
		(drill 0.4064)
		(layers "F.Cu" "B.Cu")
		(net "GND")
	)
	(via
		(at 467.47303 -257.96748)
		(size 0.5588)
		(drill 0.3048)
		(layers "F.Cu" "B.Cu")
		(net "GND")
	)
	(via
		(at 490.053122 -248.631202)
		(size 0.7112)
		(drill 0.4064)
		(layers "F.Cu" "B.Cu")
		(net "GND")
	)
	(via
		(at 363.728 -211.074)
		(size 0.5588)
		(drill 0.3048)
		(layers "F.Cu" "B.Cu")
		(net "GND")
	)
	(via
		(at 405.384 -251.46)
		(size 0.5588)
		(drill 0.3048)
		(layers "F.Cu" "B.Cu")
		(net "GND")
	)
	(via
		(at 330.835 -182.604918)
		(size 0.5588)
		(drill 0.3048)
		(layers "F.Cu" "B.Cu")
		(net "GND")
	)
	(via
		(at 441.96 -137.16)
		(size 0.5588)
		(drill 0.3048)
		(layers "F.Cu" "B.Cu")
		(net "GND")
	)
	(via
		(at 490.053122 -105.79735)
		(size 0.7112)
		(drill 0.4064)
		(layers "F.Cu" "B.Cu")
		(net "GND")
	)
	(via
		(at 102.210362 -301.831248)
		(size 0.5588)
		(drill 0.3048)
		(layers "F.Cu" "B.Cu")
		(net "GND")
	)
	(via
		(at 490.053122 -275.301202)
		(size 0.7112)
		(drill 0.4064)
		(layers "F.Cu" "B.Cu")
		(net "GND")
	)
	(via
		(at 201.422 -216.154)
		(size 0.5588)
		(drill 0.3048)
		(layers "F.Cu" "B.Cu")
		(net "GND")
	)
	(via
		(at 93.182948 -266.035028)
		(size 0.5588)
		(drill 0.3048)
		(layers "F.Cu" "B.Cu")
		(net "GND")
	)
	(via
		(at 388.754874 -279.655016)
		(size 0.5588)
		(drill 0.3048)
		(layers "F.Cu" "B.Cu")
		(net "GND")
	)
	(via
		(at 321.254882 -347.802962)
		(size 0.7112)
		(drill 0.4064)
		(layers "F.Cu" "B.Cu")
		(net "GND")
	)
	(via
		(at 252.222 -27.432)
		(size 0.5588)
		(drill 0.3048)
		(layers "F.Cu" "B.Cu")
		(net "GND")
	)
	(via
		(at 298.602908 29.868876)
		(size 0.7112)
		(drill 0.4064)
		(layers "F.Cu" "B.Cu")
		(net "GND")
	)
	(via
		(at 25.4 -111.76)
		(size 0.5588)
		(drill 0.3048)
		(layers "F.Cu" "B.Cu")
		(net "GND")
	)
	(via
		(at 338.365592 -131.399534)
		(size 0.5588)
		(drill 0.3048)
		(layers "F.Cu" "B.Cu")
		(net "GND")
	)
	(via
		(at 113.683796 -47.615094)
		(size 0.5588)
		(drill 0.3048)
		(layers "F.Cu" "B.Cu")
		(net "GND")
	)
	(via
		(at 485.787954 -212.456776)
		(size 0.5588)
		(drill 0.3048)
		(layers "F.Cu" "B.Cu")
		(net "GND")
	)
	(via
		(at 447.04 -335.28)
		(size 0.5588)
		(drill 0.3048)
		(layers "F.Cu" "B.Cu")
		(net "GND")
	)
	(via
		(at 40.64 -10.16)
		(size 0.5588)
		(drill 0.3048)
		(layers "F.Cu" "B.Cu")
		(net "GND")
	)
	(via
		(at 6.35 -238.76)
		(size 0.5588)
		(drill 0.3048)
		(layers "F.Cu" "B.Cu")
		(net "GND")
	)
	(via
		(at 469.938354 -212.120226)
		(size 0.5588)
		(drill 0.3048)
		(layers "F.Cu" "B.Cu")
		(net "GND")
	)
	(via
		(at 258.318 -277.8633)
		(size 0.5588)
		(drill 0.3048)
		(layers "F.Cu" "B.Cu")
		(net "GND")
	)
	(via
		(at 139.516866 -130.386074)
		(size 0.5588)
		(drill 0.3048)
		(layers "F.Cu" "B.Cu")
		(net "GND")
	)
	(via
		(at 133.697218 -300.510194)
		(size 0.5588)
		(drill 0.3048)
		(layers "F.Cu" "B.Cu")
		(net "GND")
	)
	(via
		(at 101.341682 -347.548962)
		(size 0.7112)
		(drill 0.4064)
		(layers "F.Cu" "B.Cu")
		(net "GND")
	)
	(via
		(at 234.943396 -236.992414)
		(size 0.5588)
		(drill 0.3048)
		(layers "F.Cu" "B.Cu")
		(net "GND")
	)
	(via
		(at 45.72 -30.48)
		(size 0.5588)
		(drill 0.3048)
		(layers "F.Cu" "B.Cu")
		(net "GND")
	)
	(via
		(at 372.054882 -347.802962)
		(size 0.7112)
		(drill 0.4064)
		(layers "F.Cu" "B.Cu")
		(net "GND")
	)
	(via
		(at 490.053122 -284.191202)
		(size 0.7112)
		(drill 0.4064)
		(layers "F.Cu" "B.Cu")
		(net "GND")
	)
	(via
		(at 490.053122 -201.04735)
		(size 0.7112)
		(drill 0.4064)
		(layers "F.Cu" "B.Cu")
		(net "GND")
	)
	(via
		(at 1.397 -74.038968)
		(size 0.7112)
		(drill 0.4064)
		(layers "F.Cu" "B.Cu")
		(net "GND")
	)
	(via
		(at 147.922996 -347.802962)
		(size 0.7112)
		(drill 0.4064)
		(layers "F.Cu" "B.Cu")
		(net "GND")
	)
	(via
		(at 394.335 -261.112)
		(size 0.5588)
		(drill 0.3048)
		(layers "F.Cu" "B.Cu")
		(net "GND")
	)
	(via
		(at 235.331 -380.9238)
		(size 0.5588)
		(drill 0.3048)
		(layers "F.Cu" "B.Cu")
		(net "GND")
	)
	(via
		(at 312.364882 -347.802962)
		(size 0.7112)
		(drill 0.4064)
		(layers "F.Cu" "B.Cu")
		(net "GND")
	)
	(via
		(at 116.84 -330.2)
		(size 0.5588)
		(drill 0.3048)
		(layers "F.Cu" "B.Cu")
		(net "GND")
	)
	(via
		(at 421.64 -127)
		(size 0.5588)
		(drill 0.3048)
		(layers "F.Cu" "B.Cu")
		(net "GND")
	)
	(via
		(at 184.05983 -35.291014)
		(size 0.5588)
		(drill 0.3048)
		(layers "F.Cu" "B.Cu")
		(net "GND")
	)
	(via
		(at 176.564798 -48.03902)
		(size 0.5588)
		(drill 0.3048)
		(layers "F.Cu" "B.Cu")
		(net "GND")
	)
	(via
		(at 1.397 -263.268968)
		(size 0.7112)
		(drill 0.4064)
		(layers "F.Cu" "B.Cu")
		(net "GND")
	)
	(via
		(at 128.713484 -130.132074)
		(size 0.5588)
		(drill 0.3048)
		(layers "F.Cu" "B.Cu")
		(net "GND")
	)
	(via
		(at 419.1 -248.92)
		(size 0.5588)
		(drill 0.3048)
		(layers "F.Cu" "B.Cu")
		(net "GND")
	)
	(via
		(at 30.082998 -79.784956)
		(size 0.5588)
		(drill 0.3048)
		(layers "F.Cu" "B.Cu")
		(net "GND")
	)
	(via
		(at 15.24 -25.4)
		(size 0.5588)
		(drill 0.3048)
		(layers "F.Cu" "B.Cu")
		(net "GND")
	)
	(via
		(at 427.694852 -158.855918)
		(size 0.5588)
		(drill 0.3048)
		(layers "F.Cu" "B.Cu")
		(net "GND")
	)
	(via
		(at 221.651068 6.49605)
		(size 0.7112)
		(drill 0.4064)
		(layers "F.Cu" "B.Cu")
		(net "GND")
	)
	(via
		(at 490.053122 -291.811202)
		(size 0.7112)
		(drill 0.4064)
		(layers "F.Cu" "B.Cu")
		(net "GND")
	)
	(via
		(at 490.053122 -271.491202)
		(size 0.7112)
		(drill 0.4064)
		(layers "F.Cu" "B.Cu")
		(net "GND")
	)
	(via
		(at 472.44 -25.4)
		(size 0.5588)
		(drill 0.3048)
		(layers "F.Cu" "B.Cu")
		(net "GND")
	)
	(via
		(at 154.504898 -157.034992)
		(size 0.5588)
		(drill 0.3048)
		(layers "F.Cu" "B.Cu")
		(net "GND")
	)
	(via
		(at 183.933084 -1.397)
		(size 0.7112)
		(drill 0.4064)
		(layers "F.Cu" "B.Cu")
		(net "GND")
	)
	(via
		(at 482.261926 -165.429946)
		(size 0.5588)
		(drill 0.3048)
		(layers "F.Cu" "B.Cu")
		(net "GND")
	)
	(via
		(at 362.715302 -47.232824)
		(size 0.5588)
		(drill 0.3048)
		(layers "F.Cu" "B.Cu")
		(net "GND")
	)
	(via
		(at 490.053122 -313.401202)
		(size 0.7112)
		(drill 0.4064)
		(layers "F.Cu" "B.Cu")
		(net "GND")
	)
	(via
		(at 60.96 -106.68)
		(size 0.5588)
		(drill 0.3048)
		(layers "F.Cu" "B.Cu")
		(net "GND")
	)
	(via
		(at 449.834 -239.903)
		(size 0.5588)
		(drill 0.3048)
		(layers "F.Cu" "B.Cu")
		(net "GND")
	)
	(via
		(at 490.053122 -131.19735)
		(size 0.7112)
		(drill 0.4064)
		(layers "F.Cu" "B.Cu")
		(net "GND")
	)
	(via
		(at 421.64 -132.08)
		(size 0.5588)
		(drill 0.3048)
		(layers "F.Cu" "B.Cu")
		(net "GND")
	)
	(via
		(at 277.646892 -419.803072)
		(size 0.7112)
		(drill 0.4064)
		(layers "F.Cu" "B.Cu")
		(net "GND")
	)
	(via
		(at 70.618096 -180.440838)
		(size 0.5588)
		(drill 0.3048)
		(layers "F.Cu" "B.Cu")
		(net "GND")
	)
	(via
		(at 244.5766 -229.87)
		(size 0.5588)
		(drill 0.3048)
		(layers "F.Cu" "B.Cu")
		(net "GND")
	)
	(via
		(at 81.788 -251.079)
		(size 0.5588)
		(drill 0.3048)
		(layers "F.Cu" "B.Cu")
		(net "GND")
	)
	(via
		(at 30.48 -238.76)
		(size 0.5588)
		(drill 0.3048)
		(layers "F.Cu" "B.Cu")
		(net "GND")
	)
	(via
		(at 490.053122 -159.13735)
		(size 0.7112)
		(drill 0.4064)
		(layers "F.Cu" "B.Cu")
		(net "GND")
	)
	(via
		(at 51.689 -285.623)
		(size 0.5588)
		(drill 0.3048)
		(layers "F.Cu" "B.Cu")
		(net "GND")
	)
	(via
		(at 488.894882 -347.802962)
		(size 0.7112)
		(drill 0.4064)
		(layers "F.Cu" "B.Cu")
		(net "GND")
	)
	(via
		(at 22.005798 -279.494742)
		(size 0.5588)
		(drill 0.3048)
		(layers "F.Cu" "B.Cu")
		(net "GND")
	)
	(via
		(at 373.324882 -347.802962)
		(size 0.7112)
		(drill 0.4064)
		(layers "F.Cu" "B.Cu")
		(net "GND")
	)
	(via
		(at 393.93495 -297.604942)
		(size 0.5588)
		(drill 0.3048)
		(layers "F.Cu" "B.Cu")
		(net "GND")
	)
	(via
		(at 1.397 -104.518968)
		(size 0.7112)
		(drill 0.4064)
		(layers "F.Cu" "B.Cu")
		(net "GND")
	)
	(via
		(at 4.821682 -347.548962)
		(size 0.7112)
		(drill 0.4064)
		(layers "F.Cu" "B.Cu")
		(net "GND")
	)
	(via
		(at 46.81093 -256.405126)
		(size 0.5588)
		(drill 0.3048)
		(layers "F.Cu" "B.Cu")
		(net "GND")
	)
	(via
		(at 47.371 -143.0528)
		(size 0.5588)
		(drill 0.3048)
		(layers "F.Cu" "B.Cu")
		(net "GND")
	)
	(via
		(at 490.053122 -133.73735)
		(size 0.7112)
		(drill 0.4064)
		(layers "F.Cu" "B.Cu")
		(net "GND")
	)
	(via
		(at 192.096898 -370.653056)
		(size 0.7112)
		(drill 0.4064)
		(layers "F.Cu" "B.Cu")
		(net "GND")
	)
	(via
		(at 490.053122 -184.53735)
		(size 0.7112)
		(drill 0.4064)
		(layers "F.Cu" "B.Cu")
		(net "GND")
	)
	(via
		(at 394.208 -148.463)
		(size 0.5588)
		(drill 0.3048)
		(layers "F.Cu" "B.Cu")
		(net "GND")
	)
	(via
		(at 46.3804 -131.148074)
		(size 0.5588)
		(drill 0.3048)
		(layers "F.Cu" "B.Cu")
		(net "GND")
	)
	(via
		(at 397.65097 -4.195318)
		(size 0.7112)
		(drill 0.4064)
		(layers "F.Cu" "B.Cu")
		(net "GND")
	)
	(via
		(at 201.397108 -400.802856)
		(size 0.7112)
		(drill 0.4064)
		(layers "F.Cu" "B.Cu")
		(net "GND")
	)
	(via
		(at 158.600394 -131.071874)
		(size 0.5588)
		(drill 0.3048)
		(layers "F.Cu" "B.Cu")
		(net "GND")
	)
	(via
		(at 48.135032 -1.397)
		(size 0.7112)
		(drill 0.4064)
		(layers "F.Cu" "B.Cu")
		(net "GND")
	)
	(via
		(at 9.525 -345.44)
		(size 0.5588)
		(drill 0.3048)
		(layers "F.Cu" "B.Cu")
		(net "GND")
	)
	(via
		(at 6.35 -251.46)
		(size 0.5588)
		(drill 0.3048)
		(layers "F.Cu" "B.Cu")
		(net "GND")
	)
	(via
		(at 490.053122 -85.47735)
		(size 0.7112)
		(drill 0.4064)
		(layers "F.Cu" "B.Cu")
		(net "GND")
	)
	(via
		(at 28.3972 -249.7328)
		(size 0.5588)
		(drill 0.3048)
		(layers "F.Cu" "B.Cu")
		(net "GND")
	)
	(via
		(at 1.397 -297.558968)
		(size 0.7112)
		(drill 0.4064)
		(layers "F.Cu" "B.Cu")
		(net "GND")
	)
	(via
		(at 178.917346 -159.206946)
		(size 0.7112)
		(drill 0.4064)
		(layers "F.Cu" "B.Cu")
		(net "GND")
	)
	(via
		(at 177.154078 -27.240738)
		(size 0.5588)
		(drill 0.3048)
		(layers "F.Cu" "B.Cu")
		(net "GND")
	)
	(via
		(at 83.82 -195.58)
		(size 0.5588)
		(drill 0.3048)
		(layers "F.Cu" "B.Cu")
		(net "GND")
	)
	(via
		(at 1.397 -162.938968)
		(size 0.7112)
		(drill 0.4064)
		(layers "F.Cu" "B.Cu")
		(net "GND")
	)
	(via
		(at 342.594184 -246.249952)
		(size 0.5588)
		(drill 0.3048)
		(layers "F.Cu" "B.Cu")
		(net "GND")
	)
	(via
		(at 1.397 -317.878968)
		(size 0.7112)
		(drill 0.4064)
		(layers "F.Cu" "B.Cu")
		(net "GND")
	)
	(via
		(at 447.04 -30.48)
		(size 0.5588)
		(drill 0.3048)
		(layers "F.Cu" "B.Cu")
		(net "GND")
	)
	(via
		(at 443.23 -279.4)
		(size 0.5588)
		(drill 0.3048)
		(layers "F.Cu" "B.Cu")
		(net "GND")
	)
	(via
		(at 305.151028 -1.397)
		(size 0.7112)
		(drill 0.4064)
		(layers "F.Cu" "B.Cu")
		(net "GND")
	)
	(via
		(at 288.911284 -336.105246)
		(size 0.6604)
		(drill 0.3556)
		(layers "F.Cu" "B.Cu")
		(net "GND")
	)
	(via
		(at 371.1194 -92.964)
		(size 0.5588)
		(drill 0.3048)
		(layers "F.Cu" "B.Cu")
		(net "GND")
	)
	(via
		(at 445.714882 -347.802962)
		(size 0.7112)
		(drill 0.4064)
		(layers "F.Cu" "B.Cu")
		(net "GND")
	)
	(via
		(at 191.486282 -236.141006)
		(size 0.5588)
		(drill 0.3048)
		(layers "F.Cu" "B.Cu")
		(net "GND")
	)
	(via
		(at 221.651068 25.54605)
		(size 0.7112)
		(drill 0.4064)
		(layers "F.Cu" "B.Cu")
		(net "GND")
	)
	(via
		(at 438.094882 -347.802962)
		(size 0.7112)
		(drill 0.4064)
		(layers "F.Cu" "B.Cu")
		(net "GND")
	)
	(via
		(at 39.098728 -300.46676)
		(size 0.5588)
		(drill 0.3048)
		(layers "F.Cu" "B.Cu")
		(net "GND")
	)
	(via
		(at 273.304 2.667)
		(size 0.5588)
		(drill 0.3048)
		(layers "F.Cu" "B.Cu")
		(net "GND")
	)
	(via
		(at 298.602908 13.358876)
		(size 0.7112)
		(drill 0.4064)
		(layers "F.Cu" "B.Cu")
		(net "GND")
	)
	(via
		(at 310.896 -26.416)
		(size 0.5588)
		(drill 0.3048)
		(layers "F.Cu" "B.Cu")
		(net "GND")
	)
	(via
		(at 490.053122 -67.69735)
		(size 0.7112)
		(drill 0.4064)
		(layers "F.Cu" "B.Cu")
		(net "GND")
	)
	(via
		(at 53.737002 -254.31115)
		(size 0.5588)
		(drill 0.3048)
		(layers "F.Cu" "B.Cu")
		(net "GND")
	)
	(via
		(at 490.053122 -52.45735)
		(size 0.7112)
		(drill 0.4064)
		(layers "F.Cu" "B.Cu")
		(net "GND")
	)
	(via
		(at 357.205026 -157.034992)
		(size 0.5588)
		(drill 0.3048)
		(layers "F.Cu" "B.Cu")
		(net "GND")
	)
	(via
		(at 1.397 -288.668968)
		(size 0.7112)
		(drill 0.4064)
		(layers "F.Cu" "B.Cu")
		(net "GND")
	)
	(via
		(at 299.664882 -347.802962)
		(size 0.7112)
		(drill 0.4064)
		(layers "F.Cu" "B.Cu")
		(net "GND")
	)
	(via
		(at 251.110496 -381.742442)
		(size 0.5588)
		(drill 0.3048)
		(layers "F.Cu" "B.Cu")
		(net "GND")
	)
	(via
		(at 325.654924 -292.355016)
		(size 0.5588)
		(drill 0.3048)
		(layers "F.Cu" "B.Cu")
		(net "GND")
	)
	(via
		(at 467.466426 -241.568478)
		(size 0.5588)
		(drill 0.3048)
		(layers "F.Cu" "B.Cu")
		(net "GND")
	)
	(via
		(at 248.412 -171.958)
		(size 0.5588)
		(drill 0.3048)
		(layers "F.Cu" "B.Cu")
		(net "GND")
	)
	(via
		(at 345.3638 -149.2504)
		(size 0.5588)
		(drill 0.3048)
		(layers "F.Cu" "B.Cu")
		(net "GND")
	)
	(via
		(at 1.397 -171.828968)
		(size 0.7112)
		(drill 0.4064)
		(layers "F.Cu" "B.Cu")
		(net "GND")
	)
	(via
		(at 401.264882 -347.802962)
		(size 0.7112)
		(drill 0.4064)
		(layers "F.Cu" "B.Cu")
		(net "GND")
	)
	(via
		(at 127 -243.84)
		(size 0.5588)
		(drill 0.3048)
		(layers "F.Cu" "B.Cu")
		(net "GND")
	)
	(via
		(at 298.602908 20.978876)
		(size 0.7112)
		(drill 0.4064)
		(layers "F.Cu" "B.Cu")
		(net "GND")
	)
	(via
		(at 96.52 -243.84)
		(size 0.5588)
		(drill 0.3048)
		(layers "F.Cu" "B.Cu")
		(net "GND")
	)
	(via
		(at 84.587334 -32.938466)
		(size 0.5588)
		(drill 0.3048)
		(layers "F.Cu" "B.Cu")
		(net "GND")
	)
	(via
		(at 1.397 -303.908968)
		(size 0.7112)
		(drill 0.4064)
		(layers "F.Cu" "B.Cu")
		(net "GND")
	)
	(via
		(at 420.304976 -160.844992)
		(size 0.5588)
		(drill 0.3048)
		(layers "F.Cu" "B.Cu")
		(net "GND")
	)
	(via
		(at 203.733908 -11.70305)
		(size 0.5588)
		(drill 0.3048)
		(layers "F.Cu" "B.Cu")
		(net "GND")
	)
	(via
		(at 317.444882 -347.802962)
		(size 0.7112)
		(drill 0.4064)
		(layers "F.Cu" "B.Cu")
		(net "GND")
	)
	(via
		(at 490.053122 -132.46735)
		(size 0.7112)
		(drill 0.4064)
		(layers "F.Cu" "B.Cu")
		(net "GND")
	)
	(via
		(at 54.990746 -161.776918)
		(size 0.5588)
		(drill 0.3048)
		(layers "F.Cu" "B.Cu")
		(net "GND")
	)
	(via
		(at 401.701 -314.96)
		(size 0.5588)
		(drill 0.3048)
		(layers "F.Cu" "B.Cu")
		(net "GND")
	)
	(via
		(at 298.602908 7.008876)
		(size 0.7112)
		(drill 0.4064)
		(layers "F.Cu" "B.Cu")
		(net "GND")
	)
	(via
		(at 490.053122 -239.14735)
		(size 0.7112)
		(drill 0.4064)
		(layers "F.Cu" "B.Cu")
		(net "GND")
	)
	(via
		(at 450.711824 -285.230062)
		(size 0.5588)
		(drill 0.3048)
		(layers "F.Cu" "B.Cu")
		(net "GND")
	)
	(via
		(at 90.261948 -52.829968)
		(size 0.5588)
		(drill 0.3048)
		(layers "F.Cu" "B.Cu")
		(net "GND")
	)
	(via
		(at 1.397 -47.368968)
		(size 0.7112)
		(drill 0.4064)
		(layers "F.Cu" "B.Cu")
		(net "GND")
	)
	(via
		(at 451.854824 -275.845016)
		(size 0.5588)
		(drill 0.3048)
		(layers "F.Cu" "B.Cu")
		(net "GND")
	)
	(via
		(at 490.053122 -194.69735)
		(size 0.7112)
		(drill 0.4064)
		(layers "F.Cu" "B.Cu")
		(net "GND")
	)
	(via
		(at 137.762996 -347.802962)
		(size 0.7112)
		(drill 0.4064)
		(layers "F.Cu" "B.Cu")
		(net "GND")
	)
	(via
		(at 182.663084 -1.397)
		(size 0.7112)
		(drill 0.4064)
		(layers "F.Cu" "B.Cu")
		(net "GND")
	)
	(via
		(at 308.602888 -415.961068)
		(size 0.7112)
		(drill 0.4064)
		(layers "F.Cu" "B.Cu")
		(net "GND")
	)
	(via
		(at 436.88 -71.12)
		(size 0.5588)
		(drill 0.3048)
		(layers "F.Cu" "B.Cu")
		(net "GND")
	)
	(via
		(at 421.64 -86.36)
		(size 0.5588)
		(drill 0.3048)
		(layers "F.Cu" "B.Cu")
		(net "GND")
	)
	(via
		(at 20.32 -86.36)
		(size 0.5588)
		(drill 0.3048)
		(layers "F.Cu" "B.Cu")
		(net "GND")
	)
	(via
		(at 25.4 -106.68)
		(size 0.5588)
		(drill 0.3048)
		(layers "F.Cu" "B.Cu")
		(net "GND")
	)
	(via
		(at 140.302996 -347.802962)
		(size 0.7112)
		(drill 0.4064)
		(layers "F.Cu" "B.Cu")
		(net "GND")
	)
	(via
		(at 24.240998 -306.240942)
		(size 0.5588)
		(drill 0.3048)
		(layers "F.Cu" "B.Cu")
		(net "GND")
	)
	(via
		(at 4.445 -320.04)
		(size 0.5588)
		(drill 0.3048)
		(layers "F.Cu" "B.Cu")
		(net "GND")
	)
	(via
		(at 490.053122 -329.911202)
		(size 0.7112)
		(drill 0.4064)
		(layers "F.Cu" "B.Cu")
		(net "GND")
	)
	(via
		(at 149.640798 -279.443942)
		(size 0.5588)
		(drill 0.3048)
		(layers "F.Cu" "B.Cu")
		(net "GND")
	)
	(via
		(at 151.396954 -12.97686)
		(size 0.7112)
		(drill 0.4064)
		(layers "F.Cu" "B.Cu")
		(net "GND")
	)
	(via
		(at 386.024882 -347.802962)
		(size 0.7112)
		(drill 0.4064)
		(layers "F.Cu" "B.Cu")
		(net "GND")
	)
	(via
		(at 1.397 -223.898968)
		(size 0.7112)
		(drill 0.4064)
		(layers "F.Cu" "B.Cu")
		(net "GND")
	)
	(via
		(at 490.053122 -24.51735)
		(size 0.7112)
		(drill 0.4064)
		(layers "F.Cu" "B.Cu")
		(net "GND")
	)
	(via
		(at 265.865102 29.35478)
		(size 0.5588)
		(drill 0.3048)
		(layers "F.Cu" "B.Cu")
		(net "GND")
	)
	(via
		(at 63.5 -335.28)
		(size 0.5588)
		(drill 0.3048)
		(layers "F.Cu" "B.Cu")
		(net "GND")
	)
	(via
		(at 431.8 -5.08)
		(size 0.5588)
		(drill 0.3048)
		(layers "F.Cu" "B.Cu")
		(net "GND")
	)
	(via
		(at 130.937 -76.454)
		(size 0.5588)
		(drill 0.3048)
		(layers "F.Cu" "B.Cu")
		(net "GND")
	)
	(via
		(at 288.911284 -321.705224)
		(size 0.6604)
		(drill 0.3556)
		(layers "F.Cu" "B.Cu")
		(net "GND")
	)
	(via
		(at 456.946 -240.157)
		(size 0.5588)
		(drill 0.3048)
		(layers "F.Cu" "B.Cu")
		(net "GND")
	)
	(via
		(at 1.397 -209.928968)
		(size 0.7112)
		(drill 0.4064)
		(layers "F.Cu" "B.Cu")
		(net "GND")
	)
	(via
		(at 23.871682 -347.548962)
		(size 0.7112)
		(drill 0.4064)
		(layers "F.Cu" "B.Cu")
		(net "GND")
	)
	(via
		(at 471.479626 -169.015918)
		(size 0.5588)
		(drill 0.3048)
		(layers "F.Cu" "B.Cu")
		(net "GND")
	)
	(via
		(at 490.053122 -266.411202)
		(size 0.7112)
		(drill 0.4064)
		(layers "F.Cu" "B.Cu")
		(net "GND")
	)
	(via
		(at 55.88 -335.28)
		(size 0.5588)
		(drill 0.3048)
		(layers "F.Cu" "B.Cu")
		(net "GND")
	)
	(via
		(at 55.88 -20.32)
		(size 0.5588)
		(drill 0.3048)
		(layers "F.Cu" "B.Cu")
		(net "GND")
	)
	(via
		(at 112.771682 -347.548962)
		(size 0.7112)
		(drill 0.4064)
		(layers "F.Cu" "B.Cu")
		(net "GND")
	)
	(via
		(at 490.053122 -68.96735)
		(size 0.7112)
		(drill 0.4064)
		(layers "F.Cu" "B.Cu")
		(net "GND")
	)
	(via
		(at 265.6332 19.287744)
		(size 0.5588)
		(drill 0.3048)
		(layers "F.Cu" "B.Cu")
		(net "GND")
	)
	(via
		(at 473.654882 -347.802962)
		(size 0.7112)
		(drill 0.4064)
		(layers "F.Cu" "B.Cu")
		(net "GND")
	)
	(via
		(at 451.854824 -157.034992)
		(size 0.5588)
		(drill 0.3048)
		(layers "F.Cu" "B.Cu")
		(net "GND")
	)
	(via
		(at 1.397 -28.318968)
		(size 0.7112)
		(drill 0.4064)
		(layers "F.Cu" "B.Cu")
		(net "GND")
	)
	(via
		(at 424.469052 -76.113894)
		(size 0.5588)
		(drill 0.3048)
		(layers "F.Cu" "B.Cu")
		(net "GND")
	)
	(via
		(at 431.8 -142.24)
		(size 0.5588)
		(drill 0.3048)
		(layers "F.Cu" "B.Cu")
		(net "GND")
	)
	(via
		(at 156.812996 -347.802962)
		(size 0.7112)
		(drill 0.4064)
		(layers "F.Cu" "B.Cu")
		(net "GND")
	)
	(via
		(at 50.583846 -277.615142)
		(size 0.5588)
		(drill 0.3048)
		(layers "F.Cu" "B.Cu")
		(net "GND")
	)
	(via
		(at 72.992996 -347.802962)
		(size 0.7112)
		(drill 0.4064)
		(layers "F.Cu" "B.Cu")
		(net "GND")
	)
	(via
		(at 223.587056 37.403024)
		(size 0.7112)
		(drill 0.4064)
		(layers "F.Cu" "B.Cu")
		(net "GND")
	)
	(via
		(at 1.397 -245.488968)
		(size 0.7112)
		(drill 0.4064)
		(layers "F.Cu" "B.Cu")
		(net "GND")
	)
	(via
		(at 161.073084 -1.397)
		(size 0.7112)
		(drill 0.4064)
		(layers "F.Cu" "B.Cu")
		(net "GND")
	)
	(via
		(at 278.522938 -395.957298)
		(size 0.5588)
		(drill 0.3048)
		(layers "F.Cu" "B.Cu")
		(net "GND")
	)
	(via
		(at 201.397108 -379.212856)
		(size 0.7112)
		(drill 0.4064)
		(layers "F.Cu" "B.Cu")
		(net "GND")
	)
	(via
		(at 217.297 -126.873)
		(size 0.5588)
		(drill 0.3048)
		(layers "F.Cu" "B.Cu")
		(net "GND")
	)
	(via
		(at 30.48 -121.92)
		(size 0.5588)
		(drill 0.3048)
		(layers "F.Cu" "B.Cu")
		(net "GND")
	)
	(via
		(at 206.375 -303.403)
		(size 0.5588)
		(drill 0.3048)
		(layers "F.Cu" "B.Cu")
		(net "GND")
	)
	(via
		(at 175.938434 -292.797738)
		(size 0.5588)
		(drill 0.3048)
		(layers "F.Cu" "B.Cu")
		(net "GND")
	)
	(via
		(at 22.606 -102.489)
		(size 0.5588)
		(drill 0.3048)
		(layers "F.Cu" "B.Cu")
		(net "GND")
	)
	(via
		(at 1.397 -133.728968)
		(size 0.7112)
		(drill 0.4064)
		(layers "F.Cu" "B.Cu")
		(net "GND")
	)
	(via
		(at 6.225032 -1.397)
		(size 0.7112)
		(drill 0.4064)
		(layers "F.Cu" "B.Cu")
		(net "GND")
	)
	(via
		(at 431.8 -35.56)
		(size 0.5588)
		(drill 0.3048)
		(layers "F.Cu" "B.Cu")
		(net "GND")
	)
	(via
		(at 220.121734 -392.228324)
		(size 0.5588)
		(drill 0.3048)
		(layers "F.Cu" "B.Cu")
		(net "GND")
	)
	(via
		(at 20.195032 -1.397)
		(size 0.7112)
		(drill 0.4064)
		(layers "F.Cu" "B.Cu")
		(net "GND")
	)
	(via
		(at 187.543694 -77.879448)
		(size 0.5588)
		(drill 0.3048)
		(layers "F.Cu" "B.Cu")
		(net "GND")
	)
	(via
		(at 154.504898 -59.814968)
		(size 0.5588)
		(drill 0.3048)
		(layers "F.Cu" "B.Cu")
		(net "GND")
	)
	(via
		(at 383.517394 -140.591794)
		(size 0.5588)
		(drill 0.3048)
		(layers "F.Cu" "B.Cu")
		(net "GND")
	)
	(via
		(at 1.397 -19.428968)
		(size 0.7112)
		(drill 0.4064)
		(layers "F.Cu" "B.Cu")
		(net "GND")
	)
	(via
		(at 411.7594 -61.102494)
		(size 0.5588)
		(drill 0.3048)
		(layers "F.Cu" "B.Cu")
		(net "GND")
	)
	(via
		(at 319.278 -330.2)
		(size 0.5588)
		(drill 0.3048)
		(layers "F.Cu" "B.Cu")
		(net "GND")
	)
	(via
		(at 55.769002 -254.31115)
		(size 0.5588)
		(drill 0.3048)
		(layers "F.Cu" "B.Cu")
		(net "GND")
	)
	(via
		(at 122.931682 -347.548962)
		(size 0.7112)
		(drill 0.4064)
		(layers "F.Cu" "B.Cu")
		(net "GND")
	)
	(via
		(at 154.504898 -164.654992)
		(size 0.5588)
		(drill 0.3048)
		(layers "F.Cu" "B.Cu")
		(net "GND")
	)
	(via
		(at 1.397 -34.668968)
		(size 0.7112)
		(drill 0.4064)
		(layers "F.Cu" "B.Cu")
		(net "GND")
	)
	(via
		(at 453.632824 -194.78498)
		(size 0.5588)
		(drill 0.3048)
		(layers "F.Cu" "B.Cu")
		(net "GND")
	)
	(via
		(at 395.96695 -165.104318)
		(size 0.5588)
		(drill 0.3048)
		(layers "F.Cu" "B.Cu")
		(net "GND")
	)
	(via
		(at 388.754874 -297.435016)
		(size 0.5588)
		(drill 0.3048)
		(layers "F.Cu" "B.Cu")
		(net "GND")
	)
	(via
		(at 1.397 -194.688968)
		(size 0.7112)
		(drill 0.4064)
		(layers "F.Cu" "B.Cu")
		(net "GND")
	)
	(via
		(at 436.37962 -1.397)
		(size 0.7112)
		(drill 0.4064)
		(layers "F.Cu" "B.Cu")
		(net "GND")
	)
	(via
		(at 412.24962 -1.397)
		(size 0.7112)
		(drill 0.4064)
		(layers "F.Cu" "B.Cu")
		(net "GND")
	)
	(via
		(at 420.304976 -177.354992)
		(size 0.5588)
		(drill 0.3048)
		(layers "F.Cu" "B.Cu")
		(net "GND")
	)
	(via
		(at 283.0576 14.138148)
		(size 0.5588)
		(drill 0.3048)
		(layers "F.Cu" "B.Cu")
		(net "GND")
	)
	(via
		(at 193.04 -10.16)
		(size 0.5588)
		(drill 0.3048)
		(layers "F.Cu" "B.Cu")
		(net "GND")
	)
	(via
		(at 69.85 -164.338)
		(size 0.5588)
		(drill 0.3048)
		(layers "F.Cu" "B.Cu")
		(net "GND")
	)
	(via
		(at 451.854824 -62.354968)
		(size 0.5588)
		(drill 0.3048)
		(layers "F.Cu" "B.Cu")
		(net "GND")
	)
	(via
		(at 378.230384 -287.389824)
		(size 0.5588)
		(drill 0.3048)
		(layers "F.Cu" "B.Cu")
		(net "GND")
	)
	(via
		(at 58.711846 -282.830016)
		(size 0.5588)
		(drill 0.3048)
		(layers "F.Cu" "B.Cu")
		(net "GND")
	)
	(via
		(at 304.258472 -185.4962)
		(size 0.5588)
		(drill 0.3048)
		(layers "F.Cu" "B.Cu")
		(net "GND")
	)
	(via
		(at 399.994882 -347.802962)
		(size 0.7112)
		(drill 0.4064)
		(layers "F.Cu" "B.Cu")
		(net "GND")
	)
	(via
		(at 482.6 -15.24)
		(size 0.5588)
		(drill 0.3048)
		(layers "F.Cu" "B.Cu")
		(net "GND")
	)
	(via
		(at 331.47 -191.113918)
		(size 0.5588)
		(drill 0.3048)
		(layers "F.Cu" "B.Cu")
		(net "GND")
	)
	(via
		(at 10.16 -254)
		(size 0.5588)
		(drill 0.3048)
		(layers "F.Cu" "B.Cu")
		(net "GND")
	)
	(via
		(at 422.082976 -79.784956)
		(size 0.5588)
		(drill 0.3048)
		(layers "F.Cu" "B.Cu")
		(net "GND")
	)
	(via
		(at 464.98891 -239.204754)
		(size 0.5588)
		(drill 0.3048)
		(layers "F.Cu" "B.Cu")
		(net "GND")
	)
	(via
		(at 490.053122 -188.34735)
		(size 0.7112)
		(drill 0.4064)
		(layers "F.Cu" "B.Cu")
		(net "GND")
	)
	(via
		(at 467.36 -137.16)
		(size 0.5588)
		(drill 0.3048)
		(layers "F.Cu" "B.Cu")
		(net "GND")
	)
	(via
		(at 165.702996 -347.802962)
		(size 0.7112)
		(drill 0.4064)
		(layers "F.Cu" "B.Cu")
		(net "GND")
	)
	(via
		(at 45.72 -228.6)
		(size 0.5588)
		(drill 0.3048)
		(layers "F.Cu" "B.Cu")
		(net "GND")
	)
	(via
		(at 1.397 -281.048968)
		(size 0.7112)
		(drill 0.4064)
		(layers "F.Cu" "B.Cu")
		(net "GND")
	)
	(via
		(at 296.696892 -419.803072)
		(size 0.7112)
		(drill 0.4064)
		(layers "F.Cu" "B.Cu")
		(net "GND")
	)
	(via
		(at 447.04 -111.76)
		(size 0.5588)
		(drill 0.3048)
		(layers "F.Cu" "B.Cu")
		(net "GND")
	)
	(via
		(at 421.64 -320.04)
		(size 0.5588)
		(drill 0.3048)
		(layers "F.Cu" "B.Cu")
		(net "GND")
	)
	(via
		(at 148.844 -265.811)
		(size 0.5588)
		(drill 0.3048)
		(layers "F.Cu" "B.Cu")
		(net "GND")
	)
	(via
		(at 385.750054 -31.624778)
		(size 0.6604)
		(drill 0.3556)
		(layers "F.Cu" "B.Cu")
		(net "GND")
	)
	(via
		(at 3.81 -238.76)
		(size 0.5588)
		(drill 0.3048)
		(layers "F.Cu" "B.Cu")
		(net "GND")
	)
	(via
		(at 91.404948 -174.814992)
		(size 0.5588)
		(drill 0.3048)
		(layers "F.Cu" "B.Cu")
		(net "GND")
	)
	(via
		(at 67.792346 -60.238894)
		(size 0.5588)
		(drill 0.3048)
		(layers "F.Cu" "B.Cu")
		(net "GND")
	)
	(via
		(at 460.50962 -1.397)
		(size 0.7112)
		(drill 0.4064)
		(layers "F.Cu" "B.Cu")
		(net "GND")
	)
	(via
		(at 436.88 -15.24)
		(size 0.5588)
		(drill 0.3048)
		(layers "F.Cu" "B.Cu")
		(net "GND")
	)
	(via
		(at 1.397 -232.788968)
		(size 0.7112)
		(drill 0.4064)
		(layers "F.Cu" "B.Cu")
		(net "GND")
	)
	(via
		(at 184.912 -282.830016)
		(size 0.5588)
		(drill 0.3048)
		(layers "F.Cu" "B.Cu")
		(net "GND")
	)
	(via
		(at 90.261948 -50.429922)
		(size 0.5588)
		(drill 0.3048)
		(layers "F.Cu" "B.Cu")
		(net "GND")
	)
	(via
		(at 62.23 -213.36)
		(size 0.5588)
		(drill 0.3048)
		(layers "F.Cu" "B.Cu")
		(net "GND")
	)
	(via
		(at 480.06 -111.76)
		(size 0.5588)
		(drill 0.3048)
		(layers "F.Cu" "B.Cu")
		(net "GND")
	)
	(via
		(at 83.82 -330.708)
		(size 0.5588)
		(drill 0.3048)
		(layers "F.Cu" "B.Cu")
		(net "GND")
	)
	(via
		(at 42.76471 -131.157472)
		(size 0.5588)
		(drill 0.3048)
		(layers "F.Cu" "B.Cu")
		(net "GND")
	)
	(via
		(at 490.053122 -251.171202)
		(size 0.7112)
		(drill 0.4064)
		(layers "F.Cu" "B.Cu")
		(net "GND")
	)
	(via
		(at 301.371 -56.007)
		(size 0.5588)
		(drill 0.3048)
		(layers "F.Cu" "B.Cu")
		(net "GND")
	)
	(via
		(at 1.397 -109.598968)
		(size 0.7112)
		(drill 0.4064)
		(layers "F.Cu" "B.Cu")
		(net "GND")
	)
	(via
		(at 221.86773 -348.034102)
		(size 0.5588)
		(drill 0.3048)
		(layers "F.Cu" "B.Cu")
		(net "GND")
	)
	(via
		(at 490.053122 -179.45735)
		(size 0.7112)
		(drill 0.4064)
		(layers "F.Cu" "B.Cu")
		(net "GND")
	)
	(via
		(at 482.261926 -280.42997)
		(size 0.5588)
		(drill 0.3048)
		(layers "F.Cu" "B.Cu")
		(net "GND")
	)
	(via
		(at 34.3408 -187.5536)
		(size 0.5588)
		(drill 0.3048)
		(layers "F.Cu" "B.Cu")
		(net "GND")
	)
	(via
		(at 298.205398 -71.461122)
		(size 0.5588)
		(drill 0.3048)
		(layers "F.Cu" "B.Cu")
		(net "GND")
	)
	(via
		(at 307.284882 -347.802962)
		(size 0.7112)
		(drill 0.4064)
		(layers "F.Cu" "B.Cu")
		(net "GND")
	)
	(via
		(at 1.397 -211.198968)
		(size 0.7112)
		(drill 0.4064)
		(layers "F.Cu" "B.Cu")
		(net "GND")
	)
	(via
		(at 28.304998 -184.974992)
		(size 0.5588)
		(drill 0.3048)
		(layers "F.Cu" "B.Cu")
		(net "GND")
	)
	(via
		(at 302.785272 -182.753)
		(size 0.5588)
		(drill 0.3048)
		(layers "F.Cu" "B.Cu")
		(net "GND")
	)
	(via
		(at 20.32 -20.32)
		(size 0.5588)
		(drill 0.3048)
		(layers "F.Cu" "B.Cu")
		(net "GND")
	)
	(via
		(at 441.96 -5.08)
		(size 0.5588)
		(drill 0.3048)
		(layers "F.Cu" "B.Cu")
		(net "GND")
	)
	(via
		(at 4.445 -330.2)
		(size 0.5588)
		(drill 0.3048)
		(layers "F.Cu" "B.Cu")
		(net "GND")
	)
	(via
		(at 453.632824 -309.785004)
		(size 0.5588)
		(drill 0.3048)
		(layers "F.Cu" "B.Cu")
		(net "GND")
	)
	(via
		(at 485.182926 -309.785004)
		(size 0.5588)
		(drill 0.3048)
		(layers "F.Cu" "B.Cu")
		(net "GND")
	)
	(via
		(at 313.892184 -131.4323)
		(size 0.5588)
		(drill 0.3048)
		(layers "F.Cu" "B.Cu")
		(net "GND")
	)
	(via
		(at 382.214882 -347.802962)
		(size 0.7112)
		(drill 0.4064)
		(layers "F.Cu" "B.Cu")
		(net "GND")
	)
	(via
		(at 55.88 -96.52)
		(size 0.5588)
		(drill 0.3048)
		(layers "F.Cu" "B.Cu")
		(net "GND")
	)
	(via
		(at 442.72962 -1.397)
		(size 0.7112)
		(drill 0.4064)
		(layers "F.Cu" "B.Cu")
		(net "GND")
	)
	(via
		(at 3.81 -248.92)
		(size 0.5588)
		(drill 0.3048)
		(layers "F.Cu" "B.Cu")
		(net "GND")
	)
	(via
		(at 1.397 -190.878968)
		(size 0.7112)
		(drill 0.4064)
		(layers "F.Cu" "B.Cu")
		(net "GND")
	)
	(via
		(at 412.467552 -175.238918)
		(size 0.5588)
		(drill 0.3048)
		(layers "F.Cu" "B.Cu")
		(net "GND")
	)
	(via
		(at 27.161998 -167.829992)
		(size 0.5588)
		(drill 0.3048)
		(layers "F.Cu" "B.Cu")
		(net "GND")
	)
	(via
		(at 161.880804 -185.981848)
		(size 0.5588)
		(drill 0.3048)
		(layers "F.Cu" "B.Cu")
		(net "GND")
	)
	(via
		(at 465.15782 -131.388866)
		(size 0.5588)
		(drill 0.3048)
		(layers "F.Cu" "B.Cu")
		(net "GND")
	)
	(via
		(at 226.314 -188.849)
		(size 0.5588)
		(drill 0.3048)
		(layers "F.Cu" "B.Cu")
		(net "GND")
	)
	(via
		(at 186.055 -299.975016)
		(size 0.5588)
		(drill 0.3048)
		(layers "F.Cu" "B.Cu")
		(net "GND")
	)
	(via
		(at 490.053122 -189.61735)
		(size 0.7112)
		(drill 0.4064)
		(layers "F.Cu" "B.Cu")
		(net "GND")
	)
	(via
		(at 17.78 -259.08)
		(size 0.5588)
		(drill 0.3048)
		(layers "F.Cu" "B.Cu")
		(net "GND")
	)
	(via
		(at 288.911284 -252.902466)
		(size 0.6604)
		(drill 0.3556)
		(layers "F.Cu" "B.Cu")
		(net "GND")
	)
	(via
		(at 3.81 -251.46)
		(size 0.5588)
		(drill 0.3048)
		(layers "F.Cu" "B.Cu")
		(net "GND")
	)
	(via
		(at 431.8 -320.04)
		(size 0.5588)
		(drill 0.3048)
		(layers "F.Cu" "B.Cu")
		(net "GND")
	)
	(via
		(at 113.302796 -62.778894)
		(size 0.5588)
		(drill 0.3048)
		(layers "F.Cu" "B.Cu")
		(net "GND")
	)
	(via
		(at 490.053122 -104.52735)
		(size 0.7112)
		(drill 0.4064)
		(layers "F.Cu" "B.Cu")
		(net "GND")
	)
	(via
		(at 349.875602 -60.2234)
		(size 0.5588)
		(drill 0.3048)
		(layers "F.Cu" "B.Cu")
		(net "GND")
	)
	(via
		(at 91.44 -238.76)
		(size 0.5588)
		(drill 0.3048)
		(layers "F.Cu" "B.Cu")
		(net "GND")
	)
	(via
		(at 167.259 -46.863)
		(size 0.5588)
		(drill 0.3048)
		(layers "F.Cu" "B.Cu")
		(net "GND")
	)
	(via
		(at 440.634882 -347.802962)
		(size 0.7112)
		(drill 0.4064)
		(layers "F.Cu" "B.Cu")
		(net "GND")
	)
	(via
		(at 475.558104 -231.662986)
		(size 0.5588)
		(drill 0.3048)
		(layers "F.Cu" "B.Cu")
		(net "GND")
	)
	(via
		(at 1.397 -321.688968)
		(size 0.7112)
		(drill 0.4064)
		(layers "F.Cu" "B.Cu")
		(net "GND")
	)
	(via
		(at 187.833 -266.035028)
		(size 0.5588)
		(drill 0.3048)
		(layers "F.Cu" "B.Cu")
		(net "GND")
	)
	(via
		(at 455.42962 -1.397)
		(size 0.7112)
		(drill 0.4064)
		(layers "F.Cu" "B.Cu")
		(net "GND")
	)
	(via
		(at 490.053122 -56.26735)
		(size 0.7112)
		(drill 0.4064)
		(layers "F.Cu" "B.Cu")
		(net "GND")
	)
	(via
		(at 201.397108 -408.422856)
		(size 0.7112)
		(drill 0.4064)
		(layers "F.Cu" "B.Cu")
		(net "GND")
	)
	(via
		(at 1.397 -89.278968)
		(size 0.7112)
		(drill 0.4064)
		(layers "F.Cu" "B.Cu")
		(net "GND")
	)
	(via
		(at 1.397 -212.468968)
		(size 0.7112)
		(drill 0.4064)
		(layers "F.Cu" "B.Cu")
		(net "GND")
	)
	(via
		(at 338.09178 -245.38686)
		(size 0.5588)
		(drill 0.3048)
		(layers "F.Cu" "B.Cu")
		(net "GND")
	)
	(via
		(at 329.566778 -49.654968)
		(size 0.5588)
		(drill 0.3048)
		(layers "F.Cu" "B.Cu")
		(net "GND")
	)
	(via
		(at 349.194882 -347.802962)
		(size 0.7112)
		(drill 0.4064)
		(layers "F.Cu" "B.Cu")
		(net "GND")
	)
	(via
		(at 490.053122 -304.511202)
		(size 0.7112)
		(drill 0.4064)
		(layers "F.Cu" "B.Cu")
		(net "GND")
	)
	(via
		(at 12.827 -138.557)
		(size 0.5588)
		(drill 0.3048)
		(layers "F.Cu" "B.Cu")
		(net "GND")
	)
	(via
		(at 357.205026 -272.035016)
		(size 0.5588)
		(drill 0.3048)
		(layers "F.Cu" "B.Cu")
		(net "GND")
	)
	(via
		(at 264.414762 -23.759922)
		(size 0.5588)
		(drill 0.3048)
		(layers "F.Cu" "B.Cu")
		(net "GND")
	)
	(via
		(at 59.854846 -42.034968)
		(size 0.5588)
		(drill 0.3048)
		(layers "F.Cu" "B.Cu")
		(net "GND")
	)
	(via
		(at 1.397 -286.128968)
		(size 0.7112)
		(drill 0.4064)
		(layers "F.Cu" "B.Cu")
		(net "GND")
	)
	(via
		(at 46.322996 -347.802962)
		(size 0.7112)
		(drill 0.4064)
		(layers "F.Cu" "B.Cu")
		(net "GND")
	)
	(via
		(at 470.336118 -161.374074)
		(size 0.5588)
		(drill 0.3048)
		(layers "F.Cu" "B.Cu")
		(net "GND")
	)
	(via
		(at 380.873 -196.596)
		(size 0.5588)
		(drill 0.3048)
		(layers "F.Cu" "B.Cu")
		(net "GND")
	)
	(via
		(at 276.2758 9.623044)
		(size 0.5588)
		(drill 0.3048)
		(layers "F.Cu" "B.Cu")
		(net "GND")
	)
	(via
		(at 5.08 -40.64)
		(size 0.5588)
		(drill 0.3048)
		(layers "F.Cu" "B.Cu")
		(net "GND")
	)
	(via
		(at 456.0189 -306.113942)
		(size 0.5588)
		(drill 0.3048)
		(layers "F.Cu" "B.Cu")
		(net "GND")
	)
	(via
		(at 1.397 -203.578968)
		(size 0.7112)
		(drill 0.4064)
		(layers "F.Cu" "B.Cu")
		(net "GND")
	)
	(via
		(at 141.572996 -347.802962)
		(size 0.7112)
		(drill 0.4064)
		(layers "F.Cu" "B.Cu")
		(net "GND")
	)
	(via
		(at 166.972996 -347.802962)
		(size 0.7112)
		(drill 0.4064)
		(layers "F.Cu" "B.Cu")
		(net "GND")
	)
	(via
		(at 61.632846 -36.03498)
		(size 0.5588)
		(drill 0.3048)
		(layers "F.Cu" "B.Cu")
		(net "GND")
	)
	(via
		(at 1.397 -168.018968)
		(size 0.7112)
		(drill 0.4064)
		(layers "F.Cu" "B.Cu")
		(net "GND")
	)
	(via
		(at 437.64962 -1.397)
		(size 0.7112)
		(drill 0.4064)
		(layers "F.Cu" "B.Cu")
		(net "GND")
	)
	(via
		(at 375.92 -335.28)
		(size 0.5588)
		(drill 0.3048)
		(layers "F.Cu" "B.Cu")
		(net "GND")
	)
	(via
		(at 98.806 -73.406)
		(size 0.5588)
		(drill 0.3048)
		(layers "F.Cu" "B.Cu")
		(net "GND")
	)
	(via
		(at 295.402 -409.448)
		(size 0.5588)
		(drill 0.3048)
		(layers "F.Cu" "B.Cu")
		(net "GND")
	)
	(via
		(at 483.404926 -297.435016)
		(size 0.5588)
		(drill 0.3048)
		(layers "F.Cu" "B.Cu")
		(net "GND")
	)
	(via
		(at 490.053122 -277.841202)
		(size 0.7112)
		(drill 0.4064)
		(layers "F.Cu" "B.Cu")
		(net "GND")
	)
	(via
		(at 463.79003 -240.144046)
		(size 0.5588)
		(drill 0.3048)
		(layers "F.Cu" "B.Cu")
		(net "GND")
	)
	(via
		(at 318.4652 -175.1584)
		(size 0.5588)
		(drill 0.3048)
		(layers "F.Cu" "B.Cu")
		(net "GND")
	)
	(via
		(at 14.981682 -347.548962)
		(size 0.7112)
		(drill 0.4064)
		(layers "F.Cu" "B.Cu")
		(net "GND")
	)
	(via
		(at 472.44 -30.48)
		(size 0.5588)
		(drill 0.3048)
		(layers "F.Cu" "B.Cu")
		(net "GND")
	)
	(via
		(at 260.35 -207.518)
		(size 0.5588)
		(drill 0.3048)
		(layers "F.Cu" "B.Cu")
		(net "GND")
	)
	(via
		(at 47.371 -146.1008)
		(size 0.5588)
		(drill 0.3048)
		(layers "F.Cu" "B.Cu")
		(net "GND")
	)
	(via
		(at 39.751 -43.307)
		(size 0.5588)
		(drill 0.3048)
		(layers "F.Cu" "B.Cu")
		(net "GND")
	)
	(via
		(at 133.497066 -136.736074)
		(size 0.5588)
		(drill 0.3048)
		(layers "F.Cu" "B.Cu")
		(net "GND")
	)
	(via
		(at 395.20495 -41.315894)
		(size 0.5588)
		(drill 0.3048)
		(layers "F.Cu" "B.Cu")
		(net "GND")
	)
	(via
		(at 459.731872 -191.158876)
		(size 0.5588)
		(drill 0.3048)
		(layers "F.Cu" "B.Cu")
		(net "GND")
	)
	(via
		(at 325.654924 -184.974992)
		(size 0.5588)
		(drill 0.3048)
		(layers "F.Cu" "B.Cu")
		(net "GND")
	)
	(via
		(at 50.8 -332.74)
		(size 0.5588)
		(drill 0.3048)
		(layers "F.Cu" "B.Cu")
		(net "GND")
	)
	(via
		(at 163.162996 -347.802962)
		(size 0.7112)
		(drill 0.4064)
		(layers "F.Cu" "B.Cu")
		(net "GND")
	)
	(via
		(at 1.397 -140.078968)
		(size 0.7112)
		(drill 0.4064)
		(layers "F.Cu" "B.Cu")
		(net "GND")
	)
	(via
		(at 10.16 -91.44)
		(size 0.5588)
		(drill 0.3048)
		(layers "F.Cu" "B.Cu")
		(net "GND")
	)
	(via
		(at 93.182948 -194.78498)
		(size 0.5588)
		(drill 0.3048)
		(layers "F.Cu" "B.Cu")
		(net "GND")
	)
	(via
		(at 490.053122 -151.51735)
		(size 0.7112)
		(drill 0.4064)
		(layers "F.Cu" "B.Cu")
		(net "GND")
	)
	(via
		(at 468.722202 -254.66675)
		(size 0.5588)
		(drill 0.3048)
		(layers "F.Cu" "B.Cu")
		(net "GND")
	)
	(via
		(at 37.432996 -347.802962)
		(size 0.7112)
		(drill 0.4064)
		(layers "F.Cu" "B.Cu")
		(net "GND")
	)
	(via
		(at 447.983356 -257.934714)
		(size 0.5588)
		(drill 0.3048)
		(layers "F.Cu" "B.Cu")
		(net "GND")
	)
	(via
		(at 1.397 -98.168968)
		(size 0.7112)
		(drill 0.4064)
		(layers "F.Cu" "B.Cu")
		(net "GND")
	)
	(via
		(at 6.35 -274.32)
		(size 0.5588)
		(drill 0.3048)
		(layers "F.Cu" "B.Cu")
		(net "GND")
	)
	(via
		(at 401.32 -198.12)
		(size 0.5588)
		(drill 0.3048)
		(layers "F.Cu" "B.Cu")
		(net "GND")
	)
	(via
		(at 54.216046 -185.322718)
		(size 0.5588)
		(drill 0.3048)
		(layers "F.Cu" "B.Cu")
		(net "GND")
	)
	(via
		(at 127.635 -307.721)
		(size 0.5588)
		(drill 0.3048)
		(layers "F.Cu" "B.Cu")
		(net "GND")
	)
	(via
		(at 490.053122 -209.93735)
		(size 0.7112)
		(drill 0.4064)
		(layers "F.Cu" "B.Cu")
		(net "GND")
	)
	(via
		(at 447.04 -137.16)
		(size 0.5588)
		(drill 0.3048)
		(layers "F.Cu" "B.Cu")
		(net "GND")
	)
	(via
		(at 477.766126 -70.322694)
		(size 0.5588)
		(drill 0.3048)
		(layers "F.Cu" "B.Cu")
		(net "GND")
	)
	(via
		(at 330.090526 -21.405088)
		(size 0.5588)
		(drill 0.3048)
		(layers "F.Cu" "B.Cu")
		(net "GND")
	)
	(via
		(at 416.56 -325.12)
		(size 0.5588)
		(drill 0.3048)
		(layers "F.Cu" "B.Cu")
		(net "GND")
	)
	(via
		(at 394.26515 -46.649894)
		(size 0.5588)
		(drill 0.3048)
		(layers "F.Cu" "B.Cu")
		(net "GND")
	)
	(via
		(at 201.397108 -374.132856)
		(size 0.7112)
		(drill 0.4064)
		(layers "F.Cu" "B.Cu")
		(net "GND")
	)
	(via
		(at 50.8 -25.4)
		(size 0.5588)
		(drill 0.3048)
		(layers "F.Cu" "B.Cu")
		(net "GND")
	)
	(via
		(at 111.029496 -54.015894)
		(size 0.5588)
		(drill 0.3048)
		(layers "F.Cu" "B.Cu")
		(net "GND")
	)
	(via
		(at 175.114204 -60.103512)
		(size 0.5588)
		(drill 0.3048)
		(layers "F.Cu" "B.Cu")
		(net "GND")
	)
	(via
		(at 396.621 -15.748)
		(size 0.7112)
		(drill 0.4064)
		(layers "F.Cu" "B.Cu")
		(net "GND")
	)
	(via
		(at 426.72 -96.52)
		(size 0.5588)
		(drill 0.3048)
		(layers "F.Cu" "B.Cu")
		(net "GND")
	)
	(via
		(at 274.955 -271.0434)
		(size 0.5588)
		(drill 0.3048)
		(layers "F.Cu" "B.Cu")
		(net "GND")
	)
	(via
		(at 396.85595 -67.223894)
		(size 0.5588)
		(drill 0.3048)
		(layers "F.Cu" "B.Cu")
		(net "GND")
	)
	(via
		(at 62.23 -238.76)
		(size 0.5588)
		(drill 0.3048)
		(layers "F.Cu" "B.Cu")
		(net "GND")
	)
	(via
		(at 436.88 -10.16)
		(size 0.5588)
		(drill 0.3048)
		(layers "F.Cu" "B.Cu")
		(net "GND")
	)
	(via
		(at 6.35 -243.84)
		(size 0.5588)
		(drill 0.3048)
		(layers "F.Cu" "B.Cu")
		(net "GND")
	)
	(via
		(at 186.055 -182.434992)
		(size 0.5588)
		(drill 0.3048)
		(layers "F.Cu" "B.Cu")
		(net "GND")
	)
	(via
		(at 454.15962 -1.397)
		(size 0.7112)
		(drill 0.4064)
		(layers "F.Cu" "B.Cu")
		(net "GND")
	)
	(via
		(at 60.96 -25.4)
		(size 0.5588)
		(drill 0.3048)
		(layers "F.Cu" "B.Cu")
		(net "GND")
	)
	(via
		(at 218.092528 -100.4824)
		(size 0.5588)
		(drill 0.3048)
		(layers "F.Cu" "B.Cu")
		(net "GND")
	)
	(via
		(at 88.775032 -1.397)
		(size 0.7112)
		(drill 0.4064)
		(layers "F.Cu" "B.Cu")
		(net "GND")
	)
	(via
		(at 214.9856 -119.2022)
		(size 0.5588)
		(drill 0.3048)
		(layers "F.Cu" "B.Cu")
		(net "GND")
	)
	(via
		(at 186.055 -157.034992)
		(size 0.5588)
		(drill 0.3048)
		(layers "F.Cu" "B.Cu")
		(net "GND")
	)
	(via
		(at 387.611874 -280.42997)
		(size 0.5588)
		(drill 0.3048)
		(layers "F.Cu" "B.Cu")
		(net "GND")
	)
	(via
		(at 279.80132 -277.14448)
		(size 0.5588)
		(drill 0.3048)
		(layers "F.Cu" "B.Cu")
		(net "GND")
	)
	(via
		(at 312.039 -3.175)
		(size 0.5588)
		(drill 0.3048)
		(layers "F.Cu" "B.Cu")
		(net "GND")
	)
	(via
		(at 178.435 -143.002)
		(size 0.5588)
		(drill 0.3048)
		(layers "F.Cu" "B.Cu")
		(net "GND")
	)
	(via
		(at 271.907 17.2466)
		(size 0.5588)
		(drill 0.3048)
		(layers "F.Cu" "B.Cu")
		(net "GND")
	)
	(via
		(at 348.996 -16.383)
		(size 0.7112)
		(drill 0.4064)
		(layers "F.Cu" "B.Cu")
		(net "GND")
	)
	(via
		(at 355.544882 -347.802962)
		(size 0.7112)
		(drill 0.4064)
		(layers "F.Cu" "B.Cu")
		(net "GND")
	)
	(via
		(at 303.954942 -375.397014)
		(size 0.7112)
		(drill 0.4064)
		(layers "F.Cu" "B.Cu")
		(net "GND")
	)
	(via
		(at 88.641682 -347.548962)
		(size 0.7112)
		(drill 0.4064)
		(layers "F.Cu" "B.Cu")
		(net "GND")
	)
	(via
		(at 490.053122 -88.01735)
		(size 0.7112)
		(drill 0.4064)
		(layers "F.Cu" "B.Cu")
		(net "GND")
	)
	(via
		(at 420.304976 -45.844968)
		(size 0.5588)
		(drill 0.3048)
		(layers "F.Cu" "B.Cu")
		(net "GND")
	)
	(via
		(at 192.0875 -289.6235)
		(size 0.5588)
		(drill 0.3048)
		(layers "F.Cu" "B.Cu")
		(net "GND")
	)
	(via
		(at 490.053122 -296.891202)
		(size 0.7112)
		(drill 0.4064)
		(layers "F.Cu" "B.Cu")
		(net "GND")
	)
	(via
		(at 490.053122 -118.49735)
		(size 0.7112)
		(drill 0.4064)
		(layers "F.Cu" "B.Cu")
		(net "GND")
	)
	(via
		(at 173.773084 -1.397)
		(size 0.7112)
		(drill 0.4064)
		(layers "F.Cu" "B.Cu")
		(net "GND")
	)
	(via
		(at 357.205026 -177.354992)
		(size 0.5588)
		(drill 0.3048)
		(layers "F.Cu" "B.Cu")
		(net "GND")
	)
	(via
		(at 413.461708 -284.213046)
		(size 0.5588)
		(drill 0.3048)
		(layers "F.Cu" "B.Cu")
		(net "GND")
	)
	(via
		(at 333.0448 -273.855942)
		(size 0.5588)
		(drill 0.3048)
		(layers "F.Cu" "B.Cu")
		(net "GND")
	)
	(via
		(at 490.053122 -175.64735)
		(size 0.7112)
		(drill 0.4064)
		(layers "F.Cu" "B.Cu")
		(net "GND")
	)
	(via
		(at 51.945032 -1.397)
		(size 0.7112)
		(drill 0.4064)
		(layers "F.Cu" "B.Cu")
		(net "GND")
	)
	(via
		(at 294.302942 -356.125018)
		(size 0.7112)
		(drill 0.4064)
		(layers "F.Cu" "B.Cu")
		(net "GND")
	)
	(via
		(at 86.540848 -164.469318)
		(size 0.5588)
		(drill 0.3048)
		(layers "F.Cu" "B.Cu")
		(net "GND")
	)
	(via
		(at 356.814882 -347.802962)
		(size 0.7112)
		(drill 0.4064)
		(layers "F.Cu" "B.Cu")
		(net "GND")
	)
	(via
		(at 446.4304 -252.7808)
		(size 0.5588)
		(drill 0.3048)
		(layers "F.Cu" "B.Cu")
		(net "GND")
	)
	(via
		(at 490.053122 -225.17735)
		(size 0.7112)
		(drill 0.4064)
		(layers "F.Cu" "B.Cu")
		(net "GND")
	)
	(via
		(at 426.72 -142.24)
		(size 0.5588)
		(drill 0.3048)
		(layers "F.Cu" "B.Cu")
		(net "GND")
	)
	(via
		(at 221.651068 23.00605)
		(size 0.7112)
		(drill 0.4064)
		(layers "F.Cu" "B.Cu")
		(net "GND")
	)
	(via
		(at 490.053122 -53.72735)
		(size 0.7112)
		(drill 0.4064)
		(layers "F.Cu" "B.Cu")
		(net "GND")
	)
	(via
		(at 490.053122 -33.40735)
		(size 0.7112)
		(drill 0.4064)
		(layers "F.Cu" "B.Cu")
		(net "GND")
	)
	(via
		(at 357.205026 -275.845016)
		(size 0.5588)
		(drill 0.3048)
		(layers "F.Cu" "B.Cu")
		(net "GND")
	)
	(via
		(at 59.565032 -1.397)
		(size 0.7112)
		(drill 0.4064)
		(layers "F.Cu" "B.Cu")
		(net "GND")
	)
	(via
		(at 50.409602 -240.16335)
		(size 0.5588)
		(drill 0.3048)
		(layers "F.Cu" "B.Cu")
		(net "GND")
	)
	(via
		(at 118.197884 -285.230062)
		(size 0.5588)
		(drill 0.3048)
		(layers "F.Cu" "B.Cu")
		(net "GND")
	)
	(via
		(at 13.711682 -347.548962)
		(size 0.7112)
		(drill 0.4064)
		(layers "F.Cu" "B.Cu")
		(net "GND")
	)
	(via
		(at 194.603624 -371.349016)
		(size 0.7112)
		(drill 0.4064)
		(layers "F.Cu" "B.Cu")
		(net "GND")
	)
	(via
		(at 19.177 -192.405)
		(size 0.5588)
		(drill 0.3048)
		(layers "F.Cu" "B.Cu")
		(net "GND")
	)
	(via
		(at 164.211 -228.219)
		(size 0.5588)
		(drill 0.3048)
		(layers "F.Cu" "B.Cu")
		(net "GND")
	)
	(via
		(at 1.397 -110.868968)
		(size 0.7112)
		(drill 0.4064)
		(layers "F.Cu" "B.Cu")
		(net "GND")
	)
	(via
		(at 436.88 -335.28)
		(size 0.5588)
		(drill 0.3048)
		(layers "F.Cu" "B.Cu")
		(net "GND")
	)
	(via
		(at 490.053122 -286.731202)
		(size 0.7112)
		(drill 0.4064)
		(layers "F.Cu" "B.Cu")
		(net "GND")
	)
	(via
		(at 17.655032 -1.397)
		(size 0.7112)
		(drill 0.4064)
		(layers "F.Cu" "B.Cu")
		(net "GND")
	)
	(via
		(at 361.061 -168.656)
		(size 0.5588)
		(drill 0.3048)
		(layers "F.Cu" "B.Cu")
		(net "GND")
	)
	(via
		(at 28.304998 -69.974968)
		(size 0.5588)
		(drill 0.3048)
		(layers "F.Cu" "B.Cu")
		(net "GND")
	)
	(via
		(at 479.340926 -191.240918)
		(size 0.5588)
		(drill 0.3048)
		(layers "F.Cu" "B.Cu")
		(net "GND")
	)
	(via
		(at 36.242498 -290.238942)
		(size 0.5588)
		(drill 0.3048)
		(layers "F.Cu" "B.Cu")
		(net "GND")
	)
	(via
		(at 90.261948 -165.429946)
		(size 0.5588)
		(drill 0.3048)
		(layers "F.Cu" "B.Cu")
		(net "GND")
	)
	(via
		(at 490.053122 -148.97735)
		(size 0.7112)
		(drill 0.4064)
		(layers "F.Cu" "B.Cu")
		(net "GND")
	)
	(via
		(at 1.397 -249.298968)
		(size 0.7112)
		(drill 0.4064)
		(layers "F.Cu" "B.Cu")
		(net "GND")
	)
	(via
		(at 11.204194 -131.19354)
		(size 0.5588)
		(drill 0.3048)
		(layers "F.Cu" "B.Cu")
		(net "GND")
	)
	(via
		(at 336.901028 -1.397)
		(size 0.7112)
		(drill 0.4064)
		(layers "F.Cu" "B.Cu")
		(net "GND")
	)
	(via
		(at 120.998742 -309.752492)
		(size 0.5588)
		(drill 0.3048)
		(layers "F.Cu" "B.Cu")
		(net "GND")
	)
	(via
		(at 490.053122 -178.18735)
		(size 0.7112)
		(drill 0.4064)
		(layers "F.Cu" "B.Cu")
		(net "GND")
	)
	(via
		(at 191.486282 -238.173006)
		(size 0.5588)
		(drill 0.3048)
		(layers "F.Cu" "B.Cu")
		(net "GND")
	)
	(via
		(at 424.469052 -306.113942)
		(size 0.5588)
		(drill 0.3048)
		(layers "F.Cu" "B.Cu")
		(net "GND")
	)
	(via
		(at 82.133948 -162.615118)
		(size 0.5588)
		(drill 0.3048)
		(layers "F.Cu" "B.Cu")
		(net "GND")
	)
	(via
		(at 117.061742 -273.691604)
		(size 0.5588)
		(drill 0.3048)
		(layers "F.Cu" "B.Cu")
		(net "GND")
	)
	(via
		(at 122.954796 -160.844992)
		(size 0.5588)
		(drill 0.3048)
		(layers "F.Cu" "B.Cu")
		(net "GND")
	)
	(via
		(at 6.35 -264.16)
		(size 0.5588)
		(drill 0.3048)
		(layers "F.Cu" "B.Cu")
		(net "GND")
	)
	(via
		(at 299.847 -1.016)
		(size 0.7112)
		(drill 0.4064)
		(layers "F.Cu" "B.Cu")
		(net "GND")
	)
	(via
		(at 1.397 -181.988968)
		(size 0.7112)
		(drill 0.4064)
		(layers "F.Cu" "B.Cu")
		(net "GND")
	)
	(via
		(at 415.464752 -289.854132)
		(size 0.5588)
		(drill 0.3048)
		(layers "F.Cu" "B.Cu")
		(net "GND")
	)
	(via
		(at 288.911284 -307.305202)
		(size 0.6604)
		(drill 0.3556)
		(layers "F.Cu" "B.Cu")
		(net "GND")
	)
	(via
		(at 60.96 -335.28)
		(size 0.5588)
		(drill 0.3048)
		(layers "F.Cu" "B.Cu")
		(net "GND")
	)
	(via
		(at 406.4 -10.16)
		(size 0.5588)
		(drill 0.3048)
		(layers "F.Cu" "B.Cu")
		(net "GND")
	)
	(via
		(at 27.596338 -249.156982)
		(size 0.6604)
		(drill 0.3302)
		(layers "F.Cu" "B.Cu")
		(net "GND")
	)
	(via
		(at 25.141682 -347.548962)
		(size 0.7112)
		(drill 0.4064)
		(layers "F.Cu" "B.Cu")
		(net "GND")
	)
	(via
		(at 181.1909 -279.443942)
		(size 0.5588)
		(drill 0.3048)
		(layers "F.Cu" "B.Cu")
		(net "GND")
	)
	(via
		(at 445.4144 -253.7968)
		(size 0.5588)
		(drill 0.3048)
		(layers "F.Cu" "B.Cu")
		(net "GND")
	)
	(via
		(at 426.72 -330.2)
		(size 0.5588)
		(drill 0.3048)
		(layers "F.Cu" "B.Cu")
		(net "GND")
	)
	(via
		(at 91.404948 -184.974992)
		(size 0.5588)
		(drill 0.3048)
		(layers "F.Cu" "B.Cu")
		(net "GND")
	)
	(via
		(at 348.488 -85.09)
		(size 0.5588)
		(drill 0.3048)
		(layers "F.Cu" "B.Cu")
		(net "GND")
	)
	(via
		(at 176.784 -162.996118)
		(size 0.5588)
		(drill 0.3048)
		(layers "F.Cu" "B.Cu")
		(net "GND")
	)
	(via
		(at 307.281072 -21.683472)
		(size 0.5588)
		(drill 0.3048)
		(layers "F.Cu" "B.Cu")
		(net "GND")
	)
	(via
		(at 1.397 -138.808968)
		(size 0.7112)
		(drill 0.4064)
		(layers "F.Cu" "B.Cu")
		(net "GND")
	)
	(via
		(at 260.546596 -254.390652)
		(size 0.5588)
		(drill 0.3048)
		(layers "F.Cu" "B.Cu")
		(net "GND")
	)
	(via
		(at 298.602908 28.598876)
		(size 0.7112)
		(drill 0.4064)
		(layers "F.Cu" "B.Cu")
		(net "GND")
	)
	(via
		(at 490.053122 -99.44735)
		(size 0.7112)
		(drill 0.4064)
		(layers "F.Cu" "B.Cu")
		(net "GND")
	)
	(via
		(at 1.397 -216.278968)
		(size 0.7112)
		(drill 0.4064)
		(layers "F.Cu" "B.Cu")
		(net "GND")
	)
	(via
		(at 302.684942 -375.397014)
		(size 0.7112)
		(drill 0.4064)
		(layers "F.Cu" "B.Cu")
		(net "GND")
	)
	(via
		(at 357.205026 -289.815016)
		(size 0.5588)
		(drill 0.3048)
		(layers "F.Cu" "B.Cu")
		(net "GND")
	)
	(via
		(at 47.931324 -239.097312)
		(size 0.5588)
		(drill 0.3048)
		(layers "F.Cu" "B.Cu")
		(net "GND")
	)
	(via
		(at 475.278196 -289.23742)
		(size 0.5588)
		(drill 0.3048)
		(layers "F.Cu" "B.Cu")
		(net "GND")
	)
	(via
		(at 71.374 -280.67)
		(size 0.5588)
		(drill 0.3048)
		(layers "F.Cu" "B.Cu")
		(net "GND")
	)
	(via
		(at 183.482996 -347.802962)
		(size 0.7112)
		(drill 0.4064)
		(layers "F.Cu" "B.Cu")
		(net "GND")
	)
	(via
		(at 100.34905 -9.814306)
		(size 0.7112)
		(drill 0.4064)
		(layers "F.Cu" "B.Cu")
		(net "GND")
	)
	(via
		(at 327.432924 -309.785004)
		(size 0.5588)
		(drill 0.3048)
		(layers "F.Cu" "B.Cu")
		(net "GND")
	)
	(via
		(at 46.81093 -257.802126)
		(size 0.5588)
		(drill 0.3048)
		(layers "F.Cu" "B.Cu")
		(net "GND")
	)
	(via
		(at 83.695032 -1.397)
		(size 0.7112)
		(drill 0.4064)
		(layers "F.Cu" "B.Cu")
		(net "GND")
	)
	(via
		(at 304.316892 -419.803072)
		(size 0.7112)
		(drill 0.4064)
		(layers "F.Cu" "B.Cu")
		(net "GND")
	)
	(via
		(at 218.463368 -137.77087)
		(size 0.5588)
		(drill 0.3048)
		(layers "F.Cu" "B.Cu")
		(net "GND")
	)
	(via
		(at 331.47 -76.0476)
		(size 0.5588)
		(drill 0.3048)
		(layers "F.Cu" "B.Cu")
		(net "GND")
	)
	(via
		(at 445.26962 -1.397)
		(size 0.7112)
		(drill 0.4064)
		(layers "F.Cu" "B.Cu")
		(net "GND")
	)
	(via
		(at 1.397 -335.658968)
		(size 0.7112)
		(drill 0.4064)
		(layers "F.Cu" "B.Cu")
		(net "GND")
	)
	(via
		(at 55.88 -116.84)
		(size 0.5588)
		(drill 0.3048)
		(layers "F.Cu" "B.Cu")
		(net "GND")
	)
	(via
		(at 98.935032 -1.397)
		(size 0.7112)
		(drill 0.4064)
		(layers "F.Cu" "B.Cu")
		(net "GND")
	)
	(via
		(at 490.053122 -114.68735)
		(size 0.7112)
		(drill 0.4064)
		(layers "F.Cu" "B.Cu")
		(net "GND")
	)
	(via
		(at 412.75 -203.2)
		(size 0.5588)
		(drill 0.3048)
		(layers "F.Cu" "B.Cu")
		(net "GND")
	)
	(via
		(at 490.053122 -340.071202)
		(size 0.7112)
		(drill 0.4064)
		(layers "F.Cu" "B.Cu")
		(net "GND")
	)
	(via
		(at 435.10962 -1.397)
		(size 0.7112)
		(drill 0.4064)
		(layers "F.Cu" "B.Cu")
		(net "GND")
	)
	(via
		(at 217.178128 -100.4824)
		(size 0.5588)
		(drill 0.3048)
		(layers "F.Cu" "B.Cu")
		(net "GND")
	)
	(via
		(at 362.3056 -78.0796)
		(size 0.5588)
		(drill 0.3048)
		(layers "F.Cu" "B.Cu")
		(net "GND")
	)
	(via
		(at 490.053122 -319.751202)
		(size 0.7112)
		(drill 0.4064)
		(layers "F.Cu" "B.Cu")
		(net "GND")
	)
	(via
		(at 483.404926 -160.844992)
		(size 0.5588)
		(drill 0.3048)
		(layers "F.Cu" "B.Cu")
		(net "GND")
	)
	(via
		(at 422.082976 -36.03498)
		(size 0.5588)
		(drill 0.3048)
		(layers "F.Cu" "B.Cu")
		(net "GND")
	)
	(via
		(at 10.16 -40.64)
		(size 0.5588)
		(drill 0.3048)
		(layers "F.Cu" "B.Cu")
		(net "GND")
	)
	(via
		(at 298.602908 22.248876)
		(size 0.7112)
		(drill 0.4064)
		(layers "F.Cu" "B.Cu")
		(net "GND")
	)
	(via
		(at 67.409568 -135.56615)
		(size 0.5588)
		(drill 0.3048)
		(layers "F.Cu" "B.Cu")
		(net "GND")
	)
	(via
		(at 59.854846 -292.355016)
		(size 0.5588)
		(drill 0.3048)
		(layers "F.Cu" "B.Cu")
		(net "GND")
	)
	(via
		(at 471.114882 -347.802962)
		(size 0.7112)
		(drill 0.4064)
		(layers "F.Cu" "B.Cu")
		(net "GND")
	)
	(via
		(at 12.7 -261.62)
		(size 0.5588)
		(drill 0.3048)
		(layers "F.Cu" "B.Cu")
		(net "GND")
	)
	(via
		(at 6.35 -266.7)
		(size 0.5588)
		(drill 0.3048)
		(layers "F.Cu" "B.Cu")
		(net "GND")
	)
	(via
		(at 464.764882 -347.802962)
		(size 0.7112)
		(drill 0.4064)
		(layers "F.Cu" "B.Cu")
		(net "GND")
	)
	(via
		(at 59.854846 -69.974968)
		(size 0.5588)
		(drill 0.3048)
		(layers "F.Cu" "B.Cu")
		(net "GND")
	)
	(via
		(at 1.397 -94.358968)
		(size 0.7112)
		(drill 0.4064)
		(layers "F.Cu" "B.Cu")
		(net "GND")
	)
	(via
		(at 36.195 -130.937)
		(size 0.5588)
		(drill 0.3048)
		(layers "F.Cu" "B.Cu")
		(net "GND")
	)
	(via
		(at 306.011072 -17.619472)
		(size 0.5588)
		(drill 0.3048)
		(layers "F.Cu" "B.Cu")
		(net "GND")
	)
	(via
		(at 289.433 14.859)
		(size 0.5588)
		(drill 0.3048)
		(layers "F.Cu" "B.Cu")
		(net "GND")
	)
	(via
		(at 99.342448 -175.238918)
		(size 0.5588)
		(drill 0.3048)
		(layers "F.Cu" "B.Cu")
		(net "GND")
	)
	(via
		(at 257.043936 21.098764)
		(size 0.5588)
		(drill 0.3048)
		(layers "F.Cu" "B.Cu")
		(net "GND")
	)
	(via
		(at 426.72 -137.16)
		(size 0.5588)
		(drill 0.3048)
		(layers "F.Cu" "B.Cu")
		(net "GND")
	)
	(via
		(at 396.14475 -43.855894)
		(size 0.5588)
		(drill 0.3048)
		(layers "F.Cu" "B.Cu")
		(net "GND")
	)
	(via
		(at 338.565236 -34.978848)
		(size 0.5588)
		(drill 0.3048)
		(layers "F.Cu" "B.Cu")
		(net "GND")
	)
	(via
		(at 394.97 -195.58)
		(size 0.5588)
		(drill 0.3048)
		(layers "F.Cu" "B.Cu")
		(net "GND")
	)
	(via
		(at 79.839566 -53.95468)
		(size 0.5588)
		(drill 0.3048)
		(layers "F.Cu" "B.Cu")
		(net "GND")
	)
	(via
		(at 114.549936 -31.624778)
		(size 0.6604)
		(drill 0.3556)
		(layers "F.Cu" "B.Cu")
		(net "GND")
	)
	(via
		(at 174.592996 -347.802962)
		(size 0.7112)
		(drill 0.4064)
		(layers "F.Cu" "B.Cu")
		(net "GND")
	)
	(via
		(at 221.651068 16.65605)
		(size 0.7112)
		(drill 0.4064)
		(layers "F.Cu" "B.Cu")
		(net "GND")
	)
	(via
		(at 302.204882 -347.802962)
		(size 0.7112)
		(drill 0.4064)
		(layers "F.Cu" "B.Cu")
		(net "GND")
	)
	(via
		(at 113.03 -152.4)
		(size 0.5588)
		(drill 0.3048)
		(layers "F.Cu" "B.Cu")
		(net "GND")
	)
	(via
		(at 463.04962 -1.397)
		(size 0.7112)
		(drill 0.4064)
		(layers "F.Cu" "B.Cu")
		(net "GND")
	)
	(via
		(at 471.770202 -254.66675)
		(size 0.5588)
		(drill 0.3048)
		(layers "F.Cu" "B.Cu")
		(net "GND")
	)
	(via
		(at 6.35 -241.3)
		(size 0.5588)
		(drill 0.3048)
		(layers "F.Cu" "B.Cu")
		(net "GND")
	)
	(via
		(at 81.92643 -18.50263)
		(size 0.5588)
		(drill 0.3048)
		(layers "F.Cu" "B.Cu")
		(net "GND")
	)
	(via
		(at 15.24 -10.16)
		(size 0.5588)
		(drill 0.3048)
		(layers "F.Cu" "B.Cu")
		(net "GND")
	)
	(via
		(at 121.92 -330.2)
		(size 0.5588)
		(drill 0.3048)
		(layers "F.Cu" "B.Cu")
		(net "GND")
	)
	(via
		(at 288.911284 -310.905144)
		(size 0.6604)
		(drill 0.3556)
		(layers "F.Cu" "B.Cu")
		(net "GND")
	)
	(via
		(at 308.602888 -412.151068)
		(size 0.7112)
		(drill 0.4064)
		(layers "F.Cu" "B.Cu")
		(net "GND")
	)
	(via
		(at 316.625478 -291.63137)
		(size 0.5588)
		(drill 0.3048)
		(layers "F.Cu" "B.Cu")
		(net "GND")
	)
	(via
		(at 194.093084 -1.397)
		(size 0.7112)
		(drill 0.4064)
		(layers "F.Cu" "B.Cu")
		(net "GND")
	)
	(via
		(at 323.794882 -347.802962)
		(size 0.7112)
		(drill 0.4064)
		(layers "F.Cu" "B.Cu")
		(net "GND")
	)
	(via
		(at 122.954796 -279.655016)
		(size 0.5588)
		(drill 0.3048)
		(layers "F.Cu" "B.Cu")
		(net "GND")
	)
	(via
		(at 27.161998 -165.429946)
		(size 0.5588)
		(drill 0.3048)
		(layers "F.Cu" "B.Cu")
		(net "GND")
	)
	(via
		(at 477.52 -20.32)
		(size 0.5588)
		(drill 0.3048)
		(layers "F.Cu" "B.Cu")
		(net "GND")
	)
	(via
		(at 119.121682 -347.548962)
		(size 0.7112)
		(drill 0.4064)
		(layers "F.Cu" "B.Cu")
		(net "GND")
	)
	(via
		(at 490.053122 -187.07735)
		(size 0.7112)
		(drill 0.4064)
		(layers "F.Cu" "B.Cu")
		(net "GND")
	)
	(via
		(at 3.81 -254)
		(size 0.5588)
		(drill 0.3048)
		(layers "F.Cu" "B.Cu")
		(net "GND")
	)
	(via
		(at 46.355 -143.0528)
		(size 0.5588)
		(drill 0.3048)
		(layers "F.Cu" "B.Cu")
		(net "GND")
	)
	(via
		(at 27.161998 -280.42997)
		(size 0.5588)
		(drill 0.3048)
		(layers "F.Cu" "B.Cu")
		(net "GND")
	)
	(via
		(at 231.207056 37.403024)
		(size 0.7112)
		(drill 0.4064)
		(layers "F.Cu" "B.Cu")
		(net "GND")
	)
	(via
		(at 1.397 -251.838968)
		(size 0.7112)
		(drill 0.4064)
		(layers "F.Cu" "B.Cu")
		(net "GND")
	)
	(via
		(at 416.56 -121.92)
		(size 0.5588)
		(drill 0.3048)
		(layers "F.Cu" "B.Cu")
		(net "GND")
	)
	(via
		(at 179.7558 -49.494694)
		(size 0.5588)
		(drill 0.3048)
		(layers "F.Cu" "B.Cu")
		(net "GND")
	)
	(via
		(at 217.922094 -13.401548)
		(size 0.5588)
		(drill 0.3048)
		(layers "F.Cu" "B.Cu")
		(net "GND")
	)
	(via
		(at 193.802 -273.05)
		(size 0.5588)
		(drill 0.3048)
		(layers "F.Cu" "B.Cu")
		(net "GND")
	)
	(via
		(at 153.416 -227.838)
		(size 0.5588)
		(drill 0.3048)
		(layers "F.Cu" "B.Cu")
		(net "GND")
	)
	(via
		(at 490.053122 -62.61735)
		(size 0.7112)
		(drill 0.4064)
		(layers "F.Cu" "B.Cu")
		(net "GND")
	)
	(via
		(at 66.642996 -347.802962)
		(size 0.7112)
		(drill 0.4064)
		(layers "F.Cu" "B.Cu")
		(net "GND")
	)
	(via
		(at 419.852348 -170.231816)
		(size 0.5588)
		(drill 0.3048)
		(layers "F.Cu" "B.Cu")
		(net "GND")
	)
	(via
		(at 262.255 -271.0434)
		(size 0.5588)
		(drill 0.3048)
		(layers "F.Cu" "B.Cu")
		(net "GND")
	)
	(via
		(at 266.7254 -100.9904)
		(size 0.5588)
		(drill 0.3048)
		(layers "F.Cu" "B.Cu")
		(net "GND")
	)
	(via
		(at 60.96 -101.6)
		(size 0.5588)
		(drill 0.3048)
		(layers "F.Cu" "B.Cu")
		(net "GND")
	)
	(via
		(at 483.404926 -42.034968)
		(size 0.5588)
		(drill 0.3048)
		(layers "F.Cu" "B.Cu")
		(net "GND")
	)
	(via
		(at 73.222612 -130.132074)
		(size 0.5588)
		(drill 0.3048)
		(layers "F.Cu" "B.Cu")
		(net "GND")
	)
	(via
		(at 1.397 -88.008968)
		(size 0.7112)
		(drill 0.4064)
		(layers "F.Cu" "B.Cu")
		(net "GND")
	)
	(via
		(at 245.177056 37.403024)
		(size 0.7112)
		(drill 0.4064)
		(layers "F.Cu" "B.Cu")
		(net "GND")
	)
	(via
		(at 76.2 -86.36)
		(size 0.5588)
		(drill 0.3048)
		(layers "F.Cu" "B.Cu")
		(net "GND")
	)
	(via
		(at 401.32 -15.24)
		(size 0.5588)
		(drill 0.3048)
		(layers "F.Cu" "B.Cu")
		(net "GND")
	)
	(via
		(at 16.379698 -284.015942)
		(size 0.5588)
		(drill 0.3048)
		(layers "F.Cu" "B.Cu")
		(net "GND")
	)
	(via
		(at 191.486282 -240.205006)
		(size 0.5588)
		(drill 0.3048)
		(layers "F.Cu" "B.Cu")
		(net "GND")
	)
	(via
		(at 446.4304 -253.7968)
		(size 0.5588)
		(drill 0.3048)
		(layers "F.Cu" "B.Cu")
		(net "GND")
	)
	(via
		(at 139.386818 -141.432026)
		(size 0.5588)
		(drill 0.3048)
		(layers "F.Cu" "B.Cu")
		(net "GND")
	)
	(via
		(at 4.445 -314.96)
		(size 0.5588)
		(drill 0.3048)
		(layers "F.Cu" "B.Cu")
		(net "GND")
	)
	(via
		(at 325.654924 -279.655016)
		(size 0.5588)
		(drill 0.3048)
		(layers "F.Cu" "B.Cu")
		(net "GND")
	)
	(via
		(at 102.143052 -182.984902)
		(size 0.5588)
		(drill 0.3048)
		(layers "F.Cu" "B.Cu")
		(net "GND")
	)
	(via
		(at 59.854846 -157.034992)
		(size 0.5588)
		(drill 0.3048)
		(layers "F.Cu" "B.Cu")
		(net "GND")
	)
	(via
		(at 50.583846 -160.329118)
		(size 0.5588)
		(drill 0.3048)
		(layers "F.Cu" "B.Cu")
		(net "GND")
	)
	(via
		(at 59.854846 -177.354992)
		(size 0.5588)
		(drill 0.3048)
		(layers "F.Cu" "B.Cu")
		(net "GND")
	)
	(via
		(at 53.555646 -162.208718)
		(size 0.5588)
		(drill 0.3048)
		(layers "F.Cu" "B.Cu")
		(net "GND")
	)
	(via
		(at 183.261 -117.475)
		(size 0.5588)
		(drill 0.3048)
		(layers "F.Cu" "B.Cu")
		(net "GND")
	)
	(via
		(at 157.263084 -1.397)
		(size 0.7112)
		(drill 0.4064)
		(layers "F.Cu" "B.Cu")
		(net "GND")
	)
	(via
		(at 490.053122 -166.75735)
		(size 0.7112)
		(drill 0.4064)
		(layers "F.Cu" "B.Cu")
		(net "GND")
	)
	(via
		(at 59.022996 -347.802962)
		(size 0.7112)
		(drill 0.4064)
		(layers "F.Cu" "B.Cu")
		(net "GND")
	)
	(via
		(at 397.256 -14.605)
		(size 0.7112)
		(drill 0.4064)
		(layers "F.Cu" "B.Cu")
		(net "GND")
	)
	(via
		(at 85.105748 -279.494742)
		(size 0.5588)
		(drill 0.3048)
		(layers "F.Cu" "B.Cu")
		(net "GND")
	)
	(via
		(at 45.72 -10.16)
		(size 0.5588)
		(drill 0.3048)
		(layers "F.Cu" "B.Cu")
		(net "GND")
	)
	(via
		(at 490.053122 -298.161202)
		(size 0.7112)
		(drill 0.4064)
		(layers "F.Cu" "B.Cu")
		(net "GND")
	)
	(via
		(at 394.26515 -161.649918)
		(size 0.5588)
		(drill 0.3048)
		(layers "F.Cu" "B.Cu")
		(net "GND")
	)
	(via
		(at 91.404948 -160.844992)
		(size 0.5588)
		(drill 0.3048)
		(layers "F.Cu" "B.Cu")
		(net "GND")
	)
	(via
		(at 374.142 -202.692)
		(size 0.5588)
		(drill 0.3048)
		(layers "F.Cu" "B.Cu")
		(net "GND")
	)
	(via
		(at 470.754202 -254.66675)
		(size 0.5588)
		(drill 0.3048)
		(layers "F.Cu" "B.Cu")
		(net "GND")
	)
	(via
		(at 194.026282 -230.553006)
		(size 0.5588)
		(drill 0.3048)
		(layers "F.Cu" "B.Cu")
		(net "GND")
	)
	(via
		(at 171.069 -87.376)
		(size 0.5588)
		(drill 0.3048)
		(layers "F.Cu" "B.Cu")
		(net "GND")
	)
	(via
		(at 469.516714 -207.209898)
		(size 0.5588)
		(drill 0.3048)
		(layers "F.Cu" "B.Cu")
		(net "GND")
	)
	(via
		(at 403.804882 -347.802962)
		(size 0.7112)
		(drill 0.4064)
		(layers "F.Cu" "B.Cu")
		(net "GND")
	)
	(via
		(at 172.052996 -347.802962)
		(size 0.7112)
		(drill 0.4064)
		(layers "F.Cu" "B.Cu")
		(net "GND")
	)
	(via
		(at 305.833272 -12.793472)
		(size 0.5588)
		(drill 0.3048)
		(layers "F.Cu" "B.Cu")
		(net "GND")
	)
	(via
		(at 201.397108 -388.102856)
		(size 0.7112)
		(drill 0.4064)
		(layers "F.Cu" "B.Cu")
		(net "GND")
	)
	(via
		(at 419.481 -232.029)
		(size 0.5588)
		(drill 0.3048)
		(layers "F.Cu" "B.Cu")
		(net "GND")
	)
	(via
		(at 19.9644 -251.2822)
		(size 0.7112)
		(drill 0.4064)
		(layers "F.Cu" "B.Cu")
		(net "GND")
	)
	(via
		(at 67.31 -201.93)
		(size 0.5588)
		(drill 0.3048)
		(layers "F.Cu" "B.Cu")
		(net "GND")
	)
	(via
		(at 341.574882 -347.802962)
		(size 0.7112)
		(drill 0.4064)
		(layers "F.Cu" "B.Cu")
		(net "GND")
	)
	(via
		(at 308.602888 -377.861068)
		(size 0.7112)
		(drill 0.4064)
		(layers "F.Cu" "B.Cu")
		(net "GND")
	)
	(via
		(at 487.68 -15.24)
		(size 0.5588)
		(drill 0.3048)
		(layers "F.Cu" "B.Cu")
		(net "GND")
	)
	(via
		(at 315.311028 -1.397)
		(size 0.7112)
		(drill 0.4064)
		(layers "F.Cu" "B.Cu")
		(net "GND")
	)
	(via
		(at 10.16 -147.32)
		(size 0.5588)
		(drill 0.3048)
		(layers "F.Cu" "B.Cu")
		(net "GND")
	)
	(via
		(at 438.15 -265.43)
		(size 0.5588)
		(drill 0.3048)
		(layers "F.Cu" "B.Cu")
		(net "GND")
	)
	(via
		(at 252.222 -83.566)
		(size 0.5588)
		(drill 0.3048)
		(layers "F.Cu" "B.Cu")
		(net "GND")
	)
	(via
		(at 222.758 -168.783)
		(size 0.5588)
		(drill 0.3048)
		(layers "F.Cu" "B.Cu")
		(net "GND")
	)
	(via
		(at 325.471028 -1.397)
		(size 0.7112)
		(drill 0.4064)
		(layers "F.Cu" "B.Cu")
		(net "GND")
	)
	(via
		(at 143.34998 -31.624778)
		(size 0.6604)
		(drill 0.3556)
		(layers "F.Cu" "B.Cu")
		(net "GND")
	)
	(via
		(at 282.155138 -230.026718)
		(size 0.5588)
		(drill 0.3048)
		(layers "F.Cu" "B.Cu")
		(net "GND")
	)
	(via
		(at 58.711846 -55.230014)
		(size 0.5588)
		(drill 0.3048)
		(layers "F.Cu" "B.Cu")
		(net "GND")
	)
	(via
		(at 15.24 -40.64)
		(size 0.5588)
		(drill 0.3048)
		(layers "F.Cu" "B.Cu")
		(net "GND")
	)
	(via
		(at 12.575032 -1.397)
		(size 0.7112)
		(drill 0.4064)
		(layers "F.Cu" "B.Cu")
		(net "GND")
	)
	(via
		(at 1.397 -284.858968)
		(size 0.7112)
		(drill 0.4064)
		(layers "F.Cu" "B.Cu")
		(net "GND")
	)
	(via
		(at 88.9 -137.16)
		(size 0.5588)
		(drill 0.3048)
		(layers "F.Cu" "B.Cu")
		(net "GND")
	)
	(via
		(at 184.912 -285.230062)
		(size 0.5588)
		(drill 0.3048)
		(layers "F.Cu" "B.Cu")
		(net "GND")
	)
	(via
		(at 469.39962 -1.397)
		(size 0.7112)
		(drill 0.4064)
		(layers "F.Cu" "B.Cu")
		(net "GND")
	)
	(via
		(at 201.397108 -381.752856)
		(size 0.7112)
		(drill 0.4064)
		(layers "F.Cu" "B.Cu")
		(net "GND")
	)
	(via
		(at 434.284882 -347.802962)
		(size 0.7112)
		(drill 0.4064)
		(layers "F.Cu" "B.Cu")
		(net "GND")
	)
	(via
		(at 18.652998 -174.603918)
		(size 0.5588)
		(drill 0.3048)
		(layers "F.Cu" "B.Cu")
		(net "GND")
	)
	(via
		(at 38.702996 -347.802962)
		(size 0.7112)
		(drill 0.4064)
		(layers "F.Cu" "B.Cu")
		(net "GND")
	)
	(via
		(at 66.04 -35.56)
		(size 0.5588)
		(drill 0.3048)
		(layers "F.Cu" "B.Cu")
		(net "GND")
	)
	(via
		(at 378.404882 -347.802962)
		(size 0.7112)
		(drill 0.4064)
		(layers "F.Cu" "B.Cu")
		(net "GND")
	)
	(via
		(at 490.053122 -77.85735)
		(size 0.7112)
		(drill 0.4064)
		(layers "F.Cu" "B.Cu")
		(net "GND")
	)
	(via
		(at 420.062406 -68.012564)
		(size 0.5588)
		(drill 0.3048)
		(layers "F.Cu" "B.Cu")
		(net "GND")
	)
	(via
		(at 356.062026 -280.42997)
		(size 0.5588)
		(drill 0.3048)
		(layers "F.Cu" "B.Cu")
		(net "GND")
	)
	(via
		(at 135.222996 -347.802962)
		(size 0.7112)
		(drill 0.4064)
		(layers "F.Cu" "B.Cu")
		(net "GND")
	)
	(via
		(at 3.81 -236.22)
		(size 0.5588)
		(drill 0.3048)
		(layers "F.Cu" "B.Cu")
		(net "GND")
	)
	(via
		(at 118.090696 -164.443918)
		(size 0.5588)
		(drill 0.3048)
		(layers "F.Cu" "B.Cu")
		(net "GND")
	)
	(via
		(at 1.397 -197.228968)
		(size 0.7112)
		(drill 0.4064)
		(layers "F.Cu" "B.Cu")
		(net "GND")
	)
	(via
		(at 165.267386 -189.146942)
		(size 0.5588)
		(drill 0.3048)
		(layers "F.Cu" "B.Cu")
		(net "GND")
	)
	(via
		(at 248.05132 -250.48972)
		(size 0.5588)
		(drill 0.3048)
		(layers "F.Cu" "B.Cu")
		(net "GND")
	)
	(via
		(at 490.053122 -207.39735)
		(size 0.7112)
		(drill 0.4064)
		(layers "F.Cu" "B.Cu")
		(net "GND")
	)
	(via
		(at 88.9 -127)
		(size 0.5588)
		(drill 0.3048)
		(layers "F.Cu" "B.Cu")
		(net "GND")
	)
	(via
		(at 186.055 -174.814992)
		(size 0.5588)
		(drill 0.3048)
		(layers "F.Cu" "B.Cu")
		(net "GND")
	)
	(via
		(at 472.215718 -42.51325)
		(size 0.5588)
		(drill 0.3048)
		(layers "F.Cu" "B.Cu")
		(net "GND")
	)
	(via
		(at 15.24 -20.32)
		(size 0.5588)
		(drill 0.3048)
		(layers "F.Cu" "B.Cu")
		(net "GND")
	)
	(via
		(at 21.1074 -248.9962)
		(size 0.7112)
		(drill 0.4064)
		(layers "F.Cu" "B.Cu")
		(net "GND")
	)
	(via
		(at 393.644882 -347.802962)
		(size 0.7112)
		(drill 0.4064)
		(layers "F.Cu" "B.Cu")
		(net "GND")
	)
	(via
		(at 88.9 -111.76)
		(size 0.5588)
		(drill 0.3048)
		(layers "F.Cu" "B.Cu")
		(net "GND")
	)
	(via
		(at 408.178 -50.546)
		(size 0.5588)
		(drill 0.3048)
		(layers "F.Cu" "B.Cu")
		(net "GND")
	)
	(via
		(at 35.56 -121.92)
		(size 0.5588)
		(drill 0.3048)
		(layers "F.Cu" "B.Cu")
		(net "GND")
	)
	(via
		(at 221.357698 -117.751606)
		(size 0.5588)
		(drill 0.3048)
		(layers "F.Cu" "B.Cu")
		(net "GND")
	)
	(via
		(at 165.259004 -300.341538)
		(size 0.5588)
		(drill 0.3048)
		(layers "F.Cu" "B.Cu")
		(net "GND")
	)
	(via
		(at 18.652998 -62.778894)
		(size 0.5588)
		(drill 0.3048)
		(layers "F.Cu" "B.Cu")
		(net "GND")
	)
	(via
		(at 490.053122 -202.31735)
		(size 0.7112)
		(drill 0.4064)
		(layers "F.Cu" "B.Cu")
		(net "GND")
	)
	(via
		(at 1.397 -80.388968)
		(size 0.7112)
		(drill 0.4064)
		(layers "F.Cu" "B.Cu")
		(net "GND")
	)
	(via
		(at 457.2 -127)
		(size 0.5588)
		(drill 0.3048)
		(layers "F.Cu" "B.Cu")
		(net "GND")
	)
	(via
		(at 446.4304 -251.7648)
		(size 0.5588)
		(drill 0.3048)
		(layers "F.Cu" "B.Cu")
		(net "GND")
	)
	(via
		(at 490.053122 -222.63735)
		(size 0.7112)
		(drill 0.4064)
		(layers "F.Cu" "B.Cu")
		(net "GND")
	)
	(via
		(at 30.355032 -1.397)
		(size 0.7112)
		(drill 0.4064)
		(layers "F.Cu" "B.Cu")
		(net "GND")
	)
	(via
		(at 217.178128 -99.568)
		(size 0.5588)
		(drill 0.3048)
		(layers "F.Cu" "B.Cu")
		(net "GND")
	)
	(via
		(at 23.440898 -164.443918)
		(size 0.5588)
		(drill 0.3048)
		(layers "F.Cu" "B.Cu")
		(net "GND")
	)
	(via
		(at 263.779762 -24.775922)
		(size 0.5588)
		(drill 0.3048)
		(layers "F.Cu" "B.Cu")
		(net "GND")
	)
	(via
		(at 201.397108 -395.722856)
		(size 0.7112)
		(drill 0.4064)
		(layers "F.Cu" "B.Cu")
		(net "GND")
	)
	(via
		(at 40.64 -228.6)
		(size 0.5588)
		(drill 0.3048)
		(layers "F.Cu" "B.Cu")
		(net "GND")
	)
	(via
		(at 100.071682 -347.548962)
		(size 0.7112)
		(drill 0.4064)
		(layers "F.Cu" "B.Cu")
		(net "GND")
	)
	(via
		(at 93.182948 -309.785004)
		(size 0.5588)
		(drill 0.3048)
		(layers "F.Cu" "B.Cu")
		(net "GND")
	)
	(via
		(at 93.182948 -36.03498)
		(size 0.5588)
		(drill 0.3048)
		(layers "F.Cu" "B.Cu")
		(net "GND")
	)
	(via
		(at 70.758558 -295.07815)
		(size 0.5588)
		(drill 0.3048)
		(layers "F.Cu" "B.Cu")
		(net "GND")
	)
	(via
		(at 396.14475 -158.855918)
		(size 0.5588)
		(drill 0.3048)
		(layers "F.Cu" "B.Cu")
		(net "GND")
	)
	(via
		(at 293.751 -165.1)
		(size 0.5588)
		(drill 0.3048)
		(layers "F.Cu" "B.Cu")
		(net "GND")
	)
	(via
		(at 273.117056 37.403024)
		(size 0.7112)
		(drill 0.4064)
		(layers "F.Cu" "B.Cu")
		(net "GND")
	)
	(via
		(at 294.302942 -367.555018)
		(size 0.7112)
		(drill 0.4064)
		(layers "F.Cu" "B.Cu")
		(net "GND")
	)
	(via
		(at 1.397 -56.258968)
		(size 0.7112)
		(drill 0.4064)
		(layers "F.Cu" "B.Cu")
		(net "GND")
	)
	(via
		(at 490.053122 -76.58735)
		(size 0.7112)
		(drill 0.4064)
		(layers "F.Cu" "B.Cu")
		(net "GND")
	)
	(via
		(at 115.57 -198.12)
		(size 0.5588)
		(drill 0.3048)
		(layers "F.Cu" "B.Cu")
		(net "GND")
	)
	(via
		(at 446.79997 -282.830016)
		(size 0.5588)
		(drill 0.3048)
		(layers "F.Cu" "B.Cu")
		(net "GND")
	)
	(via
		(at 262.868664 20.932902)
		(size 0.5588)
		(drill 0.3048)
		(layers "F.Cu" "B.Cu")
		(net "GND")
	)
	(via
		(at 119.38 -96.52)
		(size 0.5588)
		(drill 0.3048)
		(layers "F.Cu" "B.Cu")
		(net "GND")
	)
	(via
		(at 96.52 -10.16)
		(size 0.5588)
		(drill 0.3048)
		(layers "F.Cu" "B.Cu")
		(net "GND")
	)
	(via
		(at 252.797056 37.403024)
		(size 0.7112)
		(drill 0.4064)
		(layers "F.Cu" "B.Cu")
		(net "GND")
	)
	(via
		(at 490.053122 -317.211202)
		(size 0.7112)
		(drill 0.4064)
		(layers "F.Cu" "B.Cu")
		(net "GND")
	)
	(via
		(at 334.1116 -164.596318)
		(size 0.5588)
		(drill 0.3048)
		(layers "F.Cu" "B.Cu")
		(net "GND")
	)
	(via
		(at 226.8347 -378.333)
		(size 0.5588)
		(drill 0.3048)
		(layers "F.Cu" "B.Cu")
		(net "GND")
	)
	(via
		(at 303.881028 -1.397)
		(size 0.7112)
		(drill 0.4064)
		(layers "F.Cu" "B.Cu")
		(net "GND")
	)
	(via
		(at 490.053122 -89.28735)
		(size 0.7112)
		(drill 0.4064)
		(layers "F.Cu" "B.Cu")
		(net "GND")
	)
	(via
		(at 57.15 -218.44)
		(size 0.5588)
		(drill 0.3048)
		(layers "F.Cu" "B.Cu")
		(net "GND")
	)
	(via
		(at 467.304882 -347.802962)
		(size 0.7112)
		(drill 0.4064)
		(layers "F.Cu" "B.Cu")
		(net "GND")
	)
	(via
		(at 390.532874 -79.784956)
		(size 0.5588)
		(drill 0.3048)
		(layers "F.Cu" "B.Cu")
		(net "GND")
	)
	(via
		(at 288.911284 -300.105064)
		(size 0.6604)
		(drill 0.3556)
		(layers "F.Cu" "B.Cu")
		(net "GND")
	)
	(via
		(at 347.70949 -285.33471)
		(size 0.5588)
		(drill 0.3048)
		(layers "F.Cu" "B.Cu")
		(net "GND")
	)
	(via
		(at 133.736842 -298.988988)
		(size 0.5588)
		(drill 0.3048)
		(layers "F.Cu" "B.Cu")
		(net "GND")
	)
	(via
		(at 327.406 -78.613)
		(size 0.5588)
		(drill 0.3048)
		(layers "F.Cu" "B.Cu")
		(net "GND")
	)
	(via
		(at 360.172 -328.041)
		(size 0.5588)
		(drill 0.3048)
		(layers "F.Cu" "B.Cu")
		(net "GND")
	)
	(via
		(at 426.72 -25.4)
		(size 0.5588)
		(drill 0.3048)
		(layers "F.Cu" "B.Cu")
		(net "GND")
	)
	(via
		(at 294.302942 -362.475018)
		(size 0.7112)
		(drill 0.4064)
		(layers "F.Cu" "B.Cu")
		(net "GND")
	)
	(via
		(at 133.702552 -304.227738)
		(size 0.5588)
		(drill 0.3048)
		(layers "F.Cu" "B.Cu")
		(net "GND")
	)
	(via
		(at 476.445326 -241.584988)
		(size 0.5588)
		(drill 0.3048)
		(layers "F.Cu" "B.Cu")
		(net "GND")
	)
	(via
		(at 346.654882 -347.802962)
		(size 0.7112)
		(drill 0.4064)
		(layers "F.Cu" "B.Cu")
		(net "GND")
	)
	(via
		(at 460.3369 -164.596318)
		(size 0.5588)
		(drill 0.3048)
		(layers "F.Cu" "B.Cu")
		(net "GND")
	)
	(via
		(at 189.904624 -222.686118)
		(size 0.5588)
		(drill 0.3048)
		(layers "F.Cu" "B.Cu")
		(net "GND")
	)
	(via
		(at 428.406052 -182.223918)
		(size 0.5588)
		(drill 0.3048)
		(layers "F.Cu" "B.Cu")
		(net "GND")
	)
	(via
		(at 426.21962 -1.397)
		(size 0.7112)
		(drill 0.4064)
		(layers "F.Cu" "B.Cu")
		(net "GND")
	)
	(via
		(at 304.741072 -21.683472)
		(size 0.5588)
		(drill 0.3048)
		(layers "F.Cu" "B.Cu")
		(net "GND")
	)
	(via
		(at 20.32 -30.48)
		(size 0.5588)
		(drill 0.3048)
		(layers "F.Cu" "B.Cu")
		(net "GND")
	)
	(via
		(at 294.302942 -361.205018)
		(size 0.7112)
		(drill 0.4064)
		(layers "F.Cu" "B.Cu")
		(net "GND")
	)
	(via
		(at 490.053122 -14.35735)
		(size 0.7112)
		(drill 0.4064)
		(layers "F.Cu" "B.Cu")
		(net "GND")
	)
	(via
		(at 273.177 -215.392)
		(size 0.5588)
		(drill 0.3048)
		(layers "F.Cu" "B.Cu")
		(net "GND")
	)
	(via
		(at 382.27 -96.139)
		(size 0.5588)
		(drill 0.3048)
		(layers "F.Cu" "B.Cu")
		(net "GND")
	)
	(via
		(at 235.25099 -235.798868)
		(size 0.5588)
		(drill 0.3048)
		(layers "F.Cu" "B.Cu")
		(net "GND")
	)
	(via
		(at 130.81 -81.915)
		(size 0.5588)
		(drill 0.3048)
		(layers "F.Cu" "B.Cu")
		(net "GND")
	)
	(via
		(at 450.711824 -165.429946)
		(size 0.5588)
		(drill 0.3048)
		(layers "F.Cu" "B.Cu")
		(net "GND")
	)
	(via
		(at 50.8 -86.36)
		(size 0.5588)
		(drill 0.3048)
		(layers "F.Cu" "B.Cu")
		(net "GND")
	)
	(via
		(at 257.877056 37.403024)
		(size 0.7112)
		(drill 0.4064)
		(layers "F.Cu" "B.Cu")
		(net "GND")
	)
	(via
		(at 217.619326 -17.007078)
		(size 0.5588)
		(drill 0.3048)
		(layers "F.Cu" "B.Cu")
		(net "GND")
	)
	(via
		(at 59.854846 -45.844968)
		(size 0.5588)
		(drill 0.3048)
		(layers "F.Cu" "B.Cu")
		(net "GND")
	)
	(via
		(at 103.133398 -302.947324)
		(size 0.5588)
		(drill 0.3048)
		(layers "F.Cu" "B.Cu")
		(net "GND")
	)
	(via
		(at 1.397 -131.188968)
		(size 0.7112)
		(drill 0.4064)
		(layers "F.Cu" "B.Cu")
		(net "GND")
	)
	(via
		(at 137.16 -148.082)
		(size 0.5588)
		(drill 0.3048)
		(layers "F.Cu" "B.Cu")
		(net "GND")
	)
	(via
		(at 46.355 -145.0848)
		(size 0.5588)
		(drill 0.3048)
		(layers "F.Cu" "B.Cu")
		(net "GND")
	)
	(via
		(at 274.2184 12.8778)
		(size 0.5588)
		(drill 0.3048)
		(layers "F.Cu" "B.Cu")
		(net "GND")
	)
	(via
		(at 1.397 -44.828968)
		(size 0.7112)
		(drill 0.4064)
		(layers "F.Cu" "B.Cu")
		(net "GND")
	)
	(via
		(at 298.602908 33.678876)
		(size 0.7112)
		(drill 0.4064)
		(layers "F.Cu" "B.Cu")
		(net "GND")
	)
	(via
		(at 490.053122 -331.181202)
		(size 0.7112)
		(drill 0.4064)
		(layers "F.Cu" "B.Cu")
		(net "GND")
	)
	(via
		(at 74.9808 -273.9136)
		(size 0.5588)
		(drill 0.3048)
		(layers "F.Cu" "B.Cu")
		(net "GND")
	)
	(via
		(at 170.18 -135.001)
		(size 0.5588)
		(drill 0.3048)
		(layers "F.Cu" "B.Cu")
		(net "GND")
	)
	(via
		(at 103.881682 -347.548962)
		(size 0.7112)
		(drill 0.4064)
		(layers "F.Cu" "B.Cu")
		(net "GND")
	)
	(via
		(at 215.587326 -17.007078)
		(size 0.5588)
		(drill 0.3048)
		(layers "F.Cu" "B.Cu")
		(net "GND")
	)
	(via
		(at 50.8 -35.56)
		(size 0.5588)
		(drill 0.3048)
		(layers "F.Cu" "B.Cu")
		(net "GND")
	)
	(via
		(at 195.453 -326.009)
		(size 0.5588)
		(drill 0.3048)
		(layers "F.Cu" "B.Cu")
		(net "GND")
	)
	(via
		(at 373.02567 -125.361446)
		(size 0.5588)
		(drill 0.3048)
		(layers "F.Cu" "B.Cu")
		(net "GND")
	)
	(via
		(at 441.96 -35.56)
		(size 0.5588)
		(drill 0.3048)
		(layers "F.Cu" "B.Cu")
		(net "GND")
	)
	(via
		(at 1.397 -310.258968)
		(size 0.7112)
		(drill 0.4064)
		(layers "F.Cu" "B.Cu")
		(net "GND")
	)
	(via
		(at 3.81 -233.68)
		(size 0.5588)
		(drill 0.3048)
		(layers "F.Cu" "B.Cu")
		(net "GND")
	)
	(via
		(at 60.96 -327.66)
		(size 0.5588)
		(drill 0.3048)
		(layers "F.Cu" "B.Cu")
		(net "GND")
	)
	(via
		(at 425.815252 -161.649918)
		(size 0.5588)
		(drill 0.3048)
		(layers "F.Cu" "B.Cu")
		(net "GND")
	)
	(via
		(at 7.783576 -294.099234)
		(size 0.5588)
		(drill 0.3048)
		(layers "F.Cu" "B.Cu")
		(net "GND")
	)
	(via
		(at 349.367602 -175.238918)
		(size 0.5588)
		(drill 0.3048)
		(layers "F.Cu" "B.Cu")
		(net "GND")
	)
	(via
		(at 365.052102 -191.113918)
		(size 0.5588)
		(drill 0.3048)
		(layers "F.Cu" "B.Cu")
		(net "GND")
	)
	(via
		(at 22.005798 -49.494694)
		(size 0.5588)
		(drill 0.3048)
		(layers "F.Cu" "B.Cu")
		(net "GND")
	)
	(via
		(at 331.089 -110.236)
		(size 0.5588)
		(drill 0.3048)
		(layers "F.Cu" "B.Cu")
		(net "GND")
	)
	(via
		(at 490.053122 -127.38735)
		(size 0.7112)
		(drill 0.4064)
		(layers "F.Cu" "B.Cu")
		(net "GND")
	)
	(via
		(at 420.304976 -289.815016)
		(size 0.5588)
		(drill 0.3048)
		(layers "F.Cu" "B.Cu")
		(net "GND")
	)
	(via
		(at 181.991 -191.240918)
		(size 0.5588)
		(drill 0.3048)
		(layers "F.Cu" "B.Cu")
		(net "GND")
	)
	(via
		(at 81.752948 -62.778894)
		(size 0.5588)
		(drill 0.3048)
		(layers "F.Cu" "B.Cu")
		(net "GND")
	)
	(via
		(at 452.12 -127)
		(size 0.5588)
		(drill 0.3048)
		(layers "F.Cu" "B.Cu")
		(net "GND")
	)
	(via
		(at 22.606 -141.605)
		(size 0.5588)
		(drill 0.3048)
		(layers "F.Cu" "B.Cu")
		(net "GND")
	)
	(via
		(at 332.994 -81.534)
		(size 0.5588)
		(drill 0.3048)
		(layers "F.Cu" "B.Cu")
		(net "GND")
	)
	(via
		(at 490.053122 -295.621202)
		(size 0.7112)
		(drill 0.4064)
		(layers "F.Cu" "B.Cu")
		(net "GND")
	)
	(via
		(at 154.504898 -182.434992)
		(size 0.5588)
		(drill 0.3048)
		(layers "F.Cu" "B.Cu")
		(net "GND")
	)
	(via
		(at 474.542104 -231.662986)
		(size 0.5588)
		(drill 0.3048)
		(layers "F.Cu" "B.Cu")
		(net "GND")
	)
	(via
		(at 10.16 -152.4)
		(size 0.5588)
		(drill 0.3048)
		(layers "F.Cu" "B.Cu")
		(net "GND")
	)
	(via
		(at 243.907056 37.403024)
		(size 0.7112)
		(drill 0.4064)
		(layers "F.Cu" "B.Cu")
		(net "GND")
	)
	(via
		(at 490.053122 -138.81735)
		(size 0.7112)
		(drill 0.4064)
		(layers "F.Cu" "B.Cu")
		(net "GND")
	)
	(via
		(at 490.053122 -241.68735)
		(size 0.7112)
		(drill 0.4064)
		(layers "F.Cu" "B.Cu")
		(net "GND")
	)
	(via
		(at 265.100562 -27.315922)
		(size 0.5588)
		(drill 0.3048)
		(layers "F.Cu" "B.Cu")
		(net "GND")
	)
	(via
		(at 1.397 -75.308968)
		(size 0.7112)
		(drill 0.4064)
		(layers "F.Cu" "B.Cu")
		(net "GND")
	)
	(via
		(at 101.346 -15.748)
		(size 0.7112)
		(drill 0.4064)
		(layers "F.Cu" "B.Cu")
		(net "GND")
	)
	(via
		(at 294.302942 -359.935018)
		(size 0.7112)
		(drill 0.4064)
		(layers "F.Cu" "B.Cu")
		(net "GND")
	)
	(via
		(at 310.007 -332.994)
		(size 0.5588)
		(drill 0.3048)
		(layers "F.Cu" "B.Cu")
		(net "GND")
	)
	(via
		(at 126.741682 -347.548962)
		(size 0.7112)
		(drill 0.4064)
		(layers "F.Cu" "B.Cu")
		(net "GND")
	)
	(via
		(at 215.890094 -13.401548)
		(size 0.5588)
		(drill 0.3048)
		(layers "F.Cu" "B.Cu")
		(net "GND")
	)
	(via
		(at 288.911284 -343.30513)
		(size 0.6604)
		(drill 0.3556)
		(layers "F.Cu" "B.Cu")
		(net "GND")
	)
	(via
		(at 405.074882 -347.802962)
		(size 0.7112)
		(drill 0.4064)
		(layers "F.Cu" "B.Cu")
		(net "GND")
	)
	(via
		(at 298.602908 32.408876)
		(size 0.7112)
		(drill 0.4064)
		(layers "F.Cu" "B.Cu")
		(net "GND")
	)
	(via
		(at 229.855014 -370.063014)
		(size 0.5588)
		(drill 0.3048)
		(layers "F.Cu" "B.Cu")
		(net "GND")
	)
	(via
		(at 482.6 -330.2)
		(size 0.5588)
		(drill 0.3048)
		(layers "F.Cu" "B.Cu")
		(net "GND")
	)
	(via
		(at 293.751 -157.226)
		(size 0.5588)
		(drill 0.3048)
		(layers "F.Cu" "B.Cu")
		(net "GND")
	)
	(via
		(at 459.2447 -273.855942)
		(size 0.5588)
		(drill 0.3048)
		(layers "F.Cu" "B.Cu")
		(net "GND")
	)
	(via
		(at 38.928802 -144.45615)
		(size 0.5588)
		(drill 0.3048)
		(layers "F.Cu" "B.Cu")
		(net "GND")
	)
	(via
		(at 221.651068 10.30605)
		(size 0.7112)
		(drill 0.4064)
		(layers "F.Cu" "B.Cu")
		(net "GND")
	)
	(via
		(at 352.171 -319.532)
		(size 0.5588)
		(drill 0.3048)
		(layers "F.Cu" "B.Cu")
		(net "GND")
	)
	(via
		(at 60.96 -15.24)
		(size 0.5588)
		(drill 0.3048)
		(layers "F.Cu" "B.Cu")
		(net "GND")
	)
	(via
		(at 218.938094 -13.401548)
		(size 0.5588)
		(drill 0.3048)
		(layers "F.Cu" "B.Cu")
		(net "GND")
	)
	(via
		(at 368.046 -177.292)
		(size 0.5588)
		(drill 0.3048)
		(layers "F.Cu" "B.Cu")
		(net "GND")
	)
	(via
		(at 195.363084 -1.397)
		(size 0.7112)
		(drill 0.4064)
		(layers "F.Cu" "B.Cu")
		(net "GND")
	)
	(via
		(at 96.52 -15.24)
		(size 0.5588)
		(drill 0.3048)
		(layers "F.Cu" "B.Cu")
		(net "GND")
	)
	(via
		(at 60.96 -116.84)
		(size 0.5588)
		(drill 0.3048)
		(layers "F.Cu" "B.Cu")
		(net "GND")
	)
	(via
		(at 129.795016 -131.157472)
		(size 0.5588)
		(drill 0.3048)
		(layers "F.Cu" "B.Cu")
		(net "GND")
	)
	(via
		(at 248.285 -300.3042)
		(size 0.5588)
		(drill 0.3048)
		(layers "F.Cu" "B.Cu")
		(net "GND")
	)
	(via
		(at 295.977056 37.403024)
		(size 0.7112)
		(drill 0.4064)
		(layers "F.Cu" "B.Cu")
		(net "GND")
	)
	(via
		(at 12.7 -269.24)
		(size 0.5588)
		(drill 0.3048)
		(layers "F.Cu" "B.Cu")
		(net "GND")
	)
	(via
		(at 450.469 -223.393)
		(size 0.5588)
		(drill 0.3048)
		(layers "F.Cu" "B.Cu")
		(net "GND")
	)
	(via
		(at 298.602908 10.818876)
		(size 0.7112)
		(drill 0.4064)
		(layers "F.Cu" "B.Cu")
		(net "GND")
	)
	(via
		(at 458.3049 -41.315894)
		(size 0.5588)
		(drill 0.3048)
		(layers "F.Cu" "B.Cu")
		(net "GND")
	)
	(via
		(at 145.233898 -277.615142)
		(size 0.5588)
		(drill 0.3048)
		(layers "F.Cu" "B.Cu")
		(net "GND")
	)
	(via
		(at 214.874094 -14.417548)
		(size 0.5588)
		(drill 0.3048)
		(layers "F.Cu" "B.Cu")
		(net "GND")
	)
	(via
		(at 206.121 -119.253)
		(size 0.5588)
		(drill 0.3048)
		(layers "F.Cu" "B.Cu")
		(net "GND")
	)
	(via
		(at 304.741072 -16.349472)
		(size 0.5588)
		(drill 0.3048)
		(layers "F.Cu" "B.Cu")
		(net "GND")
	)
	(via
		(at 384.81 -200.406)
		(size 0.5588)
		(drill 0.3048)
		(layers "F.Cu" "B.Cu")
		(net "GND")
	)
	(via
		(at 116.84 -137.16)
		(size 0.5588)
		(drill 0.3048)
		(layers "F.Cu" "B.Cu")
		(net "GND")
	)
	(via
		(at 280.250138 -229.264718)
		(size 0.5588)
		(drill 0.3048)
		(layers "F.Cu" "B.Cu")
		(net "GND")
	)
	(via
		(at 355.217222 -79.784956)
		(size 0.5588)
		(drill 0.3048)
		(layers "F.Cu" "B.Cu")
		(net "GND")
	)
	(via
		(at 232.41 -223.266)
		(size 0.5588)
		(drill 0.3048)
		(layers "F.Cu" "B.Cu")
		(net "GND")
	)
	(via
		(at 83.82 -228.6)
		(size 0.5588)
		(drill 0.3048)
		(layers "F.Cu" "B.Cu")
		(net "GND")
	)
	(via
		(at 148.866098 -185.322718)
		(size 0.5588)
		(drill 0.3048)
		(layers "F.Cu" "B.Cu")
		(net "GND")
	)
	(via
		(at 55.88 -10.16)
		(size 0.5588)
		(drill 0.3048)
		(layers "F.Cu" "B.Cu")
		(net "GND")
	)
	(via
		(at 31.082996 -347.802962)
		(size 0.7112)
		(drill 0.4064)
		(layers "F.Cu" "B.Cu")
		(net "GND")
	)
	(via
		(at 117.315996 -300.322742)
		(size 0.5588)
		(drill 0.3048)
		(layers "F.Cu" "B.Cu")
		(net "GND")
	)
	(via
		(at 30.4292 -246.6848)
		(size 0.5588)
		(drill 0.3048)
		(layers "F.Cu" "B.Cu")
		(net "GND")
	)
	(via
		(at 66.04 -30.48)
		(size 0.5588)
		(drill 0.3048)
		(layers "F.Cu" "B.Cu")
		(net "GND")
	)
	(via
		(at 335.631028 -1.397)
		(size 0.7112)
		(drill 0.4064)
		(layers "F.Cu" "B.Cu")
		(net "GND")
	)
	(via
		(at 267.5128 -229.032562)
		(size 0.5588)
		(drill 0.3048)
		(layers "F.Cu" "B.Cu")
		(net "GND")
	)
	(via
		(at 426.120052 -191.113918)
		(size 0.5588)
		(drill 0.3048)
		(layers "F.Cu" "B.Cu")
		(net "GND")
	)
	(via
		(at 393.319 -236.982)
		(size 0.5588)
		(drill 0.3048)
		(layers "F.Cu" "B.Cu")
		(net "GND")
	)
	(via
		(at 177.419 -331.851)
		(size 0.5588)
		(drill 0.3048)
		(layers "F.Cu" "B.Cu")
		(net "GND")
	)
	(via
		(at 404.749 -301.117)
		(size 0.5588)
		(drill 0.3048)
		(layers "F.Cu" "B.Cu")
		(net "GND")
	)
	(via
		(at 371.602 -77.978)
		(size 0.5588)
		(drill 0.3048)
		(layers "F.Cu" "B.Cu")
		(net "GND")
	)
	(via
		(at 364.594902 -158.855918)
		(size 0.5588)
		(drill 0.3048)
		(layers "F.Cu" "B.Cu")
		(net "GND")
	)
	(via
		(at 1.397 -141.348968)
		(size 0.7112)
		(drill 0.4064)
		(layers "F.Cu" "B.Cu")
		(net "GND")
	)
	(via
		(at 223.774 -174.9552)
		(size 0.5588)
		(drill 0.3048)
		(layers "F.Cu" "B.Cu")
		(net "GND")
	)
	(via
		(at 64.645032 -1.397)
		(size 0.7112)
		(drill 0.4064)
		(layers "F.Cu" "B.Cu")
		(net "GND")
	)
	(via
		(at 55.88 -121.92)
		(size 0.5588)
		(drill 0.3048)
		(layers "F.Cu" "B.Cu")
		(net "GND")
	)
	(via
		(at 192.350898 -363.441742)
		(size 0.7112)
		(drill 0.4064)
		(layers "F.Cu" "B.Cu")
		(net "GND")
	)
	(via
		(at 421.64 -101.6)
		(size 0.5588)
		(drill 0.3048)
		(layers "F.Cu" "B.Cu")
		(net "GND")
	)
	(via
		(at 201.397108 -389.372856)
		(size 0.7112)
		(drill 0.4064)
		(layers "F.Cu" "B.Cu")
		(net "GND")
	)
	(via
		(at 381.6096 -140.7414)
		(size 0.5588)
		(drill 0.3048)
		(layers "F.Cu" "B.Cu")
		(net "GND")
	)
	(via
		(at 226.741228 -386.262372)
		(size 0.5588)
		(drill 0.3048)
		(layers "F.Cu" "B.Cu")
		(net "GND")
	)
	(via
		(at 336.174334 -20.111466)
		(size 0.5588)
		(drill 0.3048)
		(layers "F.Cu" "B.Cu")
		(net "GND")
	)
	(via
		(at 59.854846 -164.654992)
		(size 0.5588)
		(drill 0.3048)
		(layers "F.Cu" "B.Cu")
		(net "GND")
	)
	(via
		(at 459.2447 -43.855894)
		(size 0.5588)
		(drill 0.3048)
		(layers "F.Cu" "B.Cu")
		(net "GND")
	)
	(via
		(at 10.16 -20.32)
		(size 0.5588)
		(drill 0.3048)
		(layers "F.Cu" "B.Cu")
		(net "GND")
	)
	(via
		(at 87.371682 -347.548962)
		(size 0.7112)
		(drill 0.4064)
		(layers "F.Cu" "B.Cu")
		(net "GND")
	)
	(via
		(at 459.684882 -347.802962)
		(size 0.7112)
		(drill 0.4064)
		(layers "F.Cu" "B.Cu")
		(net "GND")
	)
	(via
		(at 318.714882 -347.802962)
		(size 0.7112)
		(drill 0.4064)
		(layers "F.Cu" "B.Cu")
		(net "GND")
	)
	(via
		(at 30.082998 -36.03498)
		(size 0.5588)
		(drill 0.3048)
		(layers "F.Cu" "B.Cu")
		(net "GND")
	)
	(via
		(at 473.526104 -232.678986)
		(size 0.5588)
		(drill 0.3048)
		(layers "F.Cu" "B.Cu")
		(net "GND")
	)
	(via
		(at 428.152052 -191.113918)
		(size 0.5588)
		(drill 0.3048)
		(layers "F.Cu" "B.Cu")
		(net "GND")
	)
	(via
		(at 422.082976 -151.035004)
		(size 0.5588)
		(drill 0.3048)
		(layers "F.Cu" "B.Cu")
		(net "GND")
	)
	(via
		(at 60.96 -20.32)
		(size 0.5588)
		(drill 0.3048)
		(layers "F.Cu" "B.Cu")
		(net "GND")
	)
	(via
		(at 145.034 -250.952)
		(size 0.5588)
		(drill 0.3048)
		(layers "F.Cu" "B.Cu")
		(net "GND")
	)
	(via
		(at 451.854824 -69.974968)
		(size 0.5588)
		(drill 0.3048)
		(layers "F.Cu" "B.Cu")
		(net "GND")
	)
	(via
		(at 408.884882 -347.802962)
		(size 0.7112)
		(drill 0.4064)
		(layers "F.Cu" "B.Cu")
		(net "GND")
	)
	(via
		(at 344.3478 -149.2504)
		(size 0.5588)
		(drill 0.3048)
		(layers "F.Cu" "B.Cu")
		(net "GND")
	)
	(via
		(at 9.901682 -347.548962)
		(size 0.7112)
		(drill 0.4064)
		(layers "F.Cu" "B.Cu")
		(net "GND")
	)
	(via
		(at 321.661028 -1.397)
		(size 0.7112)
		(drill 0.4064)
		(layers "F.Cu" "B.Cu")
		(net "GND")
	)
	(via
		(at 233.30027 -388.72287)
		(size 0.5588)
		(drill 0.3048)
		(layers "F.Cu" "B.Cu")
		(net "GND")
	)
	(via
		(at 365.687102 -279.596342)
		(size 0.5588)
		(drill 0.3048)
		(layers "F.Cu" "B.Cu")
		(net "GND")
	)
	(via
		(at 53.594 -270.51)
		(size 0.5588)
		(drill 0.3048)
		(layers "F.Cu" "B.Cu")
		(net "GND")
	)
	(via
		(at 225.171 -363.855)
		(size 0.5588)
		(drill 0.3048)
		(layers "F.Cu" "B.Cu")
		(net "GND")
	)
	(via
		(at 490.053122 -208.66735)
		(size 0.7112)
		(drill 0.4064)
		(layers "F.Cu" "B.Cu")
		(net "GND")
	)
	(via
		(at 483.404926 -164.654992)
		(size 0.5588)
		(drill 0.3048)
		(layers "F.Cu" "B.Cu")
		(net "GND")
	)
	(via
		(at 325.654924 -182.434992)
		(size 0.5588)
		(drill 0.3048)
		(layers "F.Cu" "B.Cu")
		(net "GND")
	)
	(via
		(at 66.04 -15.24)
		(size 0.5588)
		(drill 0.3048)
		(layers "F.Cu" "B.Cu")
		(net "GND")
	)
	(via
		(at 379.5014 -133.7056)
		(size 0.5588)
		(drill 0.3048)
		(layers "F.Cu" "B.Cu")
		(net "GND")
	)
	(via
		(at 490.053122 -74.04735)
		(size 0.7112)
		(drill 0.4064)
		(layers "F.Cu" "B.Cu")
		(net "GND")
	)
	(via
		(at 365.76 -335.28)
		(size 0.5588)
		(drill 0.3048)
		(layers "F.Cu" "B.Cu")
		(net "GND")
	)
	(via
		(at 277.8506 16.383)
		(size 0.5588)
		(drill 0.3048)
		(layers "F.Cu" "B.Cu")
		(net "GND")
	)
	(via
		(at 91.948 -258.318)
		(size 0.5588)
		(drill 0.3048)
		(layers "F.Cu" "B.Cu")
		(net "GND")
	)
	(via
		(at 325.654924 -275.845016)
		(size 0.5588)
		(drill 0.3048)
		(layers "F.Cu" "B.Cu")
		(net "GND")
	)
	(via
		(at 186.289188 -217.888312)
		(size 0.5588)
		(drill 0.3048)
		(layers "F.Cu" "B.Cu")
		(net "GND")
	)
	(via
		(at 30.4292 -250.7488)
		(size 0.5588)
		(drill 0.3048)
		(layers "F.Cu" "B.Cu")
		(net "GND")
	)
	(via
		(at 192.350898 -359.631742)
		(size 0.7112)
		(drill 0.4064)
		(layers "F.Cu" "B.Cu")
		(net "GND")
	)
	(via
		(at 4.445 -327.66)
		(size 0.5588)
		(drill 0.3048)
		(layers "F.Cu" "B.Cu")
		(net "GND")
	)
	(via
		(at 6.35 -271.78)
		(size 0.5588)
		(drill 0.3048)
		(layers "F.Cu" "B.Cu")
		(net "GND")
	)
	(via
		(at 482.544882 -347.802962)
		(size 0.7112)
		(drill 0.4064)
		(layers "F.Cu" "B.Cu")
		(net "GND")
	)
	(via
		(at 45.339 -145.0848)
		(size 0.5588)
		(drill 0.3048)
		(layers "F.Cu" "B.Cu")
		(net "GND")
	)
	(via
		(at 358.970072 -37.099748)
		(size 0.5588)
		(drill 0.3048)
		(layers "F.Cu" "B.Cu")
		(net "GND")
	)
	(via
		(at 395.605 -265.049)
		(size 0.5588)
		(drill 0.3048)
		(layers "F.Cu" "B.Cu")
		(net "GND")
	)
	(via
		(at 149.606 -16.256)
		(size 0.7112)
		(drill 0.4064)
		(layers "F.Cu" "B.Cu")
		(net "GND")
	)
	(via
		(at 51.705002 -254.31115)
		(size 0.5588)
		(drill 0.3048)
		(layers "F.Cu" "B.Cu")
		(net "GND")
	)
	(via
		(at 200.41743 -2.95021)
		(size 0.5588)
		(drill 0.3048)
		(layers "F.Cu" "B.Cu")
		(net "GND")
	)
	(via
		(at 77.343 -60.198)
		(size 0.5588)
		(drill 0.3048)
		(layers "F.Cu" "B.Cu")
		(net "GND")
	)
	(via
		(at 22.86 -217.932)
		(size 0.5588)
		(drill 0.3048)
		(layers "F.Cu" "B.Cu")
		(net "GND")
	)
	(via
		(at 477.52 -198.12)
		(size 0.5588)
		(drill 0.3048)
		(layers "F.Cu" "B.Cu")
		(net "GND")
	)
	(via
		(at 490.053122 -117.22735)
		(size 0.7112)
		(drill 0.4064)
		(layers "F.Cu" "B.Cu")
		(net "GND")
	)
	(via
		(at 1.397 -333.118968)
		(size 0.7112)
		(drill 0.4064)
		(layers "F.Cu" "B.Cu")
		(net "GND")
	)
	(via
		(at 55.88 -91.44)
		(size 0.5588)
		(drill 0.3048)
		(layers "F.Cu" "B.Cu")
		(net "GND")
	)
	(via
		(at 315.087 -5.08)
		(size 0.5588)
		(drill 0.3048)
		(layers "F.Cu" "B.Cu")
		(net "GND")
	)
	(via
		(at 346.349066 -2.494534)
		(size 0.7112)
		(drill 0.4064)
		(layers "F.Cu" "B.Cu")
		(net "GND")
	)
	(via
		(at 1.397 -49.908968)
		(size 0.7112)
		(drill 0.4064)
		(layers "F.Cu" "B.Cu")
		(net "GND")
	)
	(via
		(at 27.161998 -50.429922)
		(size 0.5588)
		(drill 0.3048)
		(layers "F.Cu" "B.Cu")
		(net "GND")
	)
	(via
		(at 1.397 -161.668968)
		(size 0.7112)
		(drill 0.4064)
		(layers "F.Cu" "B.Cu")
		(net "GND")
	)
	(via
		(at 201.397108 -409.692856)
		(size 0.7112)
		(drill 0.4064)
		(layers "F.Cu" "B.Cu")
		(net "GND")
	)
	(via
		(at 308.602888 -410.881068)
		(size 0.7112)
		(drill 0.4064)
		(layers "F.Cu" "B.Cu")
		(net "GND")
	)
	(via
		(at 84.582 -142.24)
		(size 0.5588)
		(drill 0.3048)
		(layers "F.Cu" "B.Cu")
		(net "GND")
	)
	(via
		(at 178.402996 -347.802962)
		(size 0.7112)
		(drill 0.4064)
		(layers "F.Cu" "B.Cu")
		(net "GND")
	)
	(via
		(at 194.945 -117.729)
		(size 0.5588)
		(drill 0.3048)
		(layers "F.Cu" "B.Cu")
		(net "GND")
	)
	(via
		(at 154.504898 -69.974968)
		(size 0.5588)
		(drill 0.3048)
		(layers "F.Cu" "B.Cu")
		(net "GND")
	)
	(via
		(at 142.24 -111.379)
		(size 0.5588)
		(drill 0.3048)
		(layers "F.Cu" "B.Cu")
		(net "GND")
	)
	(via
		(at 300.771814 -24.585676)
		(size 0.5588)
		(drill 0.3048)
		(layers "F.Cu" "B.Cu")
		(net "GND")
	)
	(via
		(at 265.471402 -213.4616)
		(size 0.5588)
		(drill 0.3048)
		(layers "F.Cu" "B.Cu")
		(net "GND")
	)
	(via
		(at 59.854846 -297.435016)
		(size 0.5588)
		(drill 0.3048)
		(layers "F.Cu" "B.Cu")
		(net "GND")
	)
	(via
		(at 122.954796 -164.654992)
		(size 0.5588)
		(drill 0.3048)
		(layers "F.Cu" "B.Cu")
		(net "GND")
	)
	(via
		(at 108.961682 -347.548962)
		(size 0.7112)
		(drill 0.4064)
		(layers "F.Cu" "B.Cu")
		(net "GND")
	)
	(via
		(at 453.632824 -79.784956)
		(size 0.5588)
		(drill 0.3048)
		(layers "F.Cu" "B.Cu")
		(net "GND")
	)
	(via
		(at 121.92 -325.12)
		(size 0.5588)
		(drill 0.3048)
		(layers "F.Cu" "B.Cu")
		(net "GND")
	)
	(via
		(at 235.761276 -350.51873)
		(size 0.5588)
		(drill 0.3048)
		(layers "F.Cu" "B.Cu")
		(net "GND")
	)
	(via
		(at 419.161976 -167.829992)
		(size 0.5588)
		(drill 0.3048)
		(layers "F.Cu" "B.Cu")
		(net "GND")
	)
	(via
		(at 266.7254 -102.2604)
		(size 0.5588)
		(drill 0.3048)
		(layers "F.Cu" "B.Cu")
		(net "GND")
	)
	(via
		(at 284.547056 37.403024)
		(size 0.7112)
		(drill 0.4064)
		(layers "F.Cu" "B.Cu")
		(net "GND")
	)
	(via
		(at 1.397 -267.078968)
		(size 0.7112)
		(drill 0.4064)
		(layers "F.Cu" "B.Cu")
		(net "GND")
	)
	(via
		(at 490.053122 -156.59735)
		(size 0.7112)
		(drill 0.4064)
		(layers "F.Cu" "B.Cu")
		(net "GND")
	)
	(via
		(at 186.055 -297.435016)
		(size 0.5588)
		(drill 0.3048)
		(layers "F.Cu" "B.Cu")
		(net "GND")
	)
	(via
		(at 325.654924 -299.975016)
		(size 0.5588)
		(drill 0.3048)
		(layers "F.Cu" "B.Cu")
		(net "GND")
	)
	(via
		(at 28.3972 -250.7488)
		(size 0.5588)
		(drill 0.3048)
		(layers "F.Cu" "B.Cu")
		(net "GND")
	)
	(via
		(at 392.43 -115.57)
		(size 0.5588)
		(drill 0.3048)
		(layers "F.Cu" "B.Cu")
		(net "GND")
	)
	(via
		(at 104.756712 -130.122676)
		(size 0.5588)
		(drill 0.3048)
		(layers "F.Cu" "B.Cu")
		(net "GND")
	)
	(via
		(at 109.22 -138.557)
		(size 0.5588)
		(drill 0.3048)
		(layers "F.Cu" "B.Cu")
		(net "GND")
	)
	(via
		(at 416.56 -91.44)
		(size 0.5588)
		(drill 0.3048)
		(layers "F.Cu" "B.Cu")
		(net "GND")
	)
	(via
		(at 426.72 -314.96)
		(size 0.5588)
		(drill 0.3048)
		(layers "F.Cu" "B.Cu")
		(net "GND")
	)
	(via
		(at 288.911284 -339.705188)
		(size 0.6604)
		(drill 0.3556)
		(layers "F.Cu" "B.Cu")
		(net "GND")
	)
	(via
		(at 431.8 -10.16)
		(size 0.5588)
		(drill 0.3048)
		(layers "F.Cu" "B.Cu")
		(net "GND")
	)
	(via
		(at 396.24 -115.57)
		(size 0.5588)
		(drill 0.3048)
		(layers "F.Cu" "B.Cu")
		(net "GND")
	)
	(via
		(at 477.52 -35.56)
		(size 0.5588)
		(drill 0.3048)
		(layers "F.Cu" "B.Cu")
		(net "GND")
	)
	(via
		(at 86.36 -5.08)
		(size 0.5588)
		(drill 0.3048)
		(layers "F.Cu" "B.Cu")
		(net "GND")
	)
	(via
		(at 1.397 -319.148968)
		(size 0.7112)
		(drill 0.4064)
		(layers "F.Cu" "B.Cu")
		(net "GND")
	)
	(via
		(at 469.516714 -208.225898)
		(size 0.5588)
		(drill 0.3048)
		(layers "F.Cu" "B.Cu")
		(net "GND")
	)
	(via
		(at 159.352996 -347.802962)
		(size 0.7112)
		(drill 0.4064)
		(layers "F.Cu" "B.Cu")
		(net "GND")
	)
	(via
		(at 55.88 -5.08)
		(size 0.5588)
		(drill 0.3048)
		(layers "F.Cu" "B.Cu")
		(net "GND")
	)
	(via
		(at 139.950698 -66.75374)
		(size 0.5588)
		(drill 0.3048)
		(layers "F.Cu" "B.Cu")
		(net "GND")
	)
	(via
		(at 246.447056 37.403024)
		(size 0.7112)
		(drill 0.4064)
		(layers "F.Cu" "B.Cu")
		(net "GND")
	)
	(via
		(at 358.983026 -266.035028)
		(size 0.5588)
		(drill 0.3048)
		(layers "F.Cu" "B.Cu")
		(net "GND")
	)
	(via
		(at 447.163444 -55.230014)
		(size 0.5588)
		(drill 0.3048)
		(layers "F.Cu" "B.Cu")
		(net "GND")
	)
	(via
		(at 30.4292 -248.7168)
		(size 0.5588)
		(drill 0.3048)
		(layers "F.Cu" "B.Cu")
		(net "GND")
	)
	(via
		(at 1.397 -160.398968)
		(size 0.7112)
		(drill 0.4064)
		(layers "F.Cu" "B.Cu")
		(net "GND")
	)
	(via
		(at 396.60195 -191.113918)
		(size 0.5588)
		(drill 0.3048)
		(layers "F.Cu" "B.Cu")
		(net "GND")
	)
	(via
		(at 75.656948 -179.683918)
		(size 0.5588)
		(drill 0.3048)
		(layers "F.Cu" "B.Cu")
		(net "GND")
	)
	(via
		(at 111.76 -335.28)
		(size 0.5588)
		(drill 0.3048)
		(layers "F.Cu" "B.Cu")
		(net "GND")
	)
	(via
		(at 1.397 -344.548968)
		(size 0.7112)
		(drill 0.4064)
		(layers "F.Cu" "B.Cu")
		(net "GND")
	)
	(via
		(at 66.04 -5.08)
		(size 0.5588)
		(drill 0.3048)
		(layers "F.Cu" "B.Cu")
		(net "GND")
	)
	(via
		(at 1.397 -112.138968)
		(size 0.7112)
		(drill 0.4064)
		(layers "F.Cu" "B.Cu")
		(net "GND")
	)
	(via
		(at 490.053122 -42.29735)
		(size 0.7112)
		(drill 0.4064)
		(layers "F.Cu" "B.Cu")
		(net "GND")
	)
	(via
		(at 154.504898 -177.354992)
		(size 0.5588)
		(drill 0.3048)
		(layers "F.Cu" "B.Cu")
		(net "GND")
	)
	(via
		(at 465.58962 -1.397)
		(size 0.7112)
		(drill 0.4064)
		(layers "F.Cu" "B.Cu")
		(net "GND")
	)
	(via
		(at 1.397 -114.678968)
		(size 0.7112)
		(drill 0.4064)
		(layers "F.Cu" "B.Cu")
		(net "GND")
	)
	(via
		(at 106.299 -298.9072)
		(size 0.5588)
		(drill 0.3048)
		(layers "F.Cu" "B.Cu")
		(net "GND")
	)
	(via
		(at 452.12 -116.84)
		(size 0.5588)
		(drill 0.3048)
		(layers "F.Cu" "B.Cu")
		(net "GND")
	)
	(via
		(at 285.5214 -285.7754)
		(size 0.5588)
		(drill 0.3048)
		(layers "F.Cu" "B.Cu")
		(net "GND")
	)
	(via
		(at 75.656948 -64.683894)
		(size 0.5588)
		(drill 0.3048)
		(layers "F.Cu" "B.Cu")
		(net "GND")
	)
	(via
		(at 261.231888 -212.046566)
		(size 0.5588)
		(drill 0.3048)
		(layers "F.Cu" "B.Cu")
		(net "GND")
	)
	(via
		(at 30.48 -30.48)
		(size 0.5588)
		(drill 0.3048)
		(layers "F.Cu" "B.Cu")
		(net "GND")
	)
	(via
		(at 490.053122 -274.031202)
		(size 0.7112)
		(drill 0.4064)
		(layers "F.Cu" "B.Cu")
		(net "GND")
	)
	(via
		(at 425.57065 -67.925696)
		(size 0.5588)
		(drill 0.3048)
		(layers "F.Cu" "B.Cu")
		(net "GND")
	)
	(via
		(at 175.043084 -1.397)
		(size 0.7112)
		(drill 0.4064)
		(layers "F.Cu" "B.Cu")
		(net "GND")
	)
	(via
		(at 298.91609 -157.209236)
		(size 0.5588)
		(drill 0.3048)
		(layers "F.Cu" "B.Cu")
		(net "GND")
	)
	(via
		(at 181.1909 -164.443918)
		(size 0.5588)
		(drill 0.3048)
		(layers "F.Cu" "B.Cu")
		(net "GND")
	)
	(via
		(at 60.835032 -1.397)
		(size 0.7112)
		(drill 0.4064)
		(layers "F.Cu" "B.Cu")
		(net "GND")
	)
	(via
		(at 39.04107 -189.187074)
		(size 0.5588)
		(drill 0.3048)
		(layers "F.Cu" "B.Cu")
		(net "GND")
	)
	(via
		(at 333.502 -306.113942)
		(size 0.5588)
		(drill 0.3048)
		(layers "F.Cu" "B.Cu")
		(net "GND")
	)
	(via
		(at 387.294882 -347.802962)
		(size 0.7112)
		(drill 0.4064)
		(layers "F.Cu" "B.Cu")
		(net "GND")
	)
	(via
		(at 276.376892 -419.803072)
		(size 0.7112)
		(drill 0.4064)
		(layers "F.Cu" "B.Cu")
		(net "GND")
	)
	(via
		(at 487.624882 -347.802962)
		(size 0.7112)
		(drill 0.4064)
		(layers "F.Cu" "B.Cu")
		(net "GND")
	)
	(via
		(at 153.361898 -285.230062)
		(size 0.5588)
		(drill 0.3048)
		(layers "F.Cu" "B.Cu")
		(net "GND")
	)
	(via
		(at 262.868664 22.329902)
		(size 0.5588)
		(drill 0.3048)
		(layers "F.Cu" "B.Cu")
		(net "GND")
	)
	(via
		(at 402.08962 -131.42087)
		(size 0.5588)
		(drill 0.3048)
		(layers "F.Cu" "B.Cu")
		(net "GND")
	)
	(via
		(at 439.364882 -347.802962)
		(size 0.7112)
		(drill 0.4064)
		(layers "F.Cu" "B.Cu")
		(net "GND")
	)
	(via
		(at 437.433974 -256.299716)
		(size 0.5588)
		(drill 0.3048)
		(layers "F.Cu" "B.Cu")
		(net "GND")
	)
	(via
		(at 1.397 -68.958968)
		(size 0.7112)
		(drill 0.4064)
		(layers "F.Cu" "B.Cu")
		(net "GND")
	)
	(via
		(at 19.9644 -248.9962)
		(size 0.7112)
		(drill 0.4064)
		(layers "F.Cu" "B.Cu")
		(net "GND")
	)
	(via
		(at 154.504898 -279.655016)
		(size 0.5588)
		(drill 0.3048)
		(layers "F.Cu" "B.Cu")
		(net "GND")
	)
	(via
		(at 65.915032 -1.397)
		(size 0.7112)
		(drill 0.4064)
		(layers "F.Cu" "B.Cu")
		(net "GND")
	)
	(via
		(at 91.404948 -67.434968)
		(size 0.5588)
		(drill 0.3048)
		(layers "F.Cu" "B.Cu")
		(net "GND")
	)
	(via
		(at 1.397 -53.718968)
		(size 0.7112)
		(drill 0.4064)
		(layers "F.Cu" "B.Cu")
		(net "GND")
	)
	(via
		(at 436.88 -30.48)
		(size 0.5588)
		(drill 0.3048)
		(layers "F.Cu" "B.Cu")
		(net "GND")
	)
	(via
		(at 377.134882 -347.802962)
		(size 0.7112)
		(drill 0.4064)
		(layers "F.Cu" "B.Cu")
		(net "GND")
	)
	(via
		(at 369.824 -265.176)
		(size 0.5588)
		(drill 0.3048)
		(layers "F.Cu" "B.Cu")
		(net "GND")
	)
	(via
		(at 266.319 -87.884)
		(size 0.5588)
		(drill 0.3048)
		(layers "F.Cu" "B.Cu")
		(net "GND")
	)
	(via
		(at 259.9182 11.2268)
		(size 0.5588)
		(drill 0.3048)
		(layers "F.Cu" "B.Cu")
		(net "GND")
	)
	(via
		(at 10.035032 -1.397)
		(size 0.7112)
		(drill 0.4064)
		(layers "F.Cu" "B.Cu")
		(net "GND")
	)
	(via
		(at 479.55962 -1.397)
		(size 0.7112)
		(drill 0.4064)
		(layers "F.Cu" "B.Cu")
		(net "GND")
	)
	(via
		(at 202.785218 -158.0896)
		(size 0.5588)
		(drill 0.3048)
		(layers "F.Cu" "B.Cu")
		(net "GND")
	)
	(via
		(at 30.607 -133.096)
		(size 0.5588)
		(drill 0.3048)
		(layers "F.Cu" "B.Cu")
		(net "GND")
	)
	(via
		(at 1.397 -264.538968)
		(size 0.7112)
		(drill 0.4064)
		(layers "F.Cu" "B.Cu")
		(net "GND")
	)
	(via
		(at 153.361898 -52.829968)
		(size 0.5588)
		(drill 0.3048)
		(layers "F.Cu" "B.Cu")
		(net "GND")
	)
	(via
		(at 255.337056 37.403024)
		(size 0.7112)
		(drill 0.4064)
		(layers "F.Cu" "B.Cu")
		(net "GND")
	)
	(via
		(at 306.011072 -16.349472)
		(size 0.5588)
		(drill 0.3048)
		(layers "F.Cu" "B.Cu")
		(net "GND")
	)
	(via
		(at 477.01962 -1.397)
		(size 0.7112)
		(drill 0.4064)
		(layers "F.Cu" "B.Cu")
		(net "GND")
	)
	(via
		(at 300.934882 -347.802962)
		(size 0.7112)
		(drill 0.4064)
		(layers "F.Cu" "B.Cu")
		(net "GND")
	)
	(via
		(at 300.37786 -64.614552)
		(size 0.5588)
		(drill 0.3048)
		(layers "F.Cu" "B.Cu")
		(net "GND")
	)
	(via
		(at 139.750038 -31.624778)
		(size 0.6604)
		(drill 0.3556)
		(layers "F.Cu" "B.Cu")
		(net "GND")
	)
	(via
		(at 1.397 -340.738968)
		(size 0.7112)
		(drill 0.4064)
		(layers "F.Cu" "B.Cu")
		(net "GND")
	)
	(via
		(at 154.272996 -347.802962)
		(size 0.7112)
		(drill 0.4064)
		(layers "F.Cu" "B.Cu")
		(net "GND")
	)
	(via
		(at 473.545408 -292.940232)
		(size 0.5588)
		(drill 0.3048)
		(layers "F.Cu" "B.Cu")
		(net "GND")
	)
	(via
		(at 490.053122 -318.481202)
		(size 0.7112)
		(drill 0.4064)
		(layers "F.Cu" "B.Cu")
		(net "GND")
	)
	(via
		(at 490.053122 -165.48735)
		(size 0.7112)
		(drill 0.4064)
		(layers "F.Cu" "B.Cu")
		(net "GND")
	)
	(via
		(at 1.397 -128.648968)
		(size 0.7112)
		(drill 0.4064)
		(layers "F.Cu" "B.Cu")
		(net "GND")
	)
	(via
		(at 1.397 -343.278968)
		(size 0.7112)
		(drill 0.4064)
		(layers "F.Cu" "B.Cu")
		(net "GND")
	)
	(via
		(at 1.397 -198.498968)
		(size 0.7112)
		(drill 0.4064)
		(layers "F.Cu" "B.Cu")
		(net "GND")
	)
	(via
		(at 1.397 -283.588968)
		(size 0.7112)
		(drill 0.4064)
		(layers "F.Cu" "B.Cu")
		(net "GND")
	)
	(via
		(at 473.802202 -254.66675)
		(size 0.5588)
		(drill 0.3048)
		(layers "F.Cu" "B.Cu")
		(net "GND")
	)
	(via
		(at 363.020102 -306.113942)
		(size 0.5588)
		(drill 0.3048)
		(layers "F.Cu" "B.Cu")
		(net "GND")
	)
	(via
		(at 220.386402 -207.983074)
		(size 0.5588)
		(drill 0.3048)
		(layers "F.Cu" "B.Cu")
		(net "GND")
	)
	(via
		(at 122.954796 -182.434992)
		(size 0.5588)
		(drill 0.3048)
		(layers "F.Cu" "B.Cu")
		(net "GND")
	)
	(via
		(at 1.397 -62.608968)
		(size 0.7112)
		(drill 0.4064)
		(layers "F.Cu" "B.Cu")
		(net "GND")
	)
	(via
		(at 282.726892 -419.803072)
		(size 0.7112)
		(drill 0.4064)
		(layers "F.Cu" "B.Cu")
		(net "GND")
	)
	(via
		(at 117.851682 -347.548962)
		(size 0.7112)
		(drill 0.4064)
		(layers "F.Cu" "B.Cu")
		(net "GND")
	)
	(via
		(at 1.397 -202.308968)
		(size 0.7112)
		(drill 0.4064)
		(layers "F.Cu" "B.Cu")
		(net "GND")
	)
	(via
		(at 144.852898 -174.603918)
		(size 0.5588)
		(drill 0.3048)
		(layers "F.Cu" "B.Cu")
		(net "GND")
	)
	(via
		(at 201.397108 -386.832856)
		(size 0.7112)
		(drill 0.4064)
		(layers "F.Cu" "B.Cu")
		(net "GND")
	)
	(via
		(at 136.149842 -31.624778)
		(size 0.6604)
		(drill 0.3556)
		(layers "F.Cu" "B.Cu")
		(net "GND")
	)
	(via
		(at 221.651068 28.08605)
		(size 0.7112)
		(drill 0.4064)
		(layers "F.Cu" "B.Cu")
		(net "GND")
	)
	(via
		(at 98.044 -53.086)
		(size 0.5588)
		(drill 0.3048)
		(layers "F.Cu" "B.Cu")
		(net "GND")
	)
	(via
		(at 417.774882 -347.802962)
		(size 0.7112)
		(drill 0.4064)
		(layers "F.Cu" "B.Cu")
		(net "GND")
	)
	(via
		(at 302.611028 -1.397)
		(size 0.7112)
		(drill 0.4064)
		(layers "F.Cu" "B.Cu")
		(net "GND")
	)
	(via
		(at 7.791704 -168.596056)
		(size 0.5588)
		(drill 0.3048)
		(layers "F.Cu" "B.Cu")
		(net "GND")
	)
	(via
		(at 426.72 -111.76)
		(size 0.5588)
		(drill 0.3048)
		(layers "F.Cu" "B.Cu")
		(net "GND")
	)
	(via
		(at 270.577056 37.403024)
		(size 0.7112)
		(drill 0.4064)
		(layers "F.Cu" "B.Cu")
		(net "GND")
	)
	(via
		(at 490.053122 -212.47735)
		(size 0.7112)
		(drill 0.4064)
		(layers "F.Cu" "B.Cu")
		(net "GND")
	)
	(via
		(at 490.053122 -168.02735)
		(size 0.7112)
		(drill 0.4064)
		(layers "F.Cu" "B.Cu")
		(net "GND")
	)
	(via
		(at 54.753002 -254.31115)
		(size 0.5588)
		(drill 0.3048)
		(layers "F.Cu" "B.Cu")
		(net "GND")
	)
	(via
		(at 306.011072 -21.683472)
		(size 0.5588)
		(drill 0.3048)
		(layers "F.Cu" "B.Cu")
		(net "GND")
	)
	(via
		(at 55.790846 -306.240942)
		(size 0.5588)
		(drill 0.3048)
		(layers "F.Cu" "B.Cu")
		(net "GND")
	)
	(via
		(at 325.527162 -51.64836)
		(size 0.5588)
		(drill 0.3048)
		(layers "F.Cu" "B.Cu")
		(net "GND")
	)
	(via
		(at 88.138 -200.279)
		(size 0.5588)
		(drill 0.3048)
		(layers "F.Cu" "B.Cu")
		(net "GND")
	)
	(via
		(at 487.68 -25.4)
		(size 0.5588)
		(drill 0.3048)
		(layers "F.Cu" "B.Cu")
		(net "GND")
	)
	(via
		(at 8.89 -113.411)
		(size 0.5588)
		(drill 0.3048)
		(layers "F.Cu" "B.Cu")
		(net "GND")
	)
	(via
		(at 47.907956 -150.238714)
		(size 0.5588)
		(drill 0.3048)
		(layers "F.Cu" "B.Cu")
		(net "GND")
	)
	(via
		(at 9.906 -164.084)
		(size 0.5588)
		(drill 0.3048)
		(layers "F.Cu" "B.Cu")
		(net "GND")
	)
	(via
		(at 482.261926 -52.829968)
		(size 0.5588)
		(drill 0.3048)
		(layers "F.Cu" "B.Cu")
		(net "GND")
	)
	(via
		(at 356.87 -116.84)
		(size 0.5588)
		(drill 0.3048)
		(layers "F.Cu" "B.Cu")
		(net "GND")
	)
	(via
		(at 331.290422 -42.140886)
		(size 0.5588)
		(drill 0.3048)
		(layers "F.Cu" "B.Cu")
		(net "GND")
	)
	(via
		(at 87.94623 -14.92123)
		(size 0.5588)
		(drill 0.3048)
		(layers "F.Cu" "B.Cu")
		(net "GND")
	)
	(via
		(at 1.397 -150.238968)
		(size 0.7112)
		(drill 0.4064)
		(layers "F.Cu" "B.Cu")
		(net "GND")
	)
	(via
		(at 108.712 -251.079)
		(size 0.5588)
		(drill 0.3048)
		(layers "F.Cu" "B.Cu")
		(net "GND")
	)
	(via
		(at 250.625102 29.35478)
		(size 0.5588)
		(drill 0.3048)
		(layers "F.Cu" "B.Cu")
		(net "GND")
	)
	(via
		(at 1.397 -176.908968)
		(size 0.7112)
		(drill 0.4064)
		(layers "F.Cu" "B.Cu")
		(net "GND")
	)
	(via
		(at 28.304998 -42.034968)
		(size 0.5588)
		(drill 0.3048)
		(layers "F.Cu" "B.Cu")
		(net "GND")
	)
	(via
		(at 121.92 -335.28)
		(size 0.5588)
		(drill 0.3048)
		(layers "F.Cu" "B.Cu")
		(net "GND")
	)
	(via
		(at 10.16 -238.76)
		(size 0.5588)
		(drill 0.3048)
		(layers "F.Cu" "B.Cu")
		(net "GND")
	)
	(via
		(at 455.874882 -347.802962)
		(size 0.7112)
		(drill 0.4064)
		(layers "F.Cu" "B.Cu")
		(net "GND")
	)
	(via
		(at 91.404948 -45.844968)
		(size 0.5588)
		(drill 0.3048)
		(layers "F.Cu" "B.Cu")
		(net "GND")
	)
	(via
		(at 325.654924 -177.354992)
		(size 0.5588)
		(drill 0.3048)
		(layers "F.Cu" "B.Cu")
		(net "GND")
	)
	(via
		(at 161.163 -19.558)
		(size 0.5588)
		(drill 0.3048)
		(layers "F.Cu" "B.Cu")
		(net "GND")
	)
	(via
		(at 40.64 -71.12)
		(size 0.5588)
		(drill 0.3048)
		(layers "F.Cu" "B.Cu")
		(net "GND")
	)
	(via
		(at 88.9 -121.92)
		(size 0.5588)
		(drill 0.3048)
		(layers "F.Cu" "B.Cu")
		(net "GND")
	)
	(via
		(at 463.494882 -347.802962)
		(size 0.7112)
		(drill 0.4064)
		(layers "F.Cu" "B.Cu")
		(net "GND")
	)
	(via
		(at 217.62974 -18.110962)
		(size 0.5588)
		(drill 0.3048)
		(layers "F.Cu" "B.Cu")
		(net "GND")
	)
	(via
		(at 431.8 -335.28)
		(size 0.5588)
		(drill 0.3048)
		(layers "F.Cu" "B.Cu")
		(net "GND")
	)
	(via
		(at 1.397 -217.548968)
		(size 0.7112)
		(drill 0.4064)
		(layers "F.Cu" "B.Cu")
		(net "GND")
	)
	(via
		(at 68.58 -45.593)
		(size 0.5588)
		(drill 0.3048)
		(layers "F.Cu" "B.Cu")
		(net "GND")
	)
	(via
		(at 304.744882 -347.802962)
		(size 0.7112)
		(drill 0.4064)
		(layers "F.Cu" "B.Cu")
		(net "GND")
	)
	(via
		(at 481.274882 -347.802962)
		(size 0.7112)
		(drill 0.4064)
		(layers "F.Cu" "B.Cu")
		(net "GND")
	)
	(via
		(at 283.996892 -419.803072)
		(size 0.7112)
		(drill 0.4064)
		(layers "F.Cu" "B.Cu")
		(net "GND")
	)
	(via
		(at 192.350898 -355.821742)
		(size 0.7112)
		(drill 0.4064)
		(layers "F.Cu" "B.Cu")
		(net "GND")
	)
	(via
		(at 22.86 -318.135)
		(size 0.5588)
		(drill 0.3048)
		(layers "F.Cu" "B.Cu")
		(net "GND")
	)
	(via
		(at 490.053122 -343.881202)
		(size 0.7112)
		(drill 0.4064)
		(layers "F.Cu" "B.Cu")
		(net "GND")
	)
	(via
		(at 236.871256 -341.9094)
		(size 0.5588)
		(drill 0.3048)
		(layers "F.Cu" "B.Cu")
		(net "GND")
	)
	(via
		(at 1.397 -143.888968)
		(size 0.7112)
		(drill 0.4064)
		(layers "F.Cu" "B.Cu")
		(net "GND")
	)
	(via
		(at 416.56 -86.36)
		(size 0.5588)
		(drill 0.3048)
		(layers "F.Cu" "B.Cu")
		(net "GND")
	)
	(via
		(at 83.82 -243.84)
		(size 0.5588)
		(drill 0.3048)
		(layers "F.Cu" "B.Cu")
		(net "GND")
	)
	(via
		(at 308.602888 -408.341068)
		(size 0.7112)
		(drill 0.4064)
		(layers "F.Cu" "B.Cu")
		(net "GND")
	)
	(via
		(at 351.734882 -347.802962)
		(size 0.7112)
		(drill 0.4064)
		(layers "F.Cu" "B.Cu")
		(net "GND")
	)
	(via
		(at 85.766148 -70.322694)
		(size 0.5588)
		(drill 0.3048)
		(layers "F.Cu" "B.Cu")
		(net "GND")
	)
	(via
		(at 1.397 -301.368968)
		(size 0.7112)
		(drill 0.4064)
		(layers "F.Cu" "B.Cu")
		(net "GND")
	)
	(via
		(at 378.233432 -284.905196)
		(size 0.5588)
		(drill 0.3048)
		(layers "F.Cu" "B.Cu")
		(net "GND")
	)
	(via
		(at 490.053122 -227.71735)
		(size 0.7112)
		(drill 0.4064)
		(layers "F.Cu" "B.Cu")
		(net "GND")
	)
	(via
		(at 428.498 -229.997)
		(size 0.5588)
		(drill 0.3048)
		(layers "F.Cu" "B.Cu")
		(net "GND")
	)
	(via
		(at 186.055 -42.034968)
		(size 0.5588)
		(drill 0.3048)
		(layers "F.Cu" "B.Cu")
		(net "GND")
	)
	(via
		(at 184.912 -167.829992)
		(size 0.5588)
		(drill 0.3048)
		(layers "F.Cu" "B.Cu")
		(net "GND")
	)
	(via
		(at 18.791682 -347.548962)
		(size 0.7112)
		(drill 0.4064)
		(layers "F.Cu" "B.Cu")
		(net "GND")
	)
	(via
		(at 142.604998 -169.015918)
		(size 0.5588)
		(drill 0.3048)
		(layers "F.Cu" "B.Cu")
		(net "GND")
	)
	(via
		(at 390.532874 -194.78498)
		(size 0.5588)
		(drill 0.3048)
		(layers "F.Cu" "B.Cu")
		(net "GND")
	)
	(via
		(at 490.053122 -183.26735)
		(size 0.7112)
		(drill 0.4064)
		(layers "F.Cu" "B.Cu")
		(net "GND")
	)
	(via
		(at 168.13911 -26.968958)
		(size 0.5588)
		(drill 0.3048)
		(layers "F.Cu" "B.Cu")
		(net "GND")
	)
	(via
		(at 306.014882 -347.802962)
		(size 0.7112)
		(drill 0.4064)
		(layers "F.Cu" "B.Cu")
		(net "GND")
	)
	(via
		(at 231.267 34.925)
		(size 0.5588)
		(drill 0.3048)
		(layers "F.Cu" "B.Cu")
		(net "GND")
	)
	(via
		(at 98.801682 -347.548962)
		(size 0.7112)
		(drill 0.4064)
		(layers "F.Cu" "B.Cu")
		(net "GND")
	)
	(via
		(at 490.053122 -293.081202)
		(size 0.7112)
		(drill 0.4064)
		(layers "F.Cu" "B.Cu")
		(net "GND")
	)
	(via
		(at 59.854846 -272.035016)
		(size 0.5588)
		(drill 0.3048)
		(layers "F.Cu" "B.Cu")
		(net "GND")
	)
	(via
		(at 92.451682 -347.548962)
		(size 0.7112)
		(drill 0.4064)
		(layers "F.Cu" "B.Cu")
		(net "GND")
	)
	(via
		(at 375.719848 -136.045448)
		(size 0.5588)
		(drill 0.3048)
		(layers "F.Cu" "B.Cu")
		(net "GND")
	)
	(via
		(at 1.397 -129.918968)
		(size 0.7112)
		(drill 0.4064)
		(layers "F.Cu" "B.Cu")
		(net "GND")
	)
	(via
		(at 396.85595 -182.223918)
		(size 0.5588)
		(drill 0.3048)
		(layers "F.Cu" "B.Cu")
		(net "GND")
	)
	(via
		(at 1.397 -127.378968)
		(size 0.7112)
		(drill 0.4064)
		(layers "F.Cu" "B.Cu")
		(net "GND")
	)
	(via
		(at 380.944882 -347.802962)
		(size 0.7112)
		(drill 0.4064)
		(layers "F.Cu" "B.Cu")
		(net "GND")
	)
	(via
		(at 216.906094 -13.401548)
		(size 0.5588)
		(drill 0.3048)
		(layers "F.Cu" "B.Cu")
		(net "GND")
	)
	(via
		(at 357.205026 -164.654992)
		(size 0.5588)
		(drill 0.3048)
		(layers "F.Cu" "B.Cu")
		(net "GND")
	)
	(via
		(at 20.061682 -347.548962)
		(size 0.7112)
		(drill 0.4064)
		(layers "F.Cu" "B.Cu")
		(net "GND")
	)
	(via
		(at 416.052 -187.96)
		(size 0.5588)
		(drill 0.3048)
		(layers "F.Cu" "B.Cu")
		(net "GND")
	)
	(via
		(at 475.558104 -232.678986)
		(size 0.5588)
		(drill 0.3048)
		(layers "F.Cu" "B.Cu")
		(net "GND")
	)
	(via
		(at 187.833 -309.785004)
		(size 0.5588)
		(drill 0.3048)
		(layers "F.Cu" "B.Cu")
		(net "GND")
	)
	(via
		(at 5.08 -30.48)
		(size 0.5588)
		(drill 0.3048)
		(layers "F.Cu" "B.Cu")
		(net "GND")
	)
	(via
		(at 426.72 -320.04)
		(size 0.5588)
		(drill 0.3048)
		(layers "F.Cu" "B.Cu")
		(net "GND")
	)
	(via
		(at 46.355 -146.1008)
		(size 0.5588)
		(drill 0.3048)
		(layers "F.Cu" "B.Cu")
		(net "GND")
	)
	(via
		(at 490.053122 -180.72735)
		(size 0.7112)
		(drill 0.4064)
		(layers "F.Cu" "B.Cu")
		(net "GND")
	)
	(via
		(at 413.308038 -290.333176)
		(size 0.5588)
		(drill 0.3048)
		(layers "F.Cu" "B.Cu")
		(net "GND")
	)
	(via
		(at 490.053122 -220.09735)
		(size 0.7112)
		(drill 0.4064)
		(layers "F.Cu" "B.Cu")
		(net "GND")
	)
	(via
		(at 451.854824 -297.435016)
		(size 0.5588)
		(drill 0.3048)
		(layers "F.Cu" "B.Cu")
		(net "GND")
	)
	(via
		(at 262.017002 -216.523062)
		(size 0.5588)
		(drill 0.3048)
		(layers "F.Cu" "B.Cu")
		(net "GND")
	)
	(via
		(at 99.06 -132.08)
		(size 0.5588)
		(drill 0.3048)
		(layers "F.Cu" "B.Cu")
		(net "GND")
	)
	(via
		(at 476.574104 -232.678986)
		(size 0.5588)
		(drill 0.3048)
		(layers "F.Cu" "B.Cu")
		(net "GND")
	)
	(via
		(at 263.398 -271.0434)
		(size 0.5588)
		(drill 0.3048)
		(layers "F.Cu" "B.Cu")
		(net "GND")
	)
	(via
		(at 483.814882 -347.802962)
		(size 0.7112)
		(drill 0.4064)
		(layers "F.Cu" "B.Cu")
		(net "GND")
	)
	(via
		(at 55.88 -330.2)
		(size 0.5588)
		(drill 0.3048)
		(layers "F.Cu" "B.Cu")
		(net "GND")
	)
	(via
		(at 447.04 -5.08)
		(size 0.5588)
		(drill 0.3048)
		(layers "F.Cu" "B.Cu")
		(net "GND")
	)
	(via
		(at 333.502 -191.113918)
		(size 0.5588)
		(drill 0.3048)
		(layers "F.Cu" "B.Cu")
		(net "GND")
	)
	(via
		(at 94.991682 -347.548962)
		(size 0.7112)
		(drill 0.4064)
		(layers "F.Cu" "B.Cu")
		(net "GND")
	)
	(via
		(at 303.344072 -185.4962)
		(size 0.5588)
		(drill 0.3048)
		(layers "F.Cu" "B.Cu")
		(net "GND")
	)
	(via
		(at 378.549916 -31.624778)
		(size 0.6604)
		(drill 0.3556)
		(layers "F.Cu" "B.Cu")
		(net "GND")
	)
	(via
		(at 284.266386 -223.04502)
		(size 0.5588)
		(drill 0.3048)
		(layers "F.Cu" "B.Cu")
		(net "GND")
	)
	(via
		(at 1.397 -132.458968)
		(size 0.7112)
		(drill 0.4064)
		(layers "F.Cu" "B.Cu")
		(net "GND")
	)
	(via
		(at 50.583846 -47.615094)
		(size 0.5588)
		(drill 0.3048)
		(layers "F.Cu" "B.Cu")
		(net "GND")
	)
	(via
		(at 443.6364 -61.102494)
		(size 0.5588)
		(drill 0.3048)
		(layers "F.Cu" "B.Cu")
		(net "GND")
	)
	(via
		(at 451.854824 -59.814968)
		(size 0.5588)
		(drill 0.3048)
		(layers "F.Cu" "B.Cu")
		(net "GND")
	)
	(via
		(at 341.376 -250.825)
		(size 0.5588)
		(drill 0.3048)
		(layers "F.Cu" "B.Cu")
		(net "GND")
	)
	(via
		(at 490.053122 -154.05735)
		(size 0.7112)
		(drill 0.4064)
		(layers "F.Cu" "B.Cu")
		(net "GND")
	)
	(via
		(at 363.020102 -191.113918)
		(size 0.5588)
		(drill 0.3048)
		(layers "F.Cu" "B.Cu")
		(net "GND")
	)
	(via
		(at 294.302942 -358.665018)
		(size 0.7112)
		(drill 0.4064)
		(layers "F.Cu" "B.Cu")
		(net "GND")
	)
	(via
		(at 84.582 -153.416)
		(size 0.5588)
		(drill 0.3048)
		(layers "F.Cu" "B.Cu")
		(net "GND")
	)
	(via
		(at 106.421682 -347.548962)
		(size 0.7112)
		(drill 0.4064)
		(layers "F.Cu" "B.Cu")
		(net "GND")
	)
	(via
		(at 235.809536 -341.99449)
		(size 0.5588)
		(drill 0.3048)
		(layers "F.Cu" "B.Cu")
		(net "GND")
	)
	(via
		(at 64.262 -66.04)
		(size 0.5588)
		(drill 0.3048)
		(layers "F.Cu" "B.Cu")
		(net "GND")
	)
	(via
		(at 490.053122 -142.62735)
		(size 0.7112)
		(drill 0.4064)
		(layers "F.Cu" "B.Cu")
		(net "GND")
	)
	(via
		(at 181.864 -288.544)
		(size 0.5588)
		(drill 0.3048)
		(layers "F.Cu" "B.Cu")
		(net "GND")
	)
	(via
		(at 109.453934 -131.138676)
		(size 0.5588)
		(drill 0.3048)
		(layers "F.Cu" "B.Cu")
		(net "GND")
	)
	(via
		(at 411.48 -5.08)
		(size 0.5588)
		(drill 0.3048)
		(layers "F.Cu" "B.Cu")
		(net "GND")
	)
	(via
		(at 212.984334 -10.558272)
		(size 0.5588)
		(drill 0.3048)
		(layers "F.Cu" "B.Cu")
		(net "GND")
	)
	(via
		(at 490.053122 -126.11735)
		(size 0.7112)
		(drill 0.4064)
		(layers "F.Cu" "B.Cu")
		(net "GND")
	)
	(via
		(at 417.32962 -1.397)
		(size 0.7112)
		(drill 0.4064)
		(layers "F.Cu" "B.Cu")
		(net "GND")
	)
	(via
		(at 63.5 -332.74)
		(size 0.5588)
		(drill 0.3048)
		(layers "F.Cu" "B.Cu")
		(net "GND")
	)
	(via
		(at 338.171028 -1.397)
		(size 0.7112)
		(drill 0.4064)
		(layers "F.Cu" "B.Cu")
		(net "GND")
	)
	(via
		(at 340.711028 -1.397)
		(size 0.7112)
		(drill 0.4064)
		(layers "F.Cu" "B.Cu")
		(net "GND")
	)
	(via
		(at 35.56 -25.4)
		(size 0.5588)
		(drill 0.3048)
		(layers "F.Cu" "B.Cu")
		(net "GND")
	)
	(via
		(at 180.213 -227.203)
		(size 0.5588)
		(drill 0.3048)
		(layers "F.Cu" "B.Cu")
		(net "GND")
	)
	(via
		(at 99.139248 -60.238894)
		(size 0.5588)
		(drill 0.3048)
		(layers "F.Cu" "B.Cu")
		(net "GND")
	)
	(via
		(at 6.35 -236.22)
		(size 0.5588)
		(drill 0.3048)
		(layers "F.Cu" "B.Cu")
		(net "GND")
	)
	(via
		(at 365.704882 -347.802962)
		(size 0.7112)
		(drill 0.4064)
		(layers "F.Cu" "B.Cu")
		(net "GND")
	)
	(via
		(at 322.931028 -1.397)
		(size 0.7112)
		(drill 0.4064)
		(layers "F.Cu" "B.Cu")
		(net "GND")
	)
	(via
		(at 469.738202 -254.66675)
		(size 0.5588)
		(drill 0.3048)
		(layers "F.Cu" "B.Cu")
		(net "GND")
	)
	(via
		(at 174.0535 -282.872942)
		(size 0.5588)
		(drill 0.3048)
		(layers "F.Cu" "B.Cu")
		(net "GND")
	)
	(via
		(at 93.182948 -79.784956)
		(size 0.5588)
		(drill 0.3048)
		(layers "F.Cu" "B.Cu")
		(net "GND")
	)
	(via
		(at 306.856892 -419.803072)
		(size 0.7112)
		(drill 0.4064)
		(layers "F.Cu" "B.Cu")
		(net "GND")
	)
	(via
		(at 122.954796 -157.034992)
		(size 0.5588)
		(drill 0.3048)
		(layers "F.Cu" "B.Cu")
		(net "GND")
	)
	(via
		(at 308.602888 -389.291068)
		(size 0.7112)
		(drill 0.4064)
		(layers "F.Cu" "B.Cu")
		(net "GND")
	)
	(via
		(at 167.423084 -1.397)
		(size 0.7112)
		(drill 0.4064)
		(layers "F.Cu" "B.Cu")
		(net "GND")
	)
	(via
		(at 144.528286 -62.963298)
		(size 0.5588)
		(drill 0.3048)
		(layers "F.Cu" "B.Cu")
		(net "GND")
	)
	(via
		(at 449.07962 -1.397)
		(size 0.7112)
		(drill 0.4064)
		(layers "F.Cu" "B.Cu")
		(net "GND")
	)
	(via
		(at 425.485052 -297.604942)
		(size 0.5588)
		(drill 0.3048)
		(layers "F.Cu" "B.Cu")
		(net "GND")
	)
	(via
		(at 96.261682 -347.548962)
		(size 0.7112)
		(drill 0.4064)
		(layers "F.Cu" "B.Cu")
		(net "GND")
	)
	(via
		(at 451.854824 -177.354992)
		(size 0.5588)
		(drill 0.3048)
		(layers "F.Cu" "B.Cu")
		(net "GND")
	)
	(via
		(at 1.397 -85.468968)
		(size 0.7112)
		(drill 0.4064)
		(layers "F.Cu" "B.Cu")
		(net "GND")
	)
	(via
		(at 298.602908 9.548876)
		(size 0.7112)
		(drill 0.4064)
		(layers "F.Cu" "B.Cu")
		(net "GND")
	)
	(via
		(at 10.16 -142.24)
		(size 0.5588)
		(drill 0.3048)
		(layers "F.Cu" "B.Cu")
		(net "GND")
	)
	(via
		(at 257.782314 -239.612678)
		(size 0.5588)
		(drill 0.3048)
		(layers "F.Cu" "B.Cu")
		(net "GND")
	)
	(via
		(at 76.2 -10.16)
		(size 0.5588)
		(drill 0.3048)
		(layers "F.Cu" "B.Cu")
		(net "GND")
	)
	(via
		(at 1.397 -52.448968)
		(size 0.7112)
		(drill 0.4064)
		(layers "F.Cu" "B.Cu")
		(net "GND")
	)
	(via
		(at 325.654924 -157.034992)
		(size 0.5588)
		(drill 0.3048)
		(layers "F.Cu" "B.Cu")
		(net "GND")
	)
	(via
		(at 437.31434 -131.167886)
		(size 0.5588)
		(drill 0.3048)
		(layers "F.Cu" "B.Cu")
		(net "GND")
	)
	(via
		(at 333.501746 -27.24912)
		(size 0.5588)
		(drill 0.3048)
		(layers "F.Cu" "B.Cu")
		(net "GND")
	)
	(via
		(at 30.48 -228.6)
		(size 0.5588)
		(drill 0.3048)
		(layers "F.Cu" "B.Cu")
		(net "GND")
	)
	(via
		(at 232.777284 -263.001252)
		(size 0.5588)
		(drill 0.3048)
		(layers "F.Cu" "B.Cu")
		(net "GND")
	)
	(via
		(at 388.754874 -49.654968)
		(size 0.5588)
		(drill 0.3048)
		(layers "F.Cu" "B.Cu")
		(net "GND")
	)
	(via
		(at 434.086 -232.41)
		(size 0.5588)
		(drill 0.3048)
		(layers "F.Cu" "B.Cu")
		(net "GND")
	)
	(via
		(at 466.402674 -289.729926)
		(size 0.5588)
		(drill 0.3048)
		(layers "F.Cu" "B.Cu")
		(net "GND")
	)
	(via
		(at 440.69 -199.39)
		(size 0.5588)
		(drill 0.3048)
		(layers "F.Cu" "B.Cu")
		(net "GND")
	)
	(via
		(at 59.854846 -275.845016)
		(size 0.5588)
		(drill 0.3048)
		(layers "F.Cu" "B.Cu")
		(net "GND")
	)
	(via
		(at 479.340926 -306.240942)
		(size 0.5588)
		(drill 0.3048)
		(layers "F.Cu" "B.Cu")
		(net "GND")
	)
	(via
		(at 480.680522 -227.1649)
		(size 0.5588)
		(drill 0.3048)
		(layers "F.Cu" "B.Cu")
		(net "GND")
	)
	(via
		(at 241.031268 -247.56237)
		(size 0.5588)
		(drill 0.3048)
		(layers "F.Cu" "B.Cu")
		(net "GND")
	)
	(via
		(at 431.8 -30.48)
		(size 0.5588)
		(drill 0.3048)
		(layers "F.Cu" "B.Cu")
		(net "GND")
	)
	(via
		(at 9.779 -51.308)
		(size 0.5588)
		(drill 0.3048)
		(layers "F.Cu" "B.Cu")
		(net "GND")
	)
	(via
		(at 204.47 -302.641)
		(size 0.5588)
		(drill 0.3048)
		(layers "F.Cu" "B.Cu")
		(net "GND")
	)
	(via
		(at 395.20495 -271.315942)
		(size 0.5588)
		(drill 0.3048)
		(layers "F.Cu" "B.Cu")
		(net "GND")
	)
	(via
		(at 30.48 -260.35)
		(size 0.5588)
		(drill 0.3048)
		(layers "F.Cu" "B.Cu")
		(net "GND")
	)
	(via
		(at 116.84 -152.4)
		(size 0.5588)
		(drill 0.3048)
		(layers "F.Cu" "B.Cu")
		(net "GND")
	)
	(via
		(at 313.055 -137.414)
		(size 0.5588)
		(drill 0.3048)
		(layers "F.Cu" "B.Cu")
		(net "GND")
	)
	(via
		(at 4.445 -325.12)
		(size 0.5588)
		(drill 0.3048)
		(layers "F.Cu" "B.Cu")
		(net "GND")
	)
	(via
		(at 54.990746 -279.443942)
		(size 0.5588)
		(drill 0.3048)
		(layers "F.Cu" "B.Cu")
		(net "GND")
	)
	(via
		(at 472.164918 -156.078174)
		(size 0.5588)
		(drill 0.3048)
		(layers "F.Cu" "B.Cu")
		(net "GND")
	)
	(via
		(at 296.291 -161.29)
		(size 0.5588)
		(drill 0.3048)
		(layers "F.Cu" "B.Cu")
		(net "GND")
	)
	(via
		(at 49.289208 -258.868164)
		(size 0.5588)
		(drill 0.3048)
		(layers "F.Cu" "B.Cu")
		(net "GND")
	)
	(via
		(at 324.511924 -55.230014)
		(size 0.5588)
		(drill 0.3048)
		(layers "F.Cu" "B.Cu")
		(net "GND")
	)
	(via
		(at 490.053122 -8.00735)
		(size 0.7112)
		(drill 0.4064)
		(layers "F.Cu" "B.Cu")
		(net "GND")
	)
	(via
		(at 128.7145 -41.992296)
		(size 0.5588)
		(drill 0.3048)
		(layers "F.Cu" "B.Cu")
		(net "GND")
	)
	(via
		(at 30.48 -111.76)
		(size 0.5588)
		(drill 0.3048)
		(layers "F.Cu" "B.Cu")
		(net "GND")
	)
	(via
		(at 154.504898 -292.355016)
		(size 0.5588)
		(drill 0.3048)
		(layers "F.Cu" "B.Cu")
		(net "GND")
	)
	(via
		(at 490.053122 -119.76735)
		(size 0.7112)
		(drill 0.4064)
		(layers "F.Cu" "B.Cu")
		(net "GND")
	)
	(via
		(at 276.2758 -285.9532)
		(size 0.5588)
		(drill 0.3048)
		(layers "F.Cu" "B.Cu")
		(net "GND")
	)
	(via
		(at 10.16 -76.2)
		(size 0.5588)
		(drill 0.3048)
		(layers "F.Cu" "B.Cu")
		(net "GND")
	)
	(via
		(at 368.192304 -125.852428)
		(size 0.5588)
		(drill 0.3048)
		(layers "F.Cu" "B.Cu")
		(net "GND")
	)
	(via
		(at 452.12 -20.32)
		(size 0.5588)
		(drill 0.3048)
		(layers "F.Cu" "B.Cu")
		(net "GND")
	)
	(via
		(at 490.053122 -160.40735)
		(size 0.7112)
		(drill 0.4064)
		(layers "F.Cu" "B.Cu")
		(net "GND")
	)
	(via
		(at 85.105748 -49.494694)
		(size 0.5588)
		(drill 0.3048)
		(layers "F.Cu" "B.Cu")
		(net "GND")
	)
	(via
		(at 293.437056 37.403024)
		(size 0.7112)
		(drill 0.4064)
		(layers "F.Cu" "B.Cu")
		(net "GND")
	)
	(via
		(at 446.4304 -249.7328)
		(size 0.5588)
		(drill 0.3048)
		(layers "F.Cu" "B.Cu")
		(net "GND")
	)
	(via
		(at 426.72 -121.92)
		(size 0.5588)
		(drill 0.3048)
		(layers "F.Cu" "B.Cu")
		(net "GND")
	)
	(via
		(at 50.8 -335.28)
		(size 0.5588)
		(drill 0.3048)
		(layers "F.Cu" "B.Cu")
		(net "GND")
	)
	(via
		(at 101.854 -22.606)
		(size 0.5588)
		(drill 0.3048)
		(layers "F.Cu" "B.Cu")
		(net "GND")
	)
	(via
		(at 305.757072 -14.114272)
		(size 0.5588)
		(drill 0.3048)
		(layers "F.Cu" "B.Cu")
		(net "GND")
	)
	(via
		(at 490.053122 -39.75735)
		(size 0.7112)
		(drill 0.4064)
		(layers "F.Cu" "B.Cu")
		(net "GND")
	)
	(via
		(at 267.87475 10.230612)
		(size 0.5588)
		(drill 0.3048)
		(layers "F.Cu" "B.Cu")
		(net "GND")
	)
	(via
		(at 285.266892 -419.803072)
		(size 0.7112)
		(drill 0.4064)
		(layers "F.Cu" "B.Cu")
		(net "GND")
	)
	(via
		(at 453.632824 -36.03498)
		(size 0.5588)
		(drill 0.3048)
		(layers "F.Cu" "B.Cu")
		(net "GND")
	)
	(via
		(at 66.802 -259.842)
		(size 0.5588)
		(drill 0.3048)
		(layers "F.Cu" "B.Cu")
		(net "GND")
	)
	(via
		(at 471.479626 -54.015894)
		(size 0.5588)
		(drill 0.3048)
		(layers "F.Cu" "B.Cu")
		(net "GND")
	)
	(via
		(at 93.182948 -151.035004)
		(size 0.5588)
		(drill 0.3048)
		(layers "F.Cu" "B.Cu")
		(net "GND")
	)
	(via
		(at 447.4464 -252.7808)
		(size 0.5588)
		(drill 0.3048)
		(layers "F.Cu" "B.Cu")
		(net "GND")
	)
	(via
		(at 468.777066 -211.259674)
		(size 0.5588)
		(drill 0.3048)
		(layers "F.Cu" "B.Cu")
		(net "GND")
	)
	(via
		(at 18.161 -306.07)
		(size 0.5588)
		(drill 0.3048)
		(layers "F.Cu" "B.Cu")
		(net "GND")
	)
	(via
		(at 195.961 -78.994)
		(size 0.5588)
		(drill 0.3048)
		(layers "F.Cu" "B.Cu")
		(net "GND")
	)
	(via
		(at 64.821562 -134.408672)
		(size 0.5588)
		(drill 0.3048)
		(layers "F.Cu" "B.Cu")
		(net "GND")
	)
	(via
		(at 185.644028 -225.679508)
		(size 0.5588)
		(drill 0.3048)
		(layers "F.Cu" "B.Cu")
		(net "GND")
	)
	(via
		(at 91.821 -228.981)
		(size 0.5588)
		(drill 0.3048)
		(layers "F.Cu" "B.Cu")
		(net "GND")
	)
	(via
		(at 432.56962 -1.397)
		(size 0.7112)
		(drill 0.4064)
		(layers "F.Cu" "B.Cu")
		(net "GND")
	)
	(via
		(at 192.350898 -358.361742)
		(size 0.7112)
		(drill 0.4064)
		(layers "F.Cu" "B.Cu")
		(net "GND")
	)
	(via
		(at 24.005032 -1.397)
		(size 0.7112)
		(drill 0.4064)
		(layers "F.Cu" "B.Cu")
		(net "GND")
	)
	(via
		(at 57.15 -223.52)
		(size 0.5588)
		(drill 0.3048)
		(layers "F.Cu" "B.Cu")
		(net "GND")
	)
	(via
		(at 32.352996 -347.802962)
		(size 0.7112)
		(drill 0.4064)
		(layers "F.Cu" "B.Cu")
		(net "GND")
	)
	(via
		(at 71.882 -45.974)
		(size 0.5588)
		(drill 0.3048)
		(layers "F.Cu" "B.Cu")
		(net "GND")
	)
	(via
		(at 186.055 -177.354992)
		(size 0.5588)
		(drill 0.3048)
		(layers "F.Cu" "B.Cu")
		(net "GND")
	)
	(via
		(at 138.756898 -294.683942)
		(size 0.5588)
		(drill 0.3048)
		(layers "F.Cu" "B.Cu")
		(net "GND")
	)
	(via
		(at 1.397 -258.188968)
		(size 0.7112)
		(drill 0.4064)
		(layers "F.Cu" "B.Cu")
		(net "GND")
	)
	(via
		(at 168.693084 -1.397)
		(size 0.7112)
		(drill 0.4064)
		(layers "F.Cu" "B.Cu")
		(net "GND")
	)
	(via
		(at 303.474882 -347.802962)
		(size 0.7112)
		(drill 0.4064)
		(layers "F.Cu" "B.Cu")
		(net "GND")
	)
	(via
		(at 14.819884 -131.184142)
		(size 0.5588)
		(drill 0.3048)
		(layers "F.Cu" "B.Cu")
		(net "GND")
	)
	(via
		(at 387.611874 -52.829968)
		(size 0.5588)
		(drill 0.3048)
		(layers "F.Cu" "B.Cu")
		(net "GND")
	)
	(via
		(at 406.4 -335.28)
		(size 0.5588)
		(drill 0.3048)
		(layers "F.Cu" "B.Cu")
		(net "GND")
	)
	(via
		(at 196.088 -121.793)
		(size 0.5588)
		(drill 0.3048)
		(layers "F.Cu" "B.Cu")
		(net "GND")
	)
	(via
		(at 490.053122 -143.89735)
		(size 0.7112)
		(drill 0.4064)
		(layers "F.Cu" "B.Cu")
		(net "GND")
	)
	(via
		(at 483.404926 -272.035016)
		(size 0.5588)
		(drill 0.3048)
		(layers "F.Cu" "B.Cu")
		(net "GND")
	)
	(via
		(at 33.147 -53.721)
		(size 0.5588)
		(drill 0.3048)
		(layers "F.Cu" "B.Cu")
		(net "GND")
	)
	(via
		(at 330.551028 -1.397)
		(size 0.7112)
		(drill 0.4064)
		(layers "F.Cu" "B.Cu")
		(net "GND")
	)
	(via
		(at 1.397 -126.108968)
		(size 0.7112)
		(drill 0.4064)
		(layers "F.Cu" "B.Cu")
		(net "GND")
	)
	(via
		(at 335.224882 -347.802962)
		(size 0.7112)
		(drill 0.4064)
		(layers "F.Cu" "B.Cu")
		(net "GND")
	)
	(via
		(at 202.72756 -160.07588)
		(size 0.5588)
		(drill 0.3048)
		(layers "F.Cu" "B.Cu")
		(net "GND")
	)
	(via
		(at 238.254286 -250.78182)
		(size 0.5588)
		(drill 0.3048)
		(layers "F.Cu" "B.Cu")
		(net "GND")
	)
	(via
		(at 357.205026 -69.974968)
		(size 0.5588)
		(drill 0.3048)
		(layers "F.Cu" "B.Cu")
		(net "GND")
	)
	(via
		(at 58.711846 -170.230038)
		(size 0.5588)
		(drill 0.3048)
		(layers "F.Cu" "B.Cu")
		(net "GND")
	)
	(via
		(at 73.535032 -1.397)
		(size 0.7112)
		(drill 0.4064)
		(layers "F.Cu" "B.Cu")
		(net "GND")
	)
	(via
		(at 100.34905 -8.544306)
		(size 0.7112)
		(drill 0.4064)
		(layers "F.Cu" "B.Cu")
		(net "GND")
	)
	(via
		(at 195.58 -312.801)
		(size 0.5588)
		(drill 0.3048)
		(layers "F.Cu" "B.Cu")
		(net "GND")
	)
	(via
		(at 40.64 -25.4)
		(size 0.5588)
		(drill 0.3048)
		(layers "F.Cu" "B.Cu")
		(net "GND")
	)
	(via
		(at 30.082998 -266.035028)
		(size 0.5588)
		(drill 0.3048)
		(layers "F.Cu" "B.Cu")
		(net "GND")
	)
	(via
		(at 428.152052 -306.113942)
		(size 0.5588)
		(drill 0.3048)
		(layers "F.Cu" "B.Cu")
		(net "GND")
	)
	(via
		(at 447.010536 -246.166894)
		(size 0.5588)
		(drill 0.3048)
		(layers "F.Cu" "B.Cu")
		(net "GND")
	)
	(via
		(at 334.361028 -1.397)
		(size 0.7112)
		(drill 0.4064)
		(layers "F.Cu" "B.Cu")
		(net "GND")
	)
	(via
		(at 1.397 -30.858968)
		(size 0.7112)
		(drill 0.4064)
		(layers "F.Cu" "B.Cu")
		(net "GND")
	)
	(via
		(at 367.282476 -44.217844)
		(size 0.5588)
		(drill 0.3048)
		(layers "F.Cu" "B.Cu")
		(net "GND")
	)
	(via
		(at 368.427 -203.835)
		(size 0.5588)
		(drill 0.3048)
		(layers "F.Cu" "B.Cu")
		(net "GND")
	)
	(via
		(at 85.766148 -185.322718)
		(size 0.5588)
		(drill 0.3048)
		(layers "F.Cu" "B.Cu")
		(net "GND")
	)
	(via
		(at 201.397108 -393.182856)
		(size 0.7112)
		(drill 0.4064)
		(layers "F.Cu" "B.Cu")
		(net "GND")
	)
	(via
		(at 299.466 -210.693)
		(size 0.5588)
		(drill 0.3048)
		(layers "F.Cu" "B.Cu")
		(net "GND")
	)
	(via
		(at 186.055 -292.355016)
		(size 0.5588)
		(drill 0.3048)
		(layers "F.Cu" "B.Cu")
		(net "GND")
	)
	(via
		(at 216.61374 -18.110962)
		(size 0.5588)
		(drill 0.3048)
		(layers "F.Cu" "B.Cu")
		(net "GND")
	)
	(via
		(at 27.161998 -55.230014)
		(size 0.5588)
		(drill 0.3048)
		(layers "F.Cu" "B.Cu")
		(net "GND")
	)
	(via
		(at 421.64 -30.48)
		(size 0.5588)
		(drill 0.3048)
		(layers "F.Cu" "B.Cu")
		(net "GND")
	)
	(via
		(at 1.397 -314.068968)
		(size 0.7112)
		(drill 0.4064)
		(layers "F.Cu" "B.Cu")
		(net "GND")
	)
	(via
		(at 5.08 -96.52)
		(size 0.5588)
		(drill 0.3048)
		(layers "F.Cu" "B.Cu")
		(net "GND")
	)
	(via
		(at 197.903084 -1.397)
		(size 0.7112)
		(drill 0.4064)
		(layers "F.Cu" "B.Cu")
		(net "GND")
	)
	(via
		(at 490.053122 -4.19735)
		(size 0.7112)
		(drill 0.4064)
		(layers "F.Cu" "B.Cu")
		(net "GND")
	)
	(via
		(at 186.055 -275.845016)
		(size 0.5588)
		(drill 0.3048)
		(layers "F.Cu" "B.Cu")
		(net "GND")
	)
	(via
		(at 324.511924 -280.42997)
		(size 0.5588)
		(drill 0.3048)
		(layers "F.Cu" "B.Cu")
		(net "GND")
	)
	(via
		(at 409.70962 -1.397)
		(size 0.7112)
		(drill 0.4064)
		(layers "F.Cu" "B.Cu")
		(net "GND")
	)
	(via
		(at 154.504898 -272.035016)
		(size 0.5588)
		(drill 0.3048)
		(layers "F.Cu" "B.Cu")
		(net "GND")
	)
	(via
		(at 452.064882 -347.802962)
		(size 0.7112)
		(drill 0.4064)
		(layers "F.Cu" "B.Cu")
		(net "GND")
	)
	(via
		(at 490.053122 -6.73735)
		(size 0.7112)
		(drill 0.4064)
		(layers "F.Cu" "B.Cu")
		(net "GND")
	)
	(via
		(at 346.349066 -7.574534)
		(size 0.7112)
		(drill 0.4064)
		(layers "F.Cu" "B.Cu")
		(net "GND")
	)
	(via
		(at 446.984882 -347.802962)
		(size 0.7112)
		(drill 0.4064)
		(layers "F.Cu" "B.Cu")
		(net "GND")
	)
	(via
		(at 490.053122 -263.871202)
		(size 0.7112)
		(drill 0.4064)
		(layers "F.Cu" "B.Cu")
		(net "GND")
	)
	(via
		(at 21.1074 -251.2822)
		(size 0.7112)
		(drill 0.4064)
		(layers "F.Cu" "B.Cu")
		(net "GND")
	)
	(via
		(at 220.345 -163.322)
		(size 0.5588)
		(drill 0.3048)
		(layers "F.Cu" "B.Cu")
		(net "GND")
	)
	(via
		(at 30.4292 -247.7008)
		(size 0.5588)
		(drill 0.3048)
		(layers "F.Cu" "B.Cu")
		(net "GND")
	)
	(via
		(at 421.64 -10.16)
		(size 0.5588)
		(drill 0.3048)
		(layers "F.Cu" "B.Cu")
		(net "GND")
	)
	(via
		(at 308.602888 -384.211068)
		(size 0.7112)
		(drill 0.4064)
		(layers "F.Cu" "B.Cu")
		(net "GND")
	)
	(via
		(at 127 -238.76)
		(size 0.5588)
		(drill 0.3048)
		(layers "F.Cu" "B.Cu")
		(net "GND")
	)
	(via
		(at 317.3984 -293.5732)
		(size 0.5588)
		(drill 0.3048)
		(layers "F.Cu" "B.Cu")
		(net "GND")
	)
	(via
		(at 121.87682 -31.624778)
		(size 0.6604)
		(drill 0.3556)
		(layers "F.Cu" "B.Cu")
		(net "GND")
	)
	(via
		(at 490.053122 -100.71735)
		(size 0.7112)
		(drill 0.4064)
		(layers "F.Cu" "B.Cu")
		(net "GND")
	)
	(via
		(at 387.611874 -285.230062)
		(size 0.5588)
		(drill 0.3048)
		(layers "F.Cu" "B.Cu")
		(net "GND")
	)
	(via
		(at 64.87414 -154.389582)
		(size 0.5588)
		(drill 0.3048)
		(layers "F.Cu" "B.Cu")
		(net "GND")
	)
	(via
		(at 419.313614 -296.83964)
		(size 0.5588)
		(drill 0.3048)
		(layers "F.Cu" "B.Cu")
		(net "GND")
	)
	(via
		(at 1.397 -339.468968)
		(size 0.7112)
		(drill 0.4064)
		(layers "F.Cu" "B.Cu")
		(net "GND")
	)
	(via
		(at 289.076892 -419.803072)
		(size 0.7112)
		(drill 0.4064)
		(layers "F.Cu" "B.Cu")
		(net "GND")
	)
	(via
		(at 5.08 -50.8)
		(size 0.5588)
		(drill 0.3048)
		(layers "F.Cu" "B.Cu")
		(net "GND")
	)
	(via
		(at 289.814 -414.528)
		(size 0.5588)
		(drill 0.3048)
		(layers "F.Cu" "B.Cu")
		(net "GND")
	)
	(via
		(at 262.141462 8.878062)
		(size 0.5588)
		(drill 0.3048)
		(layers "F.Cu" "B.Cu")
		(net "GND")
	)
	(via
		(at 388.754874 -299.975016)
		(size 0.5588)
		(drill 0.3048)
		(layers "F.Cu" "B.Cu")
		(net "GND")
	)
	(via
		(at 383.54 -218.567)
		(size 0.5588)
		(drill 0.3048)
		(layers "F.Cu" "B.Cu")
		(net "GND")
	)
	(via
		(at 421.64 -15.24)
		(size 0.5588)
		(drill 0.3048)
		(layers "F.Cu" "B.Cu")
		(net "GND")
	)
	(via
		(at 10.16 -35.56)
		(size 0.5588)
		(drill 0.3048)
		(layers "F.Cu" "B.Cu")
		(net "GND")
	)
	(via
		(at 233.618786 -246.600472)
		(size 0.5588)
		(drill 0.3048)
		(layers "F.Cu" "B.Cu")
		(net "GND")
	)
	(via
		(at 4.445 -345.44)
		(size 0.5588)
		(drill 0.3048)
		(layers "F.Cu" "B.Cu")
		(net "GND")
	)
	(via
		(at 485.182926 -79.784956)
		(size 0.5588)
		(drill 0.3048)
		(layers "F.Cu" "B.Cu")
		(net "GND")
	)
	(via
		(at 261.994396 -344.049604)
		(size 0.5588)
		(drill 0.3048)
		(layers "F.Cu" "B.Cu")
		(net "GND")
	)
	(via
		(at 114.935 -189.103)
		(size 0.5588)
		(drill 0.3048)
		(layers "F.Cu" "B.Cu")
		(net "GND")
	)
	(via
		(at 421.64 -142.24)
		(size 0.5588)
		(drill 0.3048)
		(layers "F.Cu" "B.Cu")
		(net "GND")
	)
	(via
		(at 146.2278 -134.323074)
		(size 0.5588)
		(drill 0.3048)
		(layers "F.Cu" "B.Cu")
		(net "GND")
	)
	(via
		(at 308.602888 -390.561068)
		(size 0.7112)
		(drill 0.4064)
		(layers "F.Cu" "B.Cu")
		(net "GND")
	)
	(via
		(at 1.397 -51.178968)
		(size 0.7112)
		(drill 0.4064)
		(layers "F.Cu" "B.Cu")
		(net "GND")
	)
	(via
		(at 189.832996 -347.802962)
		(size 0.7112)
		(drill 0.4064)
		(layers "F.Cu" "B.Cu")
		(net "GND")
	)
	(via
		(at 141.548866 -130.386074)
		(size 0.5588)
		(drill 0.3048)
		(layers "F.Cu" "B.Cu")
		(net "GND")
	)
	(via
		(at 97.84334 -296.252138)
		(size 0.5588)
		(drill 0.3048)
		(layers "F.Cu" "B.Cu")
		(net "GND")
	)
	(via
		(at 56.482996 -347.802962)
		(size 0.7112)
		(drill 0.4064)
		(layers "F.Cu" "B.Cu")
		(net "GND")
	)
	(via
		(at 87.340948 -306.240942)
		(size 0.5588)
		(drill 0.3048)
		(layers "F.Cu" "B.Cu")
		(net "GND")
	)
	(via
		(at 354.711 -129.794)
		(size 0.5588)
		(drill 0.3048)
		(layers "F.Cu" "B.Cu")
		(net "GND")
	)
	(via
		(at 311.501028 -1.397)
		(size 0.7112)
		(drill 0.4064)
		(layers "F.Cu" "B.Cu")
		(net "GND")
	)
	(via
		(at 262.509762 -28.585922)
		(size 0.5588)
		(drill 0.3048)
		(layers "F.Cu" "B.Cu")
		(net "GND")
	)
	(via
		(at 487.68 -330.2)
		(size 0.5588)
		(drill 0.3048)
		(layers "F.Cu" "B.Cu")
		(net "GND")
	)
	(via
		(at 490.053122 -173.10735)
		(size 0.7112)
		(drill 0.4064)
		(layers "F.Cu" "B.Cu")
		(net "GND")
	)
	(via
		(at 5.08 -66.04)
		(size 0.5588)
		(drill 0.3048)
		(layers "F.Cu" "B.Cu")
		(net "GND")
	)
	(via
		(at 274.387056 37.403024)
		(size 0.7112)
		(drill 0.4064)
		(layers "F.Cu" "B.Cu")
		(net "GND")
	)
	(via
		(at 490.053122 -185.80735)
		(size 0.7112)
		(drill 0.4064)
		(layers "F.Cu" "B.Cu")
		(net "GND")
	)
	(via
		(at 428.787052 -279.596342)
		(size 0.5588)
		(drill 0.3048)
		(layers "F.Cu" "B.Cu")
		(net "GND")
	)
	(via
		(at 1.397 -259.458968)
		(size 0.7112)
		(drill 0.4064)
		(layers "F.Cu" "B.Cu")
		(net "GND")
	)
	(via
		(at 156.282898 -151.035004)
		(size 0.5588)
		(drill 0.3048)
		(layers "F.Cu" "B.Cu")
		(net "GND")
	)
	(via
		(at 288.357056 37.403024)
		(size 0.7112)
		(drill 0.4064)
		(layers "F.Cu" "B.Cu")
		(net "GND")
	)
	(via
		(at 122.954796 -174.814992)
		(size 0.5588)
		(drill 0.3048)
		(layers "F.Cu" "B.Cu")
		(net "GND")
	)
	(via
		(at 91.404948 -164.654992)
		(size 0.5588)
		(drill 0.3048)
		(layers "F.Cu" "B.Cu")
		(net "GND")
	)
	(via
		(at 392.374882 -347.802962)
		(size 0.7112)
		(drill 0.4064)
		(layers "F.Cu" "B.Cu")
		(net "GND")
	)
	(via
		(at 58.711846 -285.230062)
		(size 0.5588)
		(drill 0.3048)
		(layers "F.Cu" "B.Cu")
		(net "GND")
	)
	(via
		(at 105.838244 -131.148074)
		(size 0.5588)
		(drill 0.3048)
		(layers "F.Cu" "B.Cu")
		(net "GND")
	)
	(via
		(at 490.053122 -109.60735)
		(size 0.7112)
		(drill 0.4064)
		(layers "F.Cu" "B.Cu")
		(net "GND")
	)
	(via
		(at 451.854824 -67.434968)
		(size 0.5588)
		(drill 0.3048)
		(layers "F.Cu" "B.Cu")
		(net "GND")
	)
	(via
		(at 121.811796 -170.230038)
		(size 0.5588)
		(drill 0.3048)
		(layers "F.Cu" "B.Cu")
		(net "GND")
	)
	(via
		(at 1.397 -222.628968)
		(size 0.7112)
		(drill 0.4064)
		(layers "F.Cu" "B.Cu")
		(net "GND")
	)
	(via
		(at 452.12 -111.76)
		(size 0.5588)
		(drill 0.3048)
		(layers "F.Cu" "B.Cu")
		(net "GND")
	)
	(via
		(at 176.403 -289.603942)
		(size 0.5588)
		(drill 0.3048)
		(layers "F.Cu" "B.Cu")
		(net "GND")
	)
	(via
		(at 419.161976 -55.230014)
		(size 0.5588)
		(drill 0.3048)
		(layers "F.Cu" "B.Cu")
		(net "GND")
	)
	(via
		(at 71.694802 -149.66315)
		(size 0.5588)
		(drill 0.3048)
		(layers "F.Cu" "B.Cu")
		(net "GND")
	)
	(via
		(at 307.691028 -1.397)
		(size 0.7112)
		(drill 0.4064)
		(layers "F.Cu" "B.Cu")
		(net "GND")
	)
	(via
		(at 213.106 -137.414)
		(size 0.5588)
		(drill 0.3048)
		(layers "F.Cu" "B.Cu")
		(net "GND")
	)
	(via
		(at 361.95 -121.92)
		(size 0.5588)
		(drill 0.3048)
		(layers "F.Cu" "B.Cu")
		(net "GND")
	)
	(via
		(at 1.397 -14.348968)
		(size 0.7112)
		(drill 0.4064)
		(layers "F.Cu" "B.Cu")
		(net "GND")
	)
	(via
		(at 143.072866 -128.709674)
		(size 0.5588)
		(drill 0.3048)
		(layers "F.Cu" "B.Cu")
		(net "GND")
	)
	(via
		(at 435.554882 -347.802962)
		(size 0.7112)
		(drill 0.4064)
		(layers "F.Cu" "B.Cu")
		(net "GND")
	)
	(via
		(at 80.612996 -347.802962)
		(size 0.7112)
		(drill 0.4064)
		(layers "F.Cu" "B.Cu")
		(net "GND")
	)
	(via
		(at 44.106846 -294.683942)
		(size 0.5588)
		(drill 0.3048)
		(layers "F.Cu" "B.Cu")
		(net "GND")
	)
	(via
		(at 330.144882 -347.802962)
		(size 0.7112)
		(drill 0.4064)
		(layers "F.Cu" "B.Cu")
		(net "GND")
	)
	(via
		(at 61.632846 -79.784956)
		(size 0.5588)
		(drill 0.3048)
		(layers "F.Cu" "B.Cu")
		(net "GND")
	)
	(via
		(at 457.2 -132.08)
		(size 0.5588)
		(drill 0.3048)
		(layers "F.Cu" "B.Cu")
		(net "GND")
	)
	(via
		(at 421.64 -121.92)
		(size 0.5588)
		(drill 0.3048)
		(layers "F.Cu" "B.Cu")
		(net "GND")
	)
	(via
		(at 53.34 -330.2)
		(size 0.5588)
		(drill 0.3048)
		(layers "F.Cu" "B.Cu")
		(net "GND")
	)
	(via
		(at 490.053122 -65.15735)
		(size 0.7112)
		(drill 0.4064)
		(layers "F.Cu" "B.Cu")
		(net "GND")
	)
	(via
		(at 452.12 -10.16)
		(size 0.5588)
		(drill 0.3048)
		(layers "F.Cu" "B.Cu")
		(net "GND")
	)
	(via
		(at 42.512996 -347.802962)
		(size 0.7112)
		(drill 0.4064)
		(layers "F.Cu" "B.Cu")
		(net "GND")
	)
	(via
		(at 394.56995 -307.059838)
		(size 0.5588)
		(drill 0.3048)
		(layers "F.Cu" "B.Cu")
		(net "GND")
	)
	(via
		(at 471.93962 -1.397)
		(size 0.7112)
		(drill 0.4064)
		(layers "F.Cu" "B.Cu")
		(net "GND")
	)
	(via
		(at 298.602908 24.788876)
		(size 0.7112)
		(drill 0.4064)
		(layers "F.Cu" "B.Cu")
		(net "GND")
	)
	(via
		(at 451.854824 -164.654992)
		(size 0.5588)
		(drill 0.3048)
		(layers "F.Cu" "B.Cu")
		(net "GND")
	)
	(via
		(at 405.89962 -1.397)
		(size 0.7112)
		(drill 0.4064)
		(layers "F.Cu" "B.Cu")
		(net "GND")
	)
	(via
		(at 301.414942 -375.397014)
		(size 0.7112)
		(drill 0.4064)
		(layers "F.Cu" "B.Cu")
		(net "GND")
	)
	(via
		(at 21.844 -325.628)
		(size 0.5588)
		(drill 0.3048)
		(layers "F.Cu" "B.Cu")
		(net "GND")
	)
	(via
		(at 28.304998 -174.814992)
		(size 0.5588)
		(drill 0.3048)
		(layers "F.Cu" "B.Cu")
		(net "GND")
	)
	(via
		(at 420.304976 -157.034992)
		(size 0.5588)
		(drill 0.3048)
		(layers "F.Cu" "B.Cu")
		(net "GND")
	)
	(via
		(at 153.162 -198.374)
		(size 0.5588)
		(drill 0.3048)
		(layers "F.Cu" "B.Cu")
		(net "GND")
	)
	(via
		(at 431.8 -116.84)
		(size 0.5588)
		(drill 0.3048)
		(layers "F.Cu" "B.Cu")
		(net "GND")
	)
	(via
		(at 482.261926 -50.429922)
		(size 0.5588)
		(drill 0.3048)
		(layers "F.Cu" "B.Cu")
		(net "GND")
	)
	(via
		(at 253.8222 16.3576)
		(size 0.5588)
		(drill 0.3048)
		(layers "F.Cu" "B.Cu")
		(net "GND")
	)
	(via
		(at 457.0349 -67.604894)
		(size 0.5588)
		(drill 0.3048)
		(layers "F.Cu" "B.Cu")
		(net "GND")
	)
	(via
		(at 401.32 -10.16)
		(size 0.5588)
		(drill 0.3048)
		(layers "F.Cu" "B.Cu")
		(net "GND")
	)
	(via
		(at 165.280594 -180.46573)
		(size 0.5588)
		(drill 0.3048)
		(layers "F.Cu" "B.Cu")
		(net "GND")
	)
	(via
		(at 42.418 -155.702)
		(size 0.5588)
		(drill 0.3048)
		(layers "F.Cu" "B.Cu")
		(net "GND")
	)
	(via
		(at 374.594882 -347.802962)
		(size 0.7112)
		(drill 0.4064)
		(layers "F.Cu" "B.Cu")
		(net "GND")
	)
	(via
		(at 258.4704 -14.9606)
		(size 0.5588)
		(drill 0.3048)
		(layers "F.Cu" "B.Cu")
		(net "GND")
	)
	(via
		(at 265.3284 -102.235)
		(size 0.5588)
		(drill 0.3048)
		(layers "F.Cu" "B.Cu")
		(net "GND")
	)
	(via
		(at 490.053122 -230.25735)
		(size 0.7112)
		(drill 0.4064)
		(layers "F.Cu" "B.Cu")
		(net "GND")
	)
	(via
		(at 397.65097 -8.005318)
		(size 0.7112)
		(drill 0.4064)
		(layers "F.Cu" "B.Cu")
		(net "GND")
	)
	(via
		(at 392.527282 -41.685464)
		(size 0.5588)
		(drill 0.3048)
		(layers "F.Cu" "B.Cu")
		(net "GND")
	)
	(via
		(at 310.231028 -1.397)
		(size 0.7112)
		(drill 0.4064)
		(layers "F.Cu" "B.Cu")
		(net "GND")
	)
	(via
		(at 433.324 -259.588)
		(size 0.5588)
		(drill 0.3048)
		(layers "F.Cu" "B.Cu")
		(net "GND")
	)
	(via
		(at 421.64 -325.12)
		(size 0.5588)
		(drill 0.3048)
		(layers "F.Cu" "B.Cu")
		(net "GND")
	)
	(via
		(at 85.105748 -164.494718)
		(size 0.5588)
		(drill 0.3048)
		(layers "F.Cu" "B.Cu")
		(net "GND")
	)
	(via
		(at 261.874 -343.027)
		(size 0.5588)
		(drill 0.3048)
		(layers "F.Cu" "B.Cu")
		(net "GND")
	)
	(via
		(at 107.696 -306.324)
		(size 0.5588)
		(drill 0.3048)
		(layers "F.Cu" "B.Cu")
		(net "GND")
	)
	(via
		(at 25.4 -20.32)
		(size 0.5588)
		(drill 0.3048)
		(layers "F.Cu" "B.Cu")
		(net "GND")
	)
	(via
		(at 224.857056 37.403024)
		(size 0.7112)
		(drill 0.4064)
		(layers "F.Cu" "B.Cu")
		(net "GND")
	)
	(via
		(at 98.754184 -185.938668)
		(size 0.5588)
		(drill 0.3048)
		(layers "F.Cu" "B.Cu")
		(net "GND")
	)
	(via
		(at 5.08 -106.68)
		(size 0.5588)
		(drill 0.3048)
		(layers "F.Cu" "B.Cu")
		(net "GND")
	)
	(via
		(at 441.96 -10.16)
		(size 0.5588)
		(drill 0.3048)
		(layers "F.Cu" "B.Cu")
		(net "GND")
	)
	(via
		(at 312.771028 -1.397)
		(size 0.7112)
		(drill 0.4064)
		(layers "F.Cu" "B.Cu")
		(net "GND")
	)
	(via
		(at 6.35 -246.38)
		(size 0.5588)
		(drill 0.3048)
		(layers "F.Cu" "B.Cu")
		(net "GND")
	)
	(via
		(at 445.77 -265.43)
		(size 0.5588)
		(drill 0.3048)
		(layers "F.Cu" "B.Cu")
		(net "GND")
	)
	(via
		(at 45.72 -218.44)
		(size 0.5588)
		(drill 0.3048)
		(layers "F.Cu" "B.Cu")
		(net "GND")
	)
	(via
		(at 242.637056 37.403024)
		(size 0.7112)
		(drill 0.4064)
		(layers "F.Cu" "B.Cu")
		(net "GND")
	)
	(via
		(at 490.053122 -20.70735)
		(size 0.7112)
		(drill 0.4064)
		(layers "F.Cu" "B.Cu")
		(net "GND")
	)
	(via
		(at 198.12 -15.24)
		(size 0.5588)
		(drill 0.3048)
		(layers "F.Cu" "B.Cu")
		(net "GND")
	)
	(via
		(at 151.650954 -8.305546)
		(size 0.7112)
		(drill 0.4064)
		(layers "F.Cu" "B.Cu")
		(net "GND")
	)
	(via
		(at 490.053122 -174.37735)
		(size 0.7112)
		(drill 0.4064)
		(layers "F.Cu" "B.Cu")
		(net "GND")
	)
	(via
		(at 23.440898 -279.443942)
		(size 0.5588)
		(drill 0.3048)
		(layers "F.Cu" "B.Cu")
		(net "GND")
	)
	(via
		(at 58.42 -332.74)
		(size 0.5588)
		(drill 0.3048)
		(layers "F.Cu" "B.Cu")
		(net "GND")
	)
	(via
		(at 66.218562 -134.408672)
		(size 0.5588)
		(drill 0.3048)
		(layers "F.Cu" "B.Cu")
		(net "GND")
	)
	(via
		(at 284.266386 -221.77502)
		(size 0.5588)
		(drill 0.3048)
		(layers "F.Cu" "B.Cu")
		(net "GND")
	)
	(via
		(at 387.35 -115.57)
		(size 0.5588)
		(drill 0.3048)
		(layers "F.Cu" "B.Cu")
		(net "GND")
	)
	(via
		(at 10.122662 -130.142742)
		(size 0.5588)
		(drill 0.3048)
		(layers "F.Cu" "B.Cu")
		(net "GND")
	)
	(via
		(at 254.067056 37.403024)
		(size 0.7112)
		(drill 0.4064)
		(layers "F.Cu" "B.Cu")
		(net "GND")
	)
	(via
		(at 288.911284 -303.70526)
		(size 0.6604)
		(drill 0.3556)
		(layers "F.Cu" "B.Cu")
		(net "GND")
	)
	(via
		(at 305.833272 -11.523472)
		(size 0.5588)
		(drill 0.3048)
		(layers "F.Cu" "B.Cu")
		(net "GND")
	)
	(via
		(at 451.854824 -292.355016)
		(size 0.5588)
		(drill 0.3048)
		(layers "F.Cu" "B.Cu")
		(net "GND")
	)
	(via
		(at 121.811796 -165.429946)
		(size 0.5588)
		(drill 0.3048)
		(layers "F.Cu" "B.Cu")
		(net "GND")
	)
	(via
		(at 185.928 -97.282)
		(size 0.5588)
		(drill 0.3048)
		(layers "F.Cu" "B.Cu")
		(net "GND")
	)
	(via
		(at 235.8644 29.2608)
		(size 0.5588)
		(drill 0.3048)
		(layers "F.Cu" "B.Cu")
		(net "GND")
	)
	(via
		(at 295.426892 -419.803072)
		(size 0.7112)
		(drill 0.4064)
		(layers "F.Cu" "B.Cu")
		(net "GND")
	)
	(via
		(at 357.124 -60.1218)
		(size 0.5588)
		(drill 0.3048)
		(layers "F.Cu" "B.Cu")
		(net "GND")
	)
	(via
		(at 240.319052 -255.599946)
		(size 0.5588)
		(drill 0.3048)
		(layers "F.Cu" "B.Cu")
		(net "GND")
	)
	(via
		(at 221.651068 11.57605)
		(size 0.7112)
		(drill 0.4064)
		(layers "F.Cu" "B.Cu")
		(net "GND")
	)
	(via
		(at 20.32 -25.4)
		(size 0.5588)
		(drill 0.3048)
		(layers "F.Cu" "B.Cu")
		(net "GND")
	)
	(via
		(at 177.8 -15.24)
		(size 0.5588)
		(drill 0.3048)
		(layers "F.Cu" "B.Cu")
		(net "GND")
	)
	(via
		(at 129.286 -196.088)
		(size 0.5588)
		(drill 0.3048)
		(layers "F.Cu" "B.Cu")
		(net "GND")
	)
	(via
		(at 184.912 -50.429922)
		(size 0.5588)
		(drill 0.3048)
		(layers "F.Cu" "B.Cu")
		(net "GND")
	)
	(via
		(at 431.8 -106.68)
		(size 0.5588)
		(drill 0.3048)
		(layers "F.Cu" "B.Cu")
		(net "GND")
	)
	(via
		(at 490.053122 -15.62735)
		(size 0.7112)
		(drill 0.4064)
		(layers "F.Cu" "B.Cu")
		(net "GND")
	)
	(via
		(at 394.914882 -347.802962)
		(size 0.7112)
		(drill 0.4064)
		(layers "F.Cu" "B.Cu")
		(net "GND")
	)
	(via
		(at 416.56 -137.16)
		(size 0.5588)
		(drill 0.3048)
		(layers "F.Cu" "B.Cu")
		(net "GND")
	)
	(via
		(at 81.28 -190.5)
		(size 0.5588)
		(drill 0.3048)
		(layers "F.Cu" "B.Cu")
		(net "GND")
	)
	(via
		(at 333.7433 -296.16146)
		(size 0.5588)
		(drill 0.3048)
		(layers "F.Cu" "B.Cu")
		(net "GND")
	)
	(via
		(at 265.049 -78.867)
		(size 0.5588)
		(drill 0.3048)
		(layers "F.Cu" "B.Cu")
		(net "GND")
	)
	(via
		(at 388.754874 -160.844992)
		(size 0.5588)
		(drill 0.3048)
		(layers "F.Cu" "B.Cu")
		(net "GND")
	)
	(via
		(at 175.895 -200.787)
		(size 0.5588)
		(drill 0.3048)
		(layers "F.Cu" "B.Cu")
		(net "GND")
	)
	(via
		(at 251.527056 37.403024)
		(size 0.7112)
		(drill 0.4064)
		(layers "F.Cu" "B.Cu")
		(net "GND")
	)
	(via
		(at 121.577354 -56.066436)
		(size 0.5588)
		(drill 0.3048)
		(layers "F.Cu" "B.Cu")
		(net "GND")
	)
	(via
		(at 238.827056 37.403024)
		(size 0.7112)
		(drill 0.4064)
		(layers "F.Cu" "B.Cu")
		(net "GND")
	)
	(via
		(at 281.3558 19.5072)
		(size 0.5588)
		(drill 0.3048)
		(layers "F.Cu" "B.Cu")
		(net "GND")
	)
	(via
		(at 490.053122 -141.35735)
		(size 0.7112)
		(drill 0.4064)
		(layers "F.Cu" "B.Cu")
		(net "GND")
	)
	(via
		(at 346.349066 -5.034534)
		(size 0.7112)
		(drill 0.4064)
		(layers "F.Cu" "B.Cu")
		(net "GND")
	)
	(via
		(at 192.350898 -362.171742)
		(size 0.7112)
		(drill 0.4064)
		(layers "F.Cu" "B.Cu")
		(net "GND")
	)
	(via
		(at 186.055 -164.654992)
		(size 0.5588)
		(drill 0.3048)
		(layers "F.Cu" "B.Cu")
		(net "GND")
	)
	(via
		(at 490.053122 -25.78735)
		(size 0.7112)
		(drill 0.4064)
		(layers "F.Cu" "B.Cu")
		(net "GND")
	)
	(via
		(at 436.88 -20.32)
		(size 0.5588)
		(drill 0.3048)
		(layers "F.Cu" "B.Cu")
		(net "GND")
	)
	(via
		(at 163.322 -291.127942)
		(size 0.5588)
		(drill 0.3048)
		(layers "F.Cu" "B.Cu")
		(net "GND")
	)
	(via
		(at 10.16 -25.4)
		(size 0.5588)
		(drill 0.3048)
		(layers "F.Cu" "B.Cu")
		(net "GND")
	)
	(via
		(at 452.12 -25.4)
		(size 0.5588)
		(drill 0.3048)
		(layers "F.Cu" "B.Cu")
		(net "GND")
	)
	(via
		(at 1.397 -96.898968)
		(size 0.7112)
		(drill 0.4064)
		(layers "F.Cu" "B.Cu")
		(net "GND")
	)
	(via
		(at 113.03 -202.692)
		(size 0.5588)
		(drill 0.3048)
		(layers "F.Cu" "B.Cu")
		(net "GND")
	)
	(via
		(at 28.304998 -299.975016)
		(size 0.5588)
		(drill 0.3048)
		(layers "F.Cu" "B.Cu")
		(net "GND")
	)
	(via
		(at 151.650954 -4.495546)
		(size 0.7112)
		(drill 0.4064)
		(layers "F.Cu" "B.Cu")
		(net "GND")
	)
	(via
		(at 356.062026 -170.230038)
		(size 0.5588)
		(drill 0.3048)
		(layers "F.Cu" "B.Cu")
		(net "GND")
	)
	(via
		(at 290.72332 -273.98472)
		(size 0.5588)
		(drill 0.3048)
		(layers "F.Cu" "B.Cu")
		(net "GND")
	)
	(via
		(at 490.053122 -145.16735)
		(size 0.7112)
		(drill 0.4064)
		(layers "F.Cu" "B.Cu")
		(net "GND")
	)
	(via
		(at 490.053122 -90.55735)
		(size 0.7112)
		(drill 0.4064)
		(layers "F.Cu" "B.Cu")
		(net "GND")
	)
	(via
		(at 490.053122 -95.63735)
		(size 0.7112)
		(drill 0.4064)
		(layers "F.Cu" "B.Cu")
		(net "GND")
	)
	(via
		(at 72.265032 -1.397)
		(size 0.7112)
		(drill 0.4064)
		(layers "F.Cu" "B.Cu")
		(net "GND")
	)
	(via
		(at 1.397 -79.118968)
		(size 0.7112)
		(drill 0.4064)
		(layers "F.Cu" "B.Cu")
		(net "GND")
	)
	(via
		(at 288.911284 -332.505304)
		(size 0.6604)
		(drill 0.3556)
		(layers "F.Cu" "B.Cu")
		(net "GND")
	)
	(via
		(at 79.342996 -347.802962)
		(size 0.7112)
		(drill 0.4064)
		(layers "F.Cu" "B.Cu")
		(net "GND")
	)
	(via
		(at 67.912996 -347.802962)
		(size 0.7112)
		(drill 0.4064)
		(layers "F.Cu" "B.Cu")
		(net "GND")
	)
	(via
		(at 454.243694 -245.027704)
		(size 0.5588)
		(drill 0.3048)
		(layers "F.Cu" "B.Cu")
		(net "GND")
	)
	(via
		(at 332.486 -11.557)
		(size 0.5588)
		(drill 0.3048)
		(layers "F.Cu" "B.Cu")
		(net "GND")
	)
	(via
		(at 235.823506 -345.482418)
		(size 0.5588)
		(drill 0.3048)
		(layers "F.Cu" "B.Cu")
		(net "GND")
	)
	(via
		(at 426.72 -20.32)
		(size 0.5588)
		(drill 0.3048)
		(layers "F.Cu" "B.Cu")
		(net "GND")
	)
	(via
		(at 388.754874 -45.844968)
		(size 0.5588)
		(drill 0.3048)
		(layers "F.Cu" "B.Cu")
		(net "GND")
	)
	(via
		(at 490.053122 -342.611202)
		(size 0.7112)
		(drill 0.4064)
		(layers "F.Cu" "B.Cu")
		(net "GND")
	)
	(via
		(at 426.72 -30.48)
		(size 0.5588)
		(drill 0.3048)
		(layers "F.Cu" "B.Cu")
		(net "GND")
	)
	(via
		(at 30.4292 -249.7328)
		(size 0.5588)
		(drill 0.3048)
		(layers "F.Cu" "B.Cu")
		(net "GND")
	)
	(via
		(at 40.64 -5.08)
		(size 0.5588)
		(drill 0.3048)
		(layers "F.Cu" "B.Cu")
		(net "GND")
	)
	(via
		(at 317.041022 -61.624972)
		(size 0.5588)
		(drill 0.3048)
		(layers "F.Cu" "B.Cu")
		(net "GND")
	)
	(via
		(at 419.161976 -52.829968)
		(size 0.5588)
		(drill 0.3048)
		(layers "F.Cu" "B.Cu")
		(net "GND")
	)
	(via
		(at 266.7254 -103.5304)
		(size 0.5588)
		(drill 0.3048)
		(layers "F.Cu" "B.Cu")
		(net "GND")
	)
	(via
		(at 1.397 -82.928968)
		(size 0.7112)
		(drill 0.4064)
		(layers "F.Cu" "B.Cu")
		(net "GND")
	)
	(via
		(at 369.514882 -347.802962)
		(size 0.7112)
		(drill 0.4064)
		(layers "F.Cu" "B.Cu")
		(net "GND")
	)
	(via
		(at 192.350898 -357.091742)
		(size 0.7112)
		(drill 0.4064)
		(layers "F.Cu" "B.Cu")
		(net "GND")
	)
	(via
		(at 1.397 -325.498968)
		(size 0.7112)
		(drill 0.4064)
		(layers "F.Cu" "B.Cu")
		(net "GND")
	)
	(via
		(at 396.24 -127)
		(size 0.5588)
		(drill 0.3048)
		(layers "F.Cu" "B.Cu")
		(net "GND")
	)
	(via
		(at 334.899 -8.763)
		(size 0.5588)
		(drill 0.3048)
		(layers "F.Cu" "B.Cu")
		(net "GND")
	)
	(via
		(at 335.026 -3.048)
		(size 0.5588)
		(drill 0.3048)
		(layers "F.Cu" "B.Cu")
		(net "GND")
	)
	(via
		(at 116.84 -142.24)
		(size 0.5588)
		(drill 0.3048)
		(layers "F.Cu" "B.Cu")
		(net "GND")
	)
	(via
		(at 458.414882 -347.802962)
		(size 0.7112)
		(drill 0.4064)
		(layers "F.Cu" "B.Cu")
		(net "GND")
	)
	(via
		(at 25.4 -233.68)
		(size 0.5588)
		(drill 0.3048)
		(layers "F.Cu" "B.Cu")
		(net "GND")
	)
	(via
		(at 478.734882 -347.802962)
		(size 0.7112)
		(drill 0.4064)
		(layers "F.Cu" "B.Cu")
		(net "GND")
	)
	(via
		(at 20.32 -35.56)
		(size 0.5588)
		(drill 0.3048)
		(layers "F.Cu" "B.Cu")
		(net "GND")
	)
	(via
		(at 436.88 -35.56)
		(size 0.5588)
		(drill 0.3048)
		(layers "F.Cu" "B.Cu")
		(net "GND")
	)
	(via
		(at 133.35 -237.998)
		(size 0.5588)
		(drill 0.3048)
		(layers "F.Cu" "B.Cu")
		(net "GND")
	)
	(via
		(at 421.13962 -1.397)
		(size 0.7112)
		(drill 0.4064)
		(layers "F.Cu" "B.Cu")
		(net "GND")
	)
	(via
		(at 27.161998 -285.230062)
		(size 0.5588)
		(drill 0.3048)
		(layers "F.Cu" "B.Cu")
		(net "GND")
	)
	(via
		(at 201.397108 -384.292856)
		(size 0.7112)
		(drill 0.4064)
		(layers "F.Cu" "B.Cu")
		(net "GND")
	)
	(via
		(at 332.684882 -347.802962)
		(size 0.7112)
		(drill 0.4064)
		(layers "F.Cu" "B.Cu")
		(net "GND")
	)
	(via
		(at 420.304976 -279.655016)
		(size 0.5588)
		(drill 0.3048)
		(layers "F.Cu" "B.Cu")
		(net "GND")
	)
	(via
		(at 177.160682 -28.321)
		(size 0.5588)
		(drill 0.3048)
		(layers "F.Cu" "B.Cu")
		(net "GND")
	)
	(via
		(at 115.182142 -276.6822)
		(size 0.5588)
		(drill 0.3048)
		(layers "F.Cu" "B.Cu")
		(net "GND")
	)
	(via
		(at 183.896 -148.209)
		(size 0.5588)
		(drill 0.3048)
		(layers "F.Cu" "B.Cu")
		(net "GND")
	)
	(via
		(at 396.184882 -347.802962)
		(size 0.7112)
		(drill 0.4064)
		(layers "F.Cu" "B.Cu")
		(net "GND")
	)
	(via
		(at 388.754874 -67.434968)
		(size 0.5588)
		(drill 0.3048)
		(layers "F.Cu" "B.Cu")
		(net "GND")
	)
	(via
		(at 40.767 -48.26)
		(size 0.5588)
		(drill 0.3048)
		(layers "F.Cu" "B.Cu")
		(net "GND")
	)
	(via
		(at 402.782278 -34.073338)
		(size 0.5588)
		(drill 0.3048)
		(layers "F.Cu" "B.Cu")
		(net "GND")
	)
	(via
		(at 490.053122 -30.86735)
		(size 0.7112)
		(drill 0.4064)
		(layers "F.Cu" "B.Cu")
		(net "GND")
	)
	(via
		(at 144.112996 -347.802962)
		(size 0.7112)
		(drill 0.4064)
		(layers "F.Cu" "B.Cu")
		(net "GND")
	)
	(via
		(at 490.053122 -232.79735)
		(size 0.7112)
		(drill 0.4064)
		(layers "F.Cu" "B.Cu")
		(net "GND")
	)
	(via
		(at 145.382996 -347.802962)
		(size 0.7112)
		(drill 0.4064)
		(layers "F.Cu" "B.Cu")
		(net "GND")
	)
	(via
		(at 117.315996 -185.322718)
		(size 0.5588)
		(drill 0.3048)
		(layers "F.Cu" "B.Cu")
		(net "GND")
	)
	(via
		(at 87.340948 -76.240894)
		(size 0.5588)
		(drill 0.3048)
		(layers "F.Cu" "B.Cu")
		(net "GND")
	)
	(via
		(at 216.603326 -19.039078)
		(size 0.5588)
		(drill 0.3048)
		(layers "F.Cu" "B.Cu")
		(net "GND")
	)
	(via
		(at 181.393084 -1.397)
		(size 0.7112)
		(drill 0.4064)
		(layers "F.Cu" "B.Cu")
		(net "GND")
	)
	(via
		(at 460.239872 -279.596342)
		(size 0.5588)
		(drill 0.3048)
		(layers "F.Cu" "B.Cu")
		(net "GND")
	)
	(via
		(at 44.45 -290.322)
		(size 0.5588)
		(drill 0.3048)
		(layers "F.Cu" "B.Cu")
		(net "GND")
	)
	(via
		(at 169.963084 -1.397)
		(size 0.7112)
		(drill 0.4064)
		(layers "F.Cu" "B.Cu")
		(net "GND")
	)
	(via
		(at 451.61962 -1.397)
		(size 0.7112)
		(drill 0.4064)
		(layers "F.Cu" "B.Cu")
		(net "GND")
	)
	(via
		(at 408.43962 -1.397)
		(size 0.7112)
		(drill 0.4064)
		(layers "F.Cu" "B.Cu")
		(net "GND")
	)
	(via
		(at 456.0189 -76.113894)
		(size 0.5588)
		(drill 0.3048)
		(layers "F.Cu" "B.Cu")
		(net "GND")
	)
	(via
		(at 1.397 -178.178968)
		(size 0.7112)
		(drill 0.4064)
		(layers "F.Cu" "B.Cu")
		(net "GND")
	)
	(via
		(at 325.654924 -59.814968)
		(size 0.5588)
		(drill 0.3048)
		(layers "F.Cu" "B.Cu")
		(net "GND")
	)
	(via
		(at 380.7206 -59.8932)
		(size 0.5588)
		(drill 0.3048)
		(layers "F.Cu" "B.Cu")
		(net "GND")
	)
	(via
		(at 416.56 -330.2)
		(size 0.5588)
		(drill 0.3048)
		(layers "F.Cu" "B.Cu")
		(net "GND")
	)
	(via
		(at 294.302942 -368.825018)
		(size 0.7112)
		(drill 0.4064)
		(layers "F.Cu" "B.Cu")
		(net "GND")
	)
	(via
		(at 433.83962 -1.397)
		(size 0.7112)
		(drill 0.4064)
		(layers "F.Cu" "B.Cu")
		(net "GND")
	)
	(via
		(at 395.478 -16.383)
		(size 0.7112)
		(drill 0.4064)
		(layers "F.Cu" "B.Cu")
		(net "GND")
	)
	(via
		(at 28.304998 -59.814968)
		(size 0.5588)
		(drill 0.3048)
		(layers "F.Cu" "B.Cu")
		(net "GND")
	)
	(via
		(at 128.016 -251.079)
		(size 0.5588)
		(drill 0.3048)
		(layers "F.Cu" "B.Cu")
		(net "GND")
	)
	(via
		(at 142.579598 -284.701742)
		(size 0.5588)
		(drill 0.3048)
		(layers "F.Cu" "B.Cu")
		(net "GND")
	)
	(via
		(at 121.811796 -167.829992)
		(size 0.5588)
		(drill 0.3048)
		(layers "F.Cu" "B.Cu")
		(net "GND")
	)
	(via
		(at 156.282898 -79.784956)
		(size 0.5588)
		(drill 0.3048)
		(layers "F.Cu" "B.Cu")
		(net "GND")
	)
	(via
		(at 4.445 -340.36)
		(size 0.5588)
		(drill 0.3048)
		(layers "F.Cu" "B.Cu")
		(net "GND")
	)
	(via
		(at 490.053122 -48.64735)
		(size 0.7112)
		(drill 0.4064)
		(layers "F.Cu" "B.Cu")
		(net "GND")
	)
	(via
		(at 1.397 -113.408968)
		(size 0.7112)
		(drill 0.4064)
		(layers "F.Cu" "B.Cu")
		(net "GND")
	)
	(via
		(at 89.662254 -20.776946)
		(size 0.5588)
		(drill 0.3048)
		(layers "F.Cu" "B.Cu")
		(net "GND")
	)
	(via
		(at 423.768012 -299.975016)
		(size 0.5588)
		(drill 0.3048)
		(layers "F.Cu" "B.Cu")
		(net "GND")
	)
	(via
		(at 431.8 -15.24)
		(size 0.5588)
		(drill 0.3048)
		(layers "F.Cu" "B.Cu")
		(net "GND")
	)
	(via
		(at 201.397108 -417.312856)
		(size 0.7112)
		(drill 0.4064)
		(layers "F.Cu" "B.Cu")
		(net "GND")
	)
	(via
		(at 247.396 -102.108)
		(size 0.5588)
		(drill 0.3048)
		(layers "F.Cu" "B.Cu")
		(net "GND")
	)
	(via
		(at 1.397 -260.728968)
		(size 0.7112)
		(drill 0.4064)
		(layers "F.Cu" "B.Cu")
		(net "GND")
	)
	(via
		(at 164.846 -109.093)
		(size 0.5588)
		(drill 0.3048)
		(layers "F.Cu" "B.Cu")
		(net "GND")
	)
	(via
		(at 15.24 -76.2)
		(size 0.5588)
		(drill 0.3048)
		(layers "F.Cu" "B.Cu")
		(net "GND")
	)
	(via
		(at 23.876 -200.406)
		(size 0.5588)
		(drill 0.3048)
		(layers "F.Cu" "B.Cu")
		(net "GND")
	)
	(via
		(at 341.976202 -131.210812)
		(size 0.5588)
		(drill 0.3048)
		(layers "F.Cu" "B.Cu")
		(net "GND")
	)
	(via
		(at 331.47 -264.541)
		(size 0.5588)
		(drill 0.3048)
		(layers "F.Cu" "B.Cu")
		(net "GND")
	)
	(via
		(at 7.361682 -347.548962)
		(size 0.7112)
		(drill 0.4064)
		(layers "F.Cu" "B.Cu")
		(net "GND")
	)
	(via
		(at 420.304976 -62.354968)
		(size 0.5588)
		(drill 0.3048)
		(layers "F.Cu" "B.Cu")
		(net "GND")
	)
	(via
		(at 36.242498 -175.238918)
		(size 0.5588)
		(drill 0.3048)
		(layers "F.Cu" "B.Cu")
		(net "GND")
	)
	(via
		(at 490.053122 -213.74735)
		(size 0.7112)
		(drill 0.4064)
		(layers "F.Cu" "B.Cu")
		(net "GND")
	)
	(via
		(at 298.602908 26.058876)
		(size 0.7112)
		(drill 0.4064)
		(layers "F.Cu" "B.Cu")
		(net "GND")
	)
	(via
		(at 76.822808 -295.951148)
		(size 0.5588)
		(drill 0.3048)
		(layers "F.Cu" "B.Cu")
		(net "GND")
	)
	(via
		(at 460.114396 -182.225442)
		(size 0.5588)
		(drill 0.3048)
		(layers "F.Cu" "B.Cu")
		(net "GND")
	)
	(via
		(at 192.350898 -354.551742)
		(size 0.7112)
		(drill 0.4064)
		(layers "F.Cu" "B.Cu")
		(net "GND")
	)
	(via
		(at 277.603458 -395.957298)
		(size 0.5588)
		(drill 0.3048)
		(layers "F.Cu" "B.Cu")
		(net "GND")
	)
	(via
		(at 387.611874 -165.429946)
		(size 0.5588)
		(drill 0.3048)
		(layers "F.Cu" "B.Cu")
		(net "GND")
	)
	(via
		(at 127 -330.2)
		(size 0.5588)
		(drill 0.3048)
		(layers "F.Cu" "B.Cu")
		(net "GND")
	)
	(via
		(at 1.397 -248.028968)
		(size 0.7112)
		(drill 0.4064)
		(layers "F.Cu" "B.Cu")
		(net "GND")
	)
	(via
		(at 113.683796 -162.615118)
		(size 0.5588)
		(drill 0.3048)
		(layers "F.Cu" "B.Cu")
		(net "GND")
	)
	(via
		(at 411.48 -30.48)
		(size 0.5588)
		(drill 0.3048)
		(layers "F.Cu" "B.Cu")
		(net "GND")
	)
	(via
		(at 285.623 -271.0688)
		(size 0.5588)
		(drill 0.3048)
		(layers "F.Cu" "B.Cu")
		(net "GND")
	)
	(via
		(at 396.24 -35.56)
		(size 0.5588)
		(drill 0.3048)
		(layers "F.Cu" "B.Cu")
		(net "GND")
	)
	(via
		(at 252.73 -123.952)
		(size 0.5588)
		(drill 0.3048)
		(layers "F.Cu" "B.Cu")
		(net "GND")
	)
	(via
		(at 46.355 -144.0688)
		(size 0.5588)
		(drill 0.3048)
		(layers "F.Cu" "B.Cu")
		(net "GND")
	)
	(via
		(at 1.397 -76.578968)
		(size 0.7112)
		(drill 0.4064)
		(layers "F.Cu" "B.Cu")
		(net "GND")
	)
	(via
		(at 35.435032 -1.397)
		(size 0.7112)
		(drill 0.4064)
		(layers "F.Cu" "B.Cu")
		(net "GND")
	)
	(via
		(at 202.971908 -12.33805)
		(size 0.5588)
		(drill 0.3048)
		(layers "F.Cu" "B.Cu")
		(net "GND")
	)
	(via
		(at 81.752948 -292.778942)
		(size 0.5588)
		(drill 0.3048)
		(layers "F.Cu" "B.Cu")
		(net "GND")
	)
	(via
		(at 419.1 -254)
		(size 0.5588)
		(drill 0.3048)
		(layers "F.Cu" "B.Cu")
		(net "GND")
	)
	(via
		(at 98.806 -151.003)
		(size 0.5588)
		(drill 0.3048)
		(layers "F.Cu" "B.Cu")
		(net "GND")
	)
	(via
		(at 151.650954 -7.035546)
		(size 0.7112)
		(drill 0.4064)
		(layers "F.Cu" "B.Cu")
		(net "GND")
	)
	(via
		(at 242.307618 -237.14329)
		(size 0.5588)
		(drill 0.3048)
		(layers "F.Cu" "B.Cu")
		(net "GND")
	)
	(via
		(at 490.053122 -147.70735)
		(size 0.7112)
		(drill 0.4064)
		(layers "F.Cu" "B.Cu")
		(net "GND")
	)
	(via
		(at 261.9756 -285.6738)
		(size 0.5588)
		(drill 0.3048)
		(layers "F.Cu" "B.Cu")
		(net "GND")
	)
	(via
		(at 192.350898 -353.281742)
		(size 0.7112)
		(drill 0.4064)
		(layers "F.Cu" "B.Cu")
		(net "GND")
	)
	(via
		(at 365.687102 -164.570918)
		(size 0.5588)
		(drill 0.3048)
		(layers "F.Cu" "B.Cu")
		(net "GND")
	)
	(via
		(at 1.397 -291.208968)
		(size 0.7112)
		(drill 0.4064)
		(layers "F.Cu" "B.Cu")
		(net "GND")
	)
	(via
		(at 212.862922 -9.453118)
		(size 0.5588)
		(drill 0.3048)
		(layers "F.Cu" "B.Cu")
		(net "GND")
	)
	(via
		(at 483.234746 -214.977472)
		(size 0.5588)
		(drill 0.3048)
		(layers "F.Cu" "B.Cu")
		(net "GND")
	)
	(via
		(at 472.190318 -41.07815)
		(size 0.5588)
		(drill 0.3048)
		(layers "F.Cu" "B.Cu")
		(net "GND")
	)
	(via
		(at 288.911284 -296.505122)
		(size 0.6604)
		(drill 0.3556)
		(layers "F.Cu" "B.Cu")
		(net "GND")
	)
	(via
		(at 265.3284 -99.695)
		(size 0.5588)
		(drill 0.3048)
		(layers "F.Cu" "B.Cu")
		(net "GND")
	)
	(via
		(at 426.72 -132.08)
		(size 0.5588)
		(drill 0.3048)
		(layers "F.Cu" "B.Cu")
		(net "GND")
	)
	(via
		(at 308.483 -335.407)
		(size 0.5588)
		(drill 0.3048)
		(layers "F.Cu" "B.Cu")
		(net "GND")
	)
	(via
		(at 12.556998 -294.683942)
		(size 0.5588)
		(drill 0.3048)
		(layers "F.Cu" "B.Cu")
		(net "GND")
	)
	(via
		(at 156.282898 -194.78498)
		(size 0.5588)
		(drill 0.3048)
		(layers "F.Cu" "B.Cu")
		(net "GND")
	)
	(via
		(at 324.511924 -170.230038)
		(size 0.5588)
		(drill 0.3048)
		(layers "F.Cu" "B.Cu")
		(net "GND")
	)
	(via
		(at 5.08 -101.6)
		(size 0.5588)
		(drill 0.3048)
		(layers "F.Cu" "B.Cu")
		(net "GND")
	)
	(via
		(at 28.304998 -157.034992)
		(size 0.5588)
		(drill 0.3048)
		(layers "F.Cu" "B.Cu")
		(net "GND")
	)
	(via
		(at 457.6699 -306.113942)
		(size 0.5588)
		(drill 0.3048)
		(layers "F.Cu" "B.Cu")
		(net "GND")
	)
	(via
		(at 1.397 -148.968968)
		(size 0.7112)
		(drill 0.4064)
		(layers "F.Cu" "B.Cu")
		(net "GND")
	)
	(via
		(at 1.397 -146.428968)
		(size 0.7112)
		(drill 0.4064)
		(layers "F.Cu" "B.Cu")
		(net "GND")
	)
	(via
		(at 1.397 -300.098968)
		(size 0.7112)
		(drill 0.4064)
		(layers "F.Cu" "B.Cu")
		(net "GND")
	)
	(via
		(at 22.352 -153.035)
		(size 0.5588)
		(drill 0.3048)
		(layers "F.Cu" "B.Cu")
		(net "GND")
	)
	(via
		(at 470.66962 -1.397)
		(size 0.7112)
		(drill 0.4064)
		(layers "F.Cu" "B.Cu")
		(net "GND")
	)
	(via
		(at 133.477 -245.618)
		(size 0.5588)
		(drill 0.3048)
		(layers "F.Cu" "B.Cu")
		(net "GND")
	)
	(via
		(at 1.397 -174.368968)
		(size 0.7112)
		(drill 0.4064)
		(layers "F.Cu" "B.Cu")
		(net "GND")
	)
	(via
		(at 303.344072 -183.6674)
		(size 0.5588)
		(drill 0.3048)
		(layers "F.Cu" "B.Cu")
		(net "GND")
	)
	(via
		(at 431.8 -101.6)
		(size 0.5588)
		(drill 0.3048)
		(layers "F.Cu" "B.Cu")
		(net "GND")
	)
	(via
		(at 430.02962 -1.397)
		(size 0.7112)
		(drill 0.4064)
		(layers "F.Cu" "B.Cu")
		(net "GND")
	)
	(via
		(at 1.397 -253.108968)
		(size 0.7112)
		(drill 0.4064)
		(layers "F.Cu" "B.Cu")
		(net "GND")
	)
	(via
		(at 457.2 -116.84)
		(size 0.5588)
		(drill 0.3048)
		(layers "F.Cu" "B.Cu")
		(net "GND")
	)
	(via
		(at 137.16 -152.4)
		(size 0.5588)
		(drill 0.3048)
		(layers "F.Cu" "B.Cu")
		(net "GND")
	)
	(via
		(at 490.053122 -268.951202)
		(size 0.7112)
		(drill 0.4064)
		(layers "F.Cu" "B.Cu")
		(net "GND")
	)
	(via
		(at 77.919834 -131.148074)
		(size 0.5588)
		(drill 0.3048)
		(layers "F.Cu" "B.Cu")
		(net "GND")
	)
	(via
		(at 74.93 -101.6)
		(size 0.5588)
		(drill 0.3048)
		(layers "F.Cu" "B.Cu")
		(net "GND")
	)
	(via
		(at 387.35 -223.012)
		(size 0.5588)
		(drill 0.3048)
		(layers "F.Cu" "B.Cu")
		(net "GND")
	)
	(via
		(at 298.602908 17.168876)
		(size 0.7112)
		(drill 0.4064)
		(layers "F.Cu" "B.Cu")
		(net "GND")
	)
	(via
		(at 92.585032 -1.397)
		(size 0.7112)
		(drill 0.4064)
		(layers "F.Cu" "B.Cu")
		(net "GND")
	)
	(via
		(at 34.036 -270.256)
		(size 0.5588)
		(drill 0.3048)
		(layers "F.Cu" "B.Cu")
		(net "GND")
	)
	(via
		(at 91.404948 -275.845016)
		(size 0.5588)
		(drill 0.3048)
		(layers "F.Cu" "B.Cu")
		(net "GND")
	)
	(via
		(at 74.93 -111.76)
		(size 0.5588)
		(drill 0.3048)
		(layers "F.Cu" "B.Cu")
		(net "GND")
	)
	(via
		(at 6.35 -256.54)
		(size 0.5588)
		(drill 0.3048)
		(layers "F.Cu" "B.Cu")
		(net "GND")
	)
	(via
		(at 394.26515 -276.649942)
		(size 0.5588)
		(drill 0.3048)
		(layers "F.Cu" "B.Cu")
		(net "GND")
	)
	(via
		(at 39.071296 -304.100992)
		(size 0.5588)
		(drill 0.3048)
		(layers "F.Cu" "B.Cu")
		(net "GND")
	)
	(via
		(at 470.035128 -292.934644)
		(size 0.5588)
		(drill 0.3048)
		(layers "F.Cu" "B.Cu")
		(net "GND")
	)
	(via
		(at 30.163262 -151.035004)
		(size 0.5588)
		(drill 0.3048)
		(layers "F.Cu" "B.Cu")
		(net "GND")
	)
	(via
		(at 490.053122 -101.98735)
		(size 0.7112)
		(drill 0.4064)
		(layers "F.Cu" "B.Cu")
		(net "GND")
	)
	(via
		(at 313.1058 -241.4016)
		(size 0.5588)
		(drill 0.3048)
		(layers "F.Cu" "B.Cu")
		(net "GND")
	)
	(via
		(at 472.44 -35.56)
		(size 0.5588)
		(drill 0.3048)
		(layers "F.Cu" "B.Cu")
		(net "GND")
	)
	(via
		(at 17.653 -197.358)
		(size 0.5588)
		(drill 0.3048)
		(layers "F.Cu" "B.Cu")
		(net "GND")
	)
	(via
		(at 1.397 -218.818968)
		(size 0.7112)
		(drill 0.4064)
		(layers "F.Cu" "B.Cu")
		(net "GND")
	)
	(via
		(at 283.21 19.685)
		(size 0.5588)
		(drill 0.3048)
		(layers "F.Cu" "B.Cu")
		(net "GND")
	)
	(via
		(at 115.443 -317.119)
		(size 0.5588)
		(drill 0.3048)
		(layers "F.Cu" "B.Cu")
		(net "GND")
	)
	(via
		(at 364.594902 -273.855942)
		(size 0.5588)
		(drill 0.3048)
		(layers "F.Cu" "B.Cu")
		(net "GND")
	)
	(via
		(at 490.053122 -312.131202)
		(size 0.7112)
		(drill 0.4064)
		(layers "F.Cu" "B.Cu")
		(net "GND")
	)
	(via
		(at 258.572 -273.431)
		(size 0.5588)
		(drill 0.3048)
		(layers "F.Cu" "B.Cu")
		(net "GND")
	)
	(via
		(at 420.304976 -275.845016)
		(size 0.5588)
		(drill 0.3048)
		(layers "F.Cu" "B.Cu")
		(net "GND")
	)
	(via
		(at 450.711824 -280.42997)
		(size 0.5588)
		(drill 0.3048)
		(layers "F.Cu" "B.Cu")
		(net "GND")
	)
	(via
		(at 482.261926 -167.829992)
		(size 0.5588)
		(drill 0.3048)
		(layers "F.Cu" "B.Cu")
		(net "GND")
	)
	(via
		(at 120.985026 -36.698174)
		(size 0.5588)
		(drill 0.3048)
		(layers "F.Cu" "B.Cu")
		(net "GND")
	)
	(via
		(at 117.124988 -49.494694)
		(size 0.5588)
		(drill 0.3048)
		(layers "F.Cu" "B.Cu")
		(net "GND")
	)
	(via
		(at 65.372996 -347.802962)
		(size 0.7112)
		(drill 0.4064)
		(layers "F.Cu" "B.Cu")
		(net "GND")
	)
	(via
		(at 1.397 -18.158968)
		(size 0.7112)
		(drill 0.4064)
		(layers "F.Cu" "B.Cu")
		(net "GND")
	)
	(via
		(at 448.747134 -181.991)
		(size 0.5588)
		(drill 0.3048)
		(layers "F.Cu" "B.Cu")
		(net "GND")
	)
	(via
		(at 453.632824 -266.035028)
		(size 0.5588)
		(drill 0.3048)
		(layers "F.Cu" "B.Cu")
		(net "GND")
	)
	(via
		(at 490.053122 -262.601202)
		(size 0.7112)
		(drill 0.4064)
		(layers "F.Cu" "B.Cu")
		(net "GND")
	)
	(via
		(at 1.397 -270.888968)
		(size 0.7112)
		(drill 0.4064)
		(layers "F.Cu" "B.Cu")
		(net "GND")
	)
	(via
		(at 45.72 -76.2)
		(size 0.5588)
		(drill 0.3048)
		(layers "F.Cu" "B.Cu")
		(net "GND")
	)
	(via
		(at 419.161976 -280.42997)
		(size 0.5588)
		(drill 0.3048)
		(layers "F.Cu" "B.Cu")
		(net "GND")
	)
	(via
		(at 436.88 -76.2)
		(size 0.5588)
		(drill 0.3048)
		(layers "F.Cu" "B.Cu")
		(net "GND")
	)
	(via
		(at 297.966892 -419.803072)
		(size 0.7112)
		(drill 0.4064)
		(layers "F.Cu" "B.Cu")
		(net "GND")
	)
	(via
		(at 65.278 -318.262)
		(size 0.5588)
		(drill 0.3048)
		(layers "F.Cu" "B.Cu")
		(net "GND")
	)
	(via
		(at 422.40962 -1.397)
		(size 0.7112)
		(drill 0.4064)
		(layers "F.Cu" "B.Cu")
		(net "GND")
	)
	(via
		(at 327.432924 -194.78498)
		(size 0.5588)
		(drill 0.3048)
		(layers "F.Cu" "B.Cu")
		(net "GND")
	)
	(via
		(at 110.949994 -31.624778)
		(size 0.6604)
		(drill 0.3556)
		(layers "F.Cu" "B.Cu")
		(net "GND")
	)
	(via
		(at 346.349066 -13.110972)
		(size 0.7112)
		(drill 0.4064)
		(layers "F.Cu" "B.Cu")
		(net "GND")
	)
	(via
		(at 490.053122 -244.22735)
		(size 0.7112)
		(drill 0.4064)
		(layers "F.Cu" "B.Cu")
		(net "GND")
	)
	(via
		(at 82.425032 -1.397)
		(size 0.7112)
		(drill 0.4064)
		(layers "F.Cu" "B.Cu")
		(net "GND")
	)
	(via
		(at 461.77962 -1.397)
		(size 0.7112)
		(drill 0.4064)
		(layers "F.Cu" "B.Cu")
		(net "GND")
	)
	(via
		(at 89.911682 -347.548962)
		(size 0.7112)
		(drill 0.4064)
		(layers "F.Cu" "B.Cu")
		(net "GND")
	)
	(via
		(at 302.785272 -180.9242)
		(size 0.5588)
		(drill 0.3048)
		(layers "F.Cu" "B.Cu")
		(net "GND")
	)
	(via
		(at 262.255 -316.992)
		(size 0.5588)
		(drill 0.3048)
		(layers "F.Cu" "B.Cu")
		(net "GND")
	)
	(via
		(at 181.991 -76.240894)
		(size 0.5588)
		(drill 0.3048)
		(layers "F.Cu" "B.Cu")
		(net "GND")
	)
	(via
		(at 449.524882 -347.802962)
		(size 0.7112)
		(drill 0.4064)
		(layers "F.Cu" "B.Cu")
		(net "GND")
	)
	(via
		(at 1.397 -345.818968)
		(size 0.7112)
		(drill 0.4064)
		(layers "F.Cu" "B.Cu")
		(net "GND")
	)
	(via
		(at 47.371 -144.0688)
		(size 0.5588)
		(drill 0.3048)
		(layers "F.Cu" "B.Cu")
		(net "GND")
	)
	(via
		(at 72.136 -154.305)
		(size 0.5588)
		(drill 0.3048)
		(layers "F.Cu" "B.Cu")
		(net "GND")
	)
	(via
		(at 133.663436 -183.049164)
		(size 0.5588)
		(drill 0.3048)
		(layers "F.Cu" "B.Cu")
		(net "GND")
	)
	(via
		(at 180.4162 -70.322694)
		(size 0.5588)
		(drill 0.3048)
		(layers "F.Cu" "B.Cu")
		(net "GND")
	)
	(via
		(at 308.602888 -400.721068)
		(size 0.7112)
		(drill 0.4064)
		(layers "F.Cu" "B.Cu")
		(net "GND")
	)
	(via
		(at 443.23 -175.26)
		(size 0.5588)
		(drill 0.3048)
		(layers "F.Cu" "B.Cu")
		(net "GND")
	)
	(via
		(at 193.04 -15.24)
		(size 0.5588)
		(drill 0.3048)
		(layers "F.Cu" "B.Cu")
		(net "GND")
	)
	(via
		(at 308.602888 -376.591068)
		(size 0.7112)
		(drill 0.4064)
		(layers "F.Cu" "B.Cu")
		(net "GND")
	)
	(via
		(at 218.973146 -14.383004)
		(size 0.5588)
		(drill 0.3048)
		(layers "F.Cu" "B.Cu")
		(net "GND")
	)
	(via
		(at 236.031278 -263.114282)
		(size 0.5588)
		(drill 0.3048)
		(layers "F.Cu" "B.Cu")
		(net "GND")
	)
	(via
		(at 490.053122 -121.03735)
		(size 0.7112)
		(drill 0.4064)
		(layers "F.Cu" "B.Cu")
		(net "GND")
	)
	(via
		(at 105.918 -165.735)
		(size 0.5588)
		(drill 0.3048)
		(layers "F.Cu" "B.Cu")
		(net "GND")
	)
	(via
		(at 490.053122 -211.20735)
		(size 0.7112)
		(drill 0.4064)
		(layers "F.Cu" "B.Cu")
		(net "GND")
	)
	(via
		(at 344.521028 -1.397)
		(size 0.7112)
		(drill 0.4064)
		(layers "F.Cu" "B.Cu")
		(net "GND")
	)
	(via
		(at 40.64 -233.68)
		(size 0.5588)
		(drill 0.3048)
		(layers "F.Cu" "B.Cu")
		(net "GND")
	)
	(via
		(at 201.397108 -391.912856)
		(size 0.7112)
		(drill 0.4064)
		(layers "F.Cu" "B.Cu")
		(net "GND")
	)
	(via
		(at 113.302796 -59.603894)
		(size 0.5588)
		(drill 0.3048)
		(layers "F.Cu" "B.Cu")
		(net "GND")
	)
	(via
		(at 20.701 -170.688)
		(size 0.5588)
		(drill 0.3048)
		(layers "F.Cu" "B.Cu")
		(net "GND")
	)
	(via
		(at 268.732 -121.158)
		(size 0.5588)
		(drill 0.3048)
		(layers "F.Cu" "B.Cu")
		(net "GND")
	)
	(via
		(at 111.76 -193.04)
		(size 0.5588)
		(drill 0.3048)
		(layers "F.Cu" "B.Cu")
		(net "GND")
	)
	(via
		(at 172.847 -306.959)
		(size 0.5588)
		(drill 0.3048)
		(layers "F.Cu" "B.Cu")
		(net "GND")
	)
	(via
		(at 1.397 -142.618968)
		(size 0.7112)
		(drill 0.4064)
		(layers "F.Cu" "B.Cu")
		(net "GND")
	)
	(via
		(at 351.409 -129.413)
		(size 0.5588)
		(drill 0.3048)
		(layers "F.Cu" "B.Cu")
		(net "GND")
	)
	(via
		(at 262.509762 -26.045922)
		(size 0.5588)
		(drill 0.3048)
		(layers "F.Cu" "B.Cu")
		(net "GND")
	)
	(via
		(at 308.554882 -347.802962)
		(size 0.7112)
		(drill 0.4064)
		(layers "F.Cu" "B.Cu")
		(net "GND")
	)
	(via
		(at 393.93495 -67.604894)
		(size 0.5588)
		(drill 0.3048)
		(layers "F.Cu" "B.Cu")
		(net "GND")
	)
	(via
		(at 308.602888 -418.501068)
		(size 0.7112)
		(drill 0.4064)
		(layers "F.Cu" "B.Cu")
		(net "GND")
	)
	(via
		(at 189.23 -211.582)
		(size 0.5588)
		(drill 0.3048)
		(layers "F.Cu" "B.Cu")
		(net "GND")
	)
	(via
		(at 180.4162 -185.322718)
		(size 0.5588)
		(drill 0.3048)
		(layers "F.Cu" "B.Cu")
		(net "GND")
	)
	(via
		(at 490.053122 -181.99735)
		(size 0.7112)
		(drill 0.4064)
		(layers "F.Cu" "B.Cu")
		(net "GND")
	)
	(via
		(at 181.991 -306.240942)
		(size 0.5588)
		(drill 0.3048)
		(layers "F.Cu" "B.Cu")
		(net "GND")
	)
	(via
		(at 490.053122 -150.24735)
		(size 0.7112)
		(drill 0.4064)
		(layers "F.Cu" "B.Cu")
		(net "GND")
	)
	(via
		(at 466.744304 -179.683918)
		(size 0.5588)
		(drill 0.3048)
		(layers "F.Cu" "B.Cu")
		(net "GND")
	)
	(via
		(at 426.72 -15.24)
		(size 0.5588)
		(drill 0.3048)
		(layers "F.Cu" "B.Cu")
		(net "GND")
	)
	(via
		(at 490.053122 -327.371202)
		(size 0.7112)
		(drill 0.4064)
		(layers "F.Cu" "B.Cu")
		(net "GND")
	)
	(via
		(at 130.892296 -175.238918)
		(size 0.5588)
		(drill 0.3048)
		(layers "F.Cu" "B.Cu")
		(net "GND")
	)
	(via
		(at 40.64 -76.2)
		(size 0.5588)
		(drill 0.3048)
		(layers "F.Cu" "B.Cu")
		(net "GND")
	)
	(via
		(at 451.854824 -299.975016)
		(size 0.5588)
		(drill 0.3048)
		(layers "F.Cu" "B.Cu")
		(net "GND")
	)
	(via
		(at 457.2 -142.24)
		(size 0.5588)
		(drill 0.3048)
		(layers "F.Cu" "B.Cu")
		(net "GND")
	)
	(via
		(at 81.752948 -177.778918)
		(size 0.5588)
		(drill 0.3048)
		(layers "F.Cu" "B.Cu")
		(net "GND")
	)
	(via
		(at 217.533728 -104.14)
		(size 0.5588)
		(drill 0.3048)
		(layers "F.Cu" "B.Cu")
		(net "GND")
	)
	(via
		(at 187.96 -10.16)
		(size 0.5588)
		(drill 0.3048)
		(layers "F.Cu" "B.Cu")
		(net "GND")
	)
	(via
		(at 396.85595 -297.223942)
		(size 0.5588)
		(drill 0.3048)
		(layers "F.Cu" "B.Cu")
		(net "GND")
	)
	(via
		(at 483.404926 -69.974968)
		(size 0.5588)
		(drill 0.3048)
		(layers "F.Cu" "B.Cu")
		(net "GND")
	)
	(via
		(at 58.295032 -1.397)
		(size 0.7112)
		(drill 0.4064)
		(layers "F.Cu" "B.Cu")
		(net "GND")
	)
	(via
		(at 485.182926 -151.035004)
		(size 0.5588)
		(drill 0.3048)
		(layers "F.Cu" "B.Cu")
		(net "GND")
	)
	(via
		(at 1.397 -269.618968)
		(size 0.7112)
		(drill 0.4064)
		(layers "F.Cu" "B.Cu")
		(net "GND")
	)
	(via
		(at 192.350898 -365.981742)
		(size 0.7112)
		(drill 0.4064)
		(layers "F.Cu" "B.Cu")
		(net "GND")
	)
	(via
		(at 450.711824 -170.230038)
		(size 0.5588)
		(drill 0.3048)
		(layers "F.Cu" "B.Cu")
		(net "GND")
	)
	(via
		(at 96.52 -5.08)
		(size 0.5588)
		(drill 0.3048)
		(layers "F.Cu" "B.Cu")
		(net "GND")
	)
	(via
		(at 80.724248 -25.12187)
		(size 0.5588)
		(drill 0.3048)
		(layers "F.Cu" "B.Cu")
		(net "GND")
	)
	(via
		(at 63.119 -200.279)
		(size 0.5588)
		(drill 0.3048)
		(layers "F.Cu" "B.Cu")
		(net "GND")
	)
	(via
		(at 26.543 -130.937)
		(size 0.5588)
		(drill 0.3048)
		(layers "F.Cu" "B.Cu")
		(net "GND")
	)
	(via
		(at 450.711824 -167.829992)
		(size 0.5588)
		(drill 0.3048)
		(layers "F.Cu" "B.Cu")
		(net "GND")
	)
	(via
		(at 441.96 -15.24)
		(size 0.5588)
		(drill 0.3048)
		(layers "F.Cu" "B.Cu")
		(net "GND")
	)
	(via
		(at 21.1074 -250.1392)
		(size 0.7112)
		(drill 0.4064)
		(layers "F.Cu" "B.Cu")
		(net "GND")
	)
	(via
		(at 185.686192 -60.595002)
		(size 0.5588)
		(drill 0.3048)
		(layers "F.Cu" "B.Cu")
		(net "GND")
	)
	(via
		(at 288.911284 -354.10521)
		(size 0.6604)
		(drill 0.3556)
		(layers "F.Cu" "B.Cu")
		(net "GND")
	)
	(via
		(at 1.397 -77.848968)
		(size 0.7112)
		(drill 0.4064)
		(layers "F.Cu" "B.Cu")
		(net "GND")
	)
	(via
		(at 299.236892 -419.803072)
		(size 0.7112)
		(drill 0.4064)
		(layers "F.Cu" "B.Cu")
		(net "GND")
	)
	(via
		(at 320.391028 -1.397)
		(size 0.7112)
		(drill 0.4064)
		(layers "F.Cu" "B.Cu")
		(net "GND")
	)
	(via
		(at 490.053122 -86.74735)
		(size 0.7112)
		(drill 0.4064)
		(layers "F.Cu" "B.Cu")
		(net "GND")
	)
	(via
		(at 180.942996 -347.802962)
		(size 0.7112)
		(drill 0.4064)
		(layers "F.Cu" "B.Cu")
		(net "GND")
	)
	(via
		(at 201.422 -210.312)
		(size 0.5588)
		(drill 0.3048)
		(layers "F.Cu" "B.Cu")
		(net "GND")
	)
	(via
		(at 228.092 -33.782)
		(size 0.5588)
		(drill 0.3048)
		(layers "F.Cu" "B.Cu")
		(net "GND")
	)
	(via
		(at 28.304998 -279.655016)
		(size 0.5588)
		(drill 0.3048)
		(layers "F.Cu" "B.Cu")
		(net "GND")
	)
	(via
		(at 59.854846 -62.354968)
		(size 0.5588)
		(drill 0.3048)
		(layers "F.Cu" "B.Cu")
		(net "GND")
	)
	(via
		(at 93.855032 -1.397)
		(size 0.7112)
		(drill 0.4064)
		(layers "F.Cu" "B.Cu")
		(net "GND")
	)
	(via
		(at 325.654924 -297.435016)
		(size 0.5588)
		(drill 0.3048)
		(layers "F.Cu" "B.Cu")
		(net "GND")
	)
	(via
		(at 153.361898 -170.230038)
		(size 0.5588)
		(drill 0.3048)
		(layers "F.Cu" "B.Cu")
		(net "GND")
	)
	(via
		(at 216.619328 -104.14)
		(size 0.5588)
		(drill 0.3048)
		(layers "F.Cu" "B.Cu")
		(net "GND")
	)
	(via
		(at 328.874882 -347.802962)
		(size 0.7112)
		(drill 0.4064)
		(layers "F.Cu" "B.Cu")
		(net "GND")
	)
	(via
		(at 490.053122 -29.59735)
		(size 0.7112)
		(drill 0.4064)
		(layers "F.Cu" "B.Cu")
		(net "GND")
	)
	(via
		(at 192.823084 -1.397)
		(size 0.7112)
		(drill 0.4064)
		(layers "F.Cu" "B.Cu")
		(net "GND")
	)
	(via
		(at 473.526104 -231.662986)
		(size 0.5588)
		(drill 0.3048)
		(layers "F.Cu" "B.Cu")
		(net "GND")
	)
	(via
		(at 410.97962 -1.397)
		(size 0.7112)
		(drill 0.4064)
		(layers "F.Cu" "B.Cu")
		(net "GND")
	)
	(via
		(at 466.38591 -239.204754)
		(size 0.5588)
		(drill 0.3048)
		(layers "F.Cu" "B.Cu")
		(net "GND")
	)
	(via
		(at 298.602908 27.328876)
		(size 0.7112)
		(drill 0.4064)
		(layers "F.Cu" "B.Cu")
		(net "GND")
	)
	(via
		(at 265.43 -92.456)
		(size 0.5588)
		(drill 0.3048)
		(layers "F.Cu" "B.Cu")
		(net "GND")
	)
	(via
		(at 201.397108 -410.962856)
		(size 0.7112)
		(drill 0.4064)
		(layers "F.Cu" "B.Cu")
		(net "GND")
	)
	(via
		(at 179.672996 -347.802962)
		(size 0.7112)
		(drill 0.4064)
		(layers "F.Cu" "B.Cu")
		(net "GND")
	)
	(via
		(at 49.405032 -1.397)
		(size 0.7112)
		(drill 0.4064)
		(layers "F.Cu" "B.Cu")
		(net "GND")
	)
	(via
		(at 466.85962 -1.397)
		(size 0.7112)
		(drill 0.4064)
		(layers "F.Cu" "B.Cu")
		(net "GND")
	)
	(via
		(at 79.479648 -284.041342)
		(size 0.5588)
		(drill 0.3048)
		(layers "F.Cu" "B.Cu")
		(net "GND")
	)
	(segment
		(start 480.695 -226.2505)
		(end 480.695 -227.150422)
		(width 0.508)
		(layer "B.Cu")
		(net "GND")
	)
	(segment
		(start 186.329828 -219.107004)
		(end 186.329828 -217.928952)
		(width 0.508)
		(layer "B.Cu")
		(net "GND")
	)
	(segment
		(start 480.695 -227.150422)
		(end 480.680522 -227.1649)
		(width 0.508)
		(layer "B.Cu")
		(net "GND")
	)
	(segment
		(start 190.934594 -222.686118)
		(end 189.904624 -222.686118)
		(width 0.508)
		(layer "B.Cu")
		(net "GND")
	)
	(segment
		(start 217.6526 -119.51081)
		(end 216.69121 -119.51081)
		(width 0.3048)
		(layer "B.Cu")
		(net "GND")
	)
	(segment
		(start 480.680522 -227.965)
		(end 480.680522 -227.1649)
		(width 0.508)
		(layer "B.Cu")
		(net "GND")
	)
	(segment
		(start 214.9856 -119.2022)
		(end 215.8111 -119.2022)
		(width 0.508)
		(layer "B.Cu")
		(net "GND")
	)
	(segment
		(start 479.552 -227.33)
		(end 478.5868 -227.33)
		(width 0.508)
		(layer "B.Cu")
		(net "GND")
	)
	(segment
		(start 182.618126 -219.93987)
		(end 182.510938 -219.93987)
		(width 0.381)
		(layer "B.Cu")
		(net "GND")
	)
	(segment
		(start 186.329828 -217.928952)
		(end 186.289188 -217.888312)
		(width 0.508)
		(layer "B.Cu")
		(net "GND")
	)
	(segment
		(start 216.69121 -119.51081)
		(end 216.4969 -119.3165)
		(width 0.3048)
		(layer "B.Cu")
		(net "GND")
	)
	(segment
		(start 222.1992 -117.8433)
		(end 221.449392 -117.8433)
		(width 0.508)
		(layer "B.Cu")
		(net "GND")
	)
	(segment
		(start 221.449392 -117.8433)
		(end 221.357698 -117.751606)
		(width 0.508)
		(layer "B.Cu")
		(net "GND")
	)
	(segment
		(start 216.4969 -119.3165)
		(end 215.9254 -119.3165)
		(width 0.3048)
		(layer "B.Cu")
		(net "GND")
	)
	(segment
		(start 181.357016 -222.747332)
		(end 180.005482 -222.747332)
		(width 0.508)
		(layer "B.Cu")
		(net "GND")
	)
	(segment
		(start 182.510938 -219.93987)
		(end 181.923182 -220.527626)
		(width 0.381)
		(layer "B.Cu")
		(net "GND")
	)
	(segment
		(start 215.8111 -119.2022)
		(end 215.9254 -119.3165)
		(width 0.508)
		(layer "B.Cu")
		(net "GND")
	)
	(segment
		(start 413.005016 -298.705016)
		(end 422.025064 -298.705016)
		(width 0.17145)
		(layer "F.Cu")
		(net "ACT_HDD_9")
	)
	(segment
		(start 413.004 -298.704)
		(end 413.005016 -298.705016)
		(width 0.17145)
		(layer "F.Cu")
		(net "ACT_HDD_9")
	)
	(segment
		(start 381.5842 -298.704)
		(end 381.585216 -298.705016)
		(width 0.17145)
		(layer "F.Cu")
		(net "ACT_HDD_8")
	)
	(segment
		(start 381.585216 -298.705016)
		(end 390.474962 -298.705016)
		(width 0.17145)
		(layer "F.Cu")
		(net "ACT_HDD_8")
	)
	(segment
		(start 350.114616 -298.705016)
		(end 358.925114 -298.705016)
		(width 0.17145)
		(layer "F.Cu")
		(net "ACT_HDD_7")
	)
	(segment
		(start 350.1136 -298.704)
		(end 350.114616 -298.705016)
		(width 0.17145)
		(layer "F.Cu")
		(net "ACT_HDD_7")
	)
	(segment
		(start 318.4906 -298.704)
		(end 318.491616 -298.705016)
		(width 0.17145)
		(layer "F.Cu")
		(net "ACT_HDD_6")
	)
	(segment
		(start 318.491616 -298.705016)
		(end 327.375012 -298.705016)
		(width 0.17145)
		(layer "F.Cu")
		(net "ACT_HDD_6")
	)
	(segment
		(start 193.2686 -298.704)
		(end 193.267584 -298.705016)
		(width 0.17145)
		(layer "F.Cu")
		(net "ACT_HDD_5")
	)
	(segment
		(start 193.267584 -298.705016)
		(end 187.775088 -298.705016)
		(width 0.17145)
		(layer "F.Cu")
		(net "ACT_HDD_5")
	)
	(segment
		(start 160.198816 -298.704)
		(end 160.1978 -298.705016)
		(width 0.17145)
		(layer "F.Cu")
		(net "ACT_HDD_4")
	)
	(segment
		(start 161.7472 -298.704)
		(end 160.198816 -298.704)
		(width 0.17145)
		(layer "F.Cu")
		(net "ACT_HDD_4")
	)
	(segment
		(start 160.1978 -298.705016)
		(end 156.224986 -298.705016)
		(width 0.17145)
		(layer "F.Cu")
		(net "ACT_HDD_4")
	)
	(segment
		(start 482.408992 -68.704968)
		(end 485.125014 -68.704968)
		(width 0.17145)
		(layer "F.Cu")
		(net "ACT_HDD_35")
	)
	(segment
		(start 481.064824 -67.3608)
		(end 482.408992 -68.704968)
		(width 0.17145)
		(layer "F.Cu")
		(net "ACT_HDD_35")
	)
	(segment
		(start 476.8596 -67.3608)
		(end 481.064824 -67.3608)
		(width 0.17145)
		(layer "F.Cu")
		(net "ACT_HDD_35")
	)
	(segment
		(start 444.730632 -68.704968)
		(end 453.574912 -68.704968)
		(width 0.17145)
		(layer "F.Cu")
		(net "ACT_HDD_34")
	)
	(segment
		(start 444.7286 -68.707)
		(end 444.730632 -68.704968)
		(width 0.17145)
		(layer "F.Cu")
		(net "ACT_HDD_34")
	)
	(segment
		(start 413.514032 -68.704968)
		(end 422.025064 -68.704968)
		(width 0.17145)
		(layer "F.Cu")
		(net "ACT_HDD_33")
	)
	(segment
		(start 413.512 -68.707)
		(end 413.514032 -68.704968)
		(width 0.17145)
		(layer "F.Cu")
		(net "ACT_HDD_33")
	)
	(segment
		(start 384.249168 -68.704968)
		(end 390.474962 -68.704968)
		(width 0.17145)
		(layer "F.Cu")
		(net "ACT_HDD_32")
	)
	(segment
		(start 383.0066 -67.4624)
		(end 384.249168 -68.704968)
		(width 0.17145)
		(layer "F.Cu")
		(net "ACT_HDD_32")
	)
	(segment
		(start 381.2286 -67.4624)
		(end 383.0066 -67.4624)
		(width 0.17145)
		(layer "F.Cu")
		(net "ACT_HDD_32")
	)
	(segment
		(start 350.213168 -68.704968)
		(end 358.925114 -68.704968)
		(width 0.17145)
		(layer "F.Cu")
		(net "ACT_HDD_31")
	)
	(segment
		(start 350.1898 -68.6816)
		(end 350.213168 -68.704968)
		(width 0.17145)
		(layer "F.Cu")
		(net "ACT_HDD_31")
	)
	(segment
		(start 327.375012 -68.704968)
		(end 318.391032 -68.704968)
		(width 0.17145)
		(layer "F.Cu")
		(net "ACT_HDD_30")
	)
	(segment
		(start 318.391032 -68.704968)
		(end 317.627 -69.469)
		(width 0.17145)
		(layer "F.Cu")
		(net "ACT_HDD_30")
	)
	(segment
		(start 127.127 -298.704)
		(end 127.125984 -298.705016)
		(width 0.17145)
		(layer "F.Cu")
		(net "ACT_HDD_3")
	)
	(segment
		(start 127.125984 -298.705016)
		(end 124.674884 -298.705016)
		(width 0.17145)
		(layer "F.Cu")
		(net "ACT_HDD_3")
	)
	(segment
		(start 130.175 -298.704)
		(end 127.127 -298.704)
		(width 0.17145)
		(layer "F.Cu")
		(net "ACT_HDD_3")
	)
	(segment
		(start 187.775088 -68.704968)
		(end 190.828168 -68.704968)
		(width 0.17145)
		(layer "F.Cu")
		(net "ACT_HDD_29")
	)
	(segment
		(start 190.828168 -68.704968)
		(end 190.8302 -68.707)
		(width 0.17145)
		(layer "F.Cu")
		(net "ACT_HDD_29")
	)
	(segment
		(start 161.743898 -68.697094)
		(end 161.736024 -68.704968)
		(width 0.17145)
		(layer "F.Cu")
		(net "ACT_HDD_28")
	)
	(segment
		(start 161.736024 -68.704968)
		(end 156.224986 -68.704968)
		(width 0.17145)
		(layer "F.Cu")
		(net "ACT_HDD_28")
	)
	(segment
		(start 130.193796 -68.747894)
		(end 130.15087 -68.704968)
		(width 0.17145)
		(layer "F.Cu")
		(net "ACT_HDD_27")
	)
	(segment
		(start 130.15087 -68.704968)
		(end 124.674884 -68.704968)
		(width 0.17145)
		(layer "F.Cu")
		(net "ACT_HDD_27")
	)
	(segment
		(start 98.643948 -68.747894)
		(end 98.601022 -68.704968)
		(width 0.17145)
		(layer "F.Cu")
		(net "ACT_HDD_26")
	)
	(segment
		(start 98.601022 -68.704968)
		(end 93.125036 -68.704968)
		(width 0.17145)
		(layer "F.Cu")
		(net "ACT_HDD_26")
	)
	(segment
		(start 67.093846 -68.747894)
		(end 67.05092 -68.704968)
		(width 0.17145)
		(layer "F.Cu")
		(net "ACT_HDD_25")
	)
	(segment
		(start 67.05092 -68.704968)
		(end 61.574934 -68.704968)
		(width 0.17145)
		(layer "F.Cu")
		(net "ACT_HDD_25")
	)
	(segment
		(start 35.543998 -68.747894)
		(end 35.501072 -68.704968)
		(width 0.17145)
		(layer "F.Cu")
		(net "ACT_HDD_24")
	)
	(segment
		(start 35.501072 -68.704968)
		(end 30.025086 -68.704968)
		(width 0.17145)
		(layer "F.Cu")
		(net "ACT_HDD_24")
	)
	(segment
		(start 478.878646 -182.326788)
		(end 481.123752 -182.326788)
		(width 0.17145)
		(layer "F.Cu")
		(net "ACT_HDD_23")
	)
	(segment
		(start 481.123752 -182.326788)
		(end 482.501956 -183.704992)
		(width 0.17145)
		(layer "F.Cu")
		(net "ACT_HDD_23")
	)
	(segment
		(start 482.501956 -183.704992)
		(end 485.125014 -183.704992)
		(width 0.17145)
		(layer "F.Cu")
		(net "ACT_HDD_23")
	)
	(segment
		(start 476.200978 -179.64912)
		(end 478.878646 -182.326788)
		(width 0.17145)
		(layer "F.Cu")
		(net "ACT_HDD_23")
	)
	(segment
		(start 450.298566 -186.74334)
		(end 450.298566 -185.106564)
		(width 0.17145)
		(layer "F.Cu")
		(net "ACT_HDD_22")
	)
	(segment
		(start 450.298566 -185.106564)
		(end 451.700138 -183.704992)
		(width 0.17145)
		(layer "F.Cu")
		(net "ACT_HDD_22")
	)
	(segment
		(start 451.700138 -183.704992)
		(end 453.574912 -183.704992)
		(width 0.17145)
		(layer "F.Cu")
		(net "ACT_HDD_22")
	)
	(segment
		(start 445.262 -191.779906)
		(end 450.298566 -186.74334)
		(width 0.17145)
		(layer "F.Cu")
		(net "ACT_HDD_22")
	)
	(segment
		(start 445.262 -192.024)
		(end 445.262 -191.779906)
		(width 0.17145)
		(layer "F.Cu")
		(net "ACT_HDD_22")
	)
	(segment
		(start 413.250126 -183.704992)
		(end 422.025064 -183.704992)
		(width 0.17145)
		(layer "F.Cu")
		(net "ACT_HDD_21")
	)
	(segment
		(start 413.166052 -183.620918)
		(end 413.250126 -183.704992)
		(width 0.17145)
		(layer "F.Cu")
		(net "ACT_HDD_21")
	)
	(segment
		(start 381.61595 -183.620918)
		(end 381.700024 -183.704992)
		(width 0.17145)
		(layer "F.Cu")
		(net "ACT_HDD_20")
	)
	(segment
		(start 381.700024 -183.704992)
		(end 390.474962 -183.704992)
		(width 0.17145)
		(layer "F.Cu")
		(net "ACT_HDD_20")
	)
	(segment
		(start 98.601784 -298.705016)
		(end 93.125036 -298.705016)
		(width 0.17145)
		(layer "F.Cu")
		(net "ACT_HDD_2")
	)
	(segment
		(start 98.6028 -298.704)
		(end 98.601784 -298.705016)
		(width 0.17145)
		(layer "F.Cu")
		(net "ACT_HDD_2")
	)
	(segment
		(start 350.066102 -183.620918)
		(end 351.324926 -183.620918)
		(width 0.17145)
		(layer "F.Cu")
		(net "ACT_HDD_19")
	)
	(segment
		(start 351.409 -183.704992)
		(end 358.925114 -183.704992)
		(width 0.17145)
		(layer "F.Cu")
		(net "ACT_HDD_19")
	)
	(segment
		(start 351.324926 -183.620918)
		(end 351.409 -183.704992)
		(width 0.17145)
		(layer "F.Cu")
		(net "ACT_HDD_19")
	)
	(segment
		(start 318.600074 -183.704992)
		(end 327.375012 -183.704992)
		(width 0.17145)
		(layer "F.Cu")
		(net "ACT_HDD_18")
	)
	(segment
		(start 318.516 -183.620918)
		(end 318.600074 -183.704992)
		(width 0.17145)
		(layer "F.Cu")
		(net "ACT_HDD_18")
	)
	(segment
		(start 190.246 -183.747918)
		(end 190.203074 -183.704992)
		(width 0.17145)
		(layer "F.Cu")
		(net "ACT_HDD_17")
	)
	(segment
		(start 190.203074 -183.704992)
		(end 187.775088 -183.704992)
		(width 0.17145)
		(layer "F.Cu")
		(net "ACT_HDD_17")
	)
	(segment
		(start 161.700972 -183.704992)
		(end 156.224986 -183.704992)
		(width 0.17145)
		(layer "F.Cu")
		(net "ACT_HDD_16")
	)
	(segment
		(start 161.743898 -183.747918)
		(end 161.700972 -183.704992)
		(width 0.17145)
		(layer "F.Cu")
		(net "ACT_HDD_16")
	)
	(segment
		(start 130.15087 -183.704992)
		(end 124.674884 -183.704992)
		(width 0.17145)
		(layer "F.Cu")
		(net "ACT_HDD_15")
	)
	(segment
		(start 130.193796 -183.747918)
		(end 130.15087 -183.704992)
		(width 0.17145)
		(layer "F.Cu")
		(net "ACT_HDD_15")
	)
	(segment
		(start 98.643948 -183.747918)
		(end 98.601022 -183.704992)
		(width 0.17145)
		(layer "F.Cu")
		(net "ACT_HDD_14")
	)
	(segment
		(start 98.601022 -183.704992)
		(end 93.125036 -183.704992)
		(width 0.17145)
		(layer "F.Cu")
		(net "ACT_HDD_14")
	)
	(segment
		(start 67.05092 -183.704992)
		(end 61.574934 -183.704992)
		(width 0.17145)
		(layer "F.Cu")
		(net "ACT_HDD_13")
	)
	(segment
		(start 67.093846 -183.747918)
		(end 67.05092 -183.704992)
		(width 0.17145)
		(layer "F.Cu")
		(net "ACT_HDD_13")
	)
	(segment
		(start 35.501072 -183.704992)
		(end 30.025086 -183.704992)
		(width 0.17145)
		(layer "F.Cu")
		(net "ACT_HDD_12")
	)
	(segment
		(start 35.543998 -183.747918)
		(end 35.501072 -183.704992)
		(width 0.17145)
		(layer "F.Cu")
		(net "ACT_HDD_12")
	)
	(segment
		(start 479.298 -297.372024)
		(end 481.076 -297.372024)
		(width 0.17145)
		(layer "F.Cu")
		(net "ACT_HDD_11")
	)
	(segment
		(start 482.408992 -298.705016)
		(end 485.125014 -298.705016)
		(width 0.17145)
		(layer "F.Cu")
		(net "ACT_HDD_11")
	)
	(segment
		(start 481.076 -297.372024)
		(end 482.408992 -298.705016)
		(width 0.17145)
		(layer "F.Cu")
		(net "ACT_HDD_11")
	)
	(segment
		(start 443.8396 -298.704)
		(end 443.840616 -298.705016)
		(width 0.17145)
		(layer "F.Cu")
		(net "ACT_HDD_10")
	)
	(segment
		(start 443.840616 -298.705016)
		(end 453.574912 -298.705016)
		(width 0.17145)
		(layer "F.Cu")
		(net "ACT_HDD_10")
	)
	(segment
		(start 67.1068 -298.704)
		(end 67.105784 -298.705016)
		(width 0.17145)
		(layer "F.Cu")
		(net "ACT_HDD_1")
	)
	(segment
		(start 67.105784 -298.705016)
		(end 61.574934 -298.705016)
		(width 0.17145)
		(layer "F.Cu")
		(net "ACT_HDD_1")
	)
	(via
		(at 130.556 -289.5346)
		(size 0.6604)
		(drill 0.3302)
		(layers "F.Cu" "B.Cu")
		(net "5V_PRE_3")
	)
	(via
		(at 427.472094 -301.127668)
		(size 0.6604)
		(drill 0.3302)
		(layers "F.Cu" "B.Cu")
		(net "12V_PRE_9")
	)
	(via
		(at 395.767814 -301.13478)
		(size 0.6604)
		(drill 0.3302)
		(layers "F.Cu" "B.Cu")
		(net "12V_PRE_8")
	)
	(via
		(at 364.372144 -301.052738)
		(size 0.6604)
		(drill 0.3302)
		(layers "F.Cu" "B.Cu")
		(net "12V_PRE_7")
	)
	(via
		(at 332.865476 -300.95952)
		(size 0.6604)
		(drill 0.3302)
		(layers "F.Cu" "B.Cu")
		(net "12V_PRE_6")
	)
	(via
		(at 178.689 -296.207942)
		(size 0.6604)
		(drill 0.3302)
		(layers "F.Cu" "B.Cu")
		(net "12V_PRE_5")
	)
	(via
		(at 147.066 -296.291)
		(size 0.6604)
		(drill 0.3302)
		(layers "F.Cu" "B.Cu")
		(net "12V_PRE_4")
	)
	(via
		(at 475.2848 -66.548)
		(size 0.6604)
		(drill 0.3302)
		(layers "F.Cu" "B.Cu")
		(net "12V_PRE_35")
	)
	(via
		(at 459.20152 -70.992746)
		(size 0.6604)
		(drill 0.3302)
		(layers "F.Cu" "B.Cu")
		(net "12V_PRE_34")
	)
	(via
		(at 427.472094 -71.12762)
		(size 0.6604)
		(drill 0.3302)
		(layers "F.Cu" "B.Cu")
		(net "12V_PRE_33")
	)
	(via
		(at 396.051278 -70.999604)
		(size 0.6604)
		(drill 0.3302)
		(layers "F.Cu" "B.Cu")
		(net "12V_PRE_32")
	)
	(via
		(at 364.46206 -71.082662)
		(size 0.6604)
		(drill 0.3302)
		(layers "F.Cu" "B.Cu")
		(net "12V_PRE_31")
	)
	(via
		(at 332.867254 -71.052944)
		(size 0.6604)
		(drill 0.3302)
		(layers "F.Cu" "B.Cu")
		(net "12V_PRE_30")
	)
	(via
		(at 178.689 -66.207894)
		(size 0.6604)
		(drill 0.3302)
		(layers "F.Cu" "B.Cu")
		(net "12V_PRE_29")
	)
	(via
		(at 147.138898 -66.207894)
		(size 0.6604)
		(drill 0.3302)
		(layers "F.Cu" "B.Cu")
		(net "12V_PRE_28")
	)
	(via
		(at 115.588796 -66.207894)
		(size 0.6604)
		(drill 0.3302)
		(layers "F.Cu" "B.Cu")
		(net "12V_PRE_27")
	)
	(via
		(at 84.038948 -66.207894)
		(size 0.6604)
		(drill 0.3302)
		(layers "F.Cu" "B.Cu")
		(net "12V_PRE_26")
	)
	(via
		(at 52.488846 -66.207894)
		(size 0.6604)
		(drill 0.3302)
		(layers "F.Cu" "B.Cu")
		(net "12V_PRE_25")
	)
	(via
		(at 20.938998 -66.207894)
		(size 0.6604)
		(drill 0.3302)
		(layers "F.Cu" "B.Cu")
		(net "12V_PRE_24")
	)
	(via
		(at 475.030292 -181.228492)
		(size 0.6604)
		(drill 0.3302)
		(layers "F.Cu" "B.Cu")
		(net "12V_PRE_23")
	)
	(via
		(at 459.365604 -185.851292)
		(size 0.6604)
		(drill 0.3302)
		(layers "F.Cu" "B.Cu")
		(net "12V_PRE_22")
	)
	(via
		(at 427.661832 -186.061604)
		(size 0.6604)
		(drill 0.3302)
		(layers "F.Cu" "B.Cu")
		(net "12V_PRE_21")
	)
	(via
		(at 396.018766 -186.033156)
		(size 0.6604)
		(drill 0.3302)
		(layers "F.Cu" "B.Cu")
		(net "12V_PRE_20")
	)
	(via
		(at 84.038948 -296.207942)
		(size 0.6604)
		(drill 0.3302)
		(layers "F.Cu" "B.Cu")
		(net "12V_PRE_2")
	)
	(via
		(at 364.615984 -185.996072)
		(size 0.6604)
		(drill 0.3302)
		(layers "F.Cu" "B.Cu")
		(net "12V_PRE_19")
	)
	(via
		(at 332.964028 -186.016392)
		(size 0.6604)
		(drill 0.3302)
		(layers "F.Cu" "B.Cu")
		(net "12V_PRE_18")
	)
	(via
		(at 178.689 -181.207918)
		(size 0.6604)
		(drill 0.3302)
		(layers "F.Cu" "B.Cu")
		(net "12V_PRE_17")
	)
	(via
		(at 147.138898 -181.207918)
		(size 0.6604)
		(drill 0.3302)
		(layers "F.Cu" "B.Cu")
		(net "12V_PRE_16")
	)
	(via
		(at 115.588796 -181.207918)
		(size 0.6604)
		(drill 0.3302)
		(layers "F.Cu" "B.Cu")
		(net "12V_PRE_15")
	)
	(via
		(at 84.038948 -181.207918)
		(size 0.6604)
		(drill 0.3302)
		(layers "F.Cu" "B.Cu")
		(net "12V_PRE_14")
	)
	(via
		(at 52.488846 -181.207918)
		(size 0.6604)
		(drill 0.3302)
		(layers "F.Cu" "B.Cu")
		(net "12V_PRE_13")
	)
	(via
		(at 20.938998 -181.207918)
		(size 0.6604)
		(drill 0.3302)
		(layers "F.Cu" "B.Cu")
		(net "12V_PRE_12")
	)
	(via
		(at 459.111858 -301.067724)
		(size 0.6604)
		(drill 0.3302)
		(layers "F.Cu" "B.Cu")
		(net "12V_PRE_10")
	)
	(via
		(at 52.488846 -296.207942)
		(size 0.6604)
		(drill 0.3302)
		(layers "F.Cu" "B.Cu")
		(net "12V_PRE_1")
	)
	(zone
		(net "P5V_HDD20")
		(layer "F.Cu")
		(hatch none 0.5)
		(connect_pads
			(clearance 0.5)
		)
		(min_thickness 0.25)
		(fill yes
			(thermal_gap 0.5)
			(thermal_bridge_width 0.5)
			(island_removal_mode 0)
		)
		(polygon
			(pts
				(xy 393.159234 -167.231314) (xy 393.017502 -167.373046) (xy 393.017502 -170.949874) (xy 394.44295 -172.375322)
				(xy 394.44295 -177.778918) (xy 392.79195 -179.429918) (xy 389.36295 -179.429918) (xy 389.10895 -179.683918)
				(xy 389.10895 -181.334918) (xy 389.36295 -181.588918) (xy 393.93495 -181.588918) (xy 394.56995 -180.953918)
				(xy 396.34795 -180.953918) (xy 396.85595 -180.445918) (xy 396.85595 -167.521128) (xy 396.566136 -167.231314)
			)
		)
		(polygon
			(pts
				(xy 393.45235 -180.598318) (xy 393.24915 -180.598318) (xy 393.24915 -180.801518) (xy 393.45235 -180.801518)
			)
		)
		(polygon
			(pts
				(xy 392.58875 -180.598318) (xy 392.38555 -180.598318) (xy 392.38555 -180.801518) (xy 392.58875 -180.801518)
			)
		)
	)
	(zone
		(net "5V_PRE_19")
		(layer "F.Cu")
		(hatch none 0.5)
		(connect_pads
			(clearance 0.5)
		)
		(min_thickness 0.25)
		(fill yes
			(thermal_gap 0.5)
			(thermal_bridge_width 0.5)
			(island_removal_mode 0)
		)
		(polygon
			(pts
				(xy 360.988102 -174.984918) (xy 360.734102 -175.238918) (xy 360.734102 -177.778918) (xy 360.353102 -178.159918)
				(xy 357.813102 -178.159918) (xy 357.559102 -178.413918) (xy 357.559102 -178.794918) (xy 357.813102 -179.048918)
				(xy 361.115102 -179.048918) (xy 362.385102 -177.778918) (xy 362.385102 -175.238918) (xy 362.131102 -174.984918)
			)
		)
	)
	(zone
		(net "GND")
		(layer "F.Cu")
		(hatch none 0.5)
		(connect_pads
			(clearance 0.5)
		)
		(min_thickness 0.25)
		(fill yes
			(thermal_gap 0.5)
			(thermal_bridge_width 0.5)
			(island_removal_mode 0)
		)
		(polygon
			(pts
				(arc
					(start 446.64376 -268.312392)
					(mid 443.479779 -269.321197)
					(end 442.123576 -272.352516)
				)
				(arc
					(start 442.123576 -275.527516)
					(mid 442.598486 -277.434277)
					(end 443.912244 -278.895556)
				)
				(arc
					(start 443.912244 -279.9334)
					(mid 443.693599 -280.169139)
					(end 443.49416 -280.421334)
				)
				(arc
					(start 443.11189 -280.421334)
					(mid 440.871875 -279.296093)
					(end 438.396126 -279.689052)
				)
				(arc
					(start 438.396126 -279.689052)
					(mid 438.317004 -279.032212)
					(end 438.127902 -278.398224)
				)
				(arc
					(start 438.127902 -278.398224)
					(mid 437.847553 -277.638109)
					(end 437.424576 -276.947122)
				)
				(xy 437.424576 -273.473418) (xy 435.671976 -273.473418) (xy 435.671976 -271.212818)
				(arc
					(start 434.57876 -271.212818)
					(mid 434.568062 -270.869647)
					(end 434.528976 -270.528542)
				)
				(xy 434.528976 -268.063218)
				(arc
					(start 433.954174 -268.063218)
					(mid 433.093686 -267.042525)
					(end 431.950368 -266.35329)
				)
				(arc
					(start 431.950368 -266.35329)
					(mid 433.794687 -263.139446)
					(end 432.28641 -259.754878)
				)
				(arc
					(start 432.28641 -259.754878)
					(mid 432.647228 -259.321572)
					(end 432.945032 -258.842764)
				)
				(arc
					(start 432.945032 -258.842764)
					(mid 433.224372 -258.691642)
					(end 433.491386 -258.519676)
				)
				(arc
					(start 433.491386 -258.519676)
					(mid 434.027082 -258.944193)
					(end 434.626004 -259.273548)
				)
				(arc
					(start 434.626004 -259.273548)
					(mid 436.494402 -260.280366)
					(end 438.615836 -260.21538)
				)
				(arc
					(start 438.615836 -260.21538)
					(mid 438.739854 -260.41625)
					(end 438.875678 -260.609334)
				)
				(xy 438.875678 -261.983474)
				(arc
					(start 440.207146 -261.983474)
					(mid 441.41084 -262.698942)
					(end 442.788802 -262.947912)
				)
				(arc
					(start 446.497202 -262.947912)
					(mid 446.570494 -262.947197)
					(end 446.64376 -262.945118)
				)
			)
		)
	)
	(zone
		(net "5V_PRE_24")
		(layer "F.Cu")
		(hatch none 0.5)
		(connect_pads
			(clearance 0.5)
		)
		(min_thickness 0.25)
		(fill yes
			(thermal_gap 0.5)
			(thermal_bridge_width 0.5)
			(island_removal_mode 0)
		)
		(polygon
			(pts
				(xy 22.869398 -60.071) (xy 22.843998 -60.0964) (xy 22.843998 -61.508894) (xy 22.970998 -61.635894)
				(xy 24.240998 -61.635894) (xy 26.780998 -64.175894) (xy 31.225998 -64.175894) (xy 31.352998 -64.048894)
				(xy 31.352998 -63.286894) (xy 31.225998 -63.159894) (xy 27.879294 -63.159894) (xy 24.7904 -60.071)
			)
		)
	)
	(zone
		(layer "F.Cu")
		(hatch none 0.5)
		(connect_pads
			(clearance 0)
		)
		(min_thickness 0.25)
		(keepout
			(tracks allowed)
			(vias allowed)
			(pads allowed)
			(copperpour allowed)
			(footprints allowed)
		)
		(placement
			(enabled no)
			(sheetname "")
		)
		(fill
			(thermal_gap 0.5)
			(thermal_bridge_width 0.5)
			(island_removal_mode 0)
		)
		(polygon
			(pts
				(xy 281.6098 16.764) (xy 281.6098 12.827) (xy 280.8478 12.827) (xy 280.8478 16.764)
			)
		)
	)
	(zone
		(layer "F.Cu")
		(hatch none 0.5)
		(connect_pads
			(clearance 0)
		)
		(min_thickness 0.25)
		(keepout
			(tracks allowed)
			(vias allowed)
			(pads allowed)
			(copperpour allowed)
			(footprints not_allowed)
		)
		(placement
			(enabled no)
			(sheetname "")
		)
		(fill
			(thermal_gap 0.5)
			(thermal_bridge_width 0.5)
			(island_removal_mode 0)
		)
		(polygon
			(pts
				(xy 209.099912 -9.59993) (xy 209.099912 -18.999962) (xy 201.399902 -18.999962) (xy 201.399902 -9.59993)
			)
		)
	)
	(zone
		(layer "F.Cu")
		(hatch none 0.5)
		(connect_pads
			(clearance 0)
		)
		(min_thickness 0.25)
		(keepout
			(tracks allowed)
			(vias allowed)
			(pads allowed)
			(copperpour allowed)
			(footprints allowed)
		)
		(placement
			(enabled no)
			(sheetname "")
		)
		(fill
			(thermal_gap 0.5)
			(thermal_bridge_width 0.5)
			(island_removal_mode 0)
		)
		(polygon
			(pts
				(xy 378.3076 -136.3472) (xy 378.3076 -135.6868) (xy 375.412 -135.6868) (xy 375.412 -136.3472)
			)
		)
	)
	(zone
		(layer "F.Cu")
		(hatch none 0.5)
		(connect_pads
			(clearance 0)
		)
		(min_thickness 0.25)
		(keepout
			(tracks allowed)
			(vias allowed)
			(pads allowed)
			(copperpour allowed)
			(footprints not_allowed)
		)
		(placement
			(enabled no)
			(sheetname "")
		)
		(fill
			(thermal_gap 0.5)
			(thermal_bridge_width 0.5)
			(island_removal_mode 0)
		)
		(polygon
			(pts
				(xy 287.699958 -154.200098) (xy 312.699908 -154.200098) (xy 312.699908 -128.199896) (xy 287.699958 -128.199896)
			)
		)
	)
	(zone
		(layer "F.Cu")
		(hatch none 0.5)
		(connect_pads
			(clearance 0)
		)
		(min_thickness 0.25)
		(keepout
			(tracks allowed)
			(vias allowed)
			(pads allowed)
			(copperpour allowed)
			(footprints allowed)
		)
		(placement
			(enabled no)
			(sheetname "")
		)
		(fill
			(thermal_gap 0.5)
			(thermal_bridge_width 0.5)
			(island_removal_mode 0)
		)
		(polygon
			(pts
				(xy 289.4584 -276.0726) (xy 289.4584 -273.6342) (xy 290.2712 -273.6342) (xy 290.2712 -276.0726)
			)
		)
	)
	(zone
		(net "P3V3_STBY_A")
		(layer "F.Cu")
		(hatch none 0.5)
		(connect_pads
			(clearance 0.5)
		)
		(min_thickness 0.25)
		(fill yes
			(thermal_gap 0.5)
			(thermal_bridge_width 0.5)
			(island_removal_mode 0)
		)
		(polygon
			(pts
				(xy 186.4614 -235.4072) (xy 185.928 -235.9406) (xy 185.928 -241.1984) (xy 186.0804 -241.3508) (xy 188.722 -241.3508)
				(xy 188.9506 -241.1222) (xy 188.9506 -235.6612) (xy 188.6966 -235.4072)
			)
		)
	)
	(zone
		(layer "F.Cu")
		(hatch none 0.5)
		(connect_pads
			(clearance 0)
		)
		(min_thickness 0.25)
		(keepout
			(tracks allowed)
			(vias allowed)
			(pads allowed)
			(copperpour allowed)
			(footprints not_allowed)
		)
		(placement
			(enabled no)
			(sheetname "")
		)
		(fill
			(thermal_gap 0.5)
			(thermal_bridge_width 0.5)
			(island_removal_mode 0)
		)
		(polygon
			(pts
				(arc
					(start 103.324914 -98.799904)
					(mid 96.324928 -105.79989)
					(end 89.324942 -98.799904)
				)
				(arc
					(start 89.324942 -92.799916)
					(mid 96.324928 -85.79993)
					(end 103.324914 -92.799916)
				)
			)
		)
	)
	(zone
		(net "P12V_A")
		(layer "F.Cu")
		(hatch none 0.5)
		(connect_pads
			(clearance 0.5)
		)
		(min_thickness 0.25)
		(fill yes
			(thermal_gap 0.5)
			(thermal_bridge_width 0.5)
			(island_removal_mode 0)
		)
		(polygon
			(pts
				(xy 77.307948 -169.142918) (xy 76.291948 -170.158918) (xy 75.656948 -170.158918) (xy 75.275948 -170.539918)
				(xy 75.275948 -173.079918) (xy 75.529948 -173.333918) (xy 78.831948 -173.333918) (xy 79.085948 -173.079918)
				(xy 79.085948 -170.793918) (xy 78.450948 -170.158918) (xy 78.069948 -170.158918) (xy 77.815948 -169.904918)
				(xy 77.815948 -169.269918) (xy 77.688948 -169.142918)
			)
		)
		(polygon
			(pts
				(xy 77.282548 -169.727118) (xy 77.079348 -169.727118) (xy 77.079348 -169.930318) (xy 77.282548 -169.930318)
			)
		)
	)
	(zone
		(layer "F.Cu")
		(hatch none 0.5)
		(connect_pads
			(clearance 0)
		)
		(min_thickness 0.25)
		(keepout
			(tracks allowed)
			(vias allowed)
			(pads allowed)
			(copperpour allowed)
			(footprints not_allowed)
		)
		(placement
			(enabled no)
			(sheetname "")
		)
		(fill
			(thermal_gap 0.5)
			(thermal_bridge_width 0.5)
			(island_removal_mode 0)
		)
		(polygon
			(pts
				(arc
					(start 386.675122 -92.799916)
					(mid 393.675108 -85.79993)
					(end 400.675094 -92.799916)
				)
				(arc
					(start 400.675094 -98.799904)
					(mid 393.675108 -105.79989)
					(end 386.675122 -98.799904)
				)
			)
		)
	)
	(zone
		(layer "F.Cu")
		(hatch none 0.5)
		(connect_pads
			(clearance 0)
		)
		(min_thickness 0.25)
		(keepout
			(tracks allowed)
			(vias allowed)
			(pads allowed)
			(copperpour allowed)
			(footprints not_allowed)
		)
		(placement
			(enabled no)
			(sheetname "")
		)
		(fill
			(thermal_gap 0.5)
			(thermal_bridge_width 0.5)
			(island_removal_mode 0)
		)
		(polygon
			(pts
				(arc
					(start 101.000052 0)
					(mid 101.707157 -0.292893)
					(end 102.00005 -0.999998)
				)
				(xy 102.00005 -9.99998) (xy 37.325046 -9.99998) (xy 37.325046 0)
			)
		)
	)
	(zone
		(layer "F.Cu")
		(hatch none 0.5)
		(connect_pads
			(clearance 0)
		)
		(min_thickness 0.25)
		(keepout
			(tracks allowed)
			(vias allowed)
			(pads allowed)
			(copperpour allowed)
			(footprints not_allowed)
		)
		(placement
			(enabled no)
			(sheetname "")
		)
		(fill
			(thermal_gap 0.5)
			(thermal_bridge_width 0.5)
			(island_removal_mode 0)
		)
		(polygon
			(pts
				(xy 312.699908 -125.800104) (xy 491.450122 -125.800104) (xy 491.450122 -75.79995) (xy 478.00006 -75.79995)
				(xy 478.00006 -65.79997) (xy 463.449924 -65.79997) (xy 463.449924 -75.79995) (xy 446.449958 -75.79995)
				(xy 446.449958 -65.79997) (xy 431.900076 -65.79997) (xy 431.900076 -75.79995) (xy 414.90011 -75.79995)
				(xy 414.90011 -65.79997) (xy 400.349974 -65.79997) (xy 400.349974 -75.79995) (xy 383.350008 -75.79995)
				(xy 383.350008 -65.79997) (xy 368.800126 -65.79997) (xy 368.800126 -75.79995) (xy 351.799906 -75.79995)
				(xy 351.799906 -65.79997) (xy 337.250024 -65.79997) (xy 337.250024 -75.79995) (xy 320.250058 -75.79995)
				(xy 320.250058 -65.79997) (xy 305.699922 -65.79997) (xy 305.699922 -75.79995) (xy 298.200064 -75.79995)
				(xy 298.200064 -128.199896) (xy 312.699908 -128.199896)
			)
		)
	)
	(zone
		(layer "F.Cu")
		(hatch none 0.5)
		(connect_pads
			(clearance 0)
		)
		(min_thickness 0.25)
		(keepout
			(tracks allowed)
			(vias allowed)
			(pads allowed)
			(copperpour allowed)
			(footprints allowed)
		)
		(placement
			(enabled no)
			(sheetname "")
		)
		(fill
			(thermal_gap 0.5)
			(thermal_bridge_width 0.5)
			(island_removal_mode 0)
		)
		(polygon
			(pts
				(xy 476.918274 -244.675406) (xy 476.918274 -246.834406) (xy 476.334074 -246.834406) (xy 476.334074 -244.675406)
			)
		)
	)
	(zone
		(layer "F.Cu")
		(hatch none 0.5)
		(connect_pads
			(clearance 0)
		)
		(min_thickness 0.25)
		(keepout
			(tracks not_allowed)
			(vias allowed)
			(pads allowed)
			(copperpour not_allowed)
			(footprints allowed)
		)
		(placement
			(enabled no)
			(sheetname "")
		)
		(fill
			(thermal_gap 0.5)
			(thermal_bridge_width 0.5)
			(island_removal_mode 0)
		)
		(polygon
			(pts
				(arc
					(start 271.970754 -330.321412)
					(mid 271.58696 -330.704825)
					(end 271.9705 -331.088492)
				)
				(arc
					(start 273.1135 -331.088492)
					(mid 273.49704 -330.704952)
					(end 273.1135 -330.321412)
				)
				(xy 272.76425 -330.321412)
				(arc
					(start 272.76425 -330.577952)
					(mid 272.779129 -330.613873)
					(end 272.81505 -330.628752)
				)
				(arc
					(start 272.857976 -330.628752)
					(mid 273.380144 -330.704952)
					(end 272.857976 -330.781152)
				)
				(xy 272.783554 -330.781152)
				(arc
					(start 272.780506 -330.778104)
					(mid 272.671429 -330.721573)
					(end 272.614898 -330.612496)
				)
				(xy 272.61185 -330.609448) (xy 272.61185 -330.321412) (xy 272.47215 -330.321412) (xy 272.47215 -330.609448)
				(arc
					(start 272.469102 -330.612496)
					(mid 272.412571 -330.721573)
					(end 272.303494 -330.778104)
				)
				(xy 272.300446 -330.781152)
				(arc
					(start 272.226024 -330.781152)
					(mid 271.703856 -330.704952)
					(end 272.226024 -330.628752)
				)
				(arc
					(start 272.26895 -330.628752)
					(mid 272.304871 -330.613873)
					(end 272.31975 -330.577952)
				)
				(xy 272.31975 -330.321412)
			)
		)
	)
	(zone
		(net "P12V_HDD16")
		(layer "F.Cu")
		(hatch none 0.5)
		(connect_pads
			(clearance 0.5)
		)
		(min_thickness 0.25)
		(fill yes
			(thermal_gap 0.5)
			(thermal_bridge_width 0.5)
			(island_removal_mode 0)
		)
		(polygon
			(pts
				(xy 138.502898 -176.254918) (xy 138.248898 -176.508918) (xy 138.248898 -178.159918) (xy 138.502898 -178.413918)
				(xy 140.661898 -178.413918) (xy 141.169898 -178.921918) (xy 141.169898 -181.461918) (xy 148.916898 -189.208918)
				(xy 157.425898 -189.208918) (xy 157.552898 -189.081918) (xy 157.552898 -187.303918) (xy 157.425898 -187.176918)
				(xy 151.456898 -187.176918) (xy 150.821898 -186.541918) (xy 149.170898 -186.541918) (xy 144.852898 -182.223918)
				(xy 144.852898 -178.667918) (xy 143.709898 -177.524918) (xy 143.709898 -176.508918) (xy 143.455898 -176.254918)
			)
		)
		(polygon
			(pts
				(xy 150.974298 -188.218318) (xy 150.771098 -188.218318) (xy 150.771098 -188.421518) (xy 150.974298 -188.421518)
			)
		)
		(polygon
			(pts
				(xy 150.110698 -188.218318) (xy 149.907498 -188.218318) (xy 149.907498 -188.421518) (xy 150.110698 -188.421518)
			)
		)
	)
	(zone
		(net "12V_PRE_22")
		(layer "F.Cu")
		(hatch none 0.5)
		(connect_pads
			(clearance 0.5)
		)
		(min_thickness 0.25)
		(fill yes
			(thermal_gap 0.5)
			(thermal_bridge_width 0.5)
			(island_removal_mode 0)
		)
		(polygon
			(pts
				(xy 457.468478 -183.31434) (xy 455.0029 -185.779918) (xy 452.4629 -185.779918) (xy 452.2089 -186.033918)
				(xy 452.2089 -186.414918) (xy 452.4629 -186.668918) (xy 459.161134 -186.668918) (xy 459.821534 -186.008518)
				(xy 459.821534 -183.43499) (xy 459.700884 -183.31434)
			)
		)
	)
	(zone
		(layer "F.Cu")
		(hatch none 0.5)
		(connect_pads
			(clearance 0)
		)
		(min_thickness 0.25)
		(keepout
			(tracks allowed)
			(vias allowed)
			(pads allowed)
			(copperpour allowed)
			(footprints allowed)
		)
		(placement
			(enabled no)
			(sheetname "")
		)
		(fill
			(thermal_gap 0.5)
			(thermal_bridge_width 0.5)
			(island_removal_mode 0)
		)
		(polygon
			(pts
				(xy 236.357668 -253.266956) (xy 236.357668 -252.594364) (xy 237.947962 -252.594364) (xy 237.947962 -253.266956)
			)
		)
	)
	(zone
		(net "P12V_HDD20")
		(layer "F.Cu")
		(hatch none 0.5)
		(connect_pads
			(clearance 0.5)
		)
		(min_thickness 0.25)
		(fill yes
			(thermal_gap 0.5)
			(thermal_bridge_width 0.5)
			(island_removal_mode 0)
		)
		(polygon
			(pts
				(xy 397.74495 -178.540918) (xy 397.49095 -178.794918) (xy 397.49095 -182.858918) (xy 397.032226 -183.317642)
				(xy 397.032226 -186.139836) (xy 396.198344 -186.973718) (xy 389.278368 -186.973718) (xy 389.10895 -187.143136)
				(xy 389.10895 -188.954918) (xy 389.36295 -189.208918) (xy 393.29995 -189.208918) (xy 393.80795 -188.700918)
				(xy 401.55495 -188.700918) (xy 402.44395 -187.811918) (xy 402.44395 -178.794918) (xy 402.18995 -178.540918)
			)
		)
		(polygon
			(pts
				(xy 393.45235 -188.091318) (xy 393.24915 -188.091318) (xy 393.24915 -188.294518) (xy 393.45235 -188.294518)
			)
		)
		(polygon
			(pts
				(xy 392.58875 -188.091318) (xy 392.38555 -188.091318) (xy 392.38555 -188.294518) (xy 392.58875 -188.294518)
			)
		)
	)
	(zone
		(net "P5V_A_1")
		(layer "F.Cu")
		(hatch none 0.5)
		(connect_pads
			(clearance 0.5)
		)
		(min_thickness 0.25)
		(fill yes
			(thermal_gap 0.5)
			(thermal_bridge_width 0.5)
			(island_removal_mode 0)
		)
		(polygon
			(pts
				(xy 176.149 -280.840942) (xy 175.895 -281.094942) (xy 175.895 -283.380942) (xy 176.149 -283.634942)
				(xy 180.848 -283.634942) (xy 181.102 -283.380942) (xy 181.102 -281.094942) (xy 180.848 -280.840942)
			)
		)
	)
	(zone
		(net "P5V_HDD22")
		(layer "F.Cu")
		(hatch none 0.5)
		(connect_pads
			(clearance 0.5)
		)
		(min_thickness 0.25)
		(fill yes
			(thermal_gap 0.5)
			(thermal_bridge_width 0.5)
			(island_removal_mode 0)
		)
		(polygon
			(pts
				(xy 457.7969 -166.729918) (xy 457.5429 -166.983918) (xy 457.5429 -177.778918) (xy 455.8919 -179.429918)
				(xy 452.4629 -179.429918) (xy 452.2089 -179.683918) (xy 452.2089 -181.334918) (xy 452.4629 -181.588918)
				(xy 457.0349 -181.588918) (xy 457.6699 -180.953918) (xy 459.4479 -180.953918) (xy 459.9559 -180.445918)
				(xy 459.9559 -166.983918) (xy 459.7019 -166.729918)
			)
		)
		(polygon
			(pts
				(xy 456.5523 -180.598318) (xy 456.3491 -180.598318) (xy 456.3491 -180.801518) (xy 456.5523 -180.801518)
			)
		)
		(polygon
			(pts
				(xy 455.6887 -180.598318) (xy 455.4855 -180.598318) (xy 455.4855 -180.801518) (xy 455.6887 -180.801518)
			)
		)
	)
	(zone
		(net "MB0_12V_CTRL_GATE1")
		(layer "F.Cu")
		(hatch none 0.5)
		(connect_pads
			(clearance 0.5)
		)
		(min_thickness 0.25)
		(fill yes
			(thermal_gap 0.5)
			(thermal_bridge_width 0.5)
			(island_removal_mode 0)
		)
		(polygon
			(pts
				(xy 162.995102 -145.75917) (xy 162.741102 -146.01317) (xy 162.741102 -149.18817) (xy 163.376102 -149.82317)
				(xy 165.408102 -149.82317) (xy 165.484302 -149.74697) (xy 165.484302 -145.96237) (xy 165.281102 -145.75917)
			)
		)
	)
	(zone
		(layer "F.Cu")
		(hatch none 0.5)
		(connect_pads
			(clearance 0)
		)
		(min_thickness 0.25)
		(keepout
			(tracks not_allowed)
			(vias allowed)
			(pads allowed)
			(copperpour not_allowed)
			(footprints allowed)
		)
		(placement
			(enabled no)
			(sheetname "")
		)
		(fill
			(thermal_gap 0.5)
			(thermal_bridge_width 0.5)
			(island_removal_mode 0)
		)
		(polygon
			(pts
				(arc
					(start 95.989902 -277.17877)
					(mid 95.609029 -276.797516)
					(end 95.227902 -277.178516)
				)
				(xy 95.227902 -277.527766)
				(arc
					(start 95.481902 -277.527766)
					(mid 95.517823 -277.512887)
					(end 95.532702 -277.476966)
				)
				(arc
					(start 95.532702 -277.43404)
					(mid 95.608902 -276.911872)
					(end 95.685102 -277.43404)
				)
				(xy 95.685102 -277.508462)
				(arc
					(start 95.682054 -277.51151)
					(mid 95.625523 -277.620587)
					(end 95.516446 -277.677118)
				)
				(xy 95.513398 -277.680166) (xy 95.227902 -277.680166) (xy 95.227902 -277.819866) (xy 95.513398 -277.819866)
				(arc
					(start 95.516446 -277.822914)
					(mid 95.625523 -277.879445)
					(end 95.682054 -277.988522)
				)
				(xy 95.685102 -277.99157)
				(arc
					(start 95.685102 -278.065992)
					(mid 95.608902 -278.58816)
					(end 95.532702 -278.065992)
				)
				(arc
					(start 95.532702 -278.023066)
					(mid 95.517823 -277.987145)
					(end 95.481902 -277.972266)
				)
				(xy 95.227902 -277.972266)
				(arc
					(start 95.227902 -278.321516)
					(mid 95.608902 -278.702516)
					(end 95.989902 -278.321516)
				)
			)
		)
	)
	(zone
		(layer "F.Cu")
		(hatch none 0.5)
		(connect_pads
			(clearance 0)
		)
		(min_thickness 0.25)
		(keepout
			(tracks allowed)
			(vias allowed)
			(pads allowed)
			(copperpour allowed)
			(footprints not_allowed)
		)
		(placement
			(enabled no)
			(sheetname "")
		)
		(fill
			(thermal_gap 0.5)
			(thermal_bridge_width 0.5)
			(island_removal_mode 0)
		)
		(polygon
			(pts
				(arc
					(start 46.500034 -164.200078)
					(mid 42.749978 -167.950134)
					(end 38.999922 -164.200078)
				)
				(arc
					(start 38.999922 -164.200078)
					(mid 42.749978 -160.450022)
					(end 46.500034 -164.200078)
				)
			)
		)
	)
	(zone
		(layer "F.Cu")
		(hatch none 0.5)
		(connect_pads
			(clearance 0)
		)
		(min_thickness 0.25)
		(keepout
			(tracks allowed)
			(vias allowed)
			(pads allowed)
			(copperpour allowed)
			(footprints allowed)
		)
		(placement
			(enabled no)
			(sheetname "")
		)
		(fill
			(thermal_gap 0.5)
			(thermal_bridge_width 0.5)
			(island_removal_mode 0)
		)
		(polygon
			(pts
				(xy 247.396 -252.5522) (xy 247.396 -250.19) (xy 248.7168 -250.19) (xy 248.7168 -252.5522)
			)
		)
	)
	(zone
		(net "GND")
		(layer "F.Cu")
		(hatch none 0.5)
		(connect_pads
			(clearance 0.5)
		)
		(min_thickness 0.25)
		(fill yes
			(thermal_gap 0.5)
			(thermal_bridge_width 0.5)
			(island_removal_mode 0)
		)
		(polygon
			(pts
				(arc
					(start 201.000106 1.23698)
					(mid 200.832534 1.16757)
					(end 200.763124 0.999998)
				)
				(arc
					(start 200.763124 0.999998)
					(mid 200.246749 -0.246641)
					(end 199.00011 -0.763016)
				)
				(arc
					(start 150.999952 -0.763016)
					(mid 150.83238 -0.832426)
					(end 150.76297 -0.999998)
				)
				(arc
					(start 150.76297 -13.999972)
					(mid 150.246595 -15.246611)
					(end 148.999956 -15.762986)
				)
				(xy 148.7424 -15.762986) (xy 148.7424 -21.653754) (xy 166.51097 -21.653754) (xy 166.915084 -21.24964)
				(xy 199.7202 -21.24964) (xy 199.7202 -15.68958) (xy 198.896478 -14.865858)
				(arc
					(start 198.896478 -12.69365)
					(mid 198.884866 -12.516018)
					(end 198.880984 -12.33805)
				)
				(arc
					(start 198.880984 -11.06805)
					(mid 198.884857 -10.890081)
					(end 198.896478 -10.71245)
				)
				(xy 198.896478 -8.664956) (xy 199.239124 -8.32231) (xy 199.239124 -7.764272) (xy 197.23989 -7.764272)
				(arc
					(start 197.23989 -5.52831)
					(mid 196.431137 -3.873698)
					(end 196.429884 -2.032)
				)
				(arc
					(start 199.00011 -2.032)
					(mid 199.796262 -1.925605)
					(end 200.536556 -1.613916)
				)
				(xy 200.536556 -1.426718)
				(arc
					(start 200.817734 -1.426718)
					(mid 201.436316 -0.804886)
					(end 201.851006 -0.032004)
				)
				(xy 202.368658 -0.032004) (xy 202.368658 1.23698)
			)
		)
		(polygon
			(pts
				(xy 177.166524 -2.032)
				(arc
					(start 161.62147 -2.032)
					(mid 158.826378 -5.043734)
					(end 157.753558 -9.010142)
				)
				(arc
					(start 157.753558 -9.010142)
					(mid 156.234909 -15.926341)
					(end 163.203128 -17.184624)
				)
				(arc
					(start 163.203128 -17.184624)
					(mid 163.599628 -17.328442)
					(end 164.00272 -17.452594)
				)
				(arc
					(start 164.00272 -17.452594)
					(mid 171.42532 -16.090734)
					(end 174.896018 -9.389618)
				)
				(arc
					(start 174.896018 -9.389618)
					(mid 176.44811 -7.876167)
					(end 177.198274 -5.842254)
				)
				(arc
					(start 177.198782 -5.842254)
					(mid 177.240929 -5.19784)
					(end 177.198274 -4.553458)
				)
				(xy 177.198274 -2.06375)
			)
		)
	)
	(zone
		(layer "F.Cu")
		(hatch none 0.5)
		(connect_pads
			(clearance 0)
		)
		(min_thickness 0.25)
		(keepout
			(tracks not_allowed)
			(vias allowed)
			(pads allowed)
			(copperpour not_allowed)
			(footprints allowed)
		)
		(placement
			(enabled no)
			(sheetname "")
		)
		(fill
			(thermal_gap 0.5)
			(thermal_bridge_width 0.5)
			(island_removal_mode 0)
		)
		(polygon
			(pts
				(arc
					(start 32.889952 -47.178722)
					(mid 32.509079 -46.797468)
					(end 32.127952 -47.178468)
				)
				(xy 32.127952 -47.527718)
				(arc
					(start 32.381952 -47.527718)
					(mid 32.417873 -47.512839)
					(end 32.432752 -47.476918)
				)
				(arc
					(start 32.432752 -47.433992)
					(mid 32.508952 -46.911824)
					(end 32.585152 -47.433992)
				)
				(xy 32.585152 -47.508414)
				(arc
					(start 32.582104 -47.511462)
					(mid 32.525573 -47.620539)
					(end 32.416496 -47.67707)
				)
				(xy 32.413448 -47.680118) (xy 32.127952 -47.680118) (xy 32.127952 -47.819818) (xy 32.413448 -47.819818)
				(arc
					(start 32.416496 -47.822866)
					(mid 32.525573 -47.879397)
					(end 32.582104 -47.988474)
				)
				(xy 32.585152 -47.991522)
				(arc
					(start 32.585152 -48.065944)
					(mid 32.508952 -48.588112)
					(end 32.432752 -48.065944)
				)
				(arc
					(start 32.432752 -48.023018)
					(mid 32.417873 -47.987097)
					(end 32.381952 -47.972218)
				)
				(xy 32.127952 -47.972218)
				(arc
					(start 32.127952 -48.321468)
					(mid 32.508952 -48.702468)
					(end 32.889952 -48.321468)
				)
			)
		)
	)
	(zone
		(layer "F.Cu")
		(hatch none 0.5)
		(connect_pads
			(clearance 0)
		)
		(min_thickness 0.25)
		(keepout
			(tracks allowed)
			(vias allowed)
			(pads allowed)
			(copperpour allowed)
			(footprints not_allowed)
		)
		(placement
			(enabled no)
			(sheetname "")
		)
		(fill
			(thermal_gap 0.5)
			(thermal_bridge_width 0.5)
			(island_removal_mode 0)
		)
		(polygon
			(pts
				(xy 289.649916 -219.700094) (xy 289.649916 -229.100126) (xy 281.949906 -229.100126) (xy 281.949906 -219.700094)
			)
		)
	)
	(zone
		(layer "F.Cu")
		(hatch none 0.5)
		(connect_pads
			(clearance 0)
		)
		(min_thickness 0.25)
		(keepout
			(tracks allowed)
			(vias allowed)
			(pads allowed)
			(copperpour allowed)
			(footprints allowed)
		)
		(placement
			(enabled no)
			(sheetname "")
		)
		(fill
			(thermal_gap 0.5)
			(thermal_bridge_width 0.5)
			(island_removal_mode 0)
		)
		(polygon
			(pts
				(xy 260.898132 -240.899696) (xy 260.898132 -237.394496) (xy 258.688332 -237.394496) (xy 258.688332 -240.899696)
			)
		)
	)
	(zone
		(layer "F.Cu")
		(hatch none 0.5)
		(connect_pads
			(clearance 0)
		)
		(min_thickness 0.25)
		(keepout
			(tracks allowed)
			(vias allowed)
			(pads allowed)
			(copperpour allowed)
			(footprints not_allowed)
		)
		(placement
			(enabled no)
			(sheetname "")
		)
		(fill
			(thermal_gap 0.5)
			(thermal_bridge_width 0.5)
			(island_removal_mode 0)
		)
		(polygon
			(pts
				(xy 155.325064 -20.200112) (xy 177.32502 -20.200112) (xy 177.32502 0) (xy 155.325064 0)
			)
		)
	)
	(zone
		(layer "F.Cu")
		(hatch none 0.5)
		(connect_pads
			(clearance 0)
		)
		(min_thickness 0.25)
		(keepout
			(tracks not_allowed)
			(vias allowed)
			(pads allowed)
			(copperpour not_allowed)
			(footprints allowed)
		)
		(placement
			(enabled no)
			(sheetname "")
		)
		(fill
			(thermal_gap 0.5)
			(thermal_bridge_width 0.5)
			(island_removal_mode 0)
		)
		(polygon
			(pts
				(arc
					(start 271.970754 -310.52135)
					(mid 271.58696 -310.904763)
					(end 271.9705 -311.28843)
				)
				(arc
					(start 273.1135 -311.28843)
					(mid 273.49704 -310.90489)
					(end 273.1135 -310.52135)
				)
				(xy 272.76425 -310.52135)
				(arc
					(start 272.76425 -310.77789)
					(mid 272.779129 -310.813811)
					(end 272.81505 -310.82869)
				)
				(arc
					(start 272.857976 -310.82869)
					(mid 273.380144 -310.90489)
					(end 272.857976 -310.98109)
				)
				(xy 272.783554 -310.98109)
				(arc
					(start 272.780506 -310.978042)
					(mid 272.671429 -310.921511)
					(end 272.614898 -310.812434)
				)
				(xy 272.61185 -310.809386) (xy 272.61185 -310.52135) (xy 272.47215 -310.52135) (xy 272.47215 -310.809386)
				(arc
					(start 272.469102 -310.812434)
					(mid 272.412571 -310.921511)
					(end 272.303494 -310.978042)
				)
				(xy 272.300446 -310.98109)
				(arc
					(start 272.226024 -310.98109)
					(mid 271.703856 -310.90489)
					(end 272.226024 -310.82869)
				)
				(arc
					(start 272.26895 -310.82869)
					(mid 272.304871 -310.813811)
					(end 272.31975 -310.77789)
				)
				(xy 272.31975 -310.52135)
			)
		)
	)
	(zone
		(layer "F.Cu")
		(hatch none 0.5)
		(connect_pads
			(clearance 0)
		)
		(min_thickness 0.25)
		(keepout
			(tracks allowed)
			(vias allowed)
			(pads allowed)
			(copperpour allowed)
			(footprints allowed)
		)
		(placement
			(enabled no)
			(sheetname "")
		)
		(fill
			(thermal_gap 0.5)
			(thermal_bridge_width 0.5)
			(island_removal_mode 0)
		)
		(polygon
			(pts
				(xy 259.8674 -283.464) (xy 259.8674 -280.5938) (xy 263.398 -280.5938) (xy 263.398 -283.464)
			)
		)
	)
	(zone
		(net "GND")
		(layer "F.Cu")
		(hatch none 0.5)
		(connect_pads
			(clearance 0.5)
		)
		(min_thickness 0.25)
		(fill yes
			(thermal_gap 0.5)
			(thermal_bridge_width 0.5)
			(island_removal_mode 0)
		)
		(polygon
			(pts
				(xy 262.564626 -23.172166) (xy 262.098282 -23.63851) (xy 262.098282 -29.134562) (xy 262.500618 -29.536898)
				(xy 265.180064 -29.536898) (xy 265.573256 -29.143706) (xy 265.573256 -23.510494) (xy 265.234928 -23.172166)
			)
		)
	)
	(zone
		(layer "F.Cu")
		(hatch none 0.5)
		(connect_pads
			(clearance 0)
		)
		(min_thickness 0.25)
		(keepout
			(tracks not_allowed)
			(vias allowed)
			(pads allowed)
			(copperpour not_allowed)
			(footprints allowed)
		)
		(placement
			(enabled no)
			(sheetname "")
		)
		(fill
			(thermal_gap 0.5)
			(thermal_bridge_width 0.5)
			(island_removal_mode 0)
		)
		(polygon
			(pts
				(arc
					(start 404.400004 -294.876982)
					(mid 404.400004 -285.122874)
					(end 404.400004 -294.876982)
				)
			)
		)
	)
	(zone
		(net "12V_PRE_32")
		(layer "F.Cu")
		(hatch none 0.5)
		(connect_pads
			(clearance 0.5)
		)
		(min_thickness 0.25)
		(fill yes
			(thermal_gap 0.5)
			(thermal_bridge_width 0.5)
			(island_removal_mode 0)
		)
		(polygon
			(pts
				(xy 394.368528 -68.314316) (xy 391.90295 -70.779894) (xy 389.36295 -70.779894) (xy 389.10895 -71.033894)
				(xy 389.10895 -71.414894) (xy 389.36295 -71.668894) (xy 396.061184 -71.668894) (xy 396.721584 -71.008494)
				(xy 396.721584 -68.434966) (xy 396.600934 -68.314316)
			)
		)
	)
	(zone
		(net "P12V_HDD17")
		(layer "F.Cu")
		(hatch none 0.5)
		(connect_pads
			(clearance 0.5)
		)
		(min_thickness 0.25)
		(fill yes
			(thermal_gap 0.5)
			(thermal_bridge_width 0.5)
			(island_removal_mode 0)
		)
		(polygon
			(pts
				(xy 170.053 -176.254918) (xy 169.799 -176.508918) (xy 169.799 -178.159918) (xy 170.053 -178.413918)
				(xy 172.212 -178.413918) (xy 172.72 -178.921918) (xy 172.72 -181.461918) (xy 180.467 -189.208918)
				(xy 188.976 -189.208918) (xy 189.103 -189.081918) (xy 189.103 -187.303918) (xy 188.976 -187.176918)
				(xy 183.007 -187.176918) (xy 182.372 -186.541918) (xy 180.721 -186.541918) (xy 176.403 -182.223918)
				(xy 176.403 -178.667918) (xy 175.26 -177.524918) (xy 175.26 -176.508918) (xy 175.006 -176.254918)
			)
		)
		(polygon
			(pts
				(xy 182.5244 -188.218318) (xy 182.3212 -188.218318) (xy 182.3212 -188.421518) (xy 182.5244 -188.421518)
			)
		)
		(polygon
			(pts
				(xy 181.6608 -188.218318) (xy 181.4576 -188.218318) (xy 181.4576 -188.421518) (xy 181.6608 -188.421518)
			)
		)
	)
	(zone
		(net "P12V_A")
		(layer "F.Cu")
		(hatch none 0.5)
		(connect_pads
			(clearance 0.5)
		)
		(min_thickness 0.25)
		(fill yes
			(thermal_gap 0.5)
			(thermal_bridge_width 0.5)
			(island_removal_mode 0)
		)
		(polygon
			(pts
				(xy 203.6572 -309.1688) (xy 203.3524 -309.4736) (xy 203.3524 -314.1218) (xy 203.6826 -314.452) (xy 206.5782 -314.452)
				(xy 206.8068 -314.2234) (xy 206.8068 -309.5244) (xy 206.4512 -309.1688)
			)
		)
	)
	(zone
		(net "GND")
		(layer "F.Cu")
		(hatch none 0.5)
		(connect_pads
			(clearance 0.5)
		)
		(min_thickness 0.25)
		(fill yes
			(thermal_gap 0.5)
			(thermal_bridge_width 0.5)
			(island_removal_mode 0)
		)
		(polygon
			(pts
				(xy 200.67905 -132.31495) (xy 188.754004 -84.891118) (xy 180.628798 -84.891118) (xy 195.791582 -126.010416)
				(xy 199.670416 -132.6642) (xy 200.3298 -132.6642)
			)
		)
	)
	(zone
		(layer "F.Cu")
		(hatch none 0.5)
		(connect_pads
			(clearance 0)
		)
		(min_thickness 0.25)
		(keepout
			(tracks not_allowed)
			(vias allowed)
			(pads allowed)
			(copperpour not_allowed)
			(footprints allowed)
		)
		(placement
			(enabled no)
			(sheetname "")
		)
		(fill
			(thermal_gap 0.5)
			(thermal_bridge_width 0.5)
			(island_removal_mode 0)
		)
		(polygon
			(pts
				(arc
					(start 116.898674 -28.150312)
					(mid 116.350161 -27.601418)
					(end 115.801394 -28.150058)
				)
				(arc
					(start 115.801394 -29.550106)
					(mid 116.350034 -30.098746)
					(end 116.898674 -29.550106)
				)
				(arc
					(start 116.898674 -29.146754)
					(mid 116.820242 -29.105591)
					(end 116.732812 -29.091382)
				)
				(arc
					(start 116.477034 -29.091382)
					(mid 116.454583 -29.100681)
					(end 116.445284 -29.123132)
				)
				(arc
					(start 116.445284 -29.16809)
					(mid 116.350034 -29.943818)
					(end 116.254784 -29.16809)
				)
				(xy 116.254784 -29.083762)
				(arc
					(start 116.259102 -29.07919)
					(mid 116.319831 -28.965929)
					(end 116.433092 -28.9052)
				)
				(xy 116.437664 -28.900882) (xy 116.772182 -28.900882)
				(arc
					(start 116.774214 -28.90266)
					(mid 116.83743 -28.912733)
					(end 116.898674 -28.931362)
				)
				(arc
					(start 116.898674 -28.82392)
					(mid 116.816658 -28.805434)
					(end 116.732812 -28.799282)
				)
				(xy 116.437664 -28.799282)
				(arc
					(start 116.433092 -28.794964)
					(mid 116.319831 -28.734235)
					(end 116.259102 -28.620974)
				)
				(xy 116.254784 -28.616402)
				(arc
					(start 116.254784 -28.532074)
					(mid 116.350034 -27.756346)
					(end 116.445284 -28.532074)
				)
				(arc
					(start 116.445284 -28.577032)
					(mid 116.454583 -28.599483)
					(end 116.477034 -28.608782)
				)
				(xy 116.772182 -28.608782)
				(arc
					(start 116.773452 -28.609798)
					(mid 116.836424 -28.615816)
					(end 116.898674 -28.62707)
				)
			)
		)
	)
	(zone
		(net "12V_PRE_12")
		(layer "F.Cu")
		(hatch none 0.5)
		(connect_pads
			(clearance 0.5)
		)
		(min_thickness 0.25)
		(fill yes
			(thermal_gap 0.5)
			(thermal_bridge_width 0.5)
			(island_removal_mode 0)
		)
		(polygon
			(pts
				(xy 19.668998 -178.794918) (xy 19.541998 -178.921918) (xy 19.541998 -180.445918) (xy 20.938998 -181.842918)
				(xy 22.335998 -181.842918) (xy 27.288998 -186.795918) (xy 31.225998 -186.795918) (xy 31.352998 -186.668918)
				(xy 31.352998 -185.906918) (xy 31.225998 -185.779918) (xy 27.923998 -185.779918) (xy 20.938998 -178.794918)
			)
		)
	)
	(zone
		(layer "F.Cu")
		(hatch none 0.5)
		(connect_pads
			(clearance 0)
		)
		(min_thickness 0.25)
		(keepout
			(tracks allowed)
			(vias allowed)
			(pads allowed)
			(copperpour allowed)
			(footprints allowed)
		)
		(placement
			(enabled no)
			(sheetname "")
		)
		(fill
			(thermal_gap 0.5)
			(thermal_bridge_width 0.5)
			(island_removal_mode 0)
		)
		(polygon
			(pts
				(xy 240.8428 -390.4488) (xy 240.8428 -386.3086) (xy 243.7384 -386.3086) (xy 243.7384 -390.4488)
			)
		)
	)
	(zone
		(net "GND")
		(layer "F.Cu")
		(hatch none 0.5)
		(connect_pads
			(clearance 0.5)
		)
		(min_thickness 0.25)
		(fill yes
			(thermal_gap 0.5)
			(thermal_bridge_width 0.5)
			(island_removal_mode 0)
		)
		(polygon
			(pts
				(arc
					(start 405.27224 -298.52874)
					(mid 404.643106 -298.569815)
					(end 404.012654 -298.564554)
				)
				(xy 404.012654 -302.542956) (xy 402.529548 -304.026062) (xy 402.529548 -304.176176) (xy 402.379434 -304.176176)
				(xy 401.111974 -305.443636) (xy 401.111974 -309.430166)
				(arc
					(start 399.982182 -309.430166)
					(mid 399.360308 -311.402138)
					(end 397.853408 -312.818018)
				)
				(arc
					(start 397.853408 -312.818018)
					(mid 400.025078 -314.037874)
					(end 401.860258 -315.722)
				)
				(xy 402.932392 -315.722)
				(arc
					(start 402.932392 -310.213248)
					(mid 403.192541 -308.813347)
					(end 403.938232 -307.60035)
				)
				(arc
					(start 403.938232 -307.60035)
					(mid 404.501886 -306.709442)
					(end 405.27224 -305.989736)
				)
			)
		)
	)
	(zone
		(net "GND")
		(layer "F.Cu")
		(hatch none 0.5)
		(connect_pads
			(clearance 0.5)
		)
		(min_thickness 0.25)
		(fill yes
			(thermal_gap 0.5)
			(thermal_bridge_width 0.5)
			(island_removal_mode 0)
		)
		(polygon
			(pts
				(arc
					(start 197.254368 -254.900684)
					(mid 198.182128 -254.328046)
					(end 199.228202 -254.020828)
				)
				(arc
					(start 197.844918 -247.724422)
					(mid 196.64312 -247.391402)
					(end 195.597526 -246.711724)
				)
				(arc
					(start 195.597526 -246.711724)
					(mid 194.080558 -245.589761)
					(end 193.228468 -243.906294)
				)
				(arc
					(start 193.228468 -243.906294)
					(mid 192.227309 -244.228205)
					(end 191.177164 -244.284246)
				)
				(xy 190.300356 -245.161054)
				(arc
					(start 186.480704 -245.161054)
					(mid 186.038438 -245.387187)
					(end 185.5724 -245.559072)
				)
				(xy 185.5724 -248.322846)
			)
		)
	)
	(zone
		(layer "F.Cu")
		(hatch none 0.5)
		(connect_pads
			(clearance 0)
		)
		(min_thickness 0.25)
		(keepout
			(tracks allowed)
			(vias allowed)
			(pads allowed)
			(copperpour allowed)
			(footprints allowed)
		)
		(placement
			(enabled no)
			(sheetname "")
		)
		(fill
			(thermal_gap 0.5)
			(thermal_bridge_width 0.5)
			(island_removal_mode 0)
		)
		(polygon
			(pts
				(xy 277.5712 18.3896) (xy 277.5712 16.0274) (xy 277.2156 16.0274) (xy 277.2156 18.3896)
			)
		)
	)
	(zone
		(net "P5V_HDD11")
		(layer "F.Cu")
		(hatch none 0.5)
		(connect_pads
			(clearance 0.5)
		)
		(min_thickness 0.25)
		(fill yes
			(thermal_gap 0.5)
			(thermal_bridge_width 0.5)
			(island_removal_mode 0)
		)
		(polygon
			(pts
				(xy 474.61424 -283.013404) (xy 474.514926 -283.112718) (xy 474.514926 -284.710124) (xy 475.208092 -285.40329)
				(xy 475.208092 -286.782764) (xy 475.8944 -287.469326) (xy 475.8944 -289.79495) (xy 480.378008 -294.278558)
				(xy 480.378008 -295.947846) (xy 481.019104 -296.588942) (xy 486.325926 -296.588942) (xy 486.452926 -296.461942)
				(xy 486.452926 -294.683942) (xy 486.325926 -294.556942) (xy 483.024942 -294.556942) (xy 479.9838 -291.5158)
				(xy 479.9838 -290.1696) (xy 479.4504 -289.6362) (xy 477.9772 -289.6362) (xy 477.563434 -289.222434)
				(xy 477.563434 -287.072324) (xy 478.141792 -286.493966) (xy 478.141792 -283.033216) (xy 478.12198 -283.013404)
			)
		)
		(polygon
			(pts
				(xy 477.151192 -288.148522) (xy 476.947992 -288.148522) (xy 476.947992 -288.351722) (xy 477.151192 -288.351722)
			)
		)
		(polygon
			(pts
				(xy 476.287592 -288.148522) (xy 476.084392 -288.148522) (xy 476.084392 -288.351722) (xy 476.287592 -288.351722)
			)
		)
		(polygon
			(pts
				(xy 477.151192 -287.284922) (xy 476.947992 -287.284922) (xy 476.947992 -287.488122) (xy 477.151192 -287.488122)
			)
		)
		(polygon
			(pts
				(xy 476.287592 -287.284922) (xy 476.084392 -287.284922) (xy 476.084392 -287.488122) (xy 476.287592 -287.488122)
			)
		)
	)
	(zone
		(net "P12V_A")
		(layer "F.Cu")
		(hatch none 0.5)
		(connect_pads
			(clearance 0.5)
		)
		(min_thickness 0.25)
		(fill yes
			(thermal_gap 0.5)
			(thermal_bridge_width 0.5)
			(island_removal_mode 0)
		)
		(polygon
			(pts
				(xy 45.916342 -283.7434) (xy 44.5008 -285.158942) (xy 44.106846 -285.158942) (xy 43.725846 -285.539942)
				(xy 43.725846 -288.079942) (xy 43.979846 -288.333942) (xy 47.327058 -288.333942) (xy 47.6758 -287.9852)
				(xy 47.6758 -284.1752) (xy 47.5742 -284.0736) (xy 47.1932 -284.0736) (xy 46.863 -283.7434)
			)
		)
		(polygon
			(pts
				(xy 47.205646 -285.616142) (xy 47.002446 -285.616142) (xy 47.002446 -285.819342) (xy 47.205646 -285.819342)
			)
		)
		(polygon
			(pts
				(xy 47.205646 -285.006542) (xy 47.002446 -285.006542) (xy 47.002446 -285.209742) (xy 47.205646 -285.209742)
			)
		)
		(polygon
			(pts
				(xy 47.256446 -284.549342) (xy 47.053246 -284.549342) (xy 47.053246 -284.752542) (xy 47.256446 -284.752542)
			)
		)
	)
	(zone
		(layer "F.Cu")
		(hatch none 0.5)
		(connect_pads
			(clearance 0)
		)
		(min_thickness 0.25)
		(keepout
			(tracks not_allowed)
			(vias allowed)
			(pads allowed)
			(copperpour not_allowed)
			(footprints allowed)
		)
		(placement
			(enabled no)
			(sheetname "")
		)
		(fill
			(thermal_gap 0.5)
			(thermal_bridge_width 0.5)
			(island_removal_mode 0)
		)
		(polygon
			(pts
				(arc
					(start 356.670102 -277.17877)
					(mid 356.289229 -276.797516)
					(end 355.908102 -277.178516)
				)
				(arc
					(start 355.908102 -278.321516)
					(mid 356.289102 -278.702516)
					(end 356.670102 -278.321516)
				)
				(xy 356.670102 -277.972266)
				(arc
					(start 356.416356 -277.972266)
					(mid 356.380255 -277.987219)
					(end 356.365302 -278.02332)
				)
				(arc
					(start 356.365302 -278.065992)
					(mid 356.289102 -278.58816)
					(end 356.212902 -278.065992)
				)
				(xy 356.212902 -277.991824)
				(arc
					(start 356.21595 -277.988776)
					(mid 356.272558 -277.879522)
					(end 356.381812 -277.822914)
				)
				(xy 356.38486 -277.819866) (xy 356.670102 -277.819866) (xy 356.670102 -277.680166) (xy 356.38486 -277.680166)
				(arc
					(start 356.381812 -277.677118)
					(mid 356.272558 -277.62051)
					(end 356.21595 -277.511256)
				)
				(xy 356.212902 -277.508208)
				(arc
					(start 356.212902 -277.43404)
					(mid 356.289102 -276.911872)
					(end 356.365302 -277.43404)
				)
				(arc
					(start 356.365302 -277.476712)
					(mid 356.380255 -277.512813)
					(end 356.416356 -277.527766)
				)
				(xy 356.670102 -277.527766)
			)
		)
	)
	(zone
		(layer "F.Cu")
		(hatch none 0.5)
		(connect_pads
			(clearance 0)
		)
		(min_thickness 0.25)
		(keepout
			(tracks allowed)
			(vias allowed)
			(pads allowed)
			(copperpour allowed)
			(footprints not_allowed)
		)
		(placement
			(enabled no)
			(sheetname "")
		)
		(fill
			(thermal_gap 0.5)
			(thermal_bridge_width 0.5)
			(island_removal_mode 0)
		)
		(polygon
			(pts
				(arc
					(start 89.324942 -207.79994)
					(mid 96.324928 -200.799954)
					(end 103.324914 -207.79994)
				)
				(arc
					(start 103.324914 -213.799928)
					(mid 96.324928 -220.799914)
					(end 89.324942 -213.799928)
				)
			)
		)
	)
	(zone
		(layer "F.Cu")
		(hatch none 0.5)
		(connect_pads
			(clearance 0)
		)
		(min_thickness 0.25)
		(keepout
			(tracks allowed)
			(vias allowed)
			(pads allowed)
			(copperpour allowed)
			(footprints not_allowed)
		)
		(placement
			(enabled no)
			(sheetname "")
		)
		(fill
			(thermal_gap 0.5)
			(thermal_bridge_width 0.5)
			(island_removal_mode 0)
		)
		(polygon
			(pts
				(xy 0 -240.799874) (xy 191.799972 -240.799874) (xy 191.799972 -305.799998) (xy 180.64988 -305.799998)
				(xy 180.64988 -295.800018) (xy 166.099998 -295.800018) (xy 166.099998 -305.799998) (xy 149.100032 -305.799998)
				(xy 149.100032 -295.800018) (xy 134.549896 -295.800018) (xy 134.549896 -305.799998) (xy 117.54993 -305.799998)
				(xy 117.54993 -295.800018) (xy 103.000048 -295.800018) (xy 103.000048 -305.799998) (xy 86.000082 -305.799998)
				(xy 86.000082 -295.800018) (xy 71.449946 -295.800018) (xy 71.449946 -305.799998) (xy 54.44998 -305.799998)
				(xy 54.44998 -295.800018) (xy 39.900098 -295.800018) (xy 39.900098 -305.799998) (xy 22.899878 -305.799998)
				(xy 22.899878 -295.800018) (xy 8.349996 -295.800018) (xy 8.349996 -305.799998) (xy 0 -305.799998)
			)
		)
	)
	(zone
		(layer "F.Cu")
		(hatch none 0.5)
		(connect_pads
			(clearance 0)
		)
		(min_thickness 0.25)
		(keepout
			(tracks allowed)
			(vias allowed)
			(pads allowed)
			(copperpour allowed)
			(footprints allowed)
		)
		(placement
			(enabled no)
			(sheetname "")
		)
		(fill
			(thermal_gap 0.5)
			(thermal_bridge_width 0.5)
			(island_removal_mode 0)
		)
		(polygon
			(pts
				(xy 368.178334 -147.5105) (xy 367.243868 -147.5105) (xy 367.243868 -145.97634) (xy 368.178334 -145.97634)
			)
		)
	)
	(zone
		(net "P5V_HDD8")
		(layer "F.Cu")
		(hatch none 0.5)
		(connect_pads
			(clearance 0.5)
		)
		(min_thickness 0.25)
		(fill yes
			(thermal_gap 0.5)
			(thermal_bridge_width 0.5)
			(island_removal_mode 0)
		)
		(polygon
			(pts
				(xy 394.56995 -284.7086) (xy 394.44295 -284.8356) (xy 394.44295 -286.5628) (xy 394.79855 -286.9184)
				(xy 395.4272 -286.9184) (xy 395.859 -287.3502) (xy 395.859 -288.67735) (xy 394.44295 -290.0934)
				(xy 394.44295 -292.778942) (xy 392.79195 -294.429942) (xy 389.36295 -294.429942) (xy 389.10895 -294.683942)
				(xy 389.10895 -296.334942) (xy 389.36295 -296.588942) (xy 393.93495 -296.588942) (xy 394.56995 -295.953942)
				(xy 396.34795 -295.953942) (xy 396.85595 -295.445942) (xy 396.85595 -290.0172) (xy 397.678148 -289.194748)
				(xy 397.678148 -284.851348) (xy 397.5354 -284.7086)
			)
		)
		(polygon
			(pts
				(xy 393.45235 -295.598342) (xy 393.24915 -295.598342) (xy 393.24915 -295.801542) (xy 393.45235 -295.801542)
			)
		)
		(polygon
			(pts
				(xy 392.58875 -295.598342) (xy 392.38555 -295.598342) (xy 392.38555 -295.801542) (xy 392.58875 -295.801542)
			)
		)
	)
	(zone
		(net "GND")
		(layer "F.Cu")
		(hatch none 0.5)
		(connect_pads
			(clearance 0.5)
		)
		(min_thickness 0.25)
		(fill yes
			(thermal_gap 0.5)
			(thermal_bridge_width 0.5)
			(island_removal_mode 0)
		)
		(polygon
			(pts
				(xy 229.941628 -14.4526) (xy 229.941628 -23.94839) (xy 226.864164 -27.025854) (xy 211.74075 -27.025854)
				(xy 209.724244 -29.04236) (xy 197.57644 -29.04236) (xy 196.8754 -29.7434) (xy 196.8754 -31.898336)
				(xy 204.641958 -36.942522)
				(arc
					(start 219.776294 -60.320682)
					(mid 225.123673 -61.712745)
					(end 224.20453 -67.16141)
				)
				(xy 231.157526 -77.9018) (xy 231.5718 -77.9018) (xy 231.70515 -77.76845)
				(arc
					(start 231.70515 -16.20012)
					(mid 231.797923 -15.307302)
					(end 232.07218 -14.4526)
				)
			)
		)
	)
	(zone
		(layer "F.Cu")
		(hatch none 0.5)
		(connect_pads
			(clearance 0)
		)
		(min_thickness 0.25)
		(keepout
			(tracks allowed)
			(vias allowed)
			(pads allowed)
			(copperpour allowed)
			(footprints not_allowed)
		)
		(placement
			(enabled no)
			(sheetname "")
		)
		(fill
			(thermal_gap 0.5)
			(thermal_bridge_width 0.5)
			(island_removal_mode 0)
		)
		(polygon
			(pts
				(arc
					(start 375.350024 -220.199966)
					(mid 371.599968 -223.950022)
					(end 367.849912 -220.199966)
				)
				(arc
					(start 367.849912 -220.199966)
					(mid 371.599968 -216.44991)
					(end 375.350024 -220.199966)
				)
			)
		)
	)
	(zone
		(layer "F.Cu")
		(hatch none 0.5)
		(connect_pads
			(clearance 0)
		)
		(min_thickness 0.25)
		(keepout
			(tracks allowed)
			(vias allowed)
			(pads allowed)
			(copperpour allowed)
			(footprints allowed)
		)
		(placement
			(enabled no)
			(sheetname "")
		)
		(fill
			(thermal_gap 0.5)
			(thermal_bridge_width 0.5)
			(island_removal_mode 0)
		)
		(polygon
			(pts
				(xy 459.025498 -279.038304) (xy 459.025498 -278.099266) (xy 461.270858 -278.099266) (xy 461.270858 -279.038304)
			)
		)
	)
	(zone
		(layer "F.Cu")
		(hatch none 0.5)
		(connect_pads
			(clearance 0)
		)
		(min_thickness 0.25)
		(keepout
			(tracks allowed)
			(vias allowed)
			(pads allowed)
			(copperpour allowed)
			(footprints allowed)
		)
		(placement
			(enabled no)
			(sheetname "")
		)
		(fill
			(thermal_gap 0.5)
			(thermal_bridge_width 0.5)
			(island_removal_mode 0)
		)
		(polygon
			(pts
				(xy 259.0546 12.5984) (xy 259.0546 10.668) (xy 258.5466 10.668) (xy 258.5466 12.5984)
			)
		)
	)
	(zone
		(layer "F.Cu")
		(hatch none 0.5)
		(connect_pads
			(clearance 0)
		)
		(min_thickness 0.25)
		(keepout
			(tracks allowed)
			(vias allowed)
			(pads allowed)
			(copperpour allowed)
			(footprints not_allowed)
		)
		(placement
			(enabled no)
			(sheetname "")
		)
		(fill
			(thermal_gap 0.5)
			(thermal_bridge_width 0.5)
			(island_removal_mode 0)
		)
		(polygon
			(pts
				(arc
					(start 323.674994 -207.79994)
					(mid 330.67498 -200.799954)
					(end 337.674966 -207.79994)
				)
				(arc
					(start 337.674966 -213.799928)
					(mid 330.67498 -220.799914)
					(end 323.674994 -213.799928)
				)
			)
		)
	)
	(zone
		(layer "F.Cu")
		(hatch none 0.5)
		(connect_pads
			(clearance 0)
		)
		(min_thickness 0.25)
		(keepout
			(tracks allowed)
			(vias allowed)
			(pads allowed)
			(copperpour allowed)
			(footprints allowed)
		)
		(placement
			(enabled no)
			(sheetname "")
		)
		(fill
			(thermal_gap 0.5)
			(thermal_bridge_width 0.5)
			(island_removal_mode 0)
		)
		(polygon
			(pts
				(xy 137.59942 -141.960092) (xy 137.59942 -140.969492) (xy 139.50442 -140.969492) (xy 139.50442 -141.960092)
			)
		)
	)
	(zone
		(layer "F.Cu")
		(hatch none 0.5)
		(connect_pads
			(clearance 0)
		)
		(min_thickness 0.25)
		(keepout
			(tracks not_allowed)
			(vias allowed)
			(pads allowed)
			(copperpour not_allowed)
			(footprints allowed)
		)
		(placement
			(enabled no)
			(sheetname "")
		)
		(fill
			(thermal_gap 0.5)
			(thermal_bridge_width 0.5)
			(island_removal_mode 0)
		)
		(polygon
			(pts
				(arc
					(start 271.970754 -351.924112)
					(mid 271.5895 -352.304985)
					(end 271.9705 -352.686112)
				)
				(arc
					(start 273.1135 -352.686112)
					(mid 273.4945 -352.305112)
					(end 273.1135 -351.924112)
				)
				(xy 272.76425 -351.924112)
				(arc
					(start 272.76425 -352.178112)
					(mid 272.779129 -352.214033)
					(end 272.81505 -352.228912)
				)
				(arc
					(start 272.857976 -352.228912)
					(mid 273.380144 -352.305112)
					(end 272.857976 -352.381312)
				)
				(xy 272.783554 -352.381312)
				(arc
					(start 272.780506 -352.378264)
					(mid 272.671429 -352.321733)
					(end 272.614898 -352.212656)
				)
				(xy 272.61185 -352.209608) (xy 272.61185 -351.924112) (xy 272.47215 -351.924112) (xy 272.47215 -352.209608)
				(arc
					(start 272.469102 -352.212656)
					(mid 272.412571 -352.321733)
					(end 272.303494 -352.378264)
				)
				(xy 272.300446 -352.381312)
				(arc
					(start 272.226024 -352.381312)
					(mid 271.703856 -352.305112)
					(end 272.226024 -352.228912)
				)
				(arc
					(start 272.26895 -352.228912)
					(mid 272.304871 -352.214033)
					(end 272.31975 -352.178112)
				)
				(xy 272.31975 -351.924112)
			)
		)
	)
	(zone
		(net "MB3_CM_GATE_R")
		(layer "F.Cu")
		(hatch none 0.5)
		(connect_pads
			(clearance 0.5)
		)
		(min_thickness 0.25)
		(fill yes
			(thermal_gap 0.5)
			(thermal_bridge_width 0.5)
			(island_removal_mode 0)
		)
		(polygon
			(pts
				(xy 264.99693 -369.147598) (xy 264.827766 -369.316508) (xy 264.827766 -371.310154) (xy 265.100054 -371.582442)
				(xy 266.394692 -371.582442) (xy 266.703556 -371.273578) (xy 266.703556 -369.273582) (xy 266.577572 -369.147598)
			)
		)
	)
	(zone
		(net "AGND_P5V_C")
		(layer "F.Cu")
		(hatch none 0.5)
		(connect_pads
			(clearance 0.5)
		)
		(min_thickness 0.25)
		(fill yes
			(thermal_gap 0.5)
			(thermal_bridge_width 0.5)
			(island_removal_mode 0)
		)
		(polygon
			(pts
				(xy 444.109602 -256.47015) (xy 443.601602 -256.97815) (xy 443.601602 -258.19735) (xy 443.754002 -258.34975)
				(xy 446.116202 -258.34975) (xy 446.548002 -257.91795) (xy 446.548002 -257.46075) (xy 446.979802 -257.02895)
				(xy 446.979802 -256.57175) (xy 446.878202 -256.47015)
			)
		)
		(polygon
			(pts
				(xy 444.211202 -257.51155) (xy 444.008002 -257.51155) (xy 444.008002 -257.71475) (xy 444.211202 -257.71475)
			)
		)
		(polygon
			(pts
				(xy 446.55613 -256.988818) (xy 446.35293 -256.988818) (xy 446.35293 -257.192018) (xy 446.55613 -257.192018)
			)
		)
		(polygon
			(pts
				(xy 445.9732 -256.96672) (xy 445.77 -256.96672) (xy 445.77 -257.16992) (xy 445.9732 -257.16992)
			)
		)
		(polygon
			(pts
				(xy 445.4144 -256.96672) (xy 445.2112 -256.96672) (xy 445.2112 -257.16992) (xy 445.4144 -257.16992)
			)
		)
		(polygon
			(pts
				(xy 444.922402 -256.95275) (xy 444.719202 -256.95275) (xy 444.719202 -257.15595) (xy 444.922402 -257.15595)
			)
		)
		(polygon
			(pts
				(xy 444.363602 -256.95275) (xy 444.160402 -256.95275) (xy 444.160402 -257.15595) (xy 444.363602 -257.15595)
			)
		)
	)
	(zone
		(layer "F.Cu")
		(hatch none 0.5)
		(connect_pads
			(clearance 0)
		)
		(min_thickness 0.25)
		(keepout
			(tracks allowed)
			(vias allowed)
			(pads allowed)
			(copperpour allowed)
			(footprints not_allowed)
		)
		(placement
			(enabled no)
			(sheetname "")
		)
		(fill
			(thermal_gap 0.5)
			(thermal_bridge_width 0.5)
			(island_removal_mode 0)
		)
		(polygon
			(pts
				(xy 309.999888 -383.199894) (xy 290.20008 -383.199894) (xy 290.20008 -409.200096) (xy 309.999888 -409.200096)
			)
		)
	)
	(zone
		(layer "F.Cu")
		(hatch none 0.5)
		(connect_pads
			(clearance 0)
		)
		(min_thickness 0.25)
		(keepout
			(tracks allowed)
			(vias allowed)
			(pads allowed)
			(copperpour allowed)
			(footprints not_allowed)
		)
		(placement
			(enabled no)
			(sheetname "")
		)
		(fill
			(thermal_gap 0.5)
			(thermal_bridge_width 0.5)
			(island_removal_mode 0)
		)
		(polygon
			(pts
				(xy 250.000008 24.800052) (xy 230.000048 24.800052)
				(arc
					(start 230.000048 10.247122)
					(mid 227.251889 9.204327)
					(end 226.099878 6.500114)
				)
				(arc
					(start 226.099878 6.500114)
					(mid 228.38305 3.048858)
					(end 232.452418 3.800094)
				)
				(arc
					(start 245.247414 3.800094)
					(mid 249.316635 3.048724)
					(end 251.599954 6.49986)
				)
				(arc
					(start 251.599954 6.500114)
					(mid 251.176012 8.232132)
					(end 250.000008 9.572498)
				)
			)
		)
	)
	(zone
		(layer "F.Cu")
		(hatch none 0.5)
		(connect_pads
			(clearance 0)
		)
		(min_thickness 0.25)
		(keepout
			(tracks allowed)
			(vias allowed)
			(pads allowed)
			(copperpour allowed)
			(footprints not_allowed)
		)
		(placement
			(enabled no)
			(sheetname "")
		)
		(fill
			(thermal_gap 0.5)
			(thermal_bridge_width 0.5)
			(island_removal_mode 0)
		)
		(polygon
			(pts
				(xy 298.200064 -409.200096) (xy 309.999888 -409.200096)
				(arc
					(start 309.999888 -420.200074)
					(mid 309.706995 -420.907179)
					(end 308.99989 -421.200072)
				)
				(xy 298.200064 -421.200072)
			)
		)
	)
	(zone
		(layer "F.Cu")
		(hatch none 0.5)
		(connect_pads
			(clearance 0)
		)
		(min_thickness 0.25)
		(keepout
			(tracks not_allowed)
			(vias allowed)
			(pads allowed)
			(copperpour not_allowed)
			(footprints allowed)
		)
		(placement
			(enabled no)
			(sheetname "")
		)
		(fill
			(thermal_gap 0.5)
			(thermal_bridge_width 0.5)
			(island_removal_mode 0)
		)
		(polygon
			(pts
				(arc
					(start 143.89862 -29.15031)
					(mid 143.350107 -28.601416)
					(end 142.80134 -29.150056)
				)
				(arc
					(start 142.80134 -29.627068)
					(mid 142.863591 -29.615825)
					(end 142.926562 -29.609796)
				)
				(xy 142.927832 -29.60878)
				(arc
					(start 143.22298 -29.60878)
					(mid 143.245431 -29.599481)
					(end 143.25473 -29.57703)
				)
				(arc
					(start 143.25473 -29.532072)
					(mid 143.34998 -28.756344)
					(end 143.44523 -29.532072)
				)
				(xy 143.44523 -29.6164)
				(arc
					(start 143.440912 -29.620972)
					(mid 143.380183 -29.734233)
					(end 143.266922 -29.794962)
				)
				(xy 143.26235 -29.79928)
				(arc
					(start 142.967202 -29.79928)
					(mid 142.88336 -29.805462)
					(end 142.80134 -29.823918)
				)
				(arc
					(start 142.80134 -29.93136)
					(mid 142.862583 -29.912731)
					(end 142.9258 -29.902658)
				)
				(xy 142.927832 -29.90088) (xy 143.26235 -29.90088)
				(arc
					(start 143.266922 -29.905198)
					(mid 143.380183 -29.965927)
					(end 143.440912 -30.079188)
				)
				(xy 143.44523 -30.08376)
				(arc
					(start 143.44523 -30.168088)
					(mid 143.34998 -30.943816)
					(end 143.25473 -30.168088)
				)
				(arc
					(start 143.25473 -30.12313)
					(mid 143.245431 -30.100679)
					(end 143.22298 -30.09138)
				)
				(arc
					(start 142.967202 -30.09138)
					(mid 142.879772 -30.105589)
					(end 142.80134 -30.146752)
				)
				(arc
					(start 142.80134 -30.550104)
					(mid 143.34998 -31.098744)
					(end 143.89862 -30.550104)
				)
			)
		)
	)
	(zone
		(layer "F.Cu")
		(hatch none 0.5)
		(connect_pads
			(clearance 0)
		)
		(min_thickness 0.25)
		(keepout
			(tracks allowed)
			(vias allowed)
			(pads allowed)
			(copperpour allowed)
			(footprints allowed)
		)
		(placement
			(enabled no)
			(sheetname "")
		)
		(fill
			(thermal_gap 0.5)
			(thermal_bridge_width 0.5)
			(island_removal_mode 0)
		)
		(polygon
			(pts
				(xy 257.9878 13.8684) (xy 257.9878 15.5448) (xy 258.8514 15.5448) (xy 258.8514 13.8684)
			)
		)
	)
	(zone
		(net "P12V_A_VIN_U21")
		(layer "F.Cu")
		(hatch none 0.5)
		(connect_pads
			(clearance 0.5)
		)
		(min_thickness 0.25)
		(fill yes
			(thermal_gap 0.5)
			(thermal_bridge_width 0.5)
			(island_removal_mode 0)
		)
		(polygon
			(pts
				(xy 41.84396 -140.397992) (xy 40.788336 -141.453616) (xy 40.788336 -143.773906) (xy 40.989504 -143.975074)
				(xy 43.668442 -143.975074) (xy 43.777408 -143.866108) (xy 43.777408 -140.502132) (xy 43.673268 -140.397992)
			)
		)
	)
	(zone
		(net "GND")
		(layer "F.Cu")
		(hatch none 0.5)
		(connect_pads
			(clearance 0.5)
		)
		(min_thickness 0.25)
		(fill yes
			(thermal_gap 0.5)
			(thermal_bridge_width 0.5)
			(island_removal_mode 0)
		)
		(polygon
			(pts
				(arc
					(start 179.946808 -226.836986)
					(mid 180.809792 -226.757598)
					(end 181.63667 -226.49815)
				)
				(arc
					(start 181.63667 -226.49815)
					(mid 183.463774 -229.140084)
					(end 186.635644 -229.64775)
				)
				(arc
					(start 186.635644 -229.64775)
					(mid 186.790487 -230.657272)
					(end 187.190634 -231.596946)
				)
				(xy 184.883044 -231.596946) (xy 182.117746 -234.362244)
				(arc
					(start 182.117746 -237.631986)
					(mid 181.930583 -237.690861)
					(end 181.746398 -237.758478)
				)
				(arc
					(start 181.746398 -237.758478)
					(mid 180.940204 -236.955483)
					(end 179.946808 -236.400594)
				)
			)
		)
	)
	(zone
		(layer "F.Cu")
		(hatch none 0.5)
		(connect_pads
			(clearance 0)
		)
		(min_thickness 0.25)
		(keepout
			(tracks not_allowed)
			(vias allowed)
			(pads allowed)
			(copperpour not_allowed)
			(footprints allowed)
		)
		(placement
			(enabled no)
			(sheetname "")
		)
		(fill
			(thermal_gap 0.5)
			(thermal_bridge_width 0.5)
			(island_removal_mode 0)
		)
		(polygon
			(pts
				(arc
					(start 472.250008 -269.999968)
					(mid 467.499954 -274.750022)
					(end 462.7499 -269.999968)
				)
				(arc
					(start 462.7499 -269.999968)
					(mid 467.499954 -265.249914)
					(end 472.250008 -269.999968)
				)
			)
		)
	)
	(zone
		(net "P12V_A")
		(layer "F.Cu")
		(hatch none 0.5)
		(connect_pads
			(clearance 0.5)
		)
		(min_thickness 0.25)
		(fill yes
			(thermal_gap 0.5)
			(thermal_bridge_width 0.5)
			(island_removal_mode 0)
		)
		(polygon
			(pts
				(xy 108.857796 -169.142918) (xy 107.841796 -170.158918) (xy 107.206796 -170.158918) (xy 106.825796 -170.539918)
				(xy 106.825796 -173.079918) (xy 107.079796 -173.333918) (xy 110.381796 -173.333918) (xy 110.635796 -173.079918)
				(xy 110.635796 -170.793918) (xy 110.000796 -170.158918) (xy 109.619796 -170.158918) (xy 109.365796 -169.904918)
				(xy 109.365796 -169.269918) (xy 109.238796 -169.142918)
			)
		)
		(polygon
			(pts
				(xy 108.832396 -169.727118) (xy 108.629196 -169.727118) (xy 108.629196 -169.930318) (xy 108.832396 -169.930318)
			)
		)
	)
	(zone
		(layer "F.Cu")
		(hatch none 0.5)
		(connect_pads
			(clearance 0)
		)
		(min_thickness 0.25)
		(keepout
			(tracks allowed)
			(vias allowed)
			(pads allowed)
			(copperpour allowed)
			(footprints not_allowed)
		)
		(placement
			(enabled no)
			(sheetname "")
		)
		(fill
			(thermal_gap 0.5)
			(thermal_bridge_width 0.5)
			(island_removal_mode 0)
		)
		(polygon
			(pts
				(arc
					(start 449.674996 -207.79994)
					(mid 456.674982 -200.799954)
					(end 463.674968 -207.79994)
				)
				(arc
					(start 463.674968 -213.799928)
					(mid 456.674982 -220.799914)
					(end 449.674996 -213.799928)
				)
			)
		)
	)
	(zone
		(layer "F.Cu")
		(hatch none 0.5)
		(connect_pads
			(clearance 0)
		)
		(min_thickness 0.25)
		(keepout
			(tracks allowed)
			(vias allowed)
			(pads allowed)
			(copperpour allowed)
			(footprints allowed)
		)
		(placement
			(enabled no)
			(sheetname "")
		)
		(fill
			(thermal_gap 0.5)
			(thermal_bridge_width 0.5)
			(island_removal_mode 0)
		)
		(polygon
			(pts
				(xy 241.789966 -382.078738) (xy 240.850928 -382.078738) (xy 240.850928 -380.544578) (xy 241.789966 -380.544578)
			)
		)
	)
	(zone
		(layer "F.Cu")
		(hatch none 0.5)
		(connect_pads
			(clearance 0)
		)
		(min_thickness 0.25)
		(keepout
			(tracks not_allowed)
			(vias allowed)
			(pads allowed)
			(copperpour not_allowed)
			(footprints allowed)
		)
		(placement
			(enabled no)
			(sheetname "")
		)
		(fill
			(thermal_gap 0.5)
			(thermal_bridge_width 0.5)
			(island_removal_mode 0)
		)
		(polygon
			(pts
				(arc
					(start 356.670102 -162.178746)
					(mid 356.289229 -161.797492)
					(end 355.908102 -162.178492)
				)
				(arc
					(start 355.908102 -163.321492)
					(mid 356.289102 -163.702492)
					(end 356.670102 -163.321492)
				)
				(xy 356.670102 -162.972242)
				(arc
					(start 356.416356 -162.972242)
					(mid 356.380255 -162.987195)
					(end 356.365302 -163.023296)
				)
				(arc
					(start 356.365302 -163.065968)
					(mid 356.289102 -163.588136)
					(end 356.212902 -163.065968)
				)
				(xy 356.212902 -162.9918)
				(arc
					(start 356.21595 -162.988752)
					(mid 356.272558 -162.879498)
					(end 356.381812 -162.82289)
				)
				(xy 356.38486 -162.819842) (xy 356.670102 -162.819842) (xy 356.670102 -162.680142) (xy 356.38486 -162.680142)
				(arc
					(start 356.381812 -162.677094)
					(mid 356.272558 -162.620486)
					(end 356.21595 -162.511232)
				)
				(xy 356.212902 -162.508184)
				(arc
					(start 356.212902 -162.434016)
					(mid 356.289102 -161.911848)
					(end 356.365302 -162.434016)
				)
				(arc
					(start 356.365302 -162.476688)
					(mid 356.380255 -162.512789)
					(end 356.416356 -162.527742)
				)
				(xy 356.670102 -162.527742)
			)
		)
	)
	(zone
		(layer "F.Cu")
		(hatch none 0.5)
		(connect_pads
			(clearance 0)
		)
		(min_thickness 0.25)
		(keepout
			(tracks allowed)
			(vias allowed)
			(pads allowed)
			(copperpour allowed)
			(footprints not_allowed)
		)
		(placement
			(enabled no)
			(sheetname "")
		)
		(fill
			(thermal_gap 0.5)
			(thermal_bridge_width 0.5)
			(island_removal_mode 0)
		)
		(polygon
			(pts
				(arc
					(start 485.000046 -120.499886)
					(mid 481.24999 -124.249942)
					(end 477.499934 -120.499886)
				)
				(arc
					(start 477.499934 -120.499886)
					(mid 481.24999 -116.74983)
					(end 485.000046 -120.499886)
				)
			)
		)
	)
	(zone
		(layer "F.Cu")
		(hatch none 0.5)
		(connect_pads
			(clearance 0)
		)
		(min_thickness 0.25)
		(keepout
			(tracks allowed)
			(vias allowed)
			(pads allowed)
			(copperpour allowed)
			(footprints not_allowed)
		)
		(placement
			(enabled no)
			(sheetname "")
		)
		(fill
			(thermal_gap 0.5)
			(thermal_bridge_width 0.5)
			(island_removal_mode 0)
		)
		(polygon
			(pts
				(xy 298.200064 -421.200072) (xy 291.599874 -421.200072) (xy 291.599874 -409.200096) (xy 298.200064 -409.200096)
			)
		)
	)
	(zone
		(layer "F.Cu")
		(hatch none 0.5)
		(connect_pads
			(clearance 0)
		)
		(min_thickness 0.25)
		(keepout
			(tracks not_allowed)
			(vias allowed)
			(pads allowed)
			(copperpour not_allowed)
			(footprints allowed)
		)
		(placement
			(enabled no)
			(sheetname "")
		)
		(fill
			(thermal_gap 0.5)
			(thermal_bridge_width 0.5)
			(island_removal_mode 0)
		)
		(polygon
			(pts
				(arc
					(start 482.870002 -47.178722)
					(mid 482.489129 -46.797468)
					(end 482.108002 -47.178468)
				)
				(arc
					(start 482.108002 -48.321468)
					(mid 482.489002 -48.702468)
					(end 482.870002 -48.321468)
				)
				(xy 482.870002 -47.972218)
				(arc
					(start 482.644704 -47.972218)
					(mid 482.588488 -47.995504)
					(end 482.565202 -48.05172)
				)
				(arc
					(start 482.565202 -48.065944)
					(mid 482.489002 -48.588112)
					(end 482.412802 -48.065944)
				)
				(xy 482.412802 -48.020224)
				(arc
					(start 482.415342 -48.017684)
					(mid 482.480745 -47.887761)
					(end 482.610668 -47.822358)
				)
				(xy 482.613208 -47.819818) (xy 482.870002 -47.819818) (xy 482.870002 -47.680118) (xy 482.613208 -47.680118)
				(arc
					(start 482.610668 -47.677578)
					(mid 482.480745 -47.612175)
					(end 482.415342 -47.482252)
				)
				(xy 482.412802 -47.479712)
				(arc
					(start 482.412802 -47.433992)
					(mid 482.489002 -46.911824)
					(end 482.565202 -47.433992)
				)
				(arc
					(start 482.565202 -47.448216)
					(mid 482.588488 -47.504432)
					(end 482.644704 -47.527718)
				)
				(xy 482.870002 -47.527718)
			)
		)
	)
	(zone
		(layer "F.Cu")
		(hatch none 0.5)
		(connect_pads
			(clearance 0)
		)
		(min_thickness 0.25)
		(keepout
			(tracks allowed)
			(vias allowed)
			(pads allowed)
			(copperpour allowed)
			(footprints not_allowed)
		)
		(placement
			(enabled no)
			(sheetname "")
		)
		(fill
			(thermal_gap 0.5)
			(thermal_bridge_width 0.5)
			(island_removal_mode 0)
		)
		(polygon
			(pts
				(xy 198.399908 -53.799994) (xy 191.799972 -53.799994) (xy 191.799972 0) (xy 198.399908 0)
			)
		)
	)
	(zone
		(net "P5V_HDD32")
		(layer "F.Cu")
		(hatch none 0.5)
		(connect_pads
			(clearance 0.5)
		)
		(min_thickness 0.25)
		(fill yes
			(thermal_gap 0.5)
			(thermal_bridge_width 0.5)
			(island_removal_mode 0)
		)
		(polygon
			(pts
				(xy 394.69695 -51.729894) (xy 394.44295 -51.983894) (xy 394.44295 -62.778894) (xy 392.79195 -64.429894)
				(xy 389.36295 -64.429894) (xy 389.10895 -64.683894) (xy 389.10895 -66.334894) (xy 389.36295 -66.588894)
				(xy 393.93495 -66.588894) (xy 394.56995 -65.953894) (xy 396.34795 -65.953894) (xy 396.85595 -65.445894)
				(xy 396.85595 -51.983894) (xy 396.60195 -51.729894)
			)
		)
		(polygon
			(pts
				(xy 393.45235 -65.598294) (xy 393.24915 -65.598294) (xy 393.24915 -65.801494) (xy 393.45235 -65.801494)
			)
		)
		(polygon
			(pts
				(xy 392.58875 -65.598294) (xy 392.38555 -65.598294) (xy 392.38555 -65.801494) (xy 392.58875 -65.801494)
			)
		)
	)
	(zone
		(net "5V_PRE_23")
		(layer "F.Cu")
		(hatch none 0.5)
		(connect_pads
			(clearance 0.5)
		)
		(min_thickness 0.25)
		(fill yes
			(thermal_gap 0.5)
			(thermal_bridge_width 0.5)
			(island_removal_mode 0)
		)
		(polygon
			(pts
				(xy 478.147126 -174.9806) (xy 477.943926 -175.1838) (xy 477.943926 -176.508918) (xy 478.070926 -176.635918)
				(xy 479.340926 -176.635918) (xy 481.880926 -179.175918) (xy 486.325926 -179.175918) (xy 486.452926 -179.048918)
				(xy 486.452926 -178.286918) (xy 486.325926 -178.159918) (xy 483.163118 -178.159918) (xy 479.9838 -174.9806)
			)
		)
	)
	(zone
		(layer "F.Cu")
		(hatch none 0.5)
		(connect_pads
			(clearance 0)
		)
		(min_thickness 0.25)
		(keepout
			(tracks allowed)
			(vias allowed)
			(pads allowed)
			(copperpour allowed)
			(footprints not_allowed)
		)
		(placement
			(enabled no)
			(sheetname "")
		)
		(fill
			(thermal_gap 0.5)
			(thermal_bridge_width 0.5)
			(island_removal_mode 0)
		)
		(polygon
			(pts
				(arc
					(start 409.150058 -289.999928)
					(mid 404.400004 -294.749982)
					(end 399.64995 -289.999928)
				)
				(arc
					(start 399.64995 -289.999928)
					(mid 404.400004 -285.249874)
					(end 409.150058 -289.999928)
				)
			)
		)
	)
	(zone
		(net "P12V_HDD14")
		(layer "F.Cu")
		(hatch none 0.5)
		(connect_pads
			(clearance 0.5)
		)
		(min_thickness 0.25)
		(fill yes
			(thermal_gap 0.5)
			(thermal_bridge_width 0.5)
			(island_removal_mode 0)
		)
		(polygon
			(pts
				(xy 75.402948 -176.254918) (xy 75.148948 -176.508918) (xy 75.148948 -178.159918) (xy 75.402948 -178.413918)
				(xy 77.561948 -178.413918) (xy 78.069948 -178.921918) (xy 78.069948 -181.461918) (xy 85.816948 -189.208918)
				(xy 94.325948 -189.208918) (xy 94.452948 -189.081918) (xy 94.452948 -187.303918) (xy 94.325948 -187.176918)
				(xy 88.356948 -187.176918) (xy 87.721948 -186.541918) (xy 86.070948 -186.541918) (xy 81.752948 -182.223918)
				(xy 81.752948 -178.667918) (xy 80.609948 -177.524918) (xy 80.609948 -176.508918) (xy 80.355948 -176.254918)
			)
		)
		(polygon
			(pts
				(xy 87.874348 -188.218318) (xy 87.671148 -188.218318) (xy 87.671148 -188.421518) (xy 87.874348 -188.421518)
			)
		)
		(polygon
			(pts
				(xy 87.010748 -188.218318) (xy 86.807548 -188.218318) (xy 86.807548 -188.421518) (xy 87.010748 -188.421518)
			)
		)
	)
	(zone
		(layer "F.Cu")
		(hatch none 0.5)
		(connect_pads
			(clearance 0)
		)
		(min_thickness 0.25)
		(keepout
			(tracks allowed)
			(vias allowed)
			(pads allowed)
			(copperpour allowed)
			(footprints allowed)
		)
		(placement
			(enabled no)
			(sheetname "")
		)
		(fill
			(thermal_gap 0.5)
			(thermal_bridge_width 0.5)
			(island_removal_mode 0)
		)
		(polygon
			(pts
				(xy 272.9738 -284.48) (xy 272.9738 -280.7462) (xy 275.3106 -280.7462) (xy 275.3106 -284.48)
			)
		)
	)
	(zone
		(layer "F.Cu")
		(hatch none 0.5)
		(connect_pads
			(clearance 0)
		)
		(min_thickness 0.25)
		(keepout
			(tracks not_allowed)
			(vias allowed)
			(pads allowed)
			(copperpour not_allowed)
			(footprints allowed)
		)
		(placement
			(enabled no)
			(sheetname "")
		)
		(fill
			(thermal_gap 0.5)
			(thermal_bridge_width 0.5)
			(island_removal_mode 0)
		)
		(polygon
			(pts
				(arc
					(start 159.089852 -162.178746)
					(mid 158.708979 -161.797492)
					(end 158.327852 -162.178492)
				)
				(xy 158.327852 -162.527742)
				(arc
					(start 158.581852 -162.527742)
					(mid 158.617773 -162.512863)
					(end 158.632652 -162.476942)
				)
				(arc
					(start 158.632652 -162.434016)
					(mid 158.708852 -161.911848)
					(end 158.785052 -162.434016)
				)
				(xy 158.785052 -162.508438)
				(arc
					(start 158.782004 -162.511486)
					(mid 158.725473 -162.620563)
					(end 158.616396 -162.677094)
				)
				(xy 158.613348 -162.680142) (xy 158.327852 -162.680142) (xy 158.327852 -162.819842) (xy 158.613348 -162.819842)
				(arc
					(start 158.616396 -162.82289)
					(mid 158.725473 -162.879421)
					(end 158.782004 -162.988498)
				)
				(xy 158.785052 -162.991546)
				(arc
					(start 158.785052 -163.065968)
					(mid 158.708852 -163.588136)
					(end 158.632652 -163.065968)
				)
				(arc
					(start 158.632652 -163.023042)
					(mid 158.617773 -162.987121)
					(end 158.581852 -162.972242)
				)
				(xy 158.327852 -162.972242)
				(arc
					(start 158.327852 -163.321492)
					(mid 158.708852 -163.702492)
					(end 159.089852 -163.321492)
				)
			)
		)
	)
	(zone
		(net "P12V_HDD30")
		(layer "F.Cu")
		(hatch none 0.5)
		(connect_pads
			(clearance 0.5)
		)
		(min_thickness 0.25)
		(fill yes
			(thermal_gap 0.5)
			(thermal_bridge_width 0.5)
			(island_removal_mode 0)
		)
		(polygon
			(pts
				(xy 334.645 -63.540894) (xy 334.391 -63.794894) (xy 334.391 -67.858894) (xy 333.932276 -68.317618)
				(xy 333.932276 -71.139812) (xy 333.098394 -71.973694) (xy 326.178418 -71.973694) (xy 326.009 -72.143112)
				(xy 326.009 -73.954894) (xy 326.263 -74.208894) (xy 330.2 -74.208894) (xy 330.708 -73.700894) (xy 338.455 -73.700894)
				(xy 339.344 -72.811894) (xy 339.344 -63.794894) (xy 339.09 -63.540894)
			)
		)
		(polygon
			(pts
				(xy 330.3524 -73.091294) (xy 330.1492 -73.091294) (xy 330.1492 -73.294494) (xy 330.3524 -73.294494)
			)
		)
		(polygon
			(pts
				(xy 329.4888 -73.091294) (xy 329.2856 -73.091294) (xy 329.2856 -73.294494) (xy 329.4888 -73.294494)
			)
		)
	)
	(zone
		(net "GND")
		(layer "F.Cu")
		(hatch none 0.5)
		(connect_pads
			(clearance 0.5)
		)
		(min_thickness 0.25)
		(fill yes
			(thermal_gap 0.5)
			(thermal_bridge_width 0.5)
			(island_removal_mode 0)
		)
		(polygon
			(pts
				(xy 112.487964 -337.823048)
				(arc
					(start 128.51384 -334.617822)
					(mid 131.430209 -332.31062)
					(end 135.009636 -333.318612)
				)
				(xy 137.287 -332.86319) (xy 137.287 -332.294992) (xy 112.45596 -312.97753) (xy 112.45596 -315.962284)
				(arc
					(start 115.441476 -318.9478)
					(mid 115.654595 -319.17885)
					(end 115.848384 -319.426336)
				)
				(xy 117.193822 -319.426336) (xy 117.193822 -329.373484) (xy 115.40109 -329.373484) (xy 113.319814 -331.45476)
				(arc
					(start 106.813858 -331.45476)
					(mid 106.572173 -332.271473)
					(end 106.266996 -333.066644)
				)
				(arc
					(start 106.266996 -333.066644)
					(mid 108.181672 -334.669341)
					(end 108.807758 -337.086448)
				)
			)
		)
	)
	(zone
		(layer "F.Cu")
		(hatch none 0.5)
		(connect_pads
			(clearance 0)
		)
		(min_thickness 0.25)
		(keepout
			(tracks not_allowed)
			(vias allowed)
			(pads allowed)
			(copperpour not_allowed)
			(footprints allowed)
		)
		(placement
			(enabled no)
			(sheetname "")
		)
		(fill
			(thermal_gap 0.5)
			(thermal_bridge_width 0.5)
			(island_removal_mode 0)
		)
		(polygon
			(pts
				(arc
					(start 478.120202 -273.368516)
					(mid 477.739202 -272.987516)
					(end 477.358202 -273.368516)
				)
				(arc
					(start 477.358202 -274.511262)
					(mid 477.739075 -274.892516)
					(end 478.120202 -274.511516)
				)
				(xy 478.120202 -274.162266)
				(arc
					(start 477.887792 -274.162266)
					(mid 477.868435 -274.166099)
					(end 477.851978 -274.176998)
				)
				(arc
					(start 477.830134 -274.198842)
					(mid 477.819208 -274.215288)
					(end 477.815402 -274.234656)
				)
				(arc
					(start 477.815402 -274.255992)
					(mid 477.739202 -274.77816)
					(end 477.663002 -274.255992)
				)
				(xy 477.663002 -274.20316)
				(arc
					(start 477.66605 -274.200112)
					(mid 477.678485 -274.156949)
					(end 477.700086 -274.117562)
				)
				(xy 477.700086 -274.113498) (xy 477.766634 -274.04695)
				(arc
					(start 477.770698 -274.04695)
					(mid 477.810076 -274.025328)
					(end 477.853248 -274.012914)
				)
				(xy 477.856296 -274.009866) (xy 478.120202 -274.009866) (xy 478.120202 -273.870166) (xy 477.846898 -273.870166)
				(arc
					(start 477.84385 -273.867118)
					(mid 477.800687 -273.854683)
					(end 477.7613 -273.833082)
				)
				(xy 477.757236 -273.833082) (xy 477.700086 -273.775932)
				(arc
					(start 477.700086 -273.771868)
					(mid 477.678464 -273.73249)
					(end 477.66605 -273.689318)
				)
				(xy 477.663002 -273.68627)
				(arc
					(start 477.663002 -273.62404)
					(mid 477.739202 -273.101872)
					(end 477.815402 -273.62404)
				)
				(arc
					(start 477.815402 -273.654774)
					(mid 477.819235 -273.674131)
					(end 477.830134 -273.690588)
				)
				(arc
					(start 477.84258 -273.703034)
					(mid 477.859026 -273.71396)
					(end 477.878394 -273.717766)
				)
				(xy 478.120202 -273.717766)
			)
		)
	)
	(zone
		(net "P5V_HDD25")
		(layer "F.Cu")
		(hatch none 0.5)
		(connect_pads
			(clearance 0.5)
		)
		(min_thickness 0.25)
		(fill yes
			(thermal_gap 0.5)
			(thermal_bridge_width 0.5)
			(island_removal_mode 0)
		)
		(polygon
			(pts
				(xy 51.218846 -56.682894) (xy 50.964846 -56.936894) (xy 50.964846 -59.222894) (xy 51.218846 -59.476894)
				(xy 51.218846 -61.508894) (xy 51.980846 -62.270894) (xy 51.980846 -63.032894) (xy 52.361846 -63.413894)
				(xy 52.742846 -63.413894) (xy 55.917846 -66.588894) (xy 62.775846 -66.588894) (xy 62.902846 -66.461894)
				(xy 62.902846 -64.683894) (xy 62.775846 -64.556894) (xy 57.695846 -64.556894) (xy 55.790846 -62.651894)
				(xy 54.901846 -62.651894) (xy 54.012846 -61.762894) (xy 54.012846 -59.222894) (xy 54.647846 -58.587894)
				(xy 54.647846 -56.936894) (xy 54.393846 -56.682894)
			)
		)
		(polygon
			(pts
				(xy 53.225446 -63.109094) (xy 53.022246 -63.109094) (xy 53.022246 -63.312294) (xy 53.225446 -63.312294)
			)
		)
		(polygon
			(pts
				(xy 53.225446 -62.245494) (xy 53.022246 -62.245494) (xy 53.022246 -62.448694) (xy 53.225446 -62.448694)
			)
		)
		(polygon
			(pts
				(xy 52.361846 -62.245494) (xy 52.158646 -62.245494) (xy 52.158646 -62.448694) (xy 52.361846 -62.448694)
			)
		)
	)
	(zone
		(layer "F.Cu")
		(hatch none 0.5)
		(connect_pads
			(clearance 0)
		)
		(min_thickness 0.25)
		(keepout
			(tracks allowed)
			(vias allowed)
			(pads allowed)
			(copperpour allowed)
			(footprints not_allowed)
		)
		(placement
			(enabled no)
			(sheetname "")
		)
		(fill
			(thermal_gap 0.5)
			(thermal_bridge_width 0.5)
			(island_removal_mode 0)
		)
		(polygon
			(pts
				(arc
					(start 233.59999 6.500114)
					(mid 229.849934 2.750058)
					(end 226.099878 6.500114)
				)
				(arc
					(start 226.099878 6.500114)
					(mid 229.849934 10.25017)
					(end 233.59999 6.500114)
				)
			)
		)
	)
	(zone
		(layer "F.Cu")
		(hatch none 0.5)
		(connect_pads
			(clearance 0)
		)
		(min_thickness 0.25)
		(keepout
			(tracks allowed)
			(vias allowed)
			(pads allowed)
			(copperpour allowed)
			(footprints allowed)
		)
		(placement
			(enabled no)
			(sheetname "")
		)
		(fill
			(thermal_gap 0.5)
			(thermal_bridge_width 0.5)
			(island_removal_mode 0)
		)
		(polygon
			(pts
				(xy 378.0282 -140.0302) (xy 378.0282 -138.0998) (xy 381.8636 -138.0998) (xy 381.8636 -140.0302)
			)
		)
	)
	(zone
		(layer "F.Cu")
		(hatch none 0.5)
		(connect_pads
			(clearance 0)
		)
		(min_thickness 0.25)
		(keepout
			(tracks allowed)
			(vias allowed)
			(pads allowed)
			(copperpour allowed)
			(footprints not_allowed)
		)
		(placement
			(enabled no)
			(sheetname "")
		)
		(fill
			(thermal_gap 0.5)
			(thermal_bridge_width 0.5)
			(island_removal_mode 0)
		)
		(polygon
			(pts
				(arc
					(start 307.200046 -249.199908)
					(mid 300.20006 -256.199894)
					(end 293.200074 -249.199908)
				)
				(arc
					(start 293.200074 -243.19992)
					(mid 300.20006 -236.199934)
					(end 307.200046 -243.19992)
				)
			)
		)
	)
	(zone
		(layer "F.Cu")
		(hatch none 0.5)
		(connect_pads
			(clearance 0)
		)
		(min_thickness 0.25)
		(keepout
			(tracks allowed)
			(vias allowed)
			(pads allowed)
			(copperpour allowed)
			(footprints not_allowed)
		)
		(placement
			(enabled no)
			(sheetname "")
		)
		(fill
			(thermal_gap 0.5)
			(thermal_bridge_width 0.5)
			(island_removal_mode 0)
		)
		(polygon
			(pts
				(xy 320.250058 -295.800018) (xy 305.699922 -295.800018) (xy 305.699922 -305.799998) (xy 298.200064 -305.799998)
				(xy 298.200064 -349.199962)
				(arc
					(start 490.450124 -349.199962)
					(mid 491.157229 -348.907069)
					(end 491.450122 -348.199964)
				)
				(xy 491.450122 -305.799998) (xy 478.00006 -305.799998) (xy 478.00006 -295.800018) (xy 463.449924 -295.800018)
				(xy 463.449924 -305.799998) (xy 446.449958 -305.799998) (xy 446.449958 -295.800018) (xy 431.900076 -295.800018)
				(xy 431.900076 -305.799998) (xy 414.90011 -305.799998) (xy 414.90011 -295.800018) (xy 400.349974 -295.800018)
				(xy 400.349974 -305.799998) (xy 383.350008 -305.799998) (xy 383.350008 -295.800018) (xy 368.800126 -295.800018)
				(xy 368.800126 -305.799998) (xy 351.799906 -305.799998) (xy 351.799906 -295.800018) (xy 337.250024 -295.800018)
				(xy 337.250024 -305.799998) (xy 320.250058 -305.799998)
			)
		)
	)
	(zone
		(net "5V_PRE_5")
		(layer "F.Cu")
		(hatch none 0.5)
		(connect_pads
			(clearance 0.5)
		)
		(min_thickness 0.25)
		(fill yes
			(thermal_gap 0.5)
			(thermal_bridge_width 0.5)
			(island_removal_mode 0)
		)
		(polygon
			(pts
				(xy 180.7972 -289.9156) (xy 180.594 -290.1188) (xy 180.594 -291.508942) (xy 180.721 -291.635942)
				(xy 181.991 -291.635942) (xy 184.531 -294.175942) (xy 188.976 -294.175942) (xy 189.103 -294.048942)
				(xy 189.103 -293.286942) (xy 188.976 -293.159942) (xy 185.692542 -293.159942) (xy 182.4482 -289.9156)
			)
		)
	)
	(zone
		(layer "F.Cu")
		(hatch none 0.5)
		(connect_pads
			(clearance 0)
		)
		(min_thickness 0.25)
		(keepout
			(tracks not_allowed)
			(vias allowed)
			(pads allowed)
			(copperpour not_allowed)
			(footprints allowed)
		)
		(placement
			(enabled no)
			(sheetname "")
		)
		(fill
			(thermal_gap 0.5)
			(thermal_bridge_width 0.5)
			(island_removal_mode 0)
		)
		(polygon
			(pts
				(arc
					(start 369.149884 -28.079954)
					(mid 372.150132 -25.079706)
					(end 375.150126 -28.079954)
				)
				(arc
					(start 375.150126 -28.079954)
					(mid 372.150132 -31.079948)
					(end 369.149884 -28.079954)
				)
			)
		)
	)
	(zone
		(net "GND")
		(layer "F.Cu")
		(hatch none 0.5)
		(connect_pads
			(clearance 0.5)
		)
		(min_thickness 0.25)
		(fill yes
			(thermal_gap 0.5)
			(thermal_bridge_width 0.5)
			(island_removal_mode 0)
		)
		(polygon
			(pts
				(xy 93.274642 -229.491794) (xy 56.590438 -206.0956) (xy 54.093618 -206.0956) (xy 54.093618 -210.635342)
				(xy 55.339996 -211.88172)
				(arc
					(start 55.339996 -229.963726)
					(mid 60.072104 -231.565987)
					(end 59.72429 -236.549946)
				)
				(arc
					(start 59.72429 -236.549946)
					(mid 59.807576 -236.896117)
					(end 59.85891 -237.248446)
				)
				(xy 60.558172 -237.248446)
				(arc
					(start 60.558172 -245.499128)
					(mid 60.82025 -245.869392)
					(end 61.040518 -246.265954)
				)
				(arc
					(start 61.040518 -246.265954)
					(mid 62.406139 -246.622341)
					(end 63.569342 -247.421654)
				)
				(arc
					(start 63.569342 -247.421654)
					(mid 64.070765 -247.395414)
					(end 64.571626 -247.430798)
				)
				(arc
					(start 64.571626 -247.430798)
					(mid 66.152967 -245.905692)
					(end 68.295266 -245.418864)
				)
				(arc
					(start 68.295266 -245.418864)
					(mid 73.199071 -247.792477)
					(end 71.394066 -252.932946)
				)
				(arc
					(start 71.394066 -252.932946)
					(mid 74.528144 -254.481218)
					(end 75.321414 -257.885692)
				)
				(arc
					(start 88.42756 -257.885692)
					(mid 90.090652 -257.963926)
					(end 91.58478 -258.698492)
				)
				(arc
					(start 100.692712 -258.698492)
					(mid 101.660473 -252.557611)
					(end 107.577128 -254.465836)
				)
				(arc
					(start 107.577128 -254.465836)
					(mid 107.956228 -254.234425)
					(end 108.358178 -254.045466)
				)
				(arc
					(start 108.358178 -254.045466)
					(mid 109.31658 -250.904419)
					(end 112.275874 -249.480578)
				)
				(arc
					(start 112.275874 -249.480578)
					(mid 111.406761 -248.905292)
					(end 110.711234 -248.129044)
				)
				(arc
					(start 110.711234 -248.129044)
					(mid 109.82112 -247.767504)
					(end 109.039914 -247.208294)
				)
				(xy 107.551728 -247.208294) (xy 107.551728 -237.299246)
				(arc
					(start 107.825286 -237.299246)
					(mid 108.034919 -236.676072)
					(end 108.341668 -236.094524)
				)
				(arc
					(start 108.341668 -236.094524)
					(mid 108.117044 -235.86499)
					(end 107.911138 -235.618528)
				)
				(arc
					(start 107.911138 -235.618528)
					(mid 106.743532 -234.053631)
					(end 106.434382 -232.125774)
				)
			)
		)
		(polygon
			(pts
				(arc
					(start 84.100416 -250.711462)
					(mid 88.826228 -256.784031)
					(end 89.085928 -249.093736)
				)
				(arc
					(start 89.085928 -249.093736)
					(mid 89.23796 -244.99561)
					(end 85.75929 -242.823746)
				)
				(arc
					(start 85.75929 -239.48136)
					(mid 88.571668 -233.163899)
					(end 81.65846 -233.32567)
				)
				(arc
					(start 81.65846 -233.32567)
					(mid 77.342488 -234.168779)
					(end 76.283058 -238.436658)
				)
				(arc
					(start 76.283058 -238.436658)
					(mid 76.236003 -238.603135)
					(end 76.195936 -238.77143)
				)
				(xy 76.00061 -238.77143) (xy 76.00061 -247.26011)
				(arc
					(start 77.5462 -247.26011)
					(mid 79.105522 -248.114356)
					(end 80.87995 -248.22658)
				)
				(arc
					(start 80.87995 -248.22658)
					(mid 81.320007 -248.271532)
					(end 81.762346 -248.268744)
				)
				(arc
					(start 81.762346 -248.268744)
					(mid 82.667276 -249.742892)
					(end 84.100416 -250.711462)
				)
			)
		)
	)
	(zone
		(layer "F.Cu")
		(hatch none 0.5)
		(connect_pads
			(clearance 0)
		)
		(min_thickness 0.25)
		(keepout
			(tracks allowed)
			(vias allowed)
			(pads allowed)
			(copperpour allowed)
			(footprints not_allowed)
		)
		(placement
			(enabled no)
			(sheetname "")
		)
		(fill
			(thermal_gap 0.5)
			(thermal_bridge_width 0.5)
			(island_removal_mode 0)
		)
		(polygon
			(pts
				(xy 334.674972 -9.99998) (xy 334.674972 0)
				(arc
					(start 347.000068 0)
					(mid 347.707173 -0.292893)
					(end 348.000066 -0.999998)
				)
				(xy 348.000066 -9.99998)
			)
		)
	)
	(zone
		(net "P12V_A")
		(layer "F.Cu")
		(hatch none 0.5)
		(connect_pads
			(clearance 0.5)
		)
		(min_thickness 0.25)
		(fill yes
			(thermal_gap 0.5)
			(thermal_bridge_width 0.5)
			(island_removal_mode 0)
		)
		(polygon
			(pts
				(xy 14.207998 -169.142918) (xy 13.191998 -170.158918) (xy 12.556998 -170.158918) (xy 12.175998 -170.539918)
				(xy 12.175998 -173.079918) (xy 12.429998 -173.333918) (xy 15.731998 -173.333918) (xy 15.985998 -173.079918)
				(xy 15.985998 -170.793918) (xy 15.350998 -170.158918) (xy 14.969998 -170.158918) (xy 14.715998 -169.904918)
				(xy 14.715998 -169.269918) (xy 14.588998 -169.142918)
			)
		)
		(polygon
			(pts
				(xy 14.182598 -169.727118) (xy 13.979398 -169.727118) (xy 13.979398 -169.930318) (xy 14.182598 -169.930318)
			)
		)
	)
	(zone
		(net "P5V_A_4")
		(layer "F.Cu")
		(hatch none 0.5)
		(connect_pads
			(clearance 0.5)
		)
		(min_thickness 0.25)
		(fill yes
			(thermal_gap 0.5)
			(thermal_bridge_width 0.5)
			(island_removal_mode 0)
		)
		(polygon
			(pts
				(xy 431.454052 -165.332918) (xy 431.200052 -165.586918) (xy 431.200052 -170.285918) (xy 431.454052 -170.539918)
				(xy 433.740052 -170.539918) (xy 433.994052 -170.285918) (xy 433.994052 -165.586918) (xy 433.740052 -165.332918)
			)
		)
	)
	(zone
		(net "P5V_HDD18")
		(layer "F.Cu")
		(hatch none 0.5)
		(connect_pads
			(clearance 0.5)
		)
		(min_thickness 0.25)
		(fill yes
			(thermal_gap 0.5)
			(thermal_bridge_width 0.5)
			(island_removal_mode 0)
		)
		(polygon
			(pts
				(xy 331.597 -166.729918) (xy 331.343 -166.983918) (xy 331.343 -177.778918) (xy 329.692 -179.429918)
				(xy 326.263 -179.429918) (xy 326.009 -179.683918) (xy 326.009 -181.334918) (xy 326.263 -181.588918)
				(xy 330.835 -181.588918) (xy 331.47 -180.953918) (xy 333.248 -180.953918) (xy 333.756 -180.445918)
				(xy 333.756 -166.983918) (xy 333.502 -166.729918)
			)
		)
		(polygon
			(pts
				(xy 330.3524 -180.598318) (xy 330.1492 -180.598318) (xy 330.1492 -180.801518) (xy 330.3524 -180.801518)
			)
		)
		(polygon
			(pts
				(xy 329.4888 -180.598318) (xy 329.2856 -180.598318) (xy 329.2856 -180.801518) (xy 329.4888 -180.801518)
			)
		)
	)
	(zone
		(net "P5V_A_1")
		(layer "F.Cu")
		(hatch none 0.5)
		(connect_pads
			(clearance 0.5)
		)
		(min_thickness 0.25)
		(fill yes
			(thermal_gap 0.5)
			(thermal_bridge_width 0.5)
			(island_removal_mode 0)
		)
		(polygon
			(pts
				(xy 144.598898 -280.840942) (xy 144.344898 -281.094942) (xy 144.344898 -283.380942) (xy 144.598898 -283.634942)
				(xy 149.297898 -283.634942) (xy 149.551898 -283.380942) (xy 149.551898 -281.094942) (xy 149.297898 -280.840942)
			)
		)
	)
	(zone
		(layer "F.Cu")
		(hatch none 0.5)
		(connect_pads
			(clearance 0)
		)
		(min_thickness 0.25)
		(keepout
			(tracks allowed)
			(vias allowed)
			(pads allowed)
			(copperpour allowed)
			(footprints allowed)
		)
		(placement
			(enabled no)
			(sheetname "")
		)
		(fill
			(thermal_gap 0.5)
			(thermal_bridge_width 0.5)
			(island_removal_mode 0)
		)
		(polygon
			(pts
				(xy 276.4028 -283.5402) (xy 279.0444 -283.5402) (xy 279.4508 -283.1338) (xy 279.4508 -280.3906)
				(xy 279.1968 -280.1366) (xy 276.7076 -280.1366) (xy 276.2758 -280.5684) (xy 276.2758 -283.4132)
			)
		)
	)
	(zone
		(layer "F.Cu")
		(hatch none 0.5)
		(connect_pads
			(clearance 0)
		)
		(min_thickness 0.25)
		(keepout
			(tracks allowed)
			(vias allowed)
			(pads allowed)
			(copperpour allowed)
			(footprints allowed)
		)
		(placement
			(enabled no)
			(sheetname "")
		)
		(fill
			(thermal_gap 0.5)
			(thermal_bridge_width 0.5)
			(island_removal_mode 0)
		)
		(polygon
			(pts
				(xy 263.1059 -215.0872) (xy 263.1059 -211.074) (xy 265.7221 -211.074) (xy 265.7221 -215.0872)
			)
		)
	)
	(zone
		(net "GND")
		(layer "F.Cu")
		(hatch none 0.5)
		(connect_pads
			(clearance 0.5)
		)
		(min_thickness 0.25)
		(fill yes
			(thermal_gap 0.5)
			(thermal_bridge_width 0.5)
			(island_removal_mode 0)
		)
		(polygon
			(pts
				(xy 110.9726 -80.85963) (xy 103.47198 -69.308218)
				(arc
					(start 102.823772 -69.308218)
					(mid 101.274542 -72.044084)
					(end 98.263202 -72.947784)
				)
				(xy 98.263202 -75.66025) (xy 98.11766 -75.805792) (xy 98.11766 -78.777592)
				(arc
					(start 97.147126 -78.777592)
					(mid 97.25842 -79.438038)
					(end 97.26041 -80.10779)
				)
				(xy 110.681008 -83.044792) (xy 110.9726 -82.7532)
			)
		)
	)
	(zone
		(net "5V_PRE_7")
		(layer "F.Cu")
		(hatch none 0.5)
		(connect_pads
			(clearance 0.5)
		)
		(min_thickness 0.25)
		(fill yes
			(thermal_gap 0.5)
			(thermal_bridge_width 0.5)
			(island_removal_mode 0)
		)
		(polygon
			(pts
				(xy 360.988102 -289.984942) (xy 360.734102 -290.238942) (xy 360.734102 -292.778942) (xy 360.353102 -293.159942)
				(xy 357.813102 -293.159942) (xy 357.559102 -293.413942) (xy 357.559102 -293.794942) (xy 357.813102 -294.048942)
				(xy 361.115102 -294.048942) (xy 362.385102 -292.778942) (xy 362.385102 -290.238942) (xy 362.131102 -289.984942)
			)
		)
	)
	(zone
		(net "P3V3_STBY_A")
		(layer "F.Cu")
		(hatch none 0.5)
		(connect_pads
			(clearance 0.5)
		)
		(min_thickness 0.25)
		(fill yes
			(thermal_gap 0.5)
			(thermal_bridge_width 0.5)
			(island_removal_mode 0)
		)
		(polygon
			(pts
				(xy 78.99654 -27.023314) (xy 78.912212 -27.107642) (xy 78.912212 -28.697936) (xy 79.277464 -29.063188)
				(xy 82.452464 -29.063188) (xy 82.683096 -28.832556) (xy 82.683096 -27.102308) (xy 82.604102 -27.023314)
			)
		)
		(polygon
			(pts
				(xy 80.114648 -27.973274) (xy 79.911448 -27.973274) (xy 79.911448 -28.176474) (xy 80.114648 -28.176474)
			)
		)
		(polygon
			(pts
				(xy 79.251048 -27.973274) (xy 79.047848 -27.973274) (xy 79.047848 -28.176474) (xy 79.251048 -28.176474)
			)
		)
		(polygon
			(pts
				(xy 81.130648 -27.465274) (xy 80.927448 -27.465274) (xy 80.927448 -27.668474) (xy 81.130648 -27.668474)
			)
		)
		(polygon
			(pts
				(xy 80.521048 -27.465274) (xy 80.317848 -27.465274) (xy 80.317848 -27.668474) (xy 80.521048 -27.668474)
			)
		)
	)
	(zone
		(net "12V_PRE_33")
		(layer "F.Cu")
		(hatch none 0.5)
		(connect_pads
			(clearance 0.5)
		)
		(min_thickness 0.25)
		(fill yes
			(thermal_gap 0.5)
			(thermal_bridge_width 0.5)
			(island_removal_mode 0)
		)
		(polygon
			(pts
				(xy 425.91863 -68.314316) (xy 423.453052 -70.779894) (xy 420.913052 -70.779894) (xy 420.659052 -71.033894)
				(xy 420.659052 -71.414894) (xy 420.913052 -71.668894) (xy 427.611286 -71.668894) (xy 428.271686 -71.008494)
				(xy 428.271686 -68.434966) (xy 428.151036 -68.314316)
			)
		)
	)
	(zone
		(layer "F.Cu")
		(hatch none 0.5)
		(connect_pads
			(clearance 0)
		)
		(min_thickness 0.25)
		(keepout
			(tracks not_allowed)
			(vias allowed)
			(pads allowed)
			(copperpour not_allowed)
			(footprints allowed)
		)
		(placement
			(enabled no)
			(sheetname "")
		)
		(fill
			(thermal_gap 0.5)
			(thermal_bridge_width 0.5)
			(island_removal_mode 0)
		)
		(polygon
			(pts
				(arc
					(start 159.089852 -47.178722)
					(mid 158.708979 -46.797468)
					(end 158.327852 -47.178468)
				)
				(xy 158.327852 -47.527718)
				(arc
					(start 158.581852 -47.527718)
					(mid 158.617773 -47.512839)
					(end 158.632652 -47.476918)
				)
				(arc
					(start 158.632652 -47.433992)
					(mid 158.708852 -46.911824)
					(end 158.785052 -47.433992)
				)
				(xy 158.785052 -47.508414)
				(arc
					(start 158.782004 -47.511462)
					(mid 158.725473 -47.620539)
					(end 158.616396 -47.67707)
				)
				(xy 158.613348 -47.680118) (xy 158.327852 -47.680118) (xy 158.327852 -47.819818) (xy 158.613348 -47.819818)
				(arc
					(start 158.616396 -47.822866)
					(mid 158.725473 -47.879397)
					(end 158.782004 -47.988474)
				)
				(xy 158.785052 -47.991522)
				(arc
					(start 158.785052 -48.065944)
					(mid 158.708852 -48.588112)
					(end 158.632652 -48.065944)
				)
				(arc
					(start 158.632652 -48.023018)
					(mid 158.617773 -47.987097)
					(end 158.581852 -47.972218)
				)
				(xy 158.327852 -47.972218)
				(arc
					(start 158.327852 -48.321468)
					(mid 158.708852 -48.702468)
					(end 159.089852 -48.321468)
				)
			)
		)
	)
	(zone
		(layer "F.Cu")
		(hatch none 0.5)
		(connect_pads
			(clearance 0)
		)
		(min_thickness 0.25)
		(keepout
			(tracks not_allowed)
			(vias allowed)
			(pads allowed)
			(copperpour not_allowed)
			(footprints allowed)
		)
		(placement
			(enabled no)
			(sheetname "")
		)
		(fill
			(thermal_gap 0.5)
			(thermal_bridge_width 0.5)
			(island_removal_mode 0)
		)
		(polygon
			(pts
				(arc
					(start 284.299914 -414.219898)
					(mid 280.550112 -417.9697)
					(end 276.800056 -414.219898)
				)
				(arc
					(start 276.800056 -414.219898)
					(mid 280.550112 -410.469842)
					(end 284.299914 -414.219898)
				)
			)
		)
	)
	(zone
		(layer "F.Cu")
		(hatch none 0.5)
		(connect_pads
			(clearance 0)
		)
		(min_thickness 0.25)
		(keepout
			(tracks allowed)
			(vias allowed)
			(pads allowed)
			(copperpour allowed)
			(footprints allowed)
		)
		(placement
			(enabled no)
			(sheetname "")
		)
		(fill
			(thermal_gap 0.5)
			(thermal_bridge_width 0.5)
			(island_removal_mode 0)
		)
		(polygon
			(pts
				(xy 254.9398 14.732) (xy 254.9398 16.3068) (xy 254.1778 16.3068) (xy 254.1778 14.732)
			)
		)
	)
	(zone
		(layer "F.Cu")
		(hatch none 0.5)
		(connect_pads
			(clearance 0)
		)
		(min_thickness 0.25)
		(keepout
			(tracks not_allowed)
			(vias allowed)
			(pads allowed)
			(copperpour not_allowed)
			(footprints allowed)
		)
		(placement
			(enabled no)
			(sheetname "")
		)
		(fill
			(thermal_gap 0.5)
			(thermal_bridge_width 0.5)
			(island_removal_mode 0)
		)
		(polygon
			(pts
				(arc
					(start 190.639954 -47.178722)
					(mid 190.259081 -46.797468)
					(end 189.877954 -47.178468)
				)
				(xy 189.877954 -47.527718)
				(arc
					(start 190.131954 -47.527718)
					(mid 190.167875 -47.512839)
					(end 190.182754 -47.476918)
				)
				(arc
					(start 190.182754 -47.433992)
					(mid 190.258954 -46.911824)
					(end 190.335154 -47.433992)
				)
				(xy 190.335154 -47.508414)
				(arc
					(start 190.332106 -47.511462)
					(mid 190.275575 -47.620539)
					(end 190.166498 -47.67707)
				)
				(xy 190.16345 -47.680118) (xy 189.877954 -47.680118) (xy 189.877954 -47.819818) (xy 190.16345 -47.819818)
				(arc
					(start 190.166498 -47.822866)
					(mid 190.275575 -47.879397)
					(end 190.332106 -47.988474)
				)
				(xy 190.335154 -47.991522)
				(arc
					(start 190.335154 -48.065944)
					(mid 190.258954 -48.588112)
					(end 190.182754 -48.065944)
				)
				(arc
					(start 190.182754 -48.023018)
					(mid 190.167875 -47.987097)
					(end 190.131954 -47.972218)
				)
				(xy 189.877954 -47.972218)
				(arc
					(start 189.877954 -48.321468)
					(mid 190.258954 -48.702468)
					(end 190.639954 -48.321468)
				)
			)
		)
	)
	(zone
		(net "P12V_HDD18")
		(layer "F.Cu")
		(hatch none 0.5)
		(connect_pads
			(clearance 0.5)
		)
		(min_thickness 0.25)
		(fill yes
			(thermal_gap 0.5)
			(thermal_bridge_width 0.5)
			(island_removal_mode 0)
		)
		(polygon
			(pts
				(xy 334.645 -178.540918) (xy 334.391 -178.794918) (xy 334.391 -182.858918) (xy 333.932276 -183.317642)
				(xy 333.932276 -186.139836) (xy 333.098394 -186.973718) (xy 326.178418 -186.973718) (xy 326.009 -187.143136)
				(xy 326.009 -188.954918) (xy 326.263 -189.208918) (xy 330.2 -189.208918) (xy 330.708 -188.700918)
				(xy 338.455 -188.700918) (xy 339.344 -187.811918) (xy 339.344 -178.794918) (xy 339.09 -178.540918)
			)
		)
		(polygon
			(pts
				(xy 330.3524 -188.091318) (xy 330.1492 -188.091318) (xy 330.1492 -188.294518) (xy 330.3524 -188.294518)
			)
		)
		(polygon
			(pts
				(xy 329.4888 -188.091318) (xy 329.2856 -188.091318) (xy 329.2856 -188.294518) (xy 329.4888 -188.294518)
			)
		)
	)
	(zone
		(net "P12V_A")
		(layer "F.Cu")
		(hatch none 0.5)
		(connect_pads
			(clearance 0.5)
		)
		(min_thickness 0.25)
		(fill yes
			(thermal_gap 0.5)
			(thermal_bridge_width 0.5)
			(island_removal_mode 0)
		)
		(polygon
			(pts
				(xy 45.757846 -54.142894) (xy 44.741846 -55.158894) (xy 44.106846 -55.158894) (xy 43.725846 -55.539894)
				(xy 43.725846 -58.079894) (xy 43.979846 -58.333894) (xy 47.281846 -58.333894) (xy 47.535846 -58.079894)
				(xy 47.535846 -55.793894) (xy 46.900846 -55.158894) (xy 46.519846 -55.158894) (xy 46.265846 -54.904894)
				(xy 46.265846 -54.269894) (xy 46.138846 -54.142894)
			)
		)
		(polygon
			(pts
				(xy 45.732446 -54.727094) (xy 45.529246 -54.727094) (xy 45.529246 -54.930294) (xy 45.732446 -54.930294)
			)
		)
	)
	(zone
		(layer "F.Cu")
		(hatch none 0.5)
		(connect_pads
			(clearance 0)
		)
		(min_thickness 0.25)
		(keepout
			(tracks allowed)
			(vias allowed)
			(pads allowed)
			(copperpour allowed)
			(footprints not_allowed)
		)
		(placement
			(enabled no)
			(sheetname "")
		)
		(fill
			(thermal_gap 0.5)
			(thermal_bridge_width 0.5)
			(island_removal_mode 0)
		)
		(polygon
			(pts
				(xy 191.799972 -199.799956) (xy 198.399908 -199.799956) (xy 198.399908 -373.000016) (xy 191.799972 -373.000016)
			)
		)
	)
	(zone
		(net "P12V_HDD22")
		(layer "F.Cu")
		(hatch none 0.5)
		(connect_pads
			(clearance 0.5)
		)
		(min_thickness 0.25)
		(fill yes
			(thermal_gap 0.5)
			(thermal_bridge_width 0.5)
			(island_removal_mode 0)
		)
		(polygon
			(pts
				(xy 460.8449 -178.540918) (xy 460.5909 -178.794918) (xy 460.5909 -182.858918) (xy 460.132176 -183.317642)
				(xy 460.132176 -186.139836) (xy 459.298294 -186.973718) (xy 452.378318 -186.973718) (xy 452.2089 -187.143136)
				(xy 452.2089 -188.954918) (xy 452.4629 -189.208918) (xy 456.3999 -189.208918) (xy 456.9079 -188.700918)
				(xy 464.6549 -188.700918) (xy 465.5439 -187.811918) (xy 465.5439 -178.794918) (xy 465.2899 -178.540918)
			)
		)
		(polygon
			(pts
				(xy 456.582272 -188.136276) (xy 456.379072 -188.136276) (xy 456.379072 -188.339476) (xy 456.582272 -188.339476)
			)
		)
		(polygon
			(pts
				(xy 455.718672 -188.136276) (xy 455.515472 -188.136276) (xy 455.515472 -188.339476) (xy 455.718672 -188.339476)
			)
		)
	)
	(zone
		(layer "F.Cu")
		(hatch none 0.5)
		(connect_pads
			(clearance 0)
		)
		(min_thickness 0.25)
		(keepout
			(tracks not_allowed)
			(vias allowed)
			(pads allowed)
			(copperpour not_allowed)
			(footprints allowed)
		)
		(placement
			(enabled no)
			(sheetname "")
		)
		(fill
			(thermal_gap 0.5)
			(thermal_bridge_width 0.5)
			(island_removal_mode 0)
		)
		(polygon
			(pts
				(arc
					(start 165.450012 -269.999968)
					(mid 170.200066 -265.249914)
					(end 174.95012 -269.999968)
				)
				(arc
					(start 174.95012 -269.999968)
					(mid 170.200066 -274.750022)
					(end 165.450012 -269.999968)
				)
			)
		)
	)
	(zone
		(net "P12V_HDD11")
		(layer "F.Cu")
		(hatch none 0.5)
		(connect_pads
			(clearance 0.5)
		)
		(min_thickness 0.25)
		(fill yes
			(thermal_gap 0.5)
			(thermal_bridge_width 0.5)
			(island_removal_mode 0)
		)
		(polygon
			(pts
				(xy 467.893654 -288.520632) (xy 467.615524 -288.798762) (xy 467.615524 -291.760656) (xy 474.50248 -291.760656)
				(xy 475.293436 -292.551612) (xy 475.293436 -294.113204) (xy 474.555312 -294.851582) (xy 474.555312 -300.947328)
				(xy 477.816926 -304.208942) (xy 486.325926 -304.208942) (xy 486.452926 -304.081942) (xy 486.452926 -302.303942)
				(xy 486.325926 -302.176942) (xy 480.356926 -302.176942) (xy 479.721926 -301.541942) (xy 478.070926 -301.541942)
				(xy 477.48571 -300.956726) (xy 477.48571 -291.632132) (xy 475.972378 -290.1188) (xy 473.219018 -290.1188)
				(xy 471.62085 -288.520632)
			)
		)
		(polygon
			(pts
				(xy 479.874326 -303.218342) (xy 479.671126 -303.218342) (xy 479.671126 -303.421542) (xy 479.874326 -303.421542)
			)
		)
		(polygon
			(pts
				(xy 479.010726 -303.218342) (xy 478.807526 -303.218342) (xy 478.807526 -303.421542) (xy 479.010726 -303.421542)
			)
		)
	)
	(zone
		(net "P3V3_STBY_A")
		(layer "F.Cu")
		(hatch none 0.5)
		(connect_pads
			(clearance 0.5)
		)
		(min_thickness 0.25)
		(fill yes
			(thermal_gap 0.5)
			(thermal_bridge_width 0.5)
			(island_removal_mode 0)
		)
		(polygon
			(pts
				(xy 257.8862 -280.1874) (xy 257.885438 -280.188162) (xy 257.875532 -280.188162) (xy 257.488182 -280.575512)
				(xy 257.488182 -284.872684) (xy 256.445258 -285.915608) (xy 252.668278 -285.915608) (xy 252.172978 -286.410908)
				(xy 252.172978 -289.936936) (xy 252.277372 -290.04133) (xy 252.993652 -290.04133) (xy 253.073408 -289.961574)
				(xy 253.073408 -288.550096) (xy 253.46914 -288.154364) (xy 255.492758 -288.154364) (xy 255.906016 -288.567622)
				(xy 255.906016 -289.98291) (xy 255.96088 -290.037774) (xy 256.509266 -290.037774) (xy 256.610104 -289.936936)
				(xy 256.610104 -288.562288) (xy 257.03403 -288.138362) (xy 257.80111 -288.138362) (xy 258.18338 -288.520632)
				(xy 258.18338 -289.971988) (xy 258.25069 -290.039298) (xy 258.726432 -290.039298) (xy 258.818126 -289.947604)
				(xy 258.818126 -289.516058) (xy 259.163312 -289.170872) (xy 264.920476 -289.170872) (xy 265.855704 -288.235644)
				(xy 287.232598 -288.235644) (xy 287.473898 -287.994344) (xy 287.473898 -284.984698) (xy 287.16732 -284.67812)
				(xy 286.321754 -284.67812) (xy 286.189166 -284.810708) (xy 286.189166 -286.443928) (xy 285.96463 -286.668464)
				(xy 282.848304 -286.668464) (xy 282.640786 -286.460946) (xy 282.640786 -283.15285) (xy 283.909262 -281.884374)
				(xy 283.909262 -280.48331) (xy 283.735272 -280.30932) (xy 280.85034 -280.30932) (xy 280.70937 -280.45029)
				(xy 280.70937 -286.511746) (xy 280.463752 -286.757364) (xy 271.621758 -286.757364) (xy 271.209008 -286.344614)
				(xy 271.209008 -284.843982) (xy 271.441164 -284.611826) (xy 272.137632 -284.611826) (xy 272.311622 -284.437836)
				(xy 272.311622 -282.96235) (xy 272.923 -282.350972) (xy 272.923 -280.4414) (xy 272.8976 -280.416)
				(xy 269.494 -280.416) (xy 268.732 -281.178) (xy 268.732 -284.785308) (xy 268.097 -285.420308) (xy 263.8933 -285.420308)
				(xy 263.610598 -285.137606) (xy 263.610598 -284.686756) (xy 263.511538 -284.587696) (xy 262.876538 -284.587696)
				(xy 262.76173 -284.702504) (xy 262.76173 -287.105598) (xy 262.301736 -287.565592) (xy 259.403596 -287.565592)
				(xy 258.977384 -287.13938) (xy 258.977384 -282.822396) (xy 260.75767 -281.04211) (xy 260.75767 -280.2255)
				(xy 260.720332 -280.188162) (xy 260.706362 -280.188162) (xy 260.7056 -280.1874)
			)
		)
		(polygon
			(pts
				(xy 252.5522 -289.3822) (xy 252.349 -289.3822) (xy 252.349 -289.5854) (xy 252.5522 -289.5854)
			)
		)
		(polygon
			(pts
				(xy 287.0962 -285.1404) (xy 286.893 -285.1404) (xy 286.893 -285.3436) (xy 287.0962 -285.3436)
			)
		)
		(polygon
			(pts
				(xy 263.4996 -285.0388) (xy 263.2964 -285.0388) (xy 263.2964 -285.242) (xy 263.4996 -285.242)
			)
		)
		(polygon
			(pts
				(xy 272.20037 -283.921962) (xy 271.99717 -283.921962) (xy 271.99717 -284.125162) (xy 272.20037 -284.125162)
			)
		)
		(polygon
			(pts
				(xy 271.64157 -283.921962) (xy 271.43837 -283.921962) (xy 271.43837 -284.125162) (xy 271.64157 -284.125162)
			)
		)
		(polygon
			(pts
				(xy 270.9164 -281.2034) (xy 270.7132 -281.2034) (xy 270.7132 -281.4066) (xy 270.9164 -281.4066)
			)
		)
		(polygon
			(pts
				(xy 270.0528 -281.2034) (xy 269.8496 -281.2034) (xy 269.8496 -281.4066) (xy 270.0528 -281.4066)
			)
		)
		(polygon
			(pts
				(xy 281.7368 -281.178) (xy 281.5336 -281.178) (xy 281.5336 -281.3812) (xy 281.7368 -281.3812)
			)
		)
		(polygon
			(pts
				(xy 271.8562 -280.9748) (xy 271.653 -280.9748) (xy 271.653 -281.178) (xy 271.8562 -281.178)
			)
		)
		(polygon
			(pts
				(xy 271.2466 -280.9748) (xy 271.0434 -280.9748) (xy 271.0434 -281.178) (xy 271.2466 -281.178)
			)
		)
		(polygon
			(pts
				(xy 258.8514 -280.9494) (xy 258.6482 -280.9494) (xy 258.6482 -281.1526) (xy 258.8514 -281.1526)
			)
		)
		(polygon
			(pts
				(xy 257.9878 -280.9494) (xy 257.7846 -280.9494) (xy 257.7846 -281.1526) (xy 257.9878 -281.1526)
			)
		)
		(polygon
			(pts
				(xy 282.7528 -280.924) (xy 282.5496 -280.924) (xy 282.5496 -281.1272) (xy 282.7528 -281.1272)
			)
		)
		(polygon
			(pts
				(xy 282.1432 -280.924) (xy 281.94 -280.924) (xy 281.94 -281.1272) (xy 282.1432 -281.1272)
			)
		)
		(polygon
			(pts
				(xy 259.7912 -280.7208) (xy 259.588 -280.7208) (xy 259.588 -280.924) (xy 259.7912 -280.924)
			)
		)
		(polygon
			(pts
				(xy 259.1816 -280.7208) (xy 258.9784 -280.7208) (xy 258.9784 -280.924) (xy 259.1816 -280.924)
			)
		)
	)
	(zone
		(layer "F.Cu")
		(hatch none 0.5)
		(connect_pads
			(clearance 0)
		)
		(min_thickness 0.25)
		(keepout
			(tracks not_allowed)
			(vias allowed)
			(pads allowed)
			(copperpour not_allowed)
			(footprints allowed)
		)
		(placement
			(enabled no)
			(sheetname "")
		)
		(fill
			(thermal_gap 0.5)
			(thermal_bridge_width 0.5)
			(island_removal_mode 0)
		)
		(polygon
			(pts
				(arc
					(start 127.53975 -277.17877)
					(mid 127.158877 -276.797516)
					(end 126.77775 -277.178516)
				)
				(xy 126.77775 -277.527766)
				(arc
					(start 127.03175 -277.527766)
					(mid 127.067671 -277.512887)
					(end 127.08255 -277.476966)
				)
				(arc
					(start 127.08255 -277.43404)
					(mid 127.15875 -276.911872)
					(end 127.23495 -277.43404)
				)
				(xy 127.23495 -277.508462)
				(arc
					(start 127.231902 -277.51151)
					(mid 127.175371 -277.620587)
					(end 127.066294 -277.677118)
				)
				(xy 127.063246 -277.680166) (xy 126.77775 -277.680166) (xy 126.77775 -277.819866) (xy 127.063246 -277.819866)
				(arc
					(start 127.066294 -277.822914)
					(mid 127.175371 -277.879445)
					(end 127.231902 -277.988522)
				)
				(xy 127.23495 -277.99157)
				(arc
					(start 127.23495 -278.065992)
					(mid 127.15875 -278.58816)
					(end 127.08255 -278.065992)
				)
				(arc
					(start 127.08255 -278.023066)
					(mid 127.067671 -277.987145)
					(end 127.03175 -277.972266)
				)
				(xy 126.77775 -277.972266)
				(arc
					(start 126.77775 -278.321516)
					(mid 127.15875 -278.702516)
					(end 127.53975 -278.321516)
				)
			)
		)
	)
	(zone
		(net "P5V_HDD19")
		(layer "F.Cu")
		(hatch none 0.5)
		(connect_pads
			(clearance 0.5)
		)
		(min_thickness 0.25)
		(fill yes
			(thermal_gap 0.5)
			(thermal_bridge_width 0.5)
			(island_removal_mode 0)
		)
		(polygon
			(pts
				(xy 363.147102 -166.729918) (xy 362.893102 -166.983918) (xy 362.893102 -177.778918) (xy 361.242102 -179.429918)
				(xy 357.813102 -179.429918) (xy 357.559102 -179.683918) (xy 357.559102 -181.334918) (xy 357.813102 -181.588918)
				(xy 362.385102 -181.588918) (xy 363.020102 -180.953918) (xy 364.798102 -180.953918) (xy 365.306102 -180.445918)
				(xy 365.306102 -166.983918) (xy 365.052102 -166.729918)
			)
		)
		(polygon
			(pts
				(xy 361.902502 -180.598318) (xy 361.699302 -180.598318) (xy 361.699302 -180.801518) (xy 361.902502 -180.801518)
			)
		)
		(polygon
			(pts
				(xy 361.038902 -180.598318) (xy 360.835702 -180.598318) (xy 360.835702 -180.801518) (xy 361.038902 -180.801518)
			)
		)
	)
	(zone
		(net "GND")
		(layer "F.Cu")
		(hatch none 0.5)
		(connect_pads
			(clearance 0.5)
		)
		(min_thickness 0.25)
		(fill yes
			(thermal_gap 0.5)
			(thermal_bridge_width 0.5)
			(island_removal_mode 0)
		)
		(polygon
			(pts
				(arc
					(start 343.61374 -193.990214)
					(mid 344.052125 -195.21928)
					(end 344.0811 -196.523864)
				)
				(arc
					(start 344.0811 -196.523864)
					(mid 342.849937 -200.106785)
					(end 339.20557 -201.142092)
				)
				(arc
					(start 339.20557 -201.142092)
					(mid 340.140206 -202.555077)
					(end 340.842854 -204.09662)
				)
				(arc
					(start 341.864442 -203.075032)
					(mid 343.12851 -202.230409)
					(end 344.61958 -201.93381)
				)
				(arc
					(start 346.022676 -201.93381)
					(mid 347.513748 -202.230403)
					(end 348.777814 -203.075032)
				)
				(arc
					(start 349.739966 -204.037184)
					(mid 349.91673 -204.226095)
					(end 350.08058 -204.426312)
				)
				(xy 351.443798 -204.426312) (xy 351.443798 -214.37346) (xy 351.096834 -214.37346)
				(arc
					(start 351.096834 -222.031814)
					(mid 357.748399 -225.220784)
					(end 351.096834 -228.409754)
				)
				(arc
					(start 351.096834 -232.211372)
					(mid 351.94392 -232.409033)
					(end 352.730054 -232.781348)
				)
				(arc
					(start 352.730054 -232.781348)
					(mid 357.358103 -237.441617)
					(end 351.558352 -240.523776)
				)
				(arc
					(start 351.558352 -243.116608)
					(mid 354.124731 -246.762903)
					(end 351.833434 -250.588018)
				)
				(arc
					(start 351.833434 -250.588018)
					(mid 355.670381 -255.806683)
					(end 349.648526 -258.192524)
				)
				(arc
					(start 349.648526 -258.192524)
					(mid 350.859292 -261.985044)
					(end 348.271846 -265.010646)
				)
				(arc
					(start 348.271846 -265.010646)
					(mid 349.238475 -266.762579)
					(end 349.772732 -268.690852)
				)
				(arc
					(start 349.772732 -268.690852)
					(mid 350.856604 -268.344645)
					(end 351.993962 -268.312392)
				)
				(xy 351.993962 -260.928866) (xy 362.206286 -260.928866)
				(arc
					(start 362.206286 -263.517126)
					(mid 362.985721 -265.193799)
					(end 362.947204 -267.042392)
				)
				(xy 363.917738 -267.042392) (xy 363.917738 -267.225018)
				(arc
					(start 364.179104 -267.225018)
					(mid 367.834866 -265.763629)
					(end 371.0305 -268.063218)
				)
				(xy 371.429026 -268.063218)
				(arc
					(start 371.429026 -270.299942)
					(mid 371.474868 -270.755242)
					(end 371.470174 -271.212818)
				)
				(xy 372.572026 -271.212818) (xy 372.572026 -273.473418) (xy 374.324626 -273.473418)
				(arc
					(start 374.324626 -276.947122)
					(mid 374.566656 -277.304683)
					(end 374.770142 -277.6855)
				)
				(arc
					(start 374.770142 -277.6855)
					(mid 375.282303 -278.368307)
					(end 375.633488 -279.146254)
				)
				(arc
					(start 375.633488 -279.146254)
					(mid 377.99126 -278.822838)
					(end 380.13005 -279.866598)
				)
				(xy 380.812294 -279.866598)
				(arc
					(start 380.812294 -278.895556)
					(mid 379.498515 -277.434288)
					(end 379.023626 -275.527516)
				)
				(arc
					(start 379.023626 -272.352516)
					(mid 380.379897 -269.321273)
					(end 383.54381 -268.312392)
				)
				(xy 383.54381 -260.928866) (xy 393.756134 -260.928866)
				(arc
					(start 393.756134 -263.517126)
					(mid 394.535569 -265.193799)
					(end 394.497052 -267.042392)
				)
				(xy 395.467586 -267.042392) (xy 395.467586 -267.225018)
				(arc
					(start 395.667738 -267.225018)
					(mid 399.377939 -265.686582)
					(end 402.615908 -268.063218)
				)
				(xy 402.978874 -268.063218)
				(arc
					(start 402.978874 -270.528542)
					(mid 403.01891 -270.882314)
					(end 403.028404 -271.238218)
				)
				(xy 404.121874 -271.238218) (xy 404.121874 -271.873218) (xy 408.185874 -271.873218)
				(arc
					(start 408.185874 -274.148042)
					(mid 409.001192 -274.529837)
					(end 409.70708 -275.088604)
				)
				(arc
					(start 410.599128 -275.980652)
					(mid 410.580106 -275.754439)
					(end 410.573728 -275.527516)
				)
				(arc
					(start 410.573728 -272.352516)
					(mid 411.929999 -269.321273)
					(end 415.093912 -268.312392)
				)
				(arc
					(start 415.093912 -264.308336)
					(mid 410.797068 -266.394963)
					(end 407.452068 -262.984996)
				)
				(arc
					(start 407.452068 -262.984996)
					(mid 404.53317 -262.174066)
					(end 402.972778 -259.577332)
				)
				(arc
					(start 402.972778 -259.577332)
					(mid 397.702021 -257.505583)
					(end 399.553938 -252.15342)
				)
				(arc
					(start 399.553938 -252.15342)
					(mid 395.96631 -249.041168)
					(end 397.73987 -244.635274)
				)
				(xy 397.73987 -239.390174)
				(arc
					(start 399.226278 -239.390174)
					(mid 399.577356 -238.086857)
					(end 400.352006 -236.981492)
				)
				(arc
					(start 400.654012 -236.679486)
					(mid 401.043689 -236.018616)
					(end 401.5486 -235.440982)
				)
				(arc
					(start 401.5486 -235.440982)
					(mid 399.409442 -233.236471)
					(end 399.407888 -230.16464)
				)
				(arc
					(start 399.407888 -230.16464)
					(mid 399.244555 -229.957098)
					(end 399.09496 -229.739444)
				)
				(arc
					(start 399.09496 -229.739444)
					(mid 395.701541 -228.194168)
					(end 394.972032 -224.537524)
				)
				(arc
					(start 394.972032 -224.537524)
					(mid 388.094801 -223.065892)
					(end 383.574544 -217.678)
				)
				(xy 382.646682 -217.678)
				(arc
					(start 382.646682 -217.95232)
					(mid 382.89127 -219.3544)
					(end 382.646682 -220.75648)
				)
				(arc
					(start 382.646682 -232.234232)
					(mid 383.275617 -232.306037)
					(end 383.885948 -232.474008)
				)
				(arc
					(start 383.885948 -232.474008)
					(mid 390.425479 -235.078151)
					(end 384.997452 -239.559592)
				)
				(arc
					(start 384.997452 -239.559592)
					(mid 384.104274 -240.083337)
					(end 383.1082 -240.366042)
				)
				(arc
					(start 383.1082 -242.021868)
					(mid 385.698722 -247.334736)
					(end 380.276354 -249.687842)
				)
				(arc
					(start 380.276354 -249.687842)
					(mid 381.015224 -252.345145)
					(end 379.899164 -254.86741)
				)
				(arc
					(start 379.899164 -254.86741)
					(mid 379.447123 -255.536306)
					(end 378.872496 -256.103374)
				)
				(arc
					(start 378.872496 -256.103374)
					(mid 379.474462 -257.570315)
					(end 379.473206 -259.155946)
				)
				(arc
					(start 379.473206 -259.155946)
					(mid 377.300922 -265.714947)
					(end 372.296436 -260.951218)
				)
				(arc
					(start 372.296436 -260.951218)
					(mid 371.605906 -259.726141)
					(end 371.371114 -258.33959)
				)
				(arc
					(start 371.371114 -258.33959)
					(mid 364.716958 -254.557413)
					(end 372.2116 -253.003812)
				)
				(arc
					(start 372.2116 -253.003812)
					(mid 372.449444 -251.545826)
					(end 373.189754 -250.26747)
				)
				(arc
					(start 373.189754 -250.26747)
					(mid 372.989774 -250.214075)
					(end 372.792752 -250.15063)
				)
				(arc
					(start 372.792752 -250.15063)
					(mid 372.102721 -250.269003)
					(end 371.40261 -250.267978)
				)
				(arc
					(start 371.40261 -250.267978)
					(mid 369.598393 -250.233095)
					(end 367.984786 -249.425206)
				)
				(xy 366.499394 -249.425206) (xy 366.499394 -248.124218) (xy 366.189768 -248.124218) (xy 366.189768 -239.35817)
				(xy 367.660682 -239.35817)
				(arc
					(start 367.660682 -238.943134)
					(mid 367.661765 -238.851542)
					(end 367.665 -238.76)
				)
				(arc
					(start 367.665 -235.22813)
					(mid 364.622775 -233.725527)
					(end 363.761528 -230.443532)
				)
				(arc
					(start 363.761528 -230.443532)
					(mid 362.391218 -229.072416)
					(end 361.806236 -227.224336)
				)
				(arc
					(start 361.806236 -227.224336)
					(mid 360.748398 -222.73837)
					(end 364.538514 -220.115638)
				)
				(arc
					(start 364.538514 -220.115638)
					(mid 366.763013 -215.054569)
					(end 371.951758 -213.146894)
				)
				(arc
					(start 371.951758 -207.107282)
					(mid 372.248351 -205.61621)
					(end 373.09298 -204.352144)
				)
				(arc
					(start 374.079262 -203.365862)
					(mid 374.430974 -203.054253)
					(end 374.81764 -202.78725)
				)
				(arc
					(start 374.81764 -202.78725)
					(mid 373.754412 -201.188918)
					(end 373.53748 -199.281542)
				)
				(arc
					(start 373.53748 -199.281542)
					(mid 370.559687 -197.710042)
					(end 369.769898 -194.437)
				)
				(arc
					(start 367.438178 -194.437)
					(mid 366.305523 -195.008166)
					(end 365.052356 -195.204842)
				)
				(xy 362.206286 -195.204842) (xy 362.206286 -199.891142) (xy 351.993962 -199.891142)
				(arc
					(start 351.993962 -197.381622)
					(mid 351.733678 -197.027533)
					(end 351.512886 -196.647562)
				)
				(arc
					(start 351.512886 -196.647562)
					(mid 347.596441 -197.408255)
					(end 344.895424 -194.472052)
				)
				(arc
					(start 344.895424 -194.472052)
					(mid 344.234281 -194.285135)
					(end 343.61374 -193.990214)
				)
			)
		)
	)
	(zone
		(layer "F.Cu")
		(hatch none 0.5)
		(connect_pads
			(clearance 0)
		)
		(min_thickness 0.25)
		(keepout
			(tracks allowed)
			(vias allowed)
			(pads allowed)
			(copperpour allowed)
			(footprints not_allowed)
		)
		(placement
			(enabled no)
			(sheetname "")
		)
		(fill
			(thermal_gap 0.5)
			(thermal_bridge_width 0.5)
			(island_removal_mode 0)
		)
		(polygon
			(pts
				(arc
					(start 165.450012 -269.999968)
					(mid 170.200066 -265.249914)
					(end 174.95012 -269.999968)
				)
				(arc
					(start 174.95012 -269.999968)
					(mid 170.200066 -274.750022)
					(end 165.450012 -269.999968)
				)
			)
		)
	)
	(zone
		(net "P5V_HDD21")
		(layer "F.Cu")
		(hatch none 0.5)
		(connect_pads
			(clearance 0.5)
		)
		(min_thickness 0.25)
		(fill yes
			(thermal_gap 0.5)
			(thermal_bridge_width 0.5)
			(island_removal_mode 0)
		)
		(polygon
			(pts
				(xy 426.247052 -166.729918) (xy 425.993052 -166.983918) (xy 425.993052 -177.778918) (xy 424.342052 -179.429918)
				(xy 420.913052 -179.429918) (xy 420.659052 -179.683918) (xy 420.659052 -181.334918) (xy 420.913052 -181.588918)
				(xy 425.485052 -181.588918) (xy 426.120052 -180.953918) (xy 427.898052 -180.953918) (xy 428.406052 -180.445918)
				(xy 428.406052 -166.983918) (xy 428.152052 -166.729918)
			)
		)
		(polygon
			(pts
				(xy 425.002452 -180.598318) (xy 424.799252 -180.598318) (xy 424.799252 -180.801518) (xy 425.002452 -180.801518)
			)
		)
		(polygon
			(pts
				(xy 424.138852 -180.598318) (xy 423.935652 -180.598318) (xy 423.935652 -180.801518) (xy 424.138852 -180.801518)
			)
		)
	)
	(zone
		(net "P12V_HDD0")
		(layer "F.Cu")
		(hatch none 0.5)
		(connect_pads
			(clearance 0.5)
		)
		(min_thickness 0.25)
		(fill yes
			(thermal_gap 0.5)
			(thermal_bridge_width 0.5)
			(island_removal_mode 0)
		)
		(polygon
			(pts
				(xy 12.302998 -291.254942) (xy 12.048998 -291.508942) (xy 12.048998 -293.159942) (xy 12.302998 -293.413942)
				(xy 14.461998 -293.413942) (xy 14.969998 -293.921942) (xy 14.969998 -296.461942) (xy 22.716998 -304.208942)
				(xy 31.225998 -304.208942) (xy 31.352998 -304.081942) (xy 31.352998 -302.303942) (xy 31.225998 -302.176942)
				(xy 25.256998 -302.176942) (xy 24.621998 -301.541942) (xy 22.970998 -301.541942) (xy 18.652998 -297.223942)
				(xy 18.652998 -293.667942) (xy 17.509998 -292.524942) (xy 17.509998 -291.508942) (xy 17.255998 -291.254942)
			)
		)
		(polygon
			(pts
				(xy 24.774398 -303.218342) (xy 24.571198 -303.218342) (xy 24.571198 -303.421542) (xy 24.774398 -303.421542)
			)
		)
		(polygon
			(pts
				(xy 23.910798 -303.218342) (xy 23.707598 -303.218342) (xy 23.707598 -303.421542) (xy 23.910798 -303.421542)
			)
		)
	)
	(zone
		(layer "F.Cu")
		(hatch none 0.5)
		(connect_pads
			(clearance 0)
		)
		(min_thickness 0.25)
		(keepout
			(tracks not_allowed)
			(vias allowed)
			(pads allowed)
			(copperpour not_allowed)
			(footprints allowed)
		)
		(placement
			(enabled no)
			(sheetname "")
		)
		(fill
			(thermal_gap 0.5)
			(thermal_bridge_width 0.5)
			(island_removal_mode 0)
		)
		(polygon
			(pts
				(arc
					(start 271.970754 -335.721452)
					(mid 271.58696 -336.104865)
					(end 271.9705 -336.488532)
				)
				(arc
					(start 273.1135 -336.488532)
					(mid 273.49704 -336.104992)
					(end 273.1135 -335.721452)
				)
				(xy 272.76425 -335.721452)
				(arc
					(start 272.76425 -335.977992)
					(mid 272.779129 -336.013913)
					(end 272.81505 -336.028792)
				)
				(arc
					(start 272.857976 -336.028792)
					(mid 273.380144 -336.104992)
					(end 272.857976 -336.181192)
				)
				(xy 272.783554 -336.181192)
				(arc
					(start 272.780506 -336.178144)
					(mid 272.671429 -336.121613)
					(end 272.614898 -336.012536)
				)
				(xy 272.61185 -336.009488) (xy 272.61185 -335.721452) (xy 272.47215 -335.721452) (xy 272.47215 -336.009488)
				(arc
					(start 272.469102 -336.012536)
					(mid 272.412571 -336.121613)
					(end 272.303494 -336.178144)
				)
				(xy 272.300446 -336.181192)
				(arc
					(start 272.226024 -336.181192)
					(mid 271.703856 -336.104992)
					(end 272.226024 -336.028792)
				)
				(arc
					(start 272.26895 -336.028792)
					(mid 272.304871 -336.013913)
					(end 272.31975 -335.977992)
				)
				(xy 272.31975 -335.721452)
			)
		)
	)
	(zone
		(layer "F.Cu")
		(hatch none 0.5)
		(connect_pads
			(clearance 0)
		)
		(min_thickness 0.25)
		(keepout
			(tracks allowed)
			(vias allowed)
			(pads allowed)
			(copperpour allowed)
			(footprints not_allowed)
		)
		(placement
			(enabled no)
			(sheetname "")
		)
		(fill
			(thermal_gap 0.5)
			(thermal_bridge_width 0.5)
			(island_removal_mode 0)
		)
		(polygon
			(pts
				(xy 267.670026 -25.100026) (xy 267.670026 -34.500058) (xy 259.970016 -34.500058) (xy 259.970016 -25.100026)
			)
		)
	)
	(zone
		(layer "F.Cu")
		(hatch none 0.5)
		(connect_pads
			(clearance 0)
		)
		(min_thickness 0.25)
		(keepout
			(tracks allowed)
			(vias allowed)
			(pads allowed)
			(copperpour allowed)
			(footprints allowed)
		)
		(placement
			(enabled no)
			(sheetname "")
		)
		(fill
			(thermal_gap 0.5)
			(thermal_bridge_width 0.5)
			(island_removal_mode 0)
		)
		(polygon
			(pts
				(xy 283.9974 -284.226) (xy 283.9974 -280.8986) (xy 286.5628 -280.8986) (xy 286.5628 -284.226)
			)
		)
	)
	(zone
		(layer "F.Cu")
		(hatch none 0.5)
		(connect_pads
			(clearance 0)
		)
		(min_thickness 0.25)
		(keepout
			(tracks allowed)
			(vias allowed)
			(pads allowed)
			(copperpour allowed)
			(footprints allowed)
		)
		(placement
			(enabled no)
			(sheetname "")
		)
		(fill
			(thermal_gap 0.5)
			(thermal_bridge_width 0.5)
			(island_removal_mode 0)
		)
		(polygon
			(pts
				(xy 249.894344 -237.173516) (xy 249.894344 -233.939588) (xy 248.852944 -233.939588) (xy 248.852944 -237.173516)
			)
		)
	)
	(zone
		(layer "F.Cu")
		(hatch none 0.5)
		(connect_pads
			(clearance 0)
		)
		(min_thickness 0.25)
		(keepout
			(tracks not_allowed)
			(vias allowed)
			(pads allowed)
			(copperpour not_allowed)
			(footprints allowed)
		)
		(placement
			(enabled no)
			(sheetname "")
		)
		(fill
			(thermal_gap 0.5)
			(thermal_bridge_width 0.5)
			(island_removal_mode 0)
		)
		(polygon
			(pts
				(arc
					(start 271.970754 -333.921354)
					(mid 271.58696 -334.304767)
					(end 271.9705 -334.688434)
				)
				(arc
					(start 273.1135 -334.688434)
					(mid 273.49704 -334.304894)
					(end 273.1135 -333.921354)
				)
				(xy 272.76425 -333.921354)
				(arc
					(start 272.76425 -334.177894)
					(mid 272.779129 -334.213815)
					(end 272.81505 -334.228694)
				)
				(arc
					(start 272.857976 -334.228694)
					(mid 273.380144 -334.304894)
					(end 272.857976 -334.381094)
				)
				(xy 272.783554 -334.381094)
				(arc
					(start 272.780506 -334.378046)
					(mid 272.671429 -334.321515)
					(end 272.614898 -334.212438)
				)
				(xy 272.61185 -334.20939) (xy 272.61185 -333.921354) (xy 272.47215 -333.921354) (xy 272.47215 -334.20939)
				(arc
					(start 272.469102 -334.212438)
					(mid 272.412571 -334.321515)
					(end 272.303494 -334.378046)
				)
				(xy 272.300446 -334.381094)
				(arc
					(start 272.226024 -334.381094)
					(mid 271.703856 -334.304894)
					(end 272.226024 -334.228694)
				)
				(arc
					(start 272.26895 -334.228694)
					(mid 272.304871 -334.213815)
					(end 272.31975 -334.177894)
				)
				(xy 272.31975 -333.921354)
			)
		)
	)
	(zone
		(net "P12V_A")
		(layer "F.Cu")
		(hatch none 0.5)
		(connect_pads
			(clearance 0.5)
		)
		(min_thickness 0.25)
		(fill yes
			(thermal_gap 0.5)
			(thermal_bridge_width 0.5)
			(island_removal_mode 0)
		)
		(polygon
			(pts
				(xy 140.407898 -54.142894) (xy 139.391898 -55.158894) (xy 138.756898 -55.158894) (xy 138.375898 -55.539894)
				(xy 138.375898 -58.079894) (xy 138.629898 -58.333894) (xy 141.931898 -58.333894) (xy 142.185898 -58.079894)
				(xy 142.185898 -56.174894) (xy 140.915898 -54.904894) (xy 140.915898 -54.269894) (xy 140.788898 -54.142894)
			)
		)
		(polygon
			(pts
				(xy 140.382498 -54.727094) (xy 140.179298 -54.727094) (xy 140.179298 -54.930294) (xy 140.382498 -54.930294)
			)
		)
	)
	(zone
		(layer "F.Cu")
		(hatch none 0.5)
		(connect_pads
			(clearance 0)
		)
		(min_thickness 0.25)
		(keepout
			(tracks allowed)
			(vias allowed)
			(pads allowed)
			(copperpour allowed)
			(footprints not_allowed)
		)
		(placement
			(enabled no)
			(sheetname "")
		)
		(fill
			(thermal_gap 0.5)
			(thermal_bridge_width 0.5)
			(island_removal_mode 0)
		)
		(polygon
			(pts
				(arc
					(start 343.250012 -164.200078)
					(mid 347.000068 -160.450022)
					(end 350.750124 -164.200078)
				)
				(arc
					(start 350.750124 -164.200078)
					(mid 347.000068 -167.950134)
					(end 343.250012 -164.200078)
				)
			)
		)
	)
	(zone
		(layer "F.Cu")
		(hatch none 0.5)
		(connect_pads
			(clearance 0)
		)
		(min_thickness 0.25)
		(keepout
			(tracks allowed)
			(vias allowed)
			(pads allowed)
			(copperpour allowed)
			(footprints not_allowed)
		)
		(placement
			(enabled no)
			(sheetname "")
		)
		(fill
			(thermal_gap 0.5)
			(thermal_bridge_width 0.5)
			(island_removal_mode 0)
		)
		(polygon
			(pts
				(arc
					(start 26.325068 -207.79994)
					(mid 33.325054 -200.799954)
					(end 40.32504 -207.79994)
				)
				(arc
					(start 40.32504 -213.799928)
					(mid 33.325054 -220.799914)
					(end 26.325068 -213.799928)
				)
			)
		)
	)
	(zone
		(net "GND")
		(layer "F.Cu")
		(hatch none 0.5)
		(connect_pads
			(clearance 0.5)
		)
		(min_thickness 0.25)
		(fill yes
			(thermal_gap 0.5)
			(thermal_bridge_width 0.5)
			(island_removal_mode 0)
		)
		(polygon
			(pts
				(xy 406.254204 -184.193942) (xy 406.254204 -189.390274) (xy 403.133306 -192.511172) (xy 401.111974 -192.511172)
				(xy 401.111974 -194.430142)
				(arc
					(start 398.997424 -194.430142)
					(mid 397.860764 -195.00635)
					(end 396.60195 -195.204842)
				)
				(arc
					(start 394.601446 -195.204842)
					(mid 394.395547 -196.130091)
					(end 393.982194 -196.983096)
				)
				(arc
					(start 393.982194 -196.983096)
					(mid 400.037641 -199.047026)
					(end 403.869144 -204.17028)
				)
				(xy 406.105614 -201.93381) (xy 410.736542 -201.93381)
				(arc
					(start 412.889192 -204.08646)
					(mid 414.437334 -201.815724)
					(end 416.399218 -199.891142)
				)
				(xy 415.093912 -199.891142) (xy 415.093912 -189.678818)
				(arc
					(start 416.241738 -189.678818)
					(mid 416.519304 -189.224386)
					(end 416.848798 -188.806074)
				)
				(xy 416.848798 -187.601352)
				(arc
					(start 414.558988 -187.601352)
					(mid 412.061218 -187.690742)
					(end 409.951428 -186.350656)
				)
				(arc
					(start 409.951428 -186.350656)
					(mid 408.801514 -185.501388)
					(end 408.01417 -184.308242)
				)
				(xy 407.576528 -184.308242) (xy 407.576528 -184.193942)
			)
		)
	)
	(zone
		(net "5V_PRE_15")
		(layer "F.Cu")
		(hatch none 0.5)
		(connect_pads
			(clearance 0.5)
		)
		(min_thickness 0.25)
		(fill yes
			(thermal_gap 0.5)
			(thermal_bridge_width 0.5)
			(island_removal_mode 0)
		)
		(polygon
			(pts
				(xy 117.595396 -175.006) (xy 117.493796 -175.1076) (xy 117.493796 -176.508918) (xy 117.620796 -176.635918)
				(xy 118.890796 -176.635918) (xy 121.430796 -179.175918) (xy 125.875796 -179.175918) (xy 126.002796 -179.048918)
				(xy 126.002796 -178.286918) (xy 125.875796 -178.159918) (xy 122.6566 -178.159918) (xy 119.502682 -175.006)
			)
		)
	)
	(zone
		(net "P12V_HDD31")
		(layer "F.Cu")
		(hatch none 0.5)
		(connect_pads
			(clearance 0.5)
		)
		(min_thickness 0.25)
		(fill yes
			(thermal_gap 0.5)
			(thermal_bridge_width 0.5)
			(island_removal_mode 0)
		)
		(polygon
			(pts
				(xy 366.195102 -63.540894) (xy 365.941102 -63.794894) (xy 365.941102 -67.858894) (xy 365.482378 -68.317618)
				(xy 365.482378 -71.139812) (xy 364.648496 -71.973694) (xy 357.72852 -71.973694) (xy 357.559102 -72.143112)
				(xy 357.559102 -73.954894) (xy 357.813102 -74.208894) (xy 361.750102 -74.208894) (xy 362.258102 -73.700894)
				(xy 370.005102 -73.700894) (xy 370.894102 -72.811894) (xy 370.894102 -63.794894) (xy 370.640102 -63.540894)
			)
		)
		(polygon
			(pts
				(xy 361.902502 -73.091294) (xy 361.699302 -73.091294) (xy 361.699302 -73.294494) (xy 361.902502 -73.294494)
			)
		)
		(polygon
			(pts
				(xy 361.038902 -73.091294) (xy 360.835702 -73.091294) (xy 360.835702 -73.294494) (xy 361.038902 -73.294494)
			)
		)
	)
	(zone
		(net "P12V_A")
		(layer "F.Cu")
		(hatch none 0.5)
		(connect_pads
			(clearance 0.5)
		)
		(min_thickness 0.25)
		(fill yes
			(thermal_gap 0.5)
			(thermal_bridge_width 0.5)
			(island_removal_mode 0)
		)
		(polygon
			(pts
				(xy 397.74495 -171.428918) (xy 397.23695 -171.936918) (xy 397.23695 -175.365918) (xy 397.49095 -175.619918)
				(xy 400.79295 -175.619918) (xy 401.04695 -175.365918) (xy 401.04695 -173.333918) (xy 401.17395 -173.206918)
				(xy 401.55495 -173.206918) (xy 401.68195 -173.079918) (xy 401.68195 -171.555918) (xy 401.55495 -171.428918)
			)
		)
		(polygon
			(pts
				(xy 401.14855 -172.444918) (xy 400.94535 -172.444918) (xy 400.94535 -172.648118) (xy 401.14855 -172.648118)
			)
		)
		(polygon
			(pts
				(xy 401.19935 -171.987718) (xy 400.99615 -171.987718) (xy 400.99615 -172.190918) (xy 401.19935 -172.190918)
			)
		)
	)
	(zone
		(net "12V_PRE_4")
		(layer "F.Cu")
		(hatch none 0.5)
		(connect_pads
			(clearance 0.5)
		)
		(min_thickness 0.25)
		(fill yes
			(thermal_gap 0.5)
			(thermal_bridge_width 0.5)
			(island_removal_mode 0)
		)
		(polygon
			(pts
				(xy 145.868898 -293.794942) (xy 145.741898 -293.921942) (xy 145.741898 -295.445942) (xy 147.138898 -296.842942)
				(xy 148.535898 -296.842942) (xy 153.488898 -301.795942) (xy 157.425898 -301.795942) (xy 157.552898 -301.668942)
				(xy 157.552898 -300.906942) (xy 157.425898 -300.779942) (xy 154.123898 -300.779942) (xy 147.138898 -293.794942)
			)
		)
	)
	(zone
		(net "P5V_A_3")
		(layer "F.Cu")
		(hatch none 0.5)
		(connect_pads
			(clearance 0.5)
		)
		(min_thickness 0.25)
		(fill yes
			(thermal_gap 0.5)
			(thermal_bridge_width 0.5)
			(island_removal_mode 0)
		)
		(polygon
			(pts
				(xy 393.083542 -278.80945) (xy 392.829542 -279.06345) (xy 392.829542 -281.34945) (xy 393.083542 -281.60345)
				(xy 397.4592 -281.60345) (xy 397.665448 -281.397202) (xy 397.665448 -278.965152) (xy 397.51 -278.80945)
			)
		)
	)
	(zone
		(net "5V_PRE_35")
		(layer "F.Cu")
		(hatch none 0.5)
		(connect_pads
			(clearance 0.5)
		)
		(min_thickness 0.25)
		(fill yes
			(thermal_gap 0.5)
			(thermal_bridge_width 0.5)
			(island_removal_mode 0)
		)
		(polygon
			(pts
				(xy 477.969326 -60.071) (xy 477.943926 -60.0964) (xy 477.943926 -61.508894) (xy 478.070926 -61.635894)
				(xy 479.340926 -61.635894) (xy 481.880926 -64.175894) (xy 486.325926 -64.175894) (xy 486.452926 -64.048894)
				(xy 486.452926 -63.286894) (xy 486.325926 -63.159894) (xy 482.742494 -63.159894) (xy 479.6536 -60.071)
			)
		)
	)
	(zone
		(net "P12V_A")
		(layer "F.Cu")
		(hatch none 0.5)
		(connect_pads
			(clearance 0.5)
		)
		(min_thickness 0.25)
		(fill yes
			(thermal_gap 0.5)
			(thermal_bridge_width 0.5)
			(island_removal_mode 0)
		)
		(polygon
			(pts
				(xy 45.160692 -169.105072) (xy 43.725846 -170.539918) (xy 43.725846 -173.079918) (xy 43.979846 -173.333918)
				(xy 47.641764 -173.333918) (xy 47.700946 -173.274736) (xy 47.700946 -169.200322) (xy 47.605696 -169.105072)
			)
		)
		(polygon
			(pts
				(xy 47.192946 -170.812206) (xy 46.989746 -170.812206) (xy 46.989746 -171.015406) (xy 47.192946 -171.015406)
			)
		)
		(polygon
			(pts
				(xy 47.192946 -170.202606) (xy 46.989746 -170.202606) (xy 46.989746 -170.405806) (xy 47.192946 -170.405806)
			)
		)
		(polygon
			(pts
				(xy 47.243746 -169.745406) (xy 47.040546 -169.745406) (xy 47.040546 -169.948606) (xy 47.243746 -169.948606)
			)
		)
	)
	(zone
		(layer "F.Cu")
		(hatch none 0.5)
		(connect_pads
			(clearance 0)
		)
		(min_thickness 0.25)
		(keepout
			(tracks not_allowed)
			(vias allowed)
			(pads allowed)
			(copperpour not_allowed)
			(footprints allowed)
		)
		(placement
			(enabled no)
			(sheetname "")
		)
		(fill
			(thermal_gap 0.5)
			(thermal_bridge_width 0.5)
			(island_removal_mode 0)
		)
		(polygon
			(pts
				(arc
					(start 328.933048 -9.199626)
					(mid 318.41694 -9.199626)
					(end 328.933048 -9.199626)
				)
			)
		)
	)
	(zone
		(layer "F.Cu")
		(hatch none 0.5)
		(connect_pads
			(clearance 0)
		)
		(min_thickness 0.25)
		(keepout
			(tracks allowed)
			(vias allowed)
			(pads allowed)
			(copperpour allowed)
			(footprints not_allowed)
		)
		(placement
			(enabled no)
			(sheetname "")
		)
		(fill
			(thermal_gap 0.5)
			(thermal_bridge_width 0.5)
			(island_removal_mode 0)
		)
		(polygon
			(pts
				(xy 256.70002 -263.19988) (xy 231.70007 -263.19988) (xy 231.70007 -289.200082) (xy 256.70002 -289.200082)
			)
		)
	)
	(zone
		(net "5V_PRE_11")
		(layer "F.Cu")
		(hatch none 0.5)
		(connect_pads
			(clearance 0.5)
		)
		(min_thickness 0.25)
		(fill yes
			(thermal_gap 0.5)
			(thermal_bridge_width 0.5)
			(island_removal_mode 0)
		)
		(polygon
			(pts
				(xy 478.191576 -286.72409) (xy 477.94545 -286.970216) (xy 477.94545 -287.99663) (xy 478.10039 -288.15157)
				(xy 479.77425 -288.15157) (xy 480.3394 -288.71672) (xy 480.3394 -291.2872) (xy 483.228142 -294.175942)
				(xy 486.325926 -294.175942) (xy 486.452926 -294.048942) (xy 486.452926 -293.286942) (xy 486.325926 -293.159942)
				(xy 483.710742 -293.159942) (xy 482.2698 -291.719) (xy 482.2698 -289.6362) (xy 482.249988 -289.616388)
				(xy 482.249988 -288.600896) (xy 480.373182 -286.72409)
			)
		)
	)
	(zone
		(net "12V_PRE_31")
		(layer "F.Cu")
		(hatch none 0.5)
		(connect_pads
			(clearance 0.5)
		)
		(min_thickness 0.25)
		(fill yes
			(thermal_gap 0.5)
			(thermal_bridge_width 0.5)
			(island_removal_mode 0)
		)
		(polygon
			(pts
				(xy 362.81868 -68.314316) (xy 360.353102 -70.779894) (xy 357.813102 -70.779894) (xy 357.559102 -71.033894)
				(xy 357.559102 -71.414894) (xy 357.813102 -71.668894) (xy 364.511336 -71.668894) (xy 365.171736 -71.008494)
				(xy 365.171736 -68.434966) (xy 365.051086 -68.314316)
			)
		)
	)
	(zone
		(layer "F.Cu")
		(hatch none 0.5)
		(connect_pads
			(clearance 0)
		)
		(min_thickness 0.25)
		(keepout
			(tracks not_allowed)
			(vias allowed)
			(pads allowed)
			(copperpour not_allowed)
			(footprints allowed)
		)
		(placement
			(enabled no)
			(sheetname "")
		)
		(fill
			(thermal_gap 0.5)
			(thermal_bridge_width 0.5)
			(island_removal_mode 0)
		)
		(polygon
			(pts
				(arc
					(start 238.374936 -17.84985)
					(mid 238.699802 -16.875252)
					(end 237.725204 -16.550386)
				)
				(xy 237.723934 -16.5481) (xy 235.724192 -17.548098) (xy 235.724192 -17.548352)
				(arc
					(start 235.725208 -17.550384)
					(mid 235.400342 -18.524982)
					(end 236.37494 -18.849848)
				)
				(xy 236.37621 -18.852134)
				(arc
					(start 237.296198 -18.39214)
					(mid 237.203981 -18.335993)
					(end 237.12551 -18.261838)
				)
				(xy 237.123224 -18.261584) (xy 236.889798 -17.94002)
				(arc
					(start 236.872018 -17.922494)
					(mid 236.842877 -17.917117)
					(end 236.814106 -17.924272)
				)
				(arc
					(start 236.573568 -18.044668)
					(mid 235.561744 -18.444542)
					(end 236.488224 -17.874234)
				)
				(xy 236.764068 -17.736312)
				(arc
					(start 236.768894 -17.737836)
					(mid 236.887356 -17.729887)
					(end 236.996986 -17.775428)
				)
				(xy 237.001812 -17.775428) (xy 237.028482 -17.802098) (xy 237.030006 -17.803368) (xy 237.057692 -17.831308)
				(xy 237.057692 -17.847056)
				(arc
					(start 237.254034 -18.117566)
					(mid 237.368863 -18.21559)
					(end 237.515654 -18.250916)
				)
				(xy 237.578646 -18.250916) (xy 237.781846 -18.149316) (xy 237.516416 -18.149316) (xy 237.515908 -18.149316)
				(xy 237.477046 -18.149316)
				(arc
					(start 237.472728 -18.144998)
					(mid 237.415515 -18.125185)
					(end 237.365794 -18.090642)
				)
				(xy 237.359698 -18.089626) (xy 237.336584 -18.057876) (xy 237.336584 -18.057622) (xy 237.181898 -17.845024)
				(xy 237.159292 -17.822418) (xy 237.159292 -17.814036) (xy 237.154212 -17.807178)
				(arc
					(start 237.156244 -17.794478)
					(mid 237.153612 -17.631253)
					(end 237.2487 -17.498568)
				)
				(xy 237.250224 -17.493742)
				(arc
					(start 237.526576 -17.355566)
					(mid 238.5384 -16.955692)
					(end 237.61192 -17.526)
				)
				(arc
					(start 237.370874 -17.646396)
					(mid 237.33803 -17.681071)
					(end 237.335314 -17.728692)
				)
				(xy 237.349792 -17.743424) (xy 237.349792 -17.75206)
				(arc
					(start 237.490508 -17.945862)
					(mid 237.501781 -17.955431)
					(end 237.516162 -17.958816)
				)
				(xy 238.162846 -17.958816) (xy 238.376206 -17.852136)
			)
		)
	)
	(zone
		(layer "F.Cu")
		(hatch none 0.5)
		(connect_pads
			(clearance 0)
		)
		(min_thickness 0.25)
		(keepout
			(tracks not_allowed)
			(vias allowed)
			(pads allowed)
			(copperpour not_allowed)
			(footprints allowed)
		)
		(placement
			(enabled no)
			(sheetname "")
		)
		(fill
			(thermal_gap 0.5)
			(thermal_bridge_width 0.5)
			(island_removal_mode 0)
		)
		(polygon
			(pts
				(arc
					(start 7.599934 -120.499886)
					(mid 3.850132 -124.249688)
					(end 0.100076 -120.499886)
				)
				(arc
					(start 0.100076 -120.499886)
					(mid 3.850132 -116.74983)
					(end 7.599934 -120.499886)
				)
			)
		)
	)
	(zone
		(net "5V_PRE_34")
		(layer "F.Cu")
		(hatch none 0.5)
		(connect_pads
			(clearance 0.5)
		)
		(min_thickness 0.25)
		(fill yes
			(thermal_gap 0.5)
			(thermal_bridge_width 0.5)
			(island_removal_mode 0)
		)
		(polygon
			(pts
				(xy 455.6379 -59.984894) (xy 455.3839 -60.238894) (xy 455.3839 -62.778894) (xy 455.0029 -63.159894)
				(xy 452.4629 -63.159894) (xy 452.2089 -63.413894) (xy 452.2089 -63.794894) (xy 452.4629 -64.048894)
				(xy 455.7649 -64.048894) (xy 457.0349 -62.778894) (xy 457.0349 -60.238894) (xy 456.7809 -59.984894)
			)
		)
	)
	(zone
		(layer "F.Cu")
		(hatch none 0.5)
		(connect_pads
			(clearance 0)
		)
		(min_thickness 0.25)
		(keepout
			(tracks allowed)
			(vias allowed)
			(pads allowed)
			(copperpour allowed)
			(footprints allowed)
		)
		(placement
			(enabled no)
			(sheetname "")
		)
		(fill
			(thermal_gap 0.5)
			(thermal_bridge_width 0.5)
			(island_removal_mode 0)
		)
		(polygon
			(pts
				(xy 147.013676 -139.804902) (xy 147.013676 -136.121902) (xy 150.493476 -136.121902) (xy 150.493476 -139.804902)
			)
		)
	)
	(zone
		(net "5V_PRE_33")
		(layer "F.Cu")
		(hatch none 0.5)
		(connect_pads
			(clearance 0.5)
		)
		(min_thickness 0.25)
		(fill yes
			(thermal_gap 0.5)
			(thermal_bridge_width 0.5)
			(island_removal_mode 0)
		)
		(polygon
			(pts
				(xy 424.088052 -59.984894) (xy 423.834052 -60.238894) (xy 423.834052 -62.778894) (xy 423.453052 -63.159894)
				(xy 420.913052 -63.159894) (xy 420.659052 -63.413894) (xy 420.659052 -63.794894) (xy 420.913052 -64.048894)
				(xy 424.215052 -64.048894) (xy 425.485052 -62.778894) (xy 425.485052 -60.238894) (xy 425.231052 -59.984894)
			)
		)
	)
	(zone
		(layer "F.Cu")
		(hatch none 0.5)
		(connect_pads
			(clearance 0)
		)
		(min_thickness 0.25)
		(keepout
			(tracks not_allowed)
			(vias allowed)
			(pads allowed)
			(copperpour not_allowed)
			(footprints allowed)
		)
		(placement
			(enabled no)
			(sheetname "")
		)
		(fill
			(thermal_gap 0.5)
			(thermal_bridge_width 0.5)
			(island_removal_mode 0)
		)
		(polygon
			(pts
				(arc
					(start 415.020252 -43.368468)
					(mid 414.639252 -42.987468)
					(end 414.258252 -43.368468)
				)
				(arc
					(start 414.258252 -44.511214)
					(mid 414.639125 -44.892468)
					(end 415.020252 -44.511468)
				)
				(xy 415.020252 -44.162218)
				(arc
					(start 414.803336 -44.162218)
					(mid 414.783979 -44.166051)
					(end 414.767522 -44.17695)
				)
				(arc
					(start 414.730184 -44.214288)
					(mid 414.719258 -44.230734)
					(end 414.715452 -44.250102)
				)
				(arc
					(start 414.715452 -44.255944)
					(mid 414.639252 -44.778112)
					(end 414.563052 -44.255944)
				)
				(xy 414.563052 -44.218606)
				(arc
					(start 414.5661 -44.215558)
					(mid 414.578535 -44.172395)
					(end 414.600136 -44.133008)
				)
				(xy 414.600136 -44.128944) (xy 414.682178 -44.046902)
				(arc
					(start 414.686242 -44.046902)
					(mid 414.72562 -44.02528)
					(end 414.768792 -44.012866)
				)
				(xy 414.77184 -44.009818) (xy 415.020252 -44.009818) (xy 415.020252 -43.870118) (xy 414.74898 -43.870118)
				(arc
					(start 414.745932 -43.86707)
					(mid 414.702769 -43.854635)
					(end 414.663382 -43.833034)
				)
				(xy 414.659318 -43.833034) (xy 414.600136 -43.773852)
				(arc
					(start 414.600136 -43.769788)
					(mid 414.578514 -43.73041)
					(end 414.5661 -43.687238)
				)
				(xy 414.563052 -43.68419)
				(arc
					(start 414.563052 -43.623992)
					(mid 414.639252 -43.101824)
					(end 414.715452 -43.623992)
				)
				(arc
					(start 414.715452 -43.652694)
					(mid 414.719285 -43.672051)
					(end 414.730184 -43.688508)
				)
				(arc
					(start 414.744662 -43.702986)
					(mid 414.761108 -43.713912)
					(end 414.780476 -43.717718)
				)
				(xy 415.020252 -43.717718)
			)
		)
	)
	(zone
		(layer "F.Cu")
		(hatch none 0.5)
		(connect_pads
			(clearance 0)
		)
		(min_thickness 0.25)
		(keepout
			(tracks allowed)
			(vias allowed)
			(pads allowed)
			(copperpour allowed)
			(footprints not_allowed)
		)
		(placement
			(enabled no)
			(sheetname "")
		)
		(fill
			(thermal_gap 0.5)
			(thermal_bridge_width 0.5)
			(island_removal_mode 0)
		)
		(polygon
			(pts
				(arc
					(start 174.95012 -269.999968)
					(mid 170.200066 -274.750022)
					(end 165.450012 -269.999968)
				)
				(arc
					(start 165.450012 -269.999968)
					(mid 170.200066 -265.249914)
					(end 174.95012 -269.999968)
				)
			)
		)
	)
	(zone
		(net "P5V_HDD29")
		(layer "F.Cu")
		(hatch none 0.5)
		(connect_pads
			(clearance 0.5)
		)
		(min_thickness 0.25)
		(fill yes
			(thermal_gap 0.5)
			(thermal_bridge_width 0.5)
			(island_removal_mode 0)
		)
		(polygon
			(pts
				(xy 177.419 -56.682894) (xy 177.165 -56.936894) (xy 177.165 -59.222894) (xy 177.419 -59.476894)
				(xy 177.419 -61.508894) (xy 178.181 -62.270894) (xy 178.181 -63.032894) (xy 178.562 -63.413894)
				(xy 178.943 -63.413894) (xy 182.118 -66.588894) (xy 188.976 -66.588894) (xy 189.103 -66.461894)
				(xy 189.103 -64.683894) (xy 188.976 -64.556894) (xy 183.896 -64.556894) (xy 181.991 -62.651894)
				(xy 181.17058 -62.651894) (xy 180.213 -61.694314) (xy 180.213 -59.222894) (xy 180.848 -58.587894)
				(xy 180.848 -56.936894) (xy 180.594 -56.682894)
			)
		)
		(polygon
			(pts
				(xy 179.4256 -63.109094) (xy 179.2224 -63.109094) (xy 179.2224 -63.312294) (xy 179.4256 -63.312294)
			)
		)
		(polygon
			(pts
				(xy 179.4256 -62.245494) (xy 179.2224 -62.245494) (xy 179.2224 -62.448694) (xy 179.4256 -62.448694)
			)
		)
		(polygon
			(pts
				(xy 178.562 -62.245494) (xy 178.3588 -62.245494) (xy 178.3588 -62.448694) (xy 178.562 -62.448694)
			)
		)
	)
	(zone
		(net "12V_PRE_0")
		(layer "F.Cu")
		(hatch none 0.5)
		(connect_pads
			(clearance 0.5)
		)
		(min_thickness 0.25)
		(fill yes
			(thermal_gap 0.5)
			(thermal_bridge_width 0.5)
			(island_removal_mode 0)
		)
		(polygon
			(pts
				(xy 19.668998 -293.794942) (xy 19.541998 -293.921942) (xy 19.541998 -295.445942) (xy 20.938998 -296.842942)
				(xy 22.335998 -296.842942) (xy 27.288998 -301.795942) (xy 31.225998 -301.795942) (xy 31.352998 -301.668942)
				(xy 31.352998 -300.906942) (xy 31.225998 -300.779942) (xy 27.923998 -300.779942) (xy 20.938998 -293.794942)
			)
		)
	)
	(zone
		(net "MB3_CM_GATE")
		(layer "F.Cu")
		(hatch none 0.5)
		(connect_pads
			(clearance 0.5)
		)
		(min_thickness 0.25)
		(fill yes
			(thermal_gap 0.5)
			(thermal_bridge_width 0.5)
			(island_removal_mode 0)
		)
		(polygon
			(pts
				(xy 242.06454 -383.081276) (xy 240.345468 -384.800348) (xy 240.345468 -386.314442) (xy 240.375694 -386.344668)
				(xy 240.64722 -386.344668) (xy 240.697512 -386.294376) (xy 241.670078 -386.294376) (xy 241.996722 -385.967732)
				(xy 242.132358 -385.967732) (xy 242.133374 -385.968748) (xy 242.777264 -385.968748) (xy 243.658136 -385.087876)
				(xy 243.658136 -383.466086) (xy 243.716556 -383.407666) (xy 243.716556 -383.111756) (xy 243.686076 -383.081276)
			)
		)
	)
	(zone
		(net "5V_PRE_3")
		(layer "F.Cu")
		(hatch none 0.5)
		(connect_pads
			(clearance 0.5)
		)
		(min_thickness 0.25)
		(fill yes
			(thermal_gap 0.5)
			(thermal_bridge_width 0.5)
			(island_removal_mode 0)
		)
		(polygon
			(pts
				(xy 130.359404 -289.095942) (xy 130.105404 -289.349942) (xy 130.105404 -290.492942) (xy 127.438404 -293.159942)
				(xy 123.501404 -293.159942) (xy 123.374404 -293.286942) (xy 123.374404 -294.048942) (xy 123.501404 -294.175942)
				(xy 127.946404 -294.175942) (xy 130.486404 -291.635942) (xy 131.756404 -291.635942) (xy 131.883404 -291.508942)
				(xy 131.883404 -289.349942) (xy 131.629404 -289.095942)
			)
		)
	)
	(zone
		(layer "F.Cu")
		(hatch none 0.5)
		(connect_pads
			(clearance 0)
		)
		(min_thickness 0.25)
		(keepout
			(tracks allowed)
			(vias allowed)
			(pads allowed)
			(copperpour allowed)
			(footprints allowed)
		)
		(placement
			(enabled no)
			(sheetname "")
		)
		(fill
			(thermal_gap 0.5)
			(thermal_bridge_width 0.5)
			(island_removal_mode 0)
		)
		(polygon
			(pts
				(xy 244.7544 -239.4458) (xy 244.7544 -242.189) (xy 241.8334 -242.189) (xy 241.8334 -239.4458)
			)
		)
	)
	(zone
		(net "P12V_HDD12")
		(layer "F.Cu")
		(hatch none 0.5)
		(connect_pads
			(clearance 0.5)
		)
		(min_thickness 0.25)
		(fill yes
			(thermal_gap 0.5)
			(thermal_bridge_width 0.5)
			(island_removal_mode 0)
		)
		(polygon
			(pts
				(xy 12.302998 -176.254918) (xy 12.048998 -176.508918) (xy 12.048998 -178.159918) (xy 12.302998 -178.413918)
				(xy 14.461998 -178.413918) (xy 14.969998 -178.921918) (xy 14.969998 -181.461918) (xy 22.716998 -189.208918)
				(xy 31.225998 -189.208918) (xy 31.352998 -189.081918) (xy 31.352998 -187.303918) (xy 31.225998 -187.176918)
				(xy 25.256998 -187.176918) (xy 24.621998 -186.541918) (xy 22.970998 -186.541918) (xy 18.652998 -182.223918)
				(xy 18.652998 -178.667918) (xy 17.509998 -177.524918) (xy 17.509998 -176.508918) (xy 17.255998 -176.254918)
			)
		)
		(polygon
			(pts
				(xy 24.774398 -188.218318) (xy 24.571198 -188.218318) (xy 24.571198 -188.421518) (xy 24.774398 -188.421518)
			)
		)
		(polygon
			(pts
				(xy 23.910798 -188.218318) (xy 23.707598 -188.218318) (xy 23.707598 -188.421518) (xy 23.910798 -188.421518)
			)
		)
	)
	(zone
		(net "P5V_HDD14")
		(layer "F.Cu")
		(hatch none 0.5)
		(connect_pads
			(clearance 0.5)
		)
		(min_thickness 0.25)
		(fill yes
			(thermal_gap 0.5)
			(thermal_bridge_width 0.5)
			(island_removal_mode 0)
		)
		(polygon
			(pts
				(xy 82.768948 -171.682918) (xy 82.514948 -171.936918) (xy 82.514948 -174.222918) (xy 82.768948 -174.476918)
				(xy 82.768948 -176.508918) (xy 83.530948 -177.270918) (xy 83.530948 -178.032918) (xy 83.911948 -178.413918)
				(xy 84.292948 -178.413918) (xy 87.467948 -181.588918) (xy 94.325948 -181.588918) (xy 94.452948 -181.461918)
				(xy 94.452948 -179.683918) (xy 94.325948 -179.556918) (xy 89.245948 -179.556918) (xy 87.340948 -177.651918)
				(xy 86.451948 -177.651918) (xy 85.562948 -176.762918) (xy 85.562948 -174.222918) (xy 86.197948 -173.587918)
				(xy 86.197948 -171.936918) (xy 85.943948 -171.682918)
			)
		)
		(polygon
			(pts
				(xy 84.775548 -178.109118) (xy 84.572348 -178.109118) (xy 84.572348 -178.312318) (xy 84.775548 -178.312318)
			)
		)
		(polygon
			(pts
				(xy 84.775548 -177.245518) (xy 84.572348 -177.245518) (xy 84.572348 -177.448718) (xy 84.775548 -177.448718)
			)
		)
		(polygon
			(pts
				(xy 83.911948 -177.245518) (xy 83.708748 -177.245518) (xy 83.708748 -177.448718) (xy 83.911948 -177.448718)
			)
		)
	)
	(zone
		(layer "F.Cu")
		(hatch none 0.5)
		(connect_pads
			(clearance 0)
		)
		(min_thickness 0.25)
		(keepout
			(tracks allowed)
			(vias allowed)
			(pads allowed)
			(copperpour allowed)
			(footprints not_allowed)
		)
		(placement
			(enabled no)
			(sheetname "")
		)
		(fill
			(thermal_gap 0.5)
			(thermal_bridge_width 0.5)
			(island_removal_mode 0)
		)
		(polygon
			(pts
				(arc
					(start 152.32507 -207.79994)
					(mid 159.325056 -200.799954)
					(end 166.325042 -207.79994)
				)
				(arc
					(start 166.325042 -213.799928)
					(mid 159.325056 -220.799914)
					(end 152.32507 -213.799928)
				)
			)
		)
	)
	(zone
		(net "GND")
		(layer "F.Cu")
		(hatch none 0.5)
		(connect_pads
			(clearance 0.5)
		)
		(min_thickness 0.25)
		(fill yes
			(thermal_gap 0.5)
			(thermal_bridge_width 0.5)
			(island_removal_mode 0)
		)
		(polygon
			(pts
				(xy 101.40569 -42.169588) (xy 103.706168 -48.410368) (xy 104.1654 -48.8696) (xy 104.6226 -48.8696)
				(xy 104.944672 -48.547528)
				(arc
					(start 104.944672 -45.092366)
					(mid 104.932742 -44.7802)
					(end 104.944672 -44.468034)
				)
				(xy 104.944672 -41.54297)
				(arc
					(start 106.523028 -41.54297)
					(mid 108.615002 -40.71048)
					(end 110.830614 -41.11117)
				)
				(xy 113.123472 -41.11117) (xy 113.123472 -40.73017)
				(arc
					(start 114.901726 -40.73017)
					(mid 116.24437 -40.045768)
					(end 117.743732 -39.894002)
				)
				(arc
					(start 117.743732 -39.192962)
					(mid 117.057694 -37.840683)
					(end 116.911374 -36.331398)
				)
				(xy 115.403122 -36.034472)
				(arc
					(start 115.174268 -35.718496)
					(mid 113.934581 -35.719778)
					(end 112.750092 -35.354006)
				)
				(arc
					(start 112.750092 -35.354006)
					(mid 110.392269 -35.728001)
					(end 108.219748 -34.73831)
				)
				(arc
					(start 108.219748 -34.73831)
					(mid 105.872875 -33.265351)
					(end 104.957372 -30.65018)
				)
				(arc
					(start 104.957372 -23.450042)
					(mid 104.973605 -23.081713)
					(end 105.022142 -22.716236)
				)
				(arc
					(start 105.022142 -22.716236)
					(mid 105.009964 -22.533409)
					(end 105.005886 -22.350222)
				)
				(xy 105.005886 -20.842224) (xy 103.721154 -20.842224) (xy 103.721154 -15.762986)
				(arc
					(start 103.000048 -15.762986)
					(mid 101.753409 -15.246611)
					(end 101.237034 -13.999972)
				)
				(arc
					(start 101.237034 -0.999998)
					(mid 101.167624 -0.832426)
					(end 101.000052 -0.763016)
				)
				(arc
					(start 0.999998 -0.763016)
					(mid 0.832426 -0.832426)
					(end 0.763016 -0.999998)
				)
				(arc
					(start 0.763016 -2.856484)
					(mid 3.214109 -1.485891)
					(end 5.968746 -2.032)
				)
				(xy 11.411966 -2.032)
				(arc
					(start 11.411966 -5.842254)
					(mid 9.760391 -10.22937)
					(end 5.842254 -12.80287)
				)
				(arc
					(start 5.842254 -12.803124)
					(mid 3.940032 -13.069541)
					(end 2.032 -12.84859)
				)
				(arc
					(start 2.032 -9.134602)
					(mid 1.347921 -8.702396)
					(end 0.763016 -8.14324)
				)
				(arc
					(start 0.763016 -117.856508)
					(mid 1.347909 -117.297337)
					(end 2.032 -116.865146)
				)
				(arc
					(start 2.032 -113.151158)
					(mid 3.940032 -112.93025)
					(end 5.842254 -113.196624)
				)
				(arc
					(start 5.842254 -113.196878)
					(mid 7.24241 -113.732691)
					(end 8.509508 -114.533934)
				)
				(arc
					(start 8.509508 -114.533934)
					(mid 8.837112 -114.318446)
					(end 9.183624 -114.1349)
				)
				(xy 10.09904 -113.219484) (xy 10.09904 -92.035884) (xy 14.464284 -87.67064) (xy 19.089116 -87.67064)
				(xy 20.826476 -89.408)
				(arc
					(start 23.04923 -89.408)
					(mid 24.210004 -86.967698)
					(end 25.939242 -84.891118)
				)
				(xy 23.093934 -84.891118)
				(arc
					(start 23.093934 -80.166972)
					(mid 22.341835 -79.863413)
					(end 21.664422 -79.417418)
				)
				(xy 19.997674 -79.417418) (xy 19.997674 -76.87818) (xy 19.882612 -76.763118) (xy 19.426174 -76.763118)
				(xy 19.426174 -76.30668) (xy 12.313412 -69.193918) (xy 9.240774 -69.193918) (xy 9.240774 -67.078098)
				(xy 9.21004 -67.034918) (xy 8.300974 -67.034918) (xy 8.300974 -64.80048) (xy 8.238744 -64.73825)
				(xy 8.238744 -59.930538) (xy 8.300974 -59.868308) (xy 8.300974 -52.68087) (xy 9.646412 -52.68087)
				(xy 10.269474 -52.057808) (xy 10.269474 -50.40757) (xy 10.320274 -50.40757) (xy 10.320274 -49.39157)
				(xy 11.133074 -49.39157)
				(arc
					(start 11.133074 -48.956468)
					(mid 9.467976 -44.829386)
					(end 12.555474 -41.62425)
				)
				(xy 12.555474 -41.18737) (xy 14.409674 -41.18737) (xy 14.409674 -41.11117) (xy 18.448274 -41.11117)
				(xy 18.448274 -40.78097) (xy 23.093934 -40.78097) (xy 23.093934 -30.928818) (xy 33.306258 -30.928818)
				(arc
					(start 33.306258 -33.517078)
					(mid 34.085693 -35.193751)
					(end 34.047176 -37.042344)
				)
				(xy 35.01771 -37.042344) (xy 35.01771 -39.671244) (xy 36.73221 -39.671244)
				(arc
					(start 36.73221 -41.336722)
					(mid 36.958492 -41.582571)
					(end 37.16274 -41.847008)
				)
				(arc
					(start 38.762432 -44.11472)
					(mid 39.026017 -44.545557)
					(end 39.231316 -45.007022)
				)
				(xy 40.848788 -49.39157) (xy 42.682922 -49.39157)
				(arc
					(start 42.682922 -48.963834)
					(mid 40.968394 -45.633894)
					(end 42.682922 -42.303954)
				)
				(xy 42.682922 -41.54297) (xy 44.105322 -41.54297) (xy 44.105322 -41.18737) (xy 45.959522 -41.18737)
				(xy 45.959522 -41.11117) (xy 50.023522 -41.11117) (xy 50.023522 -40.78097) (xy 54.643782 -40.78097)
				(xy 54.643782 -30.928818) (xy 64.856106 -30.928818)
				(arc
					(start 64.856106 -33.517078)
					(mid 65.635541 -35.193751)
					(end 65.597024 -37.042344)
				)
				(xy 66.567558 -37.042344) (xy 66.567558 -39.671244) (xy 68.282058 -39.671244) (xy 68.282058 -41.064942)
				(xy 69.558662 -41.87317) (xy 72.33031 -49.39157) (xy 74.233024 -49.39157)
				(arc
					(start 74.233024 -48.963834)
					(mid 72.518496 -45.633894)
					(end 74.233024 -42.303954)
				)
				(xy 74.233024 -41.54297) (xy 75.655424 -41.54297) (xy 75.655424 -41.18737) (xy 77.535024 -41.18737)
				(xy 77.535024 -41.11117) (xy 81.599024 -41.11117) (xy 81.599024 -40.73017) (xy 86.193884 -40.73017)
				(arc
					(start 86.193884 -37.04463)
					(mid 85.626481 -37.06251)
					(end 85.06206 -37.001704)
				)
				(arc
					(start 84.980272 -37.01034)
					(mid 83.121218 -37.962088)
					(end 81.034636 -37.872162)
				)
				(arc
					(start 81.034636 -37.872162)
					(mid 78.317462 -37.737135)
					(end 76.286106 -35.927538)
				)
				(xy 75.759056 -35.927538) (xy 75.759056 -31.886398) (xy 75.337924 -31.886398) (xy 75.337924 -30.512258)
				(xy 75.101958 -30.276292) (xy 75.101958 -25.529286) (xy 75.337924 -25.29332)
				(arc
					(start 75.337924 -22.422866)
					(mid 75.256108 -22.38642)
					(end 75.17511 -22.34819)
				)
				(xy 73.875646 -22.34819)
				(arc
					(start 73.875646 -21.353018)
					(mid 73.026711 -19.783557)
					(end 72.926702 -18.001996)
				)
				(arc
					(start 72.926702 -18.001996)
					(mid 73.038896 -16.2495)
					(end 73.875646 -14.705584)
				)
				(xy 73.875646 -13.302742)
				(arc
					(start 76.6572 -13.302742)
					(mid 76.969366 -13.290812)
					(end 77.281532 -13.302742)
				)
				(xy 78.733142 -13.302742) (xy 78.733142 -13.268706)
				(arc
					(start 81.30921 -13.268706)
					(mid 81.478045 -12.929717)
					(end 81.67751 -12.607798)
				)
				(xy 81.67751 -11.869166) (xy 81.971642 -11.869166) (xy 81.971642 -10.804906)
				(arc
					(start 89.514426 -10.804906)
					(mid 90.2208 -10.743448)
					(end 90.927174 -10.804906)
				)
				(xy 91.11869 -10.804906)
				(arc
					(start 91.11869 -10.84326)
					(mid 93.370798 -12.224667)
					(end 94.308676 -14.694662)
				)
				(arc
					(start 94.308676 -14.694662)
					(mid 95.318002 -15.760982)
					(end 95.885762 -17.115028)
				)
				(arc
					(start 95.885762 -17.115028)
					(mid 96.013826 -17.275747)
					(end 96.133666 -17.442688)
				)
				(arc
					(start 96.133666 -17.442688)
					(mid 96.695331 -17.529135)
					(end 97.239582 -17.692624)
				)
				(arc
					(start 97.239328 -17.69237)
					(mid 98.39092 -18.358423)
					(end 99.267772 -19.358864)
				)
				(arc
					(start 99.268026 -19.358864)
					(mid 99.422615 -19.630096)
					(end 99.556062 -19.91233)
				)
				(arc
					(start 99.556062 -19.91233)
					(mid 99.877605 -21.276688)
					(end 99.719638 -22.6695)
				)
				(arc
					(start 99.719638 -22.6695)
					(mid 99.648958 -26.209636)
					(end 96.842072 -28.36799)
				)
				(xy 96.842072 -28.441904)
				(arc
					(start 96.338644 -28.441904)
					(mid 95.997776 -28.456132)
					(end 95.656908 -28.441904)
				)
				(arc
					(start 94.797118 -28.441904)
					(mid 94.517467 -28.481329)
					(end 94.235778 -28.501594)
				)
				(xy 94.235778 -30.928818) (xy 96.406208 -30.928818)
				(arc
					(start 96.406208 -33.517078)
					(mid 97.185643 -35.193751)
					(end 97.147126 -37.042344)
				)
				(xy 98.11766 -37.042344) (xy 98.11766 -39.671244) (xy 99.83216 -39.671244) (xy 99.83216 -41.173654)
			)
		)
		(polygon
			(pts
				(arc
					(start 37.1983 -5.842254)
					(mid 37.042794 -3.8196)
					(end 36.083748 -2.032)
				)
				(xy 18.43659 -2.032)
				(arc
					(start 18.43659 -5.842254)
					(mid 17.944182 -7.393646)
					(end 17.753838 -9.010142)
				)
				(arc
					(start 17.753838 -9.010142)
					(mid 16.234721 -15.926565)
					(end 23.203408 -17.184624)
				)
				(arc
					(start 23.203408 -17.184624)
					(mid 31.080677 -16.333258)
					(end 34.896298 -9.389364)
				)
				(arc
					(start 34.896298 -9.389364)
					(mid 36.448238 -7.876001)
					(end 37.1983 -5.842254)
				)
			)
		)
	)
	(zone
		(net "P5V_A_1")
		(layer "F.Cu")
		(hatch none 0.5)
		(connect_pads
			(clearance 0.5)
		)
		(min_thickness 0.25)
		(fill yes
			(thermal_gap 0.5)
			(thermal_bridge_width 0.5)
			(island_removal_mode 0)
		)
		(polygon
			(pts
				(xy 49.948846 -280.840942) (xy 49.694846 -281.094942) (xy 49.694846 -283.380942) (xy 49.948846 -283.634942)
				(xy 54.647846 -283.634942) (xy 54.901846 -283.380942) (xy 54.901846 -281.094942) (xy 54.647846 -280.840942)
			)
		)
	)
	(zone
		(net "P5V_A_1")
		(layer "F.Cu")
		(hatch none 0.5)
		(connect_pads
			(clearance 0.5)
		)
		(min_thickness 0.25)
		(fill yes
			(thermal_gap 0.5)
			(thermal_bridge_width 0.5)
			(island_removal_mode 0)
		)
		(polygon
			(pts
				(xy 18.398998 -280.840942) (xy 18.144998 -281.094942) (xy 18.144998 -283.380942) (xy 18.398998 -283.634942)
				(xy 23.097998 -283.634942) (xy 23.351998 -283.380942) (xy 23.351998 -281.094942) (xy 23.097998 -280.840942)
			)
		)
	)
	(zone
		(net "GND")
		(layer "F.Cu")
		(hatch none 0.5)
		(connect_pads
			(clearance 0.5)
		)
		(min_thickness 0.25)
		(fill yes
			(thermal_gap 0.5)
			(thermal_bridge_width 0.5)
			(island_removal_mode 0)
		)
		(polygon
			(pts
				(xy 256.876804 23.386796) (xy 256.724404 23.234396) (xy 256.724404 20.313396) (xy 256.953004 20.084796)
				(xy 259.010404 20.084796) (xy 259.213604 20.287996) (xy 259.213604 23.132796) (xy 258.959604 23.386796)
			)
		)
	)
	(zone
		(layer "F.Cu")
		(hatch none 0.5)
		(connect_pads
			(clearance 0)
		)
		(min_thickness 0.25)
		(keepout
			(tracks allowed)
			(vias allowed)
			(pads allowed)
			(copperpour allowed)
			(footprints allowed)
		)
		(placement
			(enabled no)
			(sheetname "")
		)
		(fill
			(thermal_gap 0.5)
			(thermal_bridge_width 0.5)
			(island_removal_mode 0)
		)
		(polygon
			(pts
				(xy 477.55048 -235.236512) (xy 470.679272 -235.236512) (xy 470.679272 -233.985562) (xy 477.55048 -233.985562)
			)
		)
	)
	(zone
		(layer "F.Cu")
		(hatch none 0.5)
		(connect_pads
			(clearance 0)
		)
		(min_thickness 0.25)
		(keepout
			(tracks allowed)
			(vias allowed)
			(pads allowed)
			(copperpour allowed)
			(footprints allowed)
		)
		(placement
			(enabled no)
			(sheetname "")
		)
		(fill
			(thermal_gap 0.5)
			(thermal_bridge_width 0.5)
			(island_removal_mode 0)
		)
		(polygon
			(pts
				(xy 265.0998 18.288) (xy 265.0998 16.6878) (xy 262.4582 16.6878) (xy 262.4582 18.288)
			)
		)
	)
	(zone
		(layer "F.Cu")
		(hatch none 0.5)
		(connect_pads
			(clearance 0)
		)
		(min_thickness 0.25)
		(keepout
			(tracks allowed)
			(vias allowed)
			(pads allowed)
			(copperpour allowed)
			(footprints not_allowed)
		)
		(placement
			(enabled no)
			(sheetname "")
		)
		(fill
			(thermal_gap 0.5)
			(thermal_bridge_width 0.5)
			(island_removal_mode 0)
		)
		(polygon
			(pts
				(arc
					(start 209.300064 -69.799962)
					(mid 202.300078 -76.799948)
					(end 195.300092 -69.799962)
				)
				(arc
					(start 195.300092 -63.799974)
					(mid 202.300078 -56.799988)
					(end 209.300064 -63.799974)
				)
			)
		)
	)
	(zone
		(layer "F.Cu")
		(hatch none 0.5)
		(connect_pads
			(clearance 0)
		)
		(min_thickness 0.25)
		(keepout
			(tracks allowed)
			(vias allowed)
			(pads allowed)
			(copperpour allowed)
			(footprints not_allowed)
		)
		(placement
			(enabled no)
			(sheetname "")
		)
		(fill
			(thermal_gap 0.5)
			(thermal_bridge_width 0.5)
			(island_removal_mode 0)
		)
		(polygon
			(pts
				(xy 225.03003 -22.61997) (xy 215.629998 -22.61997) (xy 215.629998 -30.31998) (xy 225.03003 -30.31998)
			)
		)
	)
	(zone
		(layer "F.Cu")
		(hatch none 0.5)
		(connect_pads
			(clearance 0)
		)
		(min_thickness 0.25)
		(keepout
			(tracks allowed)
			(vias allowed)
			(pads allowed)
			(copperpour allowed)
			(footprints not_allowed)
		)
		(placement
			(enabled no)
			(sheetname "")
		)
		(fill
			(thermal_gap 0.5)
			(thermal_bridge_width 0.5)
			(island_removal_mode 0)
		)
		(polygon
			(pts
				(arc
					(start 171.45 -164.200078)
					(mid 167.699944 -167.950134)
					(end 163.949888 -164.200078)
				)
				(arc
					(start 163.949888 -164.200078)
					(mid 167.699944 -160.450022)
					(end 171.45 -164.200078)
				)
			)
		)
	)
	(zone
		(net "P12V_A_VIN_U22")
		(layer "F.Cu")
		(hatch none 0.5)
		(connect_pads
			(clearance 0.5)
		)
		(min_thickness 0.25)
		(fill yes
			(thermal_gap 0.5)
			(thermal_bridge_width 0.5)
			(island_removal_mode 0)
		)
		(polygon
			(pts
				(xy 441.91936 -248.093992) (xy 440.863736 -249.149616) (xy 440.863736 -251.469906) (xy 441.064904 -251.671074)
				(xy 443.743842 -251.671074) (xy 443.852808 -251.562108) (xy 443.852808 -248.198132) (xy 443.748668 -248.093992)
			)
		)
	)
	(zone
		(layer "F.Cu")
		(hatch none 0.5)
		(connect_pads
			(clearance 0)
		)
		(min_thickness 0.25)
		(keepout
			(tracks not_allowed)
			(vias allowed)
			(pads allowed)
			(copperpour not_allowed)
			(footprints allowed)
		)
		(placement
			(enabled no)
			(sheetname "")
		)
		(fill
			(thermal_gap 0.5)
			(thermal_bridge_width 0.5)
			(island_removal_mode 0)
		)
		(polygon
			(pts
				(arc
					(start 111.849916 -289.999928)
					(mid 107.100116 -294.749728)
					(end 102.350062 -289.999928)
				)
				(arc
					(start 102.350062 -289.999928)
					(mid 107.100116 -285.249874)
					(end 111.849916 -289.999928)
				)
			)
		)
	)
	(zone
		(layer "F.Cu")
		(hatch none 0.5)
		(connect_pads
			(clearance 0)
		)
		(min_thickness 0.25)
		(keepout
			(tracks not_allowed)
			(vias allowed)
			(pads allowed)
			(copperpour not_allowed)
			(footprints allowed)
		)
		(placement
			(enabled no)
			(sheetname "")
		)
		(fill
			(thermal_gap 0.5)
			(thermal_bridge_width 0.5)
			(island_removal_mode 0)
		)
		(polygon
			(pts
				(arc
					(start 482.870002 -277.17877)
					(mid 482.489129 -276.797516)
					(end 482.108002 -277.178516)
				)
				(arc
					(start 482.108002 -278.321516)
					(mid 482.489002 -278.702516)
					(end 482.870002 -278.321516)
				)
				(xy 482.870002 -277.972266)
				(arc
					(start 482.616256 -277.972266)
					(mid 482.580155 -277.987219)
					(end 482.565202 -278.02332)
				)
				(arc
					(start 482.565202 -278.065992)
					(mid 482.489002 -278.58816)
					(end 482.412802 -278.065992)
				)
				(xy 482.412802 -277.991824)
				(arc
					(start 482.41585 -277.988776)
					(mid 482.472458 -277.879522)
					(end 482.581712 -277.822914)
				)
				(xy 482.58476 -277.819866) (xy 482.870002 -277.819866) (xy 482.870002 -277.680166) (xy 482.58476 -277.680166)
				(arc
					(start 482.581712 -277.677118)
					(mid 482.472458 -277.62051)
					(end 482.41585 -277.511256)
				)
				(xy 482.412802 -277.508208)
				(arc
					(start 482.412802 -277.43404)
					(mid 482.489002 -276.911872)
					(end 482.565202 -277.43404)
				)
				(arc
					(start 482.565202 -277.476712)
					(mid 482.580155 -277.512813)
					(end 482.616256 -277.527766)
				)
				(xy 482.870002 -277.527766)
			)
		)
	)
	(zone
		(net "GND")
		(layer "F.Cu")
		(hatch none 0.5)
		(connect_pads
			(clearance 0.5)
		)
		(min_thickness 0.25)
		(fill yes
			(thermal_gap 0.5)
			(thermal_bridge_width 0.5)
			(island_removal_mode 0)
		)
		(polygon
			(pts
				(arc
					(start 169.225976 -218.1606)
					(mid 166.477786 -221.91421)
					(end 162.4076 -224.167192)
				)
				(xy 162.4076 -226.135438)
				(arc
					(start 166.315644 -232.270046)
					(mid 167.398661 -232.157055)
					(end 168.47312 -232.3338)
				)
				(xy 171.153328 -232.3338) (xy 171.153328 -218.1606)
			)
		)
	)
	(zone
		(net "P5V_HDD23")
		(layer "F.Cu")
		(hatch none 0.5)
		(connect_pads
			(clearance 0.5)
		)
		(min_thickness 0.25)
		(fill yes
			(thermal_gap 0.5)
			(thermal_bridge_width 0.5)
			(island_removal_mode 0)
		)
		(polygon
			(pts
				(xy 474.768926 -171.682918) (xy 474.514926 -171.936918) (xy 474.514926 -174.222918) (xy 474.768926 -174.476918)
				(xy 474.768926 -176.508918) (xy 475.530926 -177.270918) (xy 475.530926 -178.032918) (xy 475.911926 -178.413918)
				(xy 476.292926 -178.413918) (xy 479.467926 -181.588918) (xy 486.325926 -181.588918) (xy 486.452926 -181.461918)
				(xy 486.452926 -179.683918) (xy 486.325926 -179.556918) (xy 481.245926 -179.556918) (xy 479.340926 -177.651918)
				(xy 478.451926 -177.651918) (xy 477.562926 -176.762918) (xy 477.562926 -174.222918) (xy 478.197926 -173.587918)
				(xy 478.197926 -171.936918) (xy 477.943926 -171.682918)
			)
		)
		(polygon
			(pts
				(xy 476.775526 -178.109118) (xy 476.572326 -178.109118) (xy 476.572326 -178.312318) (xy 476.775526 -178.312318)
			)
		)
		(polygon
			(pts
				(xy 476.775526 -177.245518) (xy 476.572326 -177.245518) (xy 476.572326 -177.448718) (xy 476.775526 -177.448718)
			)
		)
		(polygon
			(pts
				(xy 475.911926 -177.245518) (xy 475.708726 -177.245518) (xy 475.708726 -177.448718) (xy 475.911926 -177.448718)
			)
		)
	)
	(zone
		(layer "F.Cu")
		(hatch none 0.5)
		(connect_pads
			(clearance 0)
		)
		(min_thickness 0.25)
		(keepout
			(tracks allowed)
			(vias allowed)
			(pads allowed)
			(copperpour allowed)
			(footprints allowed)
		)
		(placement
			(enabled no)
			(sheetname "")
		)
		(fill
			(thermal_gap 0.5)
			(thermal_bridge_width 0.5)
			(island_removal_mode 0)
		)
		(polygon
			(pts
				(xy 223.9264 -214.376) (xy 223.9264 -218.1606) (xy 223.4184 -218.1606) (xy 223.4184 -214.376)
			)
		)
	)
	(zone
		(layer "F.Cu")
		(hatch none 0.5)
		(connect_pads
			(clearance 0)
		)
		(min_thickness 0.25)
		(keepout
			(tracks allowed)
			(vias allowed)
			(pads allowed)
			(copperpour allowed)
			(footprints not_allowed)
		)
		(placement
			(enabled no)
			(sheetname "")
		)
		(fill
			(thermal_gap 0.5)
			(thermal_bridge_width 0.5)
			(island_removal_mode 0)
		)
		(polygon
			(pts
				(xy 298.200064 -374.000014)
				(arc
					(start 308.99989 -374.000014)
					(mid 309.706995 -374.292907)
					(end 309.999888 -375.000012)
				)
				(xy 309.999888 -383.199894) (xy 298.200064 -383.199894)
			)
		)
	)
	(zone
		(net "P12V_HDD15")
		(layer "F.Cu")
		(hatch none 0.5)
		(connect_pads
			(clearance 0.5)
		)
		(min_thickness 0.25)
		(fill yes
			(thermal_gap 0.5)
			(thermal_bridge_width 0.5)
			(island_removal_mode 0)
		)
		(polygon
			(pts
				(xy 106.952796 -176.254918) (xy 106.698796 -176.508918) (xy 106.698796 -178.159918) (xy 106.952796 -178.413918)
				(xy 109.111796 -178.413918) (xy 109.619796 -178.921918) (xy 109.619796 -181.461918) (xy 117.366796 -189.208918)
				(xy 125.875796 -189.208918) (xy 126.002796 -189.081918) (xy 126.002796 -187.303918) (xy 125.875796 -187.176918)
				(xy 119.906796 -187.176918) (xy 119.271796 -186.541918) (xy 117.620796 -186.541918) (xy 113.302796 -182.223918)
				(xy 113.302796 -178.667918) (xy 112.159796 -177.524918) (xy 112.159796 -176.508918) (xy 111.905796 -176.254918)
			)
		)
		(polygon
			(pts
				(xy 119.424196 -188.218318) (xy 119.220996 -188.218318) (xy 119.220996 -188.421518) (xy 119.424196 -188.421518)
			)
		)
		(polygon
			(pts
				(xy 118.560596 -188.218318) (xy 118.357396 -188.218318) (xy 118.357396 -188.421518) (xy 118.560596 -188.421518)
			)
		)
	)
	(zone
		(net "GND")
		(layer "F.Cu")
		(hatch none 0.5)
		(connect_pads
			(clearance 0.5)
		)
		(min_thickness 0.25)
		(fill yes
			(thermal_gap 0.5)
			(thermal_bridge_width 0.5)
			(island_removal_mode 0)
		)
		(polygon
			(pts
				(xy 444.694564 -247.68175) (xy 444.411862 -247.964452) (xy 444.411862 -251.854462) (xy 444.754 -252.1966)
				(xy 444.754 -253.783084) (xy 445.04356 -254.072644) (xy 447.867278 -254.072644) (xy 448.056 -253.883922)
				(xy 448.056 -247.85955) (xy 447.8782 -247.68175)
			)
		)
	)
	(zone
		(layer "F.Cu")
		(hatch none 0.5)
		(connect_pads
			(clearance 0)
		)
		(min_thickness 0.25)
		(keepout
			(tracks not_allowed)
			(vias allowed)
			(pads allowed)
			(copperpour not_allowed)
			(footprints allowed)
		)
		(placement
			(enabled no)
			(sheetname "")
		)
		(fill
			(thermal_gap 0.5)
			(thermal_bridge_width 0.5)
			(island_removal_mode 0)
		)
		(polygon
			(pts
				(arc
					(start 281.074876 -17.84985)
					(mid 281.399742 -16.875252)
					(end 280.425144 -16.550386)
				)
				(xy 280.423874 -16.5481)
				(arc
					(start 279.503886 -17.008094)
					(mid 279.596103 -17.064241)
					(end 279.674574 -17.138396)
				)
				(xy 279.67686 -17.13865) (xy 279.910286 -17.460214)
				(arc
					(start 279.928066 -17.47774)
					(mid 279.957207 -17.483117)
					(end 279.985978 -17.475962)
				)
				(arc
					(start 280.226516 -17.355566)
					(mid 281.23834 -16.955692)
					(end 280.31186 -17.526)
				)
				(xy 280.036016 -17.663922)
				(arc
					(start 280.03119 -17.662398)
					(mid 279.912728 -17.670347)
					(end 279.803098 -17.624806)
				)
				(xy 279.798272 -17.624806) (xy 279.771602 -17.598136) (xy 279.770078 -17.596866) (xy 279.742392 -17.568926)
				(xy 279.742392 -17.553178)
				(arc
					(start 279.54605 -17.282668)
					(mid 279.431221 -17.184644)
					(end 279.28443 -17.149318)
				)
				(xy 279.221692 -17.149318) (xy 279.018492 -17.250918) (xy 279.283668 -17.250918) (xy 279.284176 -17.250918)
				(xy 279.323038 -17.250918)
				(arc
					(start 279.327356 -17.255236)
					(mid 279.384569 -17.275049)
					(end 279.43429 -17.309592)
				)
				(xy 279.440386 -17.310608) (xy 279.4635 -17.342358) (xy 279.4635 -17.342612) (xy 279.618186 -17.55521)
				(xy 279.640792 -17.577816) (xy 279.640792 -17.586198) (xy 279.645872 -17.593056)
				(arc
					(start 279.64384 -17.605756)
					(mid 279.646472 -17.768981)
					(end 279.551384 -17.901666)
				)
				(xy 279.54986 -17.906492) (xy 279.514554 -17.924018)
				(arc
					(start 279.273508 -18.044668)
					(mid 278.261684 -18.444542)
					(end 279.188164 -17.874234)
				)
				(arc
					(start 279.42921 -17.753838)
					(mid 279.462054 -17.719163)
					(end 279.46477 -17.671542)
				)
				(xy 279.450292 -17.65681) (xy 279.450292 -17.648174)
				(arc
					(start 279.309576 -17.454372)
					(mid 279.298303 -17.444803)
					(end 279.283922 -17.441418)
				)
				(xy 278.637492 -17.441418) (xy 278.424132 -17.548098) (xy 278.424132 -17.548352)
				(arc
					(start 278.425148 -17.550384)
					(mid 278.100282 -18.524982)
					(end 279.07488 -18.849848)
				)
				(xy 279.07615 -18.852134) (xy 281.076146 -17.852136)
			)
		)
	)
	(zone
		(net "12V_PRE_21")
		(layer "F.Cu")
		(hatch none 0.5)
		(connect_pads
			(clearance 0.5)
		)
		(min_thickness 0.25)
		(fill yes
			(thermal_gap 0.5)
			(thermal_bridge_width 0.5)
			(island_removal_mode 0)
		)
		(polygon
			(pts
				(xy 425.91863 -183.31434) (xy 423.453052 -185.779918) (xy 420.913052 -185.779918) (xy 420.659052 -186.033918)
				(xy 420.659052 -186.414918) (xy 420.913052 -186.668918) (xy 427.611286 -186.668918) (xy 428.271686 -186.008518)
				(xy 428.271686 -183.43499) (xy 428.151036 -183.31434)
			)
		)
	)
	(zone
		(layer "F.Cu")
		(hatch none 0.5)
		(connect_pads
			(clearance 0)
		)
		(min_thickness 0.25)
		(keepout
			(tracks not_allowed)
			(vias allowed)
			(pads allowed)
			(copperpour not_allowed)
			(footprints allowed)
		)
		(placement
			(enabled no)
			(sheetname "")
		)
		(fill
			(thermal_gap 0.5)
			(thermal_bridge_width 0.5)
			(island_removal_mode 0)
		)
		(polygon
			(pts
				(arc
					(start 415.020252 -273.368516)
					(mid 414.639252 -272.987516)
					(end 414.258252 -273.368516)
				)
				(arc
					(start 414.258252 -274.511262)
					(mid 414.639125 -274.892516)
					(end 415.020252 -274.511516)
				)
				(xy 415.020252 -274.162266)
				(arc
					(start 414.791144 -274.162266)
					(mid 414.771787 -274.166099)
					(end 414.75533 -274.176998)
				)
				(arc
					(start 414.730184 -274.202144)
					(mid 414.719258 -274.21859)
					(end 414.715452 -274.237958)
				)
				(arc
					(start 414.715452 -274.255992)
					(mid 414.639252 -274.77816)
					(end 414.563052 -274.255992)
				)
				(xy 414.563052 -274.206462)
				(arc
					(start 414.5661 -274.203414)
					(mid 414.578535 -274.160251)
					(end 414.600136 -274.120864)
				)
				(xy 414.600136 -274.1168) (xy 414.669986 -274.04695)
				(arc
					(start 414.67405 -274.04695)
					(mid 414.713428 -274.025328)
					(end 414.7566 -274.012914)
				)
				(xy 414.759648 -274.009866) (xy 415.020252 -274.009866) (xy 415.020252 -273.870166) (xy 414.745424 -273.870166)
				(arc
					(start 414.742376 -273.867118)
					(mid 414.699213 -273.854683)
					(end 414.659826 -273.833082)
				)
				(xy 414.655762 -273.833082) (xy 414.600136 -273.777456)
				(arc
					(start 414.600136 -273.773392)
					(mid 414.578514 -273.734014)
					(end 414.5661 -273.690842)
				)
				(xy 414.563052 -273.687794)
				(arc
					(start 414.563052 -273.62404)
					(mid 414.639252 -273.101872)
					(end 414.715452 -273.62404)
				)
				(arc
					(start 414.715452 -273.656298)
					(mid 414.719285 -273.675655)
					(end 414.730184 -273.692112)
				)
				(arc
					(start 414.741106 -273.703034)
					(mid 414.757552 -273.71396)
					(end 414.77692 -273.717766)
				)
				(xy 415.020252 -273.717766)
			)
		)
	)
	(zone
		(net "P12V_A")
		(layer "F.Cu")
		(hatch none 0.5)
		(connect_pads
			(clearance 0.5)
		)
		(min_thickness 0.25)
		(fill yes
			(thermal_gap 0.5)
			(thermal_bridge_width 0.5)
			(island_removal_mode 0)
		)
		(polygon
			(pts
				(xy 460.8449 -56.428894) (xy 460.3369 -56.936894) (xy 460.3369 -60.365894) (xy 460.5909 -60.619894)
				(xy 463.8929 -60.619894) (xy 464.1469 -60.365894) (xy 464.1469 -58.333894) (xy 464.2739 -58.206894)
				(xy 464.6549 -58.206894) (xy 464.7819 -58.079894) (xy 464.7819 -56.555894) (xy 464.6549 -56.428894)
			)
		)
		(polygon
			(pts
				(xy 464.2485 -57.444894) (xy 464.0453 -57.444894) (xy 464.0453 -57.648094) (xy 464.2485 -57.648094)
			)
		)
		(polygon
			(pts
				(xy 464.2993 -56.987694) (xy 464.0961 -56.987694) (xy 464.0961 -57.190894) (xy 464.2993 -57.190894)
			)
		)
	)
	(zone
		(net "5V_PRE_22")
		(layer "F.Cu")
		(hatch none 0.5)
		(connect_pads
			(clearance 0.5)
		)
		(min_thickness 0.25)
		(fill yes
			(thermal_gap 0.5)
			(thermal_bridge_width 0.5)
			(island_removal_mode 0)
		)
		(polygon
			(pts
				(xy 455.6379 -174.984918) (xy 455.3839 -175.238918) (xy 455.3839 -177.778918) (xy 455.0029 -178.159918)
				(xy 452.4629 -178.159918) (xy 452.2089 -178.413918) (xy 452.2089 -178.794918) (xy 452.4629 -179.048918)
				(xy 455.7649 -179.048918) (xy 457.0349 -177.778918) (xy 457.0349 -175.238918) (xy 456.7809 -174.984918)
			)
		)
	)
	(zone
		(net "P5V_HDD0")
		(layer "F.Cu")
		(hatch none 0.5)
		(connect_pads
			(clearance 0.5)
		)
		(min_thickness 0.25)
		(fill yes
			(thermal_gap 0.5)
			(thermal_bridge_width 0.5)
			(island_removal_mode 0)
		)
		(polygon
			(pts
				(xy 19.668998 -286.682942) (xy 19.414998 -286.936942) (xy 19.414998 -289.222942) (xy 19.668998 -289.476942)
				(xy 19.668998 -291.508942) (xy 20.430998 -292.270942) (xy 20.430998 -293.032942) (xy 20.811998 -293.413942)
				(xy 21.192998 -293.413942) (xy 24.367998 -296.588942) (xy 31.225998 -296.588942) (xy 31.352998 -296.461942)
				(xy 31.352998 -294.683942) (xy 31.225998 -294.556942) (xy 26.145998 -294.556942) (xy 24.240998 -292.651942)
				(xy 23.351998 -292.651942) (xy 22.462998 -291.762942) (xy 22.462998 -289.222942) (xy 23.097998 -288.587942)
				(xy 23.097998 -286.936942) (xy 22.843998 -286.682942)
			)
		)
		(polygon
			(pts
				(xy 21.675598 -293.109142) (xy 21.472398 -293.109142) (xy 21.472398 -293.312342) (xy 21.675598 -293.312342)
			)
		)
		(polygon
			(pts
				(xy 21.675598 -292.245542) (xy 21.472398 -292.245542) (xy 21.472398 -292.448742) (xy 21.675598 -292.448742)
			)
		)
		(polygon
			(pts
				(xy 20.811998 -292.245542) (xy 20.608798 -292.245542) (xy 20.608798 -292.448742) (xy 20.811998 -292.448742)
			)
		)
	)
	(zone
		(layer "F.Cu")
		(hatch none 0.5)
		(connect_pads
			(clearance 0)
		)
		(min_thickness 0.25)
		(keepout
			(tracks allowed)
			(vias allowed)
			(pads allowed)
			(copperpour allowed)
			(footprints allowed)
		)
		(placement
			(enabled no)
			(sheetname "")
		)
		(fill
			(thermal_gap 0.5)
			(thermal_bridge_width 0.5)
			(island_removal_mode 0)
		)
		(polygon
			(pts
				(xy 143.781018 -135.947658) (xy 143.781018 -133.661658) (xy 146.371818 -133.661658) (xy 146.71421 -133.661658)
				(xy 148.666962 -131.708906) (xy 150.065232 -131.708906) (xy 150.170134 -131.813808) (xy 150.170134 -133.71068)
				(xy 148.186394 -135.69442) (xy 147.342352 -135.69442) (xy 147.089114 -135.947658) (xy 146.371818 -135.947658)
			)
		)
	)
	(zone
		(net "P12V_A")
		(layer "F.Cu")
		(hatch none 0.5)
		(connect_pads
			(clearance 0.5)
		)
		(min_thickness 0.25)
		(fill yes
			(thermal_gap 0.5)
			(thermal_bridge_width 0.5)
			(island_removal_mode 0)
		)
		(polygon
			(pts
				(xy 203.835254 -15.126716) (xy 203.530454 -15.431516) (xy 203.530454 -20.028916) (xy 203.835254 -20.333716)
				(xy 206.730854 -20.333716) (xy 206.984854 -20.079716) (xy 206.984854 -15.482316) (xy 206.629254 -15.126716)
			)
		)
	)
	(zone
		(net "GND")
		(layer "F.Cu")
		(hatch none 0.5)
		(connect_pads
			(clearance 0.5)
		)
		(min_thickness 0.25)
		(fill yes
			(thermal_gap 0.5)
			(thermal_bridge_width 0.5)
			(island_removal_mode 0)
		)
		(polygon
			(pts
				(xy 279.335738 -228.909118) (xy 279.081738 -229.163118) (xy 279.081738 -233.760518) (xy 279.472898 -234.151678)
				(xy 282.195778 -234.151678) (xy 282.536138 -233.811318) (xy 282.536138 -229.213918) (xy 282.231338 -228.909118)
			)
		)
	)
	(zone
		(layer "F.Cu")
		(hatch none 0.5)
		(connect_pads
			(clearance 0)
		)
		(min_thickness 0.25)
		(keepout
			(tracks allowed)
			(vias allowed)
			(pads allowed)
			(copperpour allowed)
			(footprints allowed)
		)
		(placement
			(enabled no)
			(sheetname "")
		)
		(fill
			(thermal_gap 0.5)
			(thermal_bridge_width 0.5)
			(island_removal_mode 0)
		)
		(polygon
			(pts
				(xy 245.429278 -393.099544) (xy 245.429278 -391.483596) (xy 248.12244 -391.483596) (xy 248.12244 -393.099544)
			)
		)
	)
	(zone
		(net "P12V_A_COMP")
		(layer "F.Cu")
		(hatch none 0.5)
		(connect_pads
			(clearance 0.5)
		)
		(min_thickness 0.25)
		(fill yes
			(thermal_gap 0.5)
			(thermal_bridge_width 0.5)
			(island_removal_mode 0)
		)
		(polygon
			(pts
				(xy 220.230954 -177.421794) (xy 219.879164 -177.773584) (xy 219.879164 -179.570634) (xy 222.879666 -184.352438)
				(xy 237.122462 -184.352438) (xy 239.687354 -181.787546) (xy 239.687354 -179.91709) (xy 239.195864 -179.4256)
				(xy 235.1532 -179.4256) (xy 233.149394 -177.421794)
			)
		)
	)
	(zone
		(layer "F.Cu")
		(hatch none 0.5)
		(connect_pads
			(clearance 0)
		)
		(min_thickness 0.25)
		(keepout
			(tracks allowed)
			(vias allowed)
			(pads allowed)
			(copperpour allowed)
			(footprints allowed)
		)
		(placement
			(enabled no)
			(sheetname "")
		)
		(fill
			(thermal_gap 0.5)
			(thermal_bridge_width 0.5)
			(island_removal_mode 0)
		)
		(polygon
			(pts
				(xy 221.9452 -210.9724) (xy 221.9452 -207.4418) (xy 225.2726 -207.4418) (xy 225.2726 -210.9724)
			)
		)
	)
	(zone
		(net "P5V_HDD28")
		(layer "F.Cu")
		(hatch none 0.5)
		(connect_pads
			(clearance 0.5)
		)
		(min_thickness 0.25)
		(fill yes
			(thermal_gap 0.5)
			(thermal_bridge_width 0.5)
			(island_removal_mode 0)
		)
		(polygon
			(pts
				(xy 145.868898 -56.682894) (xy 145.614898 -56.936894) (xy 145.614898 -59.222894) (xy 145.868898 -59.476894)
				(xy 145.868898 -61.508894) (xy 146.630898 -62.270894) (xy 146.630898 -63.032894) (xy 147.011898 -63.413894)
				(xy 147.392898 -63.413894) (xy 150.567898 -66.588894) (xy 157.425898 -66.588894) (xy 157.552898 -66.461894)
				(xy 157.552898 -64.683894) (xy 157.425898 -64.556894) (xy 152.345898 -64.556894) (xy 150.440898 -62.651894)
				(xy 149.551898 -62.651894) (xy 148.662898 -61.762894) (xy 148.662898 -59.222894) (xy 149.297898 -58.587894)
				(xy 149.297898 -56.936894) (xy 149.043898 -56.682894)
			)
		)
		(polygon
			(pts
				(xy 147.875498 -63.109094) (xy 147.672298 -63.109094) (xy 147.672298 -63.312294) (xy 147.875498 -63.312294)
			)
		)
		(polygon
			(pts
				(xy 147.875498 -62.245494) (xy 147.672298 -62.245494) (xy 147.672298 -62.448694) (xy 147.875498 -62.448694)
			)
		)
		(polygon
			(pts
				(xy 147.011898 -62.245494) (xy 146.808698 -62.245494) (xy 146.808698 -62.448694) (xy 147.011898 -62.448694)
			)
		)
	)
	(zone
		(net "P12V_A")
		(layer "F.Cu")
		(hatch none 0.5)
		(connect_pads
			(clearance 0.5)
		)
		(min_thickness 0.25)
		(fill yes
			(thermal_gap 0.5)
			(thermal_bridge_width 0.5)
			(island_removal_mode 0)
		)
		(polygon
			(pts
				(xy 429.295052 -56.428894) (xy 428.787052 -56.936894) (xy 428.787052 -60.365894) (xy 429.041052 -60.619894)
				(xy 432.343052 -60.619894) (xy 432.597052 -60.365894) (xy 432.597052 -58.333894) (xy 432.724052 -58.206894)
				(xy 433.105052 -58.206894) (xy 433.232052 -58.079894) (xy 433.232052 -56.555894) (xy 433.105052 -56.428894)
			)
		)
		(polygon
			(pts
				(xy 432.698652 -57.444894) (xy 432.495452 -57.444894) (xy 432.495452 -57.648094) (xy 432.698652 -57.648094)
			)
		)
		(polygon
			(pts
				(xy 432.749452 -56.987694) (xy 432.546252 -56.987694) (xy 432.546252 -57.190894) (xy 432.749452 -57.190894)
			)
		)
	)
	(zone
		(net "12V_PRE_3")
		(layer "F.Cu")
		(hatch none 0.5)
		(connect_pads
			(clearance 0.5)
		)
		(min_thickness 0.25)
		(fill yes
			(thermal_gap 0.5)
			(thermal_bridge_width 0.5)
			(island_removal_mode 0)
		)
		(polygon
			(pts
				(xy 117.983 -293.4462) (xy 117.8179 -293.6113) (xy 117.8179 -297.6499) (xy 121.938542 -301.770542)
				(xy 125.9586 -301.770542) (xy 126.1618 -301.567342) (xy 126.1618 -300.906942) (xy 126.0094 -300.754542)
				(xy 122.878342 -300.754542) (xy 122.346974 -300.223174) (xy 122.346974 -298.699428) (xy 119.925846 -296.2783)
				(xy 119.925846 -293.814246) (xy 119.5578 -293.4462)
			)
		)
	)
	(zone
		(net "P5V_HDD5")
		(layer "F.Cu")
		(hatch none 0.5)
		(connect_pads
			(clearance 0.5)
		)
		(min_thickness 0.25)
		(fill yes
			(thermal_gap 0.5)
			(thermal_bridge_width 0.5)
			(island_removal_mode 0)
		)
		(polygon
			(pts
				(xy 177.419 -286.682942) (xy 177.165 -286.936942) (xy 177.165 -289.222942) (xy 177.419 -289.476942)
				(xy 177.419 -291.508942) (xy 178.181 -292.270942) (xy 178.181 -293.032942) (xy 178.562 -293.413942)
				(xy 178.943 -293.413942) (xy 182.118 -296.588942) (xy 188.976 -296.588942) (xy 189.103 -296.461942)
				(xy 189.103 -294.683942) (xy 188.976 -294.556942) (xy 183.896 -294.556942) (xy 181.991 -292.651942)
				(xy 181.102 -292.651942) (xy 180.213 -291.762942) (xy 180.213 -289.222942) (xy 180.848 -288.587942)
				(xy 180.848 -286.936942) (xy 180.594 -286.682942)
			)
		)
		(polygon
			(pts
				(xy 179.4256 -293.109142) (xy 179.2224 -293.109142) (xy 179.2224 -293.312342) (xy 179.4256 -293.312342)
			)
		)
		(polygon
			(pts
				(xy 179.4256 -292.245542) (xy 179.2224 -292.245542) (xy 179.2224 -292.448742) (xy 179.4256 -292.448742)
			)
		)
		(polygon
			(pts
				(xy 178.562 -292.245542) (xy 178.3588 -292.245542) (xy 178.3588 -292.448742) (xy 178.562 -292.448742)
			)
		)
	)
	(zone
		(layer "F.Cu")
		(hatch none 0.5)
		(connect_pads
			(clearance 0)
		)
		(min_thickness 0.25)
		(keepout
			(tracks allowed)
			(vias allowed)
			(pads allowed)
			(copperpour allowed)
			(footprints not_allowed)
		)
		(placement
			(enabled no)
			(sheetname "")
		)
		(fill
			(thermal_gap 0.5)
			(thermal_bridge_width 0.5)
			(island_removal_mode 0)
		)
		(polygon
			(pts
				(arc
					(start 323.674994 -322.799964)
					(mid 330.67498 -315.799978)
					(end 337.674966 -322.799964)
				)
				(arc
					(start 337.674966 -328.799952)
					(mid 330.67498 -335.799938)
					(end 323.674994 -328.799952)
				)
			)
		)
	)
	(zone
		(net "GND")
		(layer "F.Cu")
		(hatch none 0.5)
		(connect_pads
			(clearance 0.5)
		)
		(min_thickness 0.25)
		(fill yes
			(thermal_gap 0.5)
			(thermal_bridge_width 0.5)
			(island_removal_mode 0)
		)
		(polygon
			(pts
				(xy 141.6558 -187.8838) (xy 141.6558 -188.215016) (xy 143.473424 -196.41312) (xy 146.685 -201.454512)
				(xy 146.685 -201.4474) (xy 149.2758 -201.4474)
				(arc
					(start 149.2758 -195.161662)
					(mid 148.533421 -194.859045)
					(end 147.864322 -194.417442)
				)
				(xy 146.197574 -194.417442) (xy 146.197574 -191.878204) (xy 146.082512 -191.763142) (xy 145.626074 -191.763142)
				(xy 145.626074 -191.306704) (xy 142.20317 -187.8838)
			)
		)
	)
	(zone
		(layer "F.Cu")
		(hatch none 0.5)
		(connect_pads
			(clearance 0)
		)
		(min_thickness 0.25)
		(keepout
			(tracks allowed)
			(vias allowed)
			(pads allowed)
			(copperpour allowed)
			(footprints not_allowed)
		)
		(placement
			(enabled no)
			(sheetname "")
		)
		(fill
			(thermal_gap 0.5)
			(thermal_bridge_width 0.5)
			(island_removal_mode 0)
		)
		(polygon
			(pts
				(xy 284.699964 -230.229918) (xy 284.699964 -239.62995) (xy 276.999954 -239.62995) (xy 276.999954 -230.229918)
			)
		)
	)
	(zone
		(net "GND")
		(layer "F.Cu")
		(hatch none 0.5)
		(connect_pads
			(clearance 0.5)
		)
		(min_thickness 0.25)
		(fill yes
			(thermal_gap 0.5)
			(thermal_bridge_width 0.5)
			(island_removal_mode 0)
		)
		(polygon
			(pts
				(xy 11.97356 -184.193942)
				(arc
					(start 11.97356 -191.690498)
					(mid 12.426235 -192.497781)
					(end 12.688316 -193.38544)
				)
				(xy 22.196806 -202.89393) (xy 22.196806 -204.4192)
				(arc
					(start 23.045166 -204.4192)
					(mid 24.206512 -201.972667)
					(end 25.938988 -199.891142)
				)
				(xy 23.093934 -199.891142)
				(arc
					(start 23.093934 -195.166996)
					(mid 22.341835 -194.863437)
					(end 21.664422 -194.417442)
				)
				(xy 19.997674 -194.417442) (xy 19.997674 -191.878204) (xy 19.882612 -191.763142) (xy 19.426174 -191.763142)
				(xy 19.426174 -191.306704) (xy 12.313412 -184.193942)
			)
		)
	)
	(zone
		(layer "F.Cu")
		(hatch none 0.5)
		(connect_pads
			(clearance 0)
		)
		(min_thickness 0.25)
		(keepout
			(tracks not_allowed)
			(vias allowed)
			(pads allowed)
			(copperpour not_allowed)
			(footprints allowed)
		)
		(placement
			(enabled no)
			(sheetname "")
		)
		(fill
			(thermal_gap 0.5)
			(thermal_bridge_width 0.5)
			(island_removal_mode 0)
		)
		(polygon
			(pts
				(arc
					(start 419.770052 -47.178722)
					(mid 419.389179 -46.797468)
					(end 419.008052 -47.178468)
				)
				(arc
					(start 419.008052 -48.321468)
					(mid 419.389052 -48.702468)
					(end 419.770052 -48.321468)
				)
				(xy 419.770052 -47.972218)
				(arc
					(start 419.516306 -47.972218)
					(mid 419.480205 -47.987171)
					(end 419.465252 -48.023272)
				)
				(arc
					(start 419.465252 -48.065944)
					(mid 419.389052 -48.588112)
					(end 419.312852 -48.065944)
				)
				(xy 419.312852 -47.991776)
				(arc
					(start 419.3159 -47.988728)
					(mid 419.372508 -47.879474)
					(end 419.481762 -47.822866)
				)
				(xy 419.48481 -47.819818) (xy 419.770052 -47.819818) (xy 419.770052 -47.680118) (xy 419.48481 -47.680118)
				(arc
					(start 419.481762 -47.67707)
					(mid 419.372508 -47.620462)
					(end 419.3159 -47.511208)
				)
				(xy 419.312852 -47.50816)
				(arc
					(start 419.312852 -47.433992)
					(mid 419.389052 -46.911824)
					(end 419.465252 -47.433992)
				)
				(arc
					(start 419.465252 -47.476664)
					(mid 419.480205 -47.512765)
					(end 419.516306 -47.527718)
				)
				(xy 419.770052 -47.527718)
			)
		)
	)
	(zone
		(net "GND")
		(layer "F.Cu")
		(hatch none 0.5)
		(connect_pads
			(clearance 0.5)
		)
		(min_thickness 0.25)
		(fill yes
			(thermal_gap 0.5)
			(thermal_bridge_width 0.5)
			(island_removal_mode 0)
		)
		(polygon
			(pts
				(xy 203.010516 -9.939528) (xy 202.706732 -10.243312) (xy 202.706732 -13.287502) (xy 202.920346 -13.501116)
				(xy 206.01813 -13.501116) (xy 206.196438 -13.322808) (xy 206.196438 -10.13714) (xy 205.998826 -9.939528)
			)
		)
	)
	(zone
		(net "5V_PRE_27")
		(layer "F.Cu")
		(hatch none 0.5)
		(connect_pads
			(clearance 0.5)
		)
		(min_thickness 0.25)
		(fill yes
			(thermal_gap 0.5)
			(thermal_bridge_width 0.5)
			(island_removal_mode 0)
		)
		(polygon
			(pts
				(xy 117.671596 -60.071) (xy 117.493796 -60.2488) (xy 117.493796 -61.508894) (xy 117.620796 -61.635894)
				(xy 118.890796 -61.635894) (xy 121.430796 -64.175894) (xy 125.875796 -64.175894) (xy 126.002796 -64.048894)
				(xy 126.002796 -63.286894) (xy 125.875796 -63.159894) (xy 122.36069 -63.159894) (xy 119.271796 -60.071)
			)
		)
	)
	(zone
		(net "P12V_A")
		(layer "F.Cu")
		(hatch none 0.5)
		(connect_pads
			(clearance 0.5)
		)
		(min_thickness 0.25)
		(fill yes
			(thermal_gap 0.5)
			(thermal_bridge_width 0.5)
			(island_removal_mode 0)
		)
		(polygon
			(pts
				(xy 366.195102 -56.428894) (xy 365.687102 -56.936894) (xy 365.687102 -60.365894) (xy 365.941102 -60.619894)
				(xy 369.243102 -60.619894) (xy 369.497102 -60.365894) (xy 369.497102 -58.333894) (xy 369.624102 -58.206894)
				(xy 370.005102 -58.206894) (xy 370.132102 -58.079894) (xy 370.132102 -56.555894) (xy 370.005102 -56.428894)
			)
		)
		(polygon
			(pts
				(xy 369.598702 -57.444894) (xy 369.395502 -57.444894) (xy 369.395502 -57.648094) (xy 369.598702 -57.648094)
			)
		)
		(polygon
			(pts
				(xy 369.649502 -56.987694) (xy 369.446302 -56.987694) (xy 369.446302 -57.190894) (xy 369.649502 -57.190894)
			)
		)
	)
	(zone
		(layer "F.Cu")
		(hatch none 0.5)
		(connect_pads
			(clearance 0)
		)
		(min_thickness 0.25)
		(keepout
			(tracks not_allowed)
			(vias allowed)
			(pads allowed)
			(copperpour not_allowed)
			(footprints allowed)
		)
		(placement
			(enabled no)
			(sheetname "")
		)
		(fill
			(thermal_gap 0.5)
			(thermal_bridge_width 0.5)
			(island_removal_mode 0)
		)
		(polygon
			(pts
				(arc
					(start 238.374936 -138.149584)
					(mid 238.699802 -137.174986)
					(end 237.725204 -136.85012)
				)
				(xy 237.723934 -136.847834) (xy 235.724192 -137.847832) (xy 235.724192 -137.848086)
				(arc
					(start 235.725208 -137.850118)
					(mid 235.400342 -138.824716)
					(end 236.37494 -139.149582)
				)
				(xy 236.37621 -139.151868)
				(arc
					(start 237.296198 -138.691874)
					(mid 237.203981 -138.635727)
					(end 237.12551 -138.561572)
				)
				(xy 237.123224 -138.561318) (xy 236.889798 -138.239754)
				(arc
					(start 236.872018 -138.222228)
					(mid 236.842877 -138.216851)
					(end 236.814106 -138.224006)
				)
				(arc
					(start 236.573568 -138.344402)
					(mid 235.561744 -138.744276)
					(end 236.488224 -138.173968)
				)
				(xy 236.764068 -138.036046)
				(arc
					(start 236.768894 -138.03757)
					(mid 236.887356 -138.029621)
					(end 236.996986 -138.075162)
				)
				(xy 237.001812 -138.075162) (xy 237.028482 -138.101832) (xy 237.030006 -138.103102) (xy 237.057692 -138.131042)
				(xy 237.057692 -138.14679)
				(arc
					(start 237.254034 -138.4173)
					(mid 237.368863 -138.515324)
					(end 237.515654 -138.55065)
				)
				(xy 237.578646 -138.55065) (xy 237.781846 -138.44905) (xy 237.477046 -138.44905)
				(arc
					(start 237.472728 -138.444732)
					(mid 237.415515 -138.424919)
					(end 237.365794 -138.390376)
				)
				(xy 237.359698 -138.38936) (xy 237.336584 -138.35761) (xy 237.336584 -138.357356) (xy 237.181898 -138.144758)
				(xy 237.159292 -138.122152) (xy 237.159292 -138.11377) (xy 237.154212 -138.106912)
				(arc
					(start 237.156244 -138.094212)
					(mid 237.153612 -137.930987)
					(end 237.2487 -137.798302)
				)
				(xy 237.250224 -137.793476)
				(arc
					(start 237.526576 -137.6553)
					(mid 238.5384 -137.255426)
					(end 237.61192 -137.825734)
				)
				(arc
					(start 237.370874 -137.94613)
					(mid 237.33803 -137.980805)
					(end 237.335314 -138.028426)
				)
				(xy 237.349792 -138.043158) (xy 237.349792 -138.051794)
				(arc
					(start 237.490508 -138.245596)
					(mid 237.501781 -138.255165)
					(end 237.516162 -138.25855)
				)
				(xy 238.162846 -138.25855) (xy 238.376206 -138.15187)
			)
		)
	)
	(zone
		(layer "F.Cu")
		(hatch none 0.5)
		(connect_pads
			(clearance 0)
		)
		(min_thickness 0.25)
		(keepout
			(tracks allowed)
			(vias allowed)
			(pads allowed)
			(copperpour allowed)
			(footprints allowed)
		)
		(placement
			(enabled no)
			(sheetname "")
		)
		(fill
			(thermal_gap 0.5)
			(thermal_bridge_width 0.5)
			(island_removal_mode 0)
		)
		(polygon
			(pts
				(xy 226.7458 -239.8268) (xy 226.7458 -236.22) (xy 228.092 -236.22) (xy 228.092 -239.8268)
			)
		)
	)
	(zone
		(net "P12V_B")
		(layer "F.Cu")
		(hatch none 0.5)
		(connect_pads
			(clearance 0.5)
		)
		(min_thickness 0.25)
		(fill yes
			(thermal_gap 0.5)
			(thermal_bridge_width 0.5)
			(island_removal_mode 0)
		)
		(polygon
			(pts
				(xy 347.779848 -146.631152) (xy 347.472 -146.939) (xy 347.472 -152.654) (xy 348.107 -153.289) (xy 353.031298 -153.289)
				(xy 353.632262 -152.688036) (xy 353.632262 -148.79828) (xy 352.936556 -148.102574) (xy 352.936556 -146.703034)
				(xy 352.864674 -146.631152)
			)
		)
		(polygon
			(pts
				(xy 349.972122 -147.096226) (xy 349.768922 -147.096226) (xy 349.768922 -147.299426) (xy 349.972122 -147.299426)
			)
		)
		(polygon
			(pts
				(xy 349.362522 -147.096226) (xy 349.159322 -147.096226) (xy 349.159322 -147.299426) (xy 349.362522 -147.299426)
			)
		)
	)
	(zone
		(net "12V_PRE_30")
		(layer "F.Cu")
		(hatch none 0.5)
		(connect_pads
			(clearance 0.5)
		)
		(min_thickness 0.25)
		(fill yes
			(thermal_gap 0.5)
			(thermal_bridge_width 0.5)
			(island_removal_mode 0)
		)
		(polygon
			(pts
				(xy 331.268578 -68.314316) (xy 328.803 -70.779894) (xy 326.263 -70.779894) (xy 326.009 -71.033894)
				(xy 326.009 -71.414894) (xy 326.263 -71.668894) (xy 332.961234 -71.668894) (xy 333.621634 -71.008494)
				(xy 333.621634 -68.434966) (xy 333.500984 -68.314316)
			)
		)
	)
	(zone
		(net "P5V_USB_A")
		(layer "F.Cu")
		(hatch none 0.5)
		(connect_pads
			(clearance 0.5)
		)
		(min_thickness 0.25)
		(fill yes
			(thermal_gap 0.5)
			(thermal_bridge_width 0.5)
			(island_removal_mode 0)
		)
		(polygon
			(pts
				(xy 257.8354 32.4104) (xy 257.7338 32.3088) (xy 257.7338 28.321) (xy 258.1021 27.9527) (xy 258.1021 26.4033)
				(xy 259.7785 24.7269) (xy 259.7785 18.6563) (xy 261.239 17.1958) (xy 261.239 15.0622) (xy 261.4676 14.8336)
				(xy 262.3058 14.8336) (xy 262.382 14.9098) (xy 262.382 16.6624) (xy 262.1534 16.891) (xy 262.1534 25.6794)
				(xy 261.2136 26.6192) (xy 261.2136 26.6446) (xy 258.590796 29.267404) (xy 258.590796 30.371796)
				(xy 258.572 30.390592) (xy 258.572 32.2834) (xy 258.445 32.4104)
			)
		)
		(polygon
			(pts
				(xy 261.648448 17.756632) (xy 261.445248 17.756632) (xy 261.445248 17.553432) (xy 261.648448 17.553432)
			)
		)
		(polygon
			(pts
				(xy 261.648448 18.366232) (xy 261.445248 18.366232) (xy 261.445248 18.163032) (xy 261.648448 18.163032)
			)
		)
	)
	(zone
		(layer "F.Cu")
		(hatch none 0.5)
		(connect_pads
			(clearance 0)
		)
		(min_thickness 0.25)
		(keepout
			(tracks allowed)
			(vias allowed)
			(pads allowed)
			(copperpour allowed)
			(footprints not_allowed)
		)
		(placement
			(enabled no)
			(sheetname "")
		)
		(fill
			(thermal_gap 0.5)
			(thermal_bridge_width 0.5)
			(island_removal_mode 0)
		)
		(polygon
			(pts
				(xy 312.675016 -20.200112) (xy 334.674972 -20.200112) (xy 334.674972 0) (xy 312.675016 0)
			)
		)
	)
	(zone
		(layer "F.Cu")
		(hatch none 0.5)
		(connect_pads
			(clearance 0)
		)
		(min_thickness 0.25)
		(keepout
			(tracks allowed)
			(vias allowed)
			(pads allowed)
			(copperpour allowed)
			(footprints not_allowed)
		)
		(placement
			(enabled no)
			(sheetname "")
		)
		(fill
			(thermal_gap 0.5)
			(thermal_bridge_width 0.5)
			(island_removal_mode 0)
		)
		(polygon
			(pts
				(arc
					(start 244.10924 6.763766)
					(mid 237.212541 5.928112)
					(end 233.499914 11.800078)
				)
				(arc
					(start 233.499914 17.800066)
					(mid 240.000028 24.30018)
					(end 246.499888 17.800066)
				)
				(arc
					(start 246.499888 11.800078)
					(mid 246.426372 10.824473)
					(end 246.20728 9.870948)
				)
				(arc
					(start 246.20728 9.870948)
					(mid 244.742061 8.598378)
					(end 244.10924 6.763766)
				)
			)
		)
	)
	(zone
		(net "P5V_A_4")
		(layer "F.Cu")
		(hatch none 0.5)
		(connect_pads
			(clearance 0.5)
		)
		(min_thickness 0.25)
		(fill yes
			(thermal_gap 0.5)
			(thermal_bridge_width 0.5)
			(island_removal_mode 0)
		)
		(polygon
			(pts
				(xy 473.385896 -165.449504) (xy 473.244926 -165.590474) (xy 473.244926 -168.380918) (xy 473.498926 -168.634918)
				(xy 478.197926 -168.634918) (xy 478.451926 -168.380918) (xy 478.451926 -165.599872) (xy 478.301558 -165.449504)
			)
		)
	)
	(zone
		(net "P5V_A_2")
		(layer "F.Cu")
		(hatch none 0.5)
		(connect_pads
			(clearance 0.5)
		)
		(min_thickness 0.25)
		(fill yes
			(thermal_gap 0.5)
			(thermal_bridge_width 0.5)
			(island_removal_mode 0)
		)
		(polygon
			(pts
				(xy 176.149 -50.840894) (xy 175.895 -51.094894) (xy 175.895 -53.380894) (xy 176.149 -53.634894)
				(xy 180.848 -53.634894) (xy 181.102 -53.380894) (xy 181.102 -51.094894) (xy 180.848 -50.840894)
			)
		)
	)
	(zone
		(net "P5V_A_2")
		(layer "F.Cu")
		(hatch none 0.5)
		(connect_pads
			(clearance 0.5)
		)
		(min_thickness 0.25)
		(fill yes
			(thermal_gap 0.5)
			(thermal_bridge_width 0.5)
			(island_removal_mode 0)
		)
		(polygon
			(pts
				(xy 81.498948 -50.840894) (xy 81.244948 -51.094894) (xy 81.244948 -53.380894) (xy 81.498948 -53.634894)
				(xy 86.197948 -53.634894) (xy 86.451948 -53.380894) (xy 86.451948 -51.094894) (xy 86.197948 -50.840894)
			)
		)
	)
	(zone
		(layer "F.Cu")
		(hatch none 0.5)
		(connect_pads
			(clearance 0)
		)
		(min_thickness 0.25)
		(keepout
			(tracks allowed)
			(vias allowed)
			(pads allowed)
			(copperpour allowed)
			(footprints not_allowed)
		)
		(placement
			(enabled no)
			(sheetname "")
		)
		(fill
			(thermal_gap 0.5)
			(thermal_bridge_width 0.5)
			(island_removal_mode 0)
		)
		(polygon
			(pts
				(arc
					(start 0.100076 -5.500116)
					(mid 3.850132 -1.75006)
					(end 7.599934 -5.500116)
				)
				(arc
					(start 7.599934 -5.500116)
					(mid 3.850132 -9.249918)
					(end 0.100076 -5.500116)
				)
			)
		)
	)
	(zone
		(layer "F.Cu")
		(hatch none 0.5)
		(connect_pads
			(clearance 0)
		)
		(min_thickness 0.25)
		(keepout
			(tracks allowed)
			(vias allowed)
			(pads allowed)
			(copperpour allowed)
			(footprints not_allowed)
		)
		(placement
			(enabled no)
			(sheetname "")
		)
		(fill
			(thermal_gap 0.5)
			(thermal_bridge_width 0.5)
			(island_removal_mode 0)
		)
		(polygon
			(pts
				(xy 256.70002 -350.19996) (xy 231.70007 -350.19996) (xy 231.70007 -376.199908) (xy 256.70002 -376.199908)
			)
		)
	)
	(zone
		(layer "F.Cu")
		(hatch none 0.5)
		(connect_pads
			(clearance 0)
		)
		(min_thickness 0.25)
		(keepout
			(tracks not_allowed)
			(vias allowed)
			(pads allowed)
			(copperpour not_allowed)
			(footprints allowed)
		)
		(placement
			(enabled no)
			(sheetname "")
		)
		(fill
			(thermal_gap 0.5)
			(thermal_bridge_width 0.5)
			(island_removal_mode 0)
		)
		(polygon
			(pts
				(arc
					(start 419.770052 -162.178746)
					(mid 419.389179 -161.797492)
					(end 419.008052 -162.178492)
				)
				(arc
					(start 419.008052 -163.321492)
					(mid 419.389052 -163.702492)
					(end 419.770052 -163.321492)
				)
				(xy 419.770052 -162.972242)
				(arc
					(start 419.516306 -162.972242)
					(mid 419.480205 -162.987195)
					(end 419.465252 -163.023296)
				)
				(arc
					(start 419.465252 -163.065968)
					(mid 419.389052 -163.588136)
					(end 419.312852 -163.065968)
				)
				(xy 419.312852 -162.9918)
				(arc
					(start 419.3159 -162.988752)
					(mid 419.372508 -162.879498)
					(end 419.481762 -162.82289)
				)
				(xy 419.48481 -162.819842) (xy 419.770052 -162.819842) (xy 419.770052 -162.680142) (xy 419.48481 -162.680142)
				(arc
					(start 419.481762 -162.677094)
					(mid 419.372508 -162.620486)
					(end 419.3159 -162.511232)
				)
				(xy 419.312852 -162.508184)
				(arc
					(start 419.312852 -162.434016)
					(mid 419.389052 -161.911848)
					(end 419.465252 -162.434016)
				)
				(arc
					(start 419.465252 -162.476688)
					(mid 419.480205 -162.512789)
					(end 419.516306 -162.527742)
				)
				(xy 419.770052 -162.527742)
			)
		)
	)
	(zone
		(layer "F.Cu")
		(hatch none 0.5)
		(connect_pads
			(clearance 0)
		)
		(min_thickness 0.25)
		(keepout
			(tracks allowed)
			(vias allowed)
			(pads allowed)
			(copperpour allowed)
			(footprints not_allowed)
		)
		(placement
			(enabled no)
			(sheetname "")
		)
		(fill
			(thermal_gap 0.5)
			(thermal_bridge_width 0.5)
			(island_removal_mode 0)
		)
		(polygon
			(pts
				(arc
					(start 403.349968 -164.200078)
					(mid 407.100024 -160.450022)
					(end 410.85008 -164.200078)
				)
				(arc
					(start 410.85008 -164.200078)
					(mid 407.100024 -167.950134)
					(end 403.349968 -164.200078)
				)
			)
		)
	)
	(zone
		(layer "F.Cu")
		(hatch none 0.5)
		(connect_pads
			(clearance 0)
		)
		(min_thickness 0.25)
		(keepout
			(tracks allowed)
			(vias allowed)
			(pads allowed)
			(copperpour allowed)
			(footprints not_allowed)
		)
		(placement
			(enabled no)
			(sheetname "")
		)
		(fill
			(thermal_gap 0.5)
			(thermal_bridge_width 0.5)
			(island_removal_mode 0)
		)
		(polygon
			(pts
				(arc
					(start 186.149996 -208.499964)
					(mid 182.39994 -212.25002)
					(end 178.649884 -208.499964)
				)
				(arc
					(start 178.649884 -208.499964)
					(mid 182.39994 -204.749908)
					(end 186.149996 -208.499964)
				)
			)
		)
	)
	(zone
		(net "P12V_B_COMP")
		(layer "F.Cu")
		(hatch none 0.5)
		(connect_pads
			(clearance 0.5)
		)
		(min_thickness 0.25)
		(fill yes
			(thermal_gap 0.5)
			(thermal_bridge_width 0.5)
			(island_removal_mode 0)
		)
		(polygon
			(pts
				(xy 277.2156 0.762) (xy 276.479 0.0254) (xy 276.479 -7.9756) (xy 277.7998 -9.2964) (xy 286.7914 -9.2964)
				(xy 289.941 -12.446) (xy 289.941 -22.606) (xy 290.449 -23.114) (xy 301.879 -23.114) (xy 302.721772 -22.271228)
				(xy 302.721772 -10.43432) (xy 291.525452 0.762)
			)
		)
	)
	(zone
		(net "GND")
		(layer "F.Cu")
		(hatch none 0.5)
		(connect_pads
			(clearance 0.5)
		)
		(min_thickness 0.25)
		(fill yes
			(thermal_gap 0.5)
			(thermal_bridge_width 0.5)
			(island_removal_mode 0)
		)
		(polygon
			(pts
				(xy 203.5556 -302.3362) (xy 203.3016 -302.5902) (xy 203.3016 -307.1876) (xy 203.6572 -307.5432)
				(xy 206.4512 -307.5432) (xy 206.756 -307.2384) (xy 206.756 -302.641) (xy 206.4512 -302.3362)
			)
		)
	)
	(zone
		(net "MB1_P12V_B_R")
		(layer "F.Cu")
		(hatch none 0.5)
		(connect_pads
			(clearance 0.5)
		)
		(min_thickness 0.25)
		(fill yes
			(thermal_gap 0.5)
			(thermal_bridge_width 0.5)
			(island_removal_mode 0)
		)
		(polygon
			(pts
				(xy 345.3384 -138.6586) (xy 344.932 -139.065) (xy 344.932 -144.399) (xy 345.3892 -144.8562) (xy 350.2152 -144.8562)
				(xy 350.52 -145.161) (xy 350.52 -146.169634) (xy 350.610932 -146.260566) (xy 352.94697 -146.260566)
				(xy 352.963988 -146.243548) (xy 352.963988 -144.74698) (xy 353.01936 -144.691608) (xy 354.926392 -144.691608)
				(xy 355.092 -144.526) (xy 355.092 -138.938) (xy 354.8126 -138.6586)
			)
		)
	)
	(zone
		(layer "F.Cu")
		(hatch none 0.5)
		(connect_pads
			(clearance 0)
		)
		(min_thickness 0.25)
		(keepout
			(tracks allowed)
			(vias allowed)
			(pads allowed)
			(copperpour allowed)
			(footprints not_allowed)
		)
		(placement
			(enabled no)
			(sheetname "")
		)
		(fill
			(thermal_gap 0.5)
			(thermal_bridge_width 0.5)
			(island_removal_mode 0)
		)
		(polygon
			(pts
				(arc
					(start 462.7499 -269.999968)
					(mid 467.499954 -265.249914)
					(end 472.250008 -269.999968)
				)
				(arc
					(start 472.250008 -269.999968)
					(mid 467.499954 -274.750022)
					(end 462.7499 -269.999968)
				)
			)
		)
	)
	(zone
		(layer "F.Cu")
		(hatch none 0.5)
		(connect_pads
			(clearance 0)
		)
		(min_thickness 0.25)
		(keepout
			(tracks allowed)
			(vias allowed)
			(pads allowed)
			(copperpour allowed)
			(footprints not_allowed)
		)
		(placement
			(enabled no)
			(sheetname "")
		)
		(fill
			(thermal_gap 0.5)
			(thermal_bridge_width 0.5)
			(island_removal_mode 0)
		)
		(polygon
			(pts
				(arc
					(start 246.20728 9.870948)
					(mid 248.144307 10.238407)
					(end 250.000008 9.572498)
				)
				(xy 250.000008 24.800052) (xy 230.000048 24.800052)
				(arc
					(start 230.000048 10.247122)
					(mid 232.554147 9.098159)
					(end 233.59999 6.500114)
				)
				(arc
					(start 233.59999 6.500114)
					(mid 233.30119 5.03323)
					(end 232.452418 3.800094)
				)
				(arc
					(start 245.247668 3.800094)
					(mid 244.398882 5.033224)
					(end 244.100096 6.500114)
				)
				(arc
					(start 244.100096 6.500114)
					(mid 244.102345 6.632021)
					(end 244.10924 6.763766)
				)
				(arc
					(start 244.10924 6.763766)
					(mid 237.212541 5.928112)
					(end 233.499914 11.800078)
				)
				(arc
					(start 233.499914 17.800066)
					(mid 240.000028 24.30018)
					(end 246.499888 17.800066)
				)
				(arc
					(start 246.499888 11.800078)
					(mid 246.426372 10.824473)
					(end 246.20728 9.870948)
				)
			)
		)
	)
	(zone
		(net "12V_PRE_5")
		(layer "F.Cu")
		(hatch none 0.5)
		(connect_pads
			(clearance 0.5)
		)
		(min_thickness 0.25)
		(fill yes
			(thermal_gap 0.5)
			(thermal_bridge_width 0.5)
			(island_removal_mode 0)
		)
		(polygon
			(pts
				(xy 177.419 -293.794942) (xy 177.292 -293.921942) (xy 177.292 -295.445942) (xy 178.689 -296.842942)
				(xy 180.086 -296.842942) (xy 185.039 -301.795942) (xy 188.976 -301.795942) (xy 189.103 -301.668942)
				(xy 189.103 -300.906942) (xy 188.976 -300.779942) (xy 185.674 -300.779942) (xy 178.689 -293.794942)
			)
		)
	)
	(zone
		(net "5V_PRE_2")
		(layer "F.Cu")
		(hatch none 0.5)
		(connect_pads
			(clearance 0.5)
		)
		(min_thickness 0.25)
		(fill yes
			(thermal_gap 0.5)
			(thermal_bridge_width 0.5)
			(island_removal_mode 0)
		)
		(polygon
			(pts
				(xy 86.045548 -290.0172) (xy 85.943948 -290.1188) (xy 85.943948 -291.508942) (xy 86.070948 -291.635942)
				(xy 87.340948 -291.635942) (xy 89.880948 -294.175942) (xy 94.325948 -294.175942) (xy 94.452948 -294.048942)
				(xy 94.452948 -293.286942) (xy 94.325948 -293.159942) (xy 91.1098 -293.159942) (xy 87.967058 -290.0172)
			)
		)
	)
	(zone
		(net "GND")
		(layer "F.Cu")
		(hatch none 0.5)
		(connect_pads
			(clearance 0.5)
		)
		(min_thickness 0.25)
		(fill yes
			(thermal_gap 0.5)
			(thermal_bridge_width 0.5)
			(island_removal_mode 0)
		)
		(polygon
			(pts
				(xy 151.987504 -116.681504)
				(arc
					(start 117.84457 -93.525848)
					(mid 117.525459 -93.683785)
					(end 117.193822 -93.813376)
				)
				(xy 117.193822 -99.37369)
				(arc
					(start 115.745514 -99.37369)
					(mid 114.453001 -100.191407)
					(end 112.950498 -100.47732)
				)
				(arc
					(start 111.949738 -100.47732)
					(mid 110.447227 -100.191427)
					(end 109.154722 -99.37369)
				)
				(xy 107.706414 -99.37369) (xy 107.706414 -90.62466)
				(arc
					(start 106.886756 -90.445336)
					(mid 107.081044 -91.615509)
					(end 107.14609 -92.799916)
				)
				(arc
					(start 107.14609 -98.794316)
					(mid 106.299546 -102.990092)
					(end 103.89235 -106.529378)
				)
				(arc
					(start 111.177832 -108.338366)
					(mid 115.996942 -102.941944)
					(end 117.731794 -109.965744)
				)
				(xy 152.455626 -118.587774) (xy 152.6032 -118.4402) (xy 152.6032 -117.2972)
			)
		)
	)
	(zone
		(net "MB3_CM_GATE_R")
		(layer "F.Cu")
		(hatch none 0.5)
		(connect_pads
			(clearance 0.5)
		)
		(min_thickness 0.25)
		(fill yes
			(thermal_gap 0.5)
			(thermal_bridge_width 0.5)
			(island_removal_mode 0)
		)
		(polygon
			(pts
				(xy 272.13433 -369.147598) (xy 271.965166 -369.316508) (xy 271.965166 -371.310154) (xy 272.237454 -371.582442)
				(xy 273.532092 -371.582442) (xy 273.840956 -371.273578) (xy 273.840956 -369.273582) (xy 273.714972 -369.147598)
			)
		)
	)
	(zone
		(net "GND")
		(layer "F.Cu")
		(hatch none 0.5)
		(connect_pads
			(clearance 0.5)
		)
		(min_thickness 0.25)
		(fill yes
			(thermal_gap 0.5)
			(thermal_bridge_width 0.5)
			(island_removal_mode 0)
		)
		(polygon
			(pts
				(arc
					(start 44.130468 -214.37346)
					(mid 34.694522 -224.528477)
					(end 23.010876 -217.0684)
				)
				(xy 22.196806 -217.0684)
				(arc
					(start 22.196806 -233.06532)
					(mid 22.441394 -234.4674)
					(end 22.196806 -235.86948)
				)
				(xy 22.196806 -237.299246) (xy 22.658324 -237.299246) (xy 22.658324 -241.336576) (xy 23.222966 -241.336576)
				(xy 23.323804 -241.235738) (xy 25.460452 -241.235738) (xy 25.460452 -240.873026) (xy 26.049478 -240.873026)
				(xy 26.099008 -240.823496)
				(arc
					(start 27.404568 -240.823496)
					(mid 30.161632 -239.655941)
					(end 32.975296 -240.679478)
				)
				(arc
					(start 32.975296 -240.679478)
					(mid 36.527665 -239.337051)
					(end 39.693596 -241.434366)
				)
				(xy 40.191436 -241.434366) (xy 40.191436 -242.711224) (xy 40.198548 -242.711224)
				(arc
					(start 40.198548 -242.9764)
					(mid 40.228766 -243.477288)
					(end 40.198548 -243.978176)
				)
				(arc
					(start 40.198548 -247.963436)
					(mid 40.233145 -248.367588)
					(end 40.228266 -248.773188)
				)
				(arc
					(start 42.632884 -248.773188)
					(mid 42.505856 -248.19088)
					(end 42.463212 -247.596406)
				)
				(arc
					(start 42.463212 -246.326406)
					(mid 42.680323 -244.998923)
					(end 43.309032 -243.809774)
				)
				(arc
					(start 43.309032 -243.809774)
					(mid 42.817789 -242.743916)
					(end 42.649394 -241.582448)
				)
				(arc
					(start 42.649394 -240.185448)
					(mid 43.17897 -238.172376)
					(end 44.630594 -236.680502)
				)
				(arc
					(start 44.630594 -236.680502)
					(mid 45.565221 -235.760046)
					(end 46.743112 -235.182664)
				)
				(arc
					(start 46.743112 -235.182664)
					(mid 46.687017 -234.636845)
					(end 46.704504 -234.088432)
				)
				(arc
					(start 46.704504 -234.088432)
					(mid 46.608832 -233.597873)
					(end 46.576742 -233.099102)
				)
				(xy 46.576742 -216.729818)
				(arc
					(start 46.094396 -216.247472)
					(mid 45.442802 -215.383414)
					(end 45.054012 -214.37346)
				)
			)
		)
	)
	(zone
		(layer "F.Cu")
		(hatch none 0.5)
		(connect_pads
			(clearance 0)
		)
		(min_thickness 0.25)
		(keepout
			(tracks allowed)
			(vias allowed)
			(pads allowed)
			(copperpour allowed)
			(footprints allowed)
		)
		(placement
			(enabled no)
			(sheetname "")
		)
		(fill
			(thermal_gap 0.5)
			(thermal_bridge_width 0.5)
			(island_removal_mode 0)
		)
		(polygon
			(pts
				(xy 255.905 13.8684) (xy 255.905 12.1158) (xy 254.8382 12.1158) (xy 254.8382 13.8684)
			)
		)
	)
	(zone
		(layer "F.Cu")
		(hatch none 0.5)
		(connect_pads
			(clearance 0)
		)
		(min_thickness 0.25)
		(keepout
			(tracks not_allowed)
			(vias allowed)
			(pads allowed)
			(copperpour not_allowed)
			(footprints allowed)
		)
		(placement
			(enabled no)
			(sheetname "")
		)
		(fill
			(thermal_gap 0.5)
			(thermal_bridge_width 0.5)
			(island_removal_mode 0)
		)
		(polygon
			(pts
				(arc
					(start 478.120202 -43.368468)
					(mid 477.739202 -42.987468)
					(end 477.358202 -43.368468)
				)
				(arc
					(start 477.358202 -44.511214)
					(mid 477.739075 -44.892468)
					(end 478.120202 -44.511468)
				)
				(xy 478.120202 -44.162218)
				(arc
					(start 477.89338 -44.162218)
					(mid 477.874023 -44.166051)
					(end 477.857566 -44.17695)
				)
				(arc
					(start 477.830134 -44.204382)
					(mid 477.819208 -44.220828)
					(end 477.815402 -44.240196)
				)
				(arc
					(start 477.815402 -44.255944)
					(mid 477.739202 -44.778112)
					(end 477.663002 -44.255944)
				)
				(xy 477.663002 -44.2087)
				(arc
					(start 477.66605 -44.205652)
					(mid 477.678485 -44.162489)
					(end 477.700086 -44.123102)
				)
				(xy 477.700086 -44.119038) (xy 477.772222 -44.046902)
				(arc
					(start 477.776286 -44.046902)
					(mid 477.815664 -44.02528)
					(end 477.858836 -44.012866)
				)
				(xy 477.861884 -44.009818) (xy 478.120202 -44.009818) (xy 478.120202 -43.870118) (xy 477.84639 -43.870118)
				(arc
					(start 477.843342 -43.86707)
					(mid 477.800179 -43.854635)
					(end 477.760792 -43.833034)
				)
				(xy 477.756728 -43.833034) (xy 477.700086 -43.776392)
				(arc
					(start 477.700086 -43.772328)
					(mid 477.678464 -43.73295)
					(end 477.66605 -43.689778)
				)
				(xy 477.663002 -43.68673)
				(arc
					(start 477.663002 -43.623992)
					(mid 477.739202 -43.101824)
					(end 477.815402 -43.623992)
				)
				(arc
					(start 477.815402 -43.655234)
					(mid 477.819235 -43.674591)
					(end 477.830134 -43.691048)
				)
				(arc
					(start 477.842072 -43.702986)
					(mid 477.858518 -43.713912)
					(end 477.877886 -43.717718)
				)
				(xy 478.120202 -43.717718)
			)
		)
	)
	(zone
		(net "P12V_A")
		(layer "F.Cu")
		(hatch none 0.5)
		(connect_pads
			(clearance 0.5)
		)
		(min_thickness 0.25)
		(fill yes
			(thermal_gap 0.5)
			(thermal_bridge_width 0.5)
			(island_removal_mode 0)
		)
		(polygon
			(pts
				(xy 171.9834 -283.9212) (xy 170.745658 -285.158942) (xy 170.307 -285.158942) (xy 169.926 -285.539942)
				(xy 169.926 -288.079942) (xy 170.18 -288.333942) (xy 173.482 -288.333942) (xy 173.8884 -287.927542)
				(xy 173.8884 -284.1498) (xy 173.6598 -283.9212)
			)
		)
		(polygon
			(pts
				(xy 173.4058 -285.717742) (xy 173.2026 -285.717742) (xy 173.2026 -285.920942) (xy 173.4058 -285.920942)
			)
		)
		(polygon
			(pts
				(xy 173.4058 -285.108142) (xy 173.2026 -285.108142) (xy 173.2026 -285.311342) (xy 173.4058 -285.311342)
			)
		)
		(polygon
			(pts
				(xy 173.4566 -284.650942) (xy 173.2534 -284.650942) (xy 173.2534 -284.854142) (xy 173.4566 -284.854142)
			)
		)
		(polygon
			(pts
				(xy 173.4566 -284.092142) (xy 173.2534 -284.092142) (xy 173.2534 -284.295342) (xy 173.4566 -284.295342)
			)
		)
	)
	(zone
		(net "MB0_CM_GATE_C")
		(layer "F.Cu")
		(hatch none 0.5)
		(connect_pads
			(clearance 0.5)
		)
		(min_thickness 0.25)
		(fill yes
			(thermal_gap 0.5)
			(thermal_bridge_width 0.5)
			(island_removal_mode 0)
		)
		(polygon
			(pts
				(xy 145.848578 -126.627128) (xy 145.618962 -126.856744) (xy 145.618962 -129.198878) (xy 145.970498 -129.550414)
				(xy 147.962112 -129.550414) (xy 148.169376 -129.34315) (xy 148.169376 -126.819914) (xy 147.97659 -126.627128)
			)
		)
		(polygon
			(pts
				(xy 146.666966 -129.013458) (xy 146.463766 -129.013458) (xy 146.463766 -129.216658) (xy 146.666966 -129.216658)
			)
		)
		(polygon
			(pts
				(xy 146.666966 -128.149858) (xy 146.463766 -128.149858) (xy 146.463766 -128.353058) (xy 146.666966 -128.353058)
			)
		)
	)
	(zone
		(net "12V_PRE_6")
		(layer "F.Cu")
		(hatch none 0.5)
		(connect_pads
			(clearance 0.5)
		)
		(min_thickness 0.25)
		(fill yes
			(thermal_gap 0.5)
			(thermal_bridge_width 0.5)
			(island_removal_mode 0)
		)
		(polygon
			(pts
				(xy 331.268578 -298.314364) (xy 328.803 -300.779942) (xy 326.263 -300.779942) (xy 326.009 -301.033942)
				(xy 326.009 -301.414942) (xy 326.263 -301.668942) (xy 332.961234 -301.668942) (xy 333.621634 -301.008542)
				(xy 333.621634 -298.435014) (xy 333.500984 -298.314364)
			)
		)
	)
	(zone
		(layer "F.Cu")
		(hatch none 0.5)
		(connect_pads
			(clearance 0)
		)
		(min_thickness 0.25)
		(keepout
			(tracks allowed)
			(vias allowed)
			(pads allowed)
			(copperpour allowed)
			(footprints allowed)
		)
		(placement
			(enabled no)
			(sheetname "")
		)
		(fill
			(thermal_gap 0.5)
			(thermal_bridge_width 0.5)
			(island_removal_mode 0)
		)
		(polygon
			(pts
				(xy 314.706 -60.325) (xy 314.706 -57.9374) (xy 318.5668 -57.9374) (xy 318.5668 -60.325)
			)
		)
	)
	(zone
		(net "GND")
		(layer "F.Cu")
		(hatch none 0.5)
		(connect_pads
			(clearance 0.5)
		)
		(min_thickness 0.25)
		(fill yes
			(thermal_gap 0.5)
			(thermal_bridge_width 0.5)
			(island_removal_mode 0)
		)
		(polygon
			(pts
				(xy 80.899 -190.0936) (xy 80.772 -190.2206) (xy 80.772 -190.530988) (xy 85.37829 -201.8284)
				(arc
					(start 87.300562 -201.8284)
					(mid 87.86394 -201.053819)
					(end 88.4936 -200.332086)
				)
				(xy 88.4936 -199.891142) (xy 86.193884 -199.891142)
				(arc
					(start 86.193884 -195.166996)
					(mid 85.441785 -194.863437)
					(end 84.764372 -194.417442)
				)
				(xy 83.097624 -194.417442) (xy 83.097624 -191.878204) (xy 82.982562 -191.763142) (xy 82.526124 -191.763142)
				(xy 82.526124 -191.306704) (xy 81.31302 -190.0936)
			)
		)
	)
	(zone
		(layer "F.Cu")
		(hatch none 0.5)
		(connect_pads
			(clearance 0)
		)
		(min_thickness 0.25)
		(keepout
			(tracks allowed)
			(vias allowed)
			(pads allowed)
			(copperpour allowed)
			(footprints not_allowed)
		)
		(placement
			(enabled no)
			(sheetname "")
		)
		(fill
			(thermal_gap 0.5)
			(thermal_bridge_width 0.5)
			(island_removal_mode 0)
		)
		(polygon
			(pts
				(arc
					(start 129.15011 -28.079954)
					(mid 126.150116 -31.079948)
					(end 123.150122 -28.079954)
				)
				(arc
					(start 123.150122 -28.079954)
					(mid 126.150116 -25.07996)
					(end 129.15011 -28.079954)
				)
			)
		)
	)
	(zone
		(layer "F.Cu")
		(hatch none 0.5)
		(connect_pads
			(clearance 0)
		)
		(min_thickness 0.25)
		(keepout
			(tracks allowed)
			(vias allowed)
			(pads allowed)
			(copperpour allowed)
			(footprints not_allowed)
		)
		(placement
			(enabled no)
			(sheetname "")
		)
		(fill
			(thermal_gap 0.5)
			(thermal_bridge_width 0.5)
			(island_removal_mode 0)
		)
		(polygon
			(pts
				(xy 264.500106 -384.199892) (xy 264.500106 -397.20012) (xy 254.500126 -397.20012) (xy 254.500126 -384.199892)
			)
		)
	)
	(zone
		(net "5V_PRE_26")
		(layer "F.Cu")
		(hatch none 0.5)
		(connect_pads
			(clearance 0.5)
		)
		(min_thickness 0.25)
		(fill yes
			(thermal_gap 0.5)
			(thermal_bridge_width 0.5)
			(island_removal_mode 0)
		)
		(polygon
			(pts
				(xy 86.020148 -59.9694) (xy 85.943948 -60.0456) (xy 85.943948 -61.508894) (xy 86.070948 -61.635894)
				(xy 87.340948 -61.635894) (xy 89.880948 -64.175894) (xy 94.325948 -64.175894) (xy 94.452948 -64.048894)
				(xy 94.452948 -63.286894) (xy 94.325948 -63.159894) (xy 90.912442 -63.159894) (xy 87.721948 -59.9694)
			)
		)
	)
	(zone
		(layer "F.Cu")
		(hatch none 0.5)
		(connect_pads
			(clearance 0)
		)
		(min_thickness 0.25)
		(keepout
			(tracks allowed)
			(vias allowed)
			(pads allowed)
			(copperpour allowed)
			(footprints not_allowed)
		)
		(placement
			(enabled no)
			(sheetname "")
		)
		(fill
			(thermal_gap 0.5)
			(thermal_bridge_width 0.5)
			(island_removal_mode 0)
		)
		(polygon
			(pts
				(xy 258.35991 -20.299934) (xy 258.35991 -12.599924) (xy 267.759942 -12.599924) (xy 267.759942 -20.299934)
			)
		)
	)
	(zone
		(layer "F.Cu")
		(hatch none 0.5)
		(connect_pads
			(clearance 0)
		)
		(min_thickness 0.25)
		(keepout
			(tracks not_allowed)
			(vias allowed)
			(pads allowed)
			(copperpour not_allowed)
			(footprints allowed)
		)
		(placement
			(enabled no)
			(sheetname "")
		)
		(fill
			(thermal_gap 0.5)
			(thermal_bridge_width 0.5)
			(island_removal_mode 0)
		)
		(polygon
			(pts
				(arc
					(start 240.874804 -134.850124)
					(mid 239.900206 -135.17499)
					(end 240.225072 -136.149588)
				)
				(xy 240.223802 -136.151874) (xy 242.223798 -137.151872)
				(arc
					(start 242.225068 -137.149586)
					(mid 243.199666 -136.82472)
					(end 242.8748 -135.850122)
				)
				(xy 242.87607 -135.847836)
				(arc
					(start 242.11661 -135.468106)
					(mid 242.069227 -135.630294)
					(end 241.977418 -135.772144)
				)
				(xy 241.935508 -135.830056) (xy 241.91214 -135.861806) (xy 241.889026 -135.89381) (xy 241.849656 -135.947912)
				(xy 241.849656 -135.956548)
				(arc
					(start 241.835178 -135.97128)
					(mid 241.838061 -136.018829)
					(end 241.870738 -136.053576)
				)
				(arc
					(start 242.111784 -136.173972)
					(mid 243.038235 -136.744265)
					(end 242.02644 -136.344406)
				)
				(xy 241.750088 -136.20623)
				(arc
					(start 241.748564 -136.201404)
					(mid 241.653499 -136.068712)
					(end 241.656108 -135.905494)
				)
				(xy 241.654076 -135.892794) (xy 241.659156 -135.885936) (xy 241.659156 -135.877554) (xy 241.681762 -135.854948)
				(xy 241.758216 -135.750046) (xy 241.849148 -135.62457)
				(arc
					(start 241.85245 -135.624062)
					(mid 241.913098 -135.506584)
					(end 241.931444 -135.37565)
				)
				(arc
					(start 241.822224 -135.320786)
					(mid 241.81972 -135.463318)
					(end 241.750088 -135.58774)
				)
				(xy 241.557556 -135.852916) (xy 241.557556 -135.868664) (xy 241.52987 -135.896604) (xy 241.528346 -135.897874)
				(xy 241.501676 -135.924544)
				(arc
					(start 241.49685 -135.924544)
					(mid 241.387209 -135.970015)
					(end 241.268758 -135.962136)
				)
				(xy 241.263932 -135.96366)
				(arc
					(start 240.988088 -135.825738)
					(mid 240.061637 -135.255445)
					(end 241.073432 -135.655304)
				)
				(arc
					(start 241.31397 -135.7757)
					(mid 241.342739 -135.782927)
					(end 241.371882 -135.777478)
				)
				(xy 241.389662 -135.759952) (xy 241.623088 -135.438388)
				(arc
					(start 241.625628 -135.43788)
					(mid 241.6384 -135.373945)
					(end 241.609626 -135.315452)
				)
				(xy 241.407696 -135.113776) (xy 240.876074 -134.847838) (xy 240.87582 -134.848092)
			)
		)
	)
	(zone
		(layer "F.Cu")
		(hatch none 0.5)
		(connect_pads
			(clearance 0)
		)
		(min_thickness 0.25)
		(keepout
			(tracks allowed)
			(vias allowed)
			(pads allowed)
			(copperpour allowed)
			(footprints allowed)
		)
		(placement
			(enabled no)
			(sheetname "")
		)
		(fill
			(thermal_gap 0.5)
			(thermal_bridge_width 0.5)
			(island_removal_mode 0)
		)
		(polygon
			(pts
				(xy 147.176998 -139.761214) (xy 147.176998 -142.707614) (xy 142.325598 -142.707614) (xy 142.325598 -139.761214)
			)
		)
	)
	(zone
		(net "5V_PRE_14")
		(layer "F.Cu")
		(hatch none 0.5)
		(connect_pads
			(clearance 0.5)
		)
		(min_thickness 0.25)
		(fill yes
			(thermal_gap 0.5)
			(thermal_bridge_width 0.5)
			(island_removal_mode 0)
		)
		(polygon
			(pts
				(xy 86.121748 -174.9806) (xy 85.943948 -175.1584) (xy 85.943948 -176.508918) (xy 86.070948 -176.635918)
				(xy 87.340948 -176.635918) (xy 89.880948 -179.175918) (xy 94.325948 -179.175918) (xy 94.452948 -179.048918)
				(xy 94.452948 -178.286918) (xy 94.325948 -178.159918) (xy 91.0082 -178.159918) (xy 87.828882 -174.9806)
			)
		)
	)
	(zone
		(net "P5V_A_2")
		(layer "F.Cu")
		(hatch none 0.5)
		(connect_pads
			(clearance 0.5)
		)
		(min_thickness 0.25)
		(fill yes
			(thermal_gap 0.5)
			(thermal_bridge_width 0.5)
			(island_removal_mode 0)
		)
		(polygon
			(pts
				(xy 113.048796 -165.840918) (xy 112.794796 -166.094918) (xy 112.794796 -168.380918) (xy 113.048796 -168.634918)
				(xy 117.747796 -168.634918) (xy 118.001796 -168.380918) (xy 118.001796 -166.094918) (xy 117.747796 -165.840918)
			)
		)
	)
	(zone
		(net "P5V_HDD3")
		(layer "F.Cu")
		(hatch none 0.5)
		(connect_pads
			(clearance 0.5)
		)
		(min_thickness 0.25)
		(fill yes
			(thermal_gap 0.5)
			(thermal_bridge_width 0.5)
			(island_removal_mode 0)
		)
		(polygon
			(pts
				(xy 131.883404 -286.682942) (xy 131.629404 -286.936942) (xy 131.629404 -288.587942) (xy 132.264404 -289.222942)
				(xy 132.264404 -291.762942) (xy 131.375404 -292.651942) (xy 130.486404 -292.651942) (xy 128.581404 -294.556942)
				(xy 123.501404 -294.556942) (xy 123.374404 -294.683942) (xy 123.374404 -296.461942) (xy 123.501404 -296.588942)
				(xy 130.359404 -296.588942) (xy 133.534404 -293.413942) (xy 133.915404 -293.413942) (xy 134.175246 -293.1541)
				(xy 134.175246 -292.3921) (xy 134.874 -291.693346) (xy 134.874 -289.661346) (xy 135.312404 -289.222942)
				(xy 135.312404 -286.936942) (xy 135.058404 -286.682942)
			)
		)
		(polygon
			(pts
				(xy 133.241796 -293.134542) (xy 133.038596 -293.134542) (xy 133.038596 -293.337742) (xy 133.241796 -293.337742)
			)
		)
		(polygon
			(pts
				(xy 133.241796 -292.270942) (xy 133.038596 -292.270942) (xy 133.038596 -292.474142) (xy 133.241796 -292.474142)
			)
		)
	)
	(zone
		(layer "F.Cu")
		(hatch none 0.5)
		(connect_pads
			(clearance 0)
		)
		(min_thickness 0.25)
		(keepout
			(tracks allowed)
			(vias allowed)
			(pads allowed)
			(copperpour allowed)
			(footprints not_allowed)
		)
		(placement
			(enabled no)
			(sheetname "")
		)
		(fill
			(thermal_gap 0.5)
			(thermal_bridge_width 0.5)
			(island_removal_mode 0)
		)
		(polygon
			(pts
				(arc
					(start 284.299914 -414.219898)
					(mid 280.550112 -417.9697)
					(end 276.800056 -414.219898)
				)
				(arc
					(start 276.800056 -414.219898)
					(mid 280.550112 -410.469842)
					(end 284.299914 -414.219898)
				)
			)
		)
	)
	(zone
		(layer "F.Cu")
		(hatch none 0.5)
		(connect_pads
			(clearance 0)
		)
		(min_thickness 0.25)
		(keepout
			(tracks not_allowed)
			(vias allowed)
			(pads allowed)
			(copperpour not_allowed)
			(footprints allowed)
		)
		(placement
			(enabled no)
			(sheetname "")
		)
		(fill
			(thermal_gap 0.5)
			(thermal_bridge_width 0.5)
			(island_removal_mode 0)
		)
		(polygon
			(pts
				(arc
					(start 159.089852 -277.17877)
					(mid 158.708979 -276.797516)
					(end 158.327852 -277.178516)
				)
				(xy 158.327852 -277.527766)
				(arc
					(start 158.581852 -277.527766)
					(mid 158.617773 -277.512887)
					(end 158.632652 -277.476966)
				)
				(arc
					(start 158.632652 -277.43404)
					(mid 158.708852 -276.911872)
					(end 158.785052 -277.43404)
				)
				(xy 158.785052 -277.508462)
				(arc
					(start 158.782004 -277.51151)
					(mid 158.725473 -277.620587)
					(end 158.616396 -277.677118)
				)
				(xy 158.613348 -277.680166) (xy 158.327852 -277.680166) (xy 158.327852 -277.819866) (xy 158.613348 -277.819866)
				(arc
					(start 158.616396 -277.822914)
					(mid 158.725473 -277.879445)
					(end 158.782004 -277.988522)
				)
				(xy 158.785052 -277.99157)
				(arc
					(start 158.785052 -278.065992)
					(mid 158.708852 -278.58816)
					(end 158.632652 -278.065992)
				)
				(arc
					(start 158.632652 -278.023066)
					(mid 158.617773 -277.987145)
					(end 158.581852 -277.972266)
				)
				(xy 158.327852 -277.972266)
				(arc
					(start 158.327852 -278.321516)
					(mid 158.708852 -278.702516)
					(end 159.089852 -278.321516)
				)
			)
		)
	)
	(zone
		(layer "F.Cu")
		(hatch none 0.5)
		(connect_pads
			(clearance 0)
		)
		(min_thickness 0.25)
		(keepout
			(tracks allowed)
			(vias allowed)
			(pads allowed)
			(copperpour allowed)
			(footprints allowed)
		)
		(placement
			(enabled no)
			(sheetname "")
		)
		(fill
			(thermal_gap 0.5)
			(thermal_bridge_width 0.5)
			(island_removal_mode 0)
		)
		(polygon
			(pts
				(xy 255.4224 26.7208) (xy 255.4224 24.1554) (xy 254.7366 24.1554) (xy 254.7366 26.7208)
			)
		)
	)
	(zone
		(net "P3V3_STBY_B")
		(layer "F.Cu")
		(hatch none 0.5)
		(connect_pads
			(clearance 0.5)
		)
		(min_thickness 0.25)
		(fill yes
			(thermal_gap 0.5)
			(thermal_bridge_width 0.5)
			(island_removal_mode 0)
		)
		(polygon
			(pts
				(xy 312.9788 -56.0324) (xy 312.6994 -56.3118) (xy 312.6994 -58.8264) (xy 312.801 -58.928) (xy 315.5696 -58.928)
				(xy 315.7474 -58.7502) (xy 315.7474 -56.5404) (xy 315.2394 -56.0324)
			)
		)
		(polygon
			(pts
				(xy 313.459368 -57.38495) (xy 313.256168 -57.38495) (xy 313.256168 -57.58815) (xy 313.459368 -57.58815)
			)
		)
		(polygon
			(pts
				(xy 313.459368 -56.77535) (xy 313.256168 -56.77535) (xy 313.256168 -56.97855) (xy 313.459368 -56.97855)
			)
		)
	)
	(zone
		(net "P5V_A_4")
		(layer "F.Cu")
		(hatch none 0.5)
		(connect_pads
			(clearance 0.5)
		)
		(min_thickness 0.25)
		(fill yes
			(thermal_gap 0.5)
			(thermal_bridge_width 0.5)
			(island_removal_mode 0)
		)
		(polygon
			(pts
				(xy 463.0039 -50.332894) (xy 462.7499 -50.586894) (xy 462.7499 -55.285894) (xy 463.0039 -55.539894)
				(xy 465.2899 -55.539894) (xy 465.5439 -55.285894) (xy 465.5439 -50.586894) (xy 465.2899 -50.332894)
			)
		)
	)
	(zone
		(layer "F.Cu")
		(hatch none 0.5)
		(connect_pads
			(clearance 0)
		)
		(min_thickness 0.25)
		(keepout
			(tracks allowed)
			(vias allowed)
			(pads allowed)
			(copperpour allowed)
			(footprints not_allowed)
		)
		(placement
			(enabled no)
			(sheetname "")
		)
		(fill
			(thermal_gap 0.5)
			(thermal_bridge_width 0.5)
			(island_removal_mode 0)
		)
		(polygon
			(pts
				(xy 258.590034 -10.299954) (xy 258.590034 -2.599944) (xy 267.990066 -2.599944) (xy 267.990066 -10.299954)
			)
		)
	)
	(zone
		(layer "F.Cu")
		(hatch none 0.5)
		(connect_pads
			(clearance 0)
		)
		(min_thickness 0.25)
		(keepout
			(tracks allowed)
			(vias allowed)
			(pads allowed)
			(copperpour allowed)
			(footprints not_allowed)
		)
		(placement
			(enabled no)
			(sheetname "")
		)
		(fill
			(thermal_gap 0.5)
			(thermal_bridge_width 0.5)
			(island_removal_mode 0)
		)
		(polygon
			(pts
				(xy 208.049876 -158.299912) (xy 208.049876 -167.699944) (xy 200.35012 -167.699944) (xy 200.35012 -158.299912)
			)
		)
	)
	(zone
		(layer "F.Cu")
		(hatch none 0.5)
		(connect_pads
			(clearance 0)
		)
		(min_thickness 0.25)
		(keepout
			(tracks allowed)
			(vias allowed)
			(pads allowed)
			(copperpour allowed)
			(footprints not_allowed)
		)
		(placement
			(enabled no)
			(sheetname "")
		)
		(fill
			(thermal_gap 0.5)
			(thermal_bridge_width 0.5)
			(island_removal_mode 0)
		)
		(polygon
			(pts
				(arc
					(start 370.944902 -20.550124)
					(mid 372.150132 -19.344894)
					(end 373.355108 -20.550124)
				)
				(arc
					(start 373.355108 -20.550124)
					(mid 372.150132 -21.7551)
					(end 370.944902 -20.550124)
				)
			)
		)
	)
	(zone
		(net "P5V_A_1")
		(layer "F.Cu")
		(hatch none 0.5)
		(connect_pads
			(clearance 0.5)
		)
		(min_thickness 0.25)
		(fill yes
			(thermal_gap 0.5)
			(thermal_bridge_width 0.5)
			(island_removal_mode 0)
		)
		(polygon
			(pts
				(xy 18.398998 -165.840918) (xy 18.144998 -166.094918) (xy 18.144998 -168.380918) (xy 18.398998 -168.634918)
				(xy 23.097998 -168.634918) (xy 23.351998 -168.380918) (xy 23.351998 -166.094918) (xy 23.097998 -165.840918)
			)
		)
	)
	(zone
		(layer "F.Cu")
		(hatch none 0.5)
		(connect_pads
			(clearance 0)
		)
		(min_thickness 0.25)
		(keepout
			(tracks allowed)
			(vias allowed)
			(pads allowed)
			(copperpour allowed)
			(footprints not_allowed)
		)
		(placement
			(enabled no)
			(sheetname "")
		)
		(fill
			(thermal_gap 0.5)
			(thermal_bridge_width 0.5)
			(island_removal_mode 0)
		)
		(polygon
			(pts
				(xy 474.674946 -9.99998) (xy 474.674946 0)
				(arc
					(start 490.450124 0)
					(mid 491.157229 -0.292893)
					(end 491.450122 -0.999998)
				)
				(xy 491.450122 -9.99998)
			)
		)
	)
	(zone
		(net "P12V_HDD19")
		(layer "F.Cu")
		(hatch none 0.5)
		(connect_pads
			(clearance 0.5)
		)
		(min_thickness 0.25)
		(fill yes
			(thermal_gap 0.5)
			(thermal_bridge_width 0.5)
			(island_removal_mode 0)
		)
		(polygon
			(pts
				(xy 366.195102 -178.540918) (xy 365.941102 -178.794918) (xy 365.941102 -182.858918) (xy 365.482378 -183.317642)
				(xy 365.482378 -186.139836) (xy 364.648496 -186.973718) (xy 357.72852 -186.973718) (xy 357.559102 -187.143136)
				(xy 357.559102 -188.954918) (xy 357.813102 -189.208918) (xy 361.750102 -189.208918) (xy 362.258102 -188.700918)
				(xy 370.005102 -188.700918) (xy 370.894102 -187.811918) (xy 370.894102 -178.794918) (xy 370.640102 -178.540918)
			)
		)
		(polygon
			(pts
				(xy 361.902502 -188.091318) (xy 361.699302 -188.091318) (xy 361.699302 -188.294518) (xy 361.902502 -188.294518)
			)
		)
		(polygon
			(pts
				(xy 361.038902 -188.091318) (xy 360.835702 -188.091318) (xy 360.835702 -188.294518) (xy 361.038902 -188.294518)
			)
		)
	)
	(zone
		(net "P3V3_STBY_B")
		(layer "F.Cu")
		(hatch none 0.5)
		(connect_pads
			(clearance 0.5)
		)
		(min_thickness 0.25)
		(fill yes
			(thermal_gap 0.5)
			(thermal_bridge_width 0.5)
			(island_removal_mode 0)
		)
		(polygon
			(pts
				(xy 221.38894 -373.135144) (xy 221.28353 -373.240554) (xy 221.28353 -375.585482) (xy 221.607126 -375.909078)
				(xy 221.607126 -378.063506) (xy 221.775528 -378.231908) (xy 222.51289 -378.231908) (xy 222.700596 -378.044202)
				(xy 222.700596 -375.035572) (xy 222.901002 -374.835166) (xy 222.901002 -373.191786) (xy 222.84436 -373.135144)
			)
		)
		(polygon
			(pts
				(xy 222.266002 -377.33351) (xy 222.062802 -377.33351) (xy 222.062802 -377.53671) (xy 222.266002 -377.53671)
			)
		)
	)
	(zone
		(layer "F.Cu")
		(hatch none 0.5)
		(connect_pads
			(clearance 0)
		)
		(min_thickness 0.25)
		(keepout
			(tracks allowed)
			(vias allowed)
			(pads allowed)
			(copperpour allowed)
			(footprints not_allowed)
		)
		(placement
			(enabled no)
			(sheetname "")
		)
		(fill
			(thermal_gap 0.5)
			(thermal_bridge_width 0.5)
			(island_removal_mode 0)
		)
		(polygon
			(pts
				(xy 491.450122 -75.79995) (xy 491.450122 -9.99998) (xy 474.674946 -9.99998) (xy 474.674946 -20.200112)
				(xy 452.67499 -20.200112) (xy 452.67499 -9.99998) (xy 395.99997 -9.99998)
				(arc
					(start 395.99997 -13.999972)
					(mid 395.707077 -14.707077)
					(end 394.999972 -14.99997)
				)
				(arc
					(start 349.000064 -14.99997)
					(mid 348.292959 -14.707077)
					(end 348.000066 -13.999972)
				)
				(xy 348.000066 -9.99998) (xy 334.674972 -9.99998) (xy 334.674972 -20.200112) (xy 312.675016 -20.200112)
				(xy 312.675016 -9.99998) (xy 298.200064 -9.99998) (xy 298.200064 -75.79995) (xy 305.699922 -75.79995)
				(xy 305.699922 -65.79997) (xy 320.250058 -65.79997) (xy 320.250058 -75.79995) (xy 337.250024 -75.79995)
				(xy 337.250024 -65.79997) (xy 351.799906 -65.79997) (xy 351.799906 -75.79995) (xy 368.800126 -75.79995)
				(xy 368.800126 -65.79997) (xy 383.350008 -65.79997) (xy 383.350008 -75.79995) (xy 400.349974 -75.79995)
				(xy 400.349974 -65.79997) (xy 414.90011 -65.79997) (xy 414.90011 -75.79995) (xy 431.900076 -75.79995)
				(xy 431.900076 -65.79997) (xy 446.449958 -65.79997) (xy 446.449958 -75.79995) (xy 463.449924 -75.79995)
				(xy 463.449924 -65.79997) (xy 478.00006 -65.79997) (xy 478.00006 -75.79995)
			)
		)
	)
	(zone
		(net "P12V_HDD1")
		(layer "F.Cu")
		(hatch none 0.5)
		(connect_pads
			(clearance 0.5)
		)
		(min_thickness 0.25)
		(fill yes
			(thermal_gap 0.5)
			(thermal_bridge_width 0.5)
			(island_removal_mode 0)
		)
		(polygon
			(pts
				(xy 43.852846 -291.254942) (xy 43.598846 -291.508942) (xy 43.598846 -293.159942) (xy 43.852846 -293.413942)
				(xy 46.011846 -293.413942) (xy 46.519846 -293.921942) (xy 46.519846 -296.461942) (xy 54.266846 -304.208942)
				(xy 62.775846 -304.208942) (xy 62.902846 -304.081942) (xy 62.902846 -302.303942) (xy 62.775846 -302.176942)
				(xy 56.806846 -302.176942) (xy 56.171846 -301.541942) (xy 54.520846 -301.541942) (xy 50.202846 -297.223942)
				(xy 50.202846 -293.667942) (xy 49.059846 -292.524942) (xy 49.059846 -291.508942) (xy 48.805846 -291.254942)
			)
		)
		(polygon
			(pts
				(xy 56.324246 -303.218342) (xy 56.121046 -303.218342) (xy 56.121046 -303.421542) (xy 56.324246 -303.421542)
			)
		)
		(polygon
			(pts
				(xy 55.460646 -303.218342) (xy 55.257446 -303.218342) (xy 55.257446 -303.421542) (xy 55.460646 -303.421542)
			)
		)
	)
	(zone
		(layer "F.Cu")
		(hatch none 0.5)
		(connect_pads
			(clearance 0)
		)
		(min_thickness 0.25)
		(keepout
			(tracks allowed)
			(vias allowed)
			(pads allowed)
			(copperpour allowed)
			(footprints not_allowed)
		)
		(placement
			(enabled no)
			(sheetname "")
		)
		(fill
			(thermal_gap 0.5)
			(thermal_bridge_width 0.5)
			(island_removal_mode 0)
		)
		(polygon
			(pts
				(xy 231.70007 -350.19996) (xy 231.70007 -376.199908) (xy 256.70002 -376.199908) (xy 256.70002 -350.19996)
			)
		)
	)
	(zone
		(net "P5V_HDD26")
		(layer "F.Cu")
		(hatch none 0.5)
		(connect_pads
			(clearance 0.5)
		)
		(min_thickness 0.25)
		(fill yes
			(thermal_gap 0.5)
			(thermal_bridge_width 0.5)
			(island_removal_mode 0)
		)
		(polygon
			(pts
				(xy 82.768948 -56.682894) (xy 82.514948 -56.936894) (xy 82.514948 -59.222894) (xy 82.768948 -59.476894)
				(xy 82.768948 -61.508894) (xy 83.530948 -62.270894) (xy 83.530948 -63.032894) (xy 83.911948 -63.413894)
				(xy 84.292948 -63.413894) (xy 87.467948 -66.588894) (xy 94.325948 -66.588894) (xy 94.452948 -66.461894)
				(xy 94.452948 -64.683894) (xy 94.325948 -64.556894) (xy 89.245948 -64.556894) (xy 87.340948 -62.651894)
				(xy 86.451948 -62.651894) (xy 85.562948 -61.762894) (xy 85.562948 -59.222894) (xy 86.197948 -58.587894)
				(xy 86.197948 -56.936894) (xy 85.943948 -56.682894)
			)
		)
		(polygon
			(pts
				(xy 84.775548 -63.109094) (xy 84.572348 -63.109094) (xy 84.572348 -63.312294) (xy 84.775548 -63.312294)
			)
		)
		(polygon
			(pts
				(xy 84.775548 -62.245494) (xy 84.572348 -62.245494) (xy 84.572348 -62.448694) (xy 84.775548 -62.448694)
			)
		)
		(polygon
			(pts
				(xy 83.911948 -62.245494) (xy 83.708748 -62.245494) (xy 83.708748 -62.448694) (xy 83.911948 -62.448694)
			)
		)
	)
	(zone
		(layer "F.Cu")
		(hatch none 0.5)
		(connect_pads
			(clearance 0)
		)
		(min_thickness 0.25)
		(keepout
			(tracks allowed)
			(vias allowed)
			(pads allowed)
			(copperpour allowed)
			(footprints allowed)
		)
		(placement
			(enabled no)
			(sheetname "")
		)
		(fill
			(thermal_gap 0.5)
			(thermal_bridge_width 0.5)
			(island_removal_mode 0)
		)
		(polygon
			(pts
				(xy 126.5174 -159.4358) (xy 127.6858 -159.4358) (xy 127.889 -159.2326) (xy 127.889 -158.6738) (xy 127.6096 -158.3944)
				(xy 126.5428 -158.3944) (xy 126.3904 -158.5468) (xy 126.3904 -159.3088)
			)
		)
	)
	(zone
		(layer "F.Cu")
		(hatch none 0.5)
		(connect_pads
			(clearance 0)
		)
		(min_thickness 0.25)
		(keepout
			(tracks not_allowed)
			(vias allowed)
			(pads allowed)
			(copperpour not_allowed)
			(footprints allowed)
		)
		(placement
			(enabled no)
			(sheetname "")
		)
		(fill
			(thermal_gap 0.5)
			(thermal_bridge_width 0.5)
			(island_removal_mode 0)
		)
		(polygon
			(pts
				(arc
					(start 325.12 -162.178746)
					(mid 324.739127 -161.797492)
					(end 324.358 -162.178492)
				)
				(arc
					(start 324.358 -163.321492)
					(mid 324.739 -163.702492)
					(end 325.12 -163.321492)
				)
				(xy 325.12 -162.972242)
				(arc
					(start 324.866254 -162.972242)
					(mid 324.830153 -162.987195)
					(end 324.8152 -163.023296)
				)
				(arc
					(start 324.8152 -163.065968)
					(mid 324.739 -163.588136)
					(end 324.6628 -163.065968)
				)
				(xy 324.6628 -162.9918)
				(arc
					(start 324.665848 -162.988752)
					(mid 324.722456 -162.879498)
					(end 324.83171 -162.82289)
				)
				(xy 324.834758 -162.819842) (xy 325.12 -162.819842) (xy 325.12 -162.680142) (xy 324.834758 -162.680142)
				(arc
					(start 324.83171 -162.677094)
					(mid 324.722456 -162.620486)
					(end 324.665848 -162.511232)
				)
				(xy 324.6628 -162.508184)
				(arc
					(start 324.6628 -162.434016)
					(mid 324.739 -161.911848)
					(end 324.8152 -162.434016)
				)
				(arc
					(start 324.8152 -162.476688)
					(mid 324.830153 -162.512789)
					(end 324.866254 -162.527742)
				)
				(xy 325.12 -162.527742)
			)
		)
	)
	(zone
		(layer "F.Cu")
		(hatch none 0.5)
		(connect_pads
			(clearance 0)
		)
		(min_thickness 0.25)
		(keepout
			(tracks allowed)
			(vias allowed)
			(pads allowed)
			(copperpour allowed)
			(footprints allowed)
		)
		(placement
			(enabled no)
			(sheetname "")
		)
		(fill
			(thermal_gap 0.5)
			(thermal_bridge_width 0.5)
			(island_removal_mode 0)
		)
		(polygon
			(pts
				(xy 82.9818 -27.6606) (xy 82.9818 -30.4546) (xy 88.3412 -30.4546) (xy 88.3412 -27.6606)
			)
		)
	)
	(zone
		(net "P12V_A")
		(layer "F.Cu")
		(hatch none 0.5)
		(connect_pads
			(clearance 0.5)
		)
		(min_thickness 0.25)
		(fill yes
			(thermal_gap 0.5)
			(thermal_bridge_width 0.5)
			(island_removal_mode 0)
		)
		(polygon
			(pts
				(xy 366.195102 -171.428918) (xy 365.687102 -171.936918) (xy 365.687102 -175.365918) (xy 365.941102 -175.619918)
				(xy 369.243102 -175.619918) (xy 369.497102 -175.365918) (xy 369.497102 -173.333918) (xy 369.624102 -173.206918)
				(xy 370.005102 -173.206918) (xy 370.132102 -173.079918) (xy 370.132102 -171.555918) (xy 370.005102 -171.428918)
			)
		)
		(polygon
			(pts
				(xy 369.598702 -172.444918) (xy 369.395502 -172.444918) (xy 369.395502 -172.648118) (xy 369.598702 -172.648118)
			)
		)
		(polygon
			(pts
				(xy 369.649502 -171.987718) (xy 369.446302 -171.987718) (xy 369.446302 -172.190918) (xy 369.649502 -172.190918)
			)
		)
	)
	(zone
		(layer "F.Cu")
		(hatch none 0.5)
		(connect_pads
			(clearance 0)
		)
		(min_thickness 0.25)
		(keepout
			(tracks allowed)
			(vias allowed)
			(pads allowed)
			(copperpour allowed)
			(footprints allowed)
		)
		(placement
			(enabled no)
			(sheetname "")
		)
		(fill
			(thermal_gap 0.5)
			(thermal_bridge_width 0.5)
			(island_removal_mode 0)
		)
		(polygon
			(pts
				(xy 222.501206 -176.329848) (xy 224.86239 -176.329848) (xy 224.86239 -177.580798) (xy 222.501206 -177.580798)
			)
		)
	)
	(zone
		(net "P5V_HDD15")
		(layer "F.Cu")
		(hatch none 0.5)
		(connect_pads
			(clearance 0.5)
		)
		(min_thickness 0.25)
		(fill yes
			(thermal_gap 0.5)
			(thermal_bridge_width 0.5)
			(island_removal_mode 0)
		)
		(polygon
			(pts
				(xy 114.318796 -171.682918) (xy 114.064796 -171.936918) (xy 114.064796 -174.222918) (xy 114.318796 -174.476918)
				(xy 114.318796 -176.508918) (xy 115.080796 -177.270918) (xy 115.080796 -178.032918) (xy 115.461796 -178.413918)
				(xy 115.842796 -178.413918) (xy 119.017796 -181.588918) (xy 125.875796 -181.588918) (xy 126.002796 -181.461918)
				(xy 126.002796 -179.683918) (xy 125.875796 -179.556918) (xy 120.795796 -179.556918) (xy 118.890796 -177.651918)
				(xy 118.001796 -177.651918) (xy 117.112796 -176.762918) (xy 117.112796 -174.222918) (xy 117.747796 -173.587918)
				(xy 117.747796 -171.936918) (xy 117.493796 -171.682918)
			)
		)
		(polygon
			(pts
				(xy 116.325396 -178.109118) (xy 116.122196 -178.109118) (xy 116.122196 -178.312318) (xy 116.325396 -178.312318)
			)
		)
		(polygon
			(pts
				(xy 116.325396 -177.245518) (xy 116.122196 -177.245518) (xy 116.122196 -177.448718) (xy 116.325396 -177.448718)
			)
		)
		(polygon
			(pts
				(xy 115.461796 -177.245518) (xy 115.258596 -177.245518) (xy 115.258596 -177.448718) (xy 115.461796 -177.448718)
			)
		)
	)
	(zone
		(layer "F.Cu")
		(hatch none 0.5)
		(connect_pads
			(clearance 0)
		)
		(min_thickness 0.25)
		(keepout
			(tracks allowed)
			(vias allowed)
			(pads allowed)
			(copperpour allowed)
			(footprints not_allowed)
		)
		(placement
			(enabled no)
			(sheetname "")
		)
		(fill
			(thermal_gap 0.5)
			(thermal_bridge_width 0.5)
			(island_removal_mode 0)
		)
		(polygon
			(pts
				(arc
					(start 152.32507 -92.799916)
					(mid 159.325056 -85.79993)
					(end 166.325042 -92.799916)
				)
				(arc
					(start 166.325042 -98.799904)
					(mid 159.325056 -105.79989)
					(end 152.32507 -98.799904)
				)
			)
		)
	)
	(zone
		(net "GND")
		(layer "F.Cu")
		(hatch none 0.5)
		(connect_pads
			(clearance 0.5)
		)
		(min_thickness 0.25)
		(fill yes
			(thermal_gap 0.5)
			(thermal_bridge_width 0.5)
			(island_removal_mode 0)
		)
		(polygon
			(pts
				(xy 114.075972 -191.306704) (xy 110.475522 -187.706) (xy 109.6264 -187.706) (xy 109.6264 -189.10046)
				(xy 111.99876 -199.811132) (xy 112.786414 -203.367386)
				(arc
					(start 112.950498 -203.367386)
					(mid 114.278292 -203.58895)
					(end 115.462304 -204.229462)
				)
				(arc
					(start 115.462304 -204.229462)
					(mid 116.487204 -202.586509)
					(end 117.729 -201.10069)
				)
				(arc
					(start 117.729 -195.162678)
					(mid 116.984841 -194.859865)
					(end 116.31422 -194.417442)
				)
				(xy 114.647472 -194.417442) (xy 114.647472 -191.878204) (xy 114.53241 -191.763142) (xy 114.075972 -191.763142)
			)
		)
	)
	(zone
		(net "5V_PRE_12")
		(layer "F.Cu")
		(hatch none 0.5)
		(connect_pads
			(clearance 0.5)
		)
		(min_thickness 0.25)
		(fill yes
			(thermal_gap 0.5)
			(thermal_bridge_width 0.5)
			(island_removal_mode 0)
		)
		(polygon
			(pts
				(xy 22.920198 -175.0568) (xy 22.843998 -175.133) (xy 22.843998 -176.508918) (xy 22.970998 -176.635918)
				(xy 24.240998 -176.635918) (xy 26.780998 -179.175918) (xy 31.225998 -179.175918) (xy 31.352998 -179.048918)
				(xy 31.352998 -178.286918) (xy 31.225998 -178.159918) (xy 28.321 -178.159918) (xy 25.217882 -175.0568)
			)
		)
	)
	(zone
		(layer "F.Cu")
		(hatch none 0.5)
		(connect_pads
			(clearance 0)
		)
		(min_thickness 0.25)
		(keepout
			(tracks not_allowed)
			(vias allowed)
			(pads allowed)
			(copperpour not_allowed)
			(footprints allowed)
		)
		(placement
			(enabled no)
			(sheetname "")
		)
		(fill
			(thermal_gap 0.5)
			(thermal_bridge_width 0.5)
			(island_removal_mode 0)
		)
		(polygon
			(pts
				(arc
					(start 271.970754 -357.323898)
					(mid 271.5895 -357.704771)
					(end 271.9705 -358.085898)
				)
				(arc
					(start 273.1135 -358.085898)
					(mid 273.4945 -357.704898)
					(end 273.1135 -357.323898)
				)
				(xy 272.76425 -357.323898)
				(arc
					(start 272.76425 -357.577898)
					(mid 272.779129 -357.613819)
					(end 272.81505 -357.628698)
				)
				(arc
					(start 272.857976 -357.628698)
					(mid 273.380144 -357.704898)
					(end 272.857976 -357.781098)
				)
				(xy 272.783554 -357.781098)
				(arc
					(start 272.780506 -357.77805)
					(mid 272.671429 -357.721519)
					(end 272.614898 -357.612442)
				)
				(xy 272.61185 -357.609394) (xy 272.61185 -357.323898) (xy 272.47215 -357.323898) (xy 272.47215 -357.609394)
				(arc
					(start 272.469102 -357.612442)
					(mid 272.412571 -357.721519)
					(end 272.303494 -357.77805)
				)
				(xy 272.300446 -357.781098)
				(arc
					(start 272.226024 -357.781098)
					(mid 271.703856 -357.704898)
					(end 272.226024 -357.628698)
				)
				(arc
					(start 272.26895 -357.628698)
					(mid 272.304871 -357.613819)
					(end 272.31975 -357.577898)
				)
				(xy 272.31975 -357.323898)
			)
		)
	)
	(zone
		(layer "F.Cu")
		(hatch none 0.5)
		(connect_pads
			(clearance 0)
		)
		(min_thickness 0.25)
		(keepout
			(tracks allowed)
			(vias allowed)
			(pads allowed)
			(copperpour allowed)
			(footprints not_allowed)
		)
		(placement
			(enabled no)
			(sheetname "")
		)
		(fill
			(thermal_gap 0.5)
			(thermal_bridge_width 0.5)
			(island_removal_mode 0)
		)
		(polygon
			(pts
				(arc
					(start 152.32507 -322.799964)
					(mid 159.325056 -315.799978)
					(end 166.325042 -322.799964)
				)
				(arc
					(start 166.325042 -328.799952)
					(mid 159.325056 -335.799938)
					(end 152.32507 -328.799952)
				)
			)
		)
	)
	(zone
		(net "12V_PRE_10")
		(layer "F.Cu")
		(hatch none 0.5)
		(connect_pads
			(clearance 0.5)
		)
		(min_thickness 0.25)
		(fill yes
			(thermal_gap 0.5)
			(thermal_bridge_width 0.5)
			(island_removal_mode 0)
		)
		(polygon
			(pts
				(xy 457.468478 -298.314364) (xy 455.0029 -300.779942) (xy 452.4629 -300.779942) (xy 452.2089 -301.033942)
				(xy 452.2089 -301.414942) (xy 452.4629 -301.668942) (xy 459.161134 -301.668942) (xy 459.821534 -301.008542)
				(xy 459.821534 -298.435014) (xy 459.700884 -298.314364)
			)
		)
	)
	(zone
		(net "GND")
		(layer "F.Cu")
		(hatch none 0.5)
		(connect_pads
			(clearance 0.5)
		)
		(min_thickness 0.25)
		(fill yes
			(thermal_gap 0.5)
			(thermal_bridge_width 0.5)
			(island_removal_mode 0)
		)
		(polygon
			(pts
				(xy 220.68282 -6.793738) (xy 220.57487 -6.901688) (xy 220.57487 -8.551672) (xy 220.113098 -9.013444)
				(xy 220.113098 -11.585448) (xy 220.274642 -11.746992) (xy 222.344234 -11.746992) (xy 223.186752 -10.904474)
				(xy 223.186752 -6.960616) (xy 223.019874 -6.793738)
			)
		)
		(polygon
			(pts
				(xy 221.101158 -9.787636) (xy 220.897958 -9.787636) (xy 220.897958 -9.990836) (xy 221.101158 -9.990836)
			)
		)
		(polygon
			(pts
				(xy 221.101158 -8.924036) (xy 220.897958 -8.924036) (xy 220.897958 -9.127236) (xy 221.101158 -9.127236)
			)
		)
	)
	(zone
		(layer "F.Cu")
		(hatch none 0.5)
		(connect_pads
			(clearance 0)
		)
		(min_thickness 0.25)
		(keepout
			(tracks allowed)
			(vias allowed)
			(pads allowed)
			(copperpour allowed)
			(footprints not_allowed)
		)
		(placement
			(enabled no)
			(sheetname "")
		)
		(fill
			(thermal_gap 0.5)
			(thermal_bridge_width 0.5)
			(island_removal_mode 0)
		)
		(polygon
			(pts
				(xy 312.699908 -240.799874) (xy 491.450122 -240.799874) (xy 491.450122 -305.799998) (xy 478.00006 -305.799998)
				(xy 478.00006 -295.800018) (xy 463.449924 -295.800018) (xy 463.449924 -305.799998) (xy 446.449958 -305.799998)
				(xy 446.449958 -295.800018) (xy 431.900076 -295.800018) (xy 431.900076 -305.799998) (xy 414.90011 -305.799998)
				(xy 414.90011 -295.800018) (xy 400.349974 -295.800018) (xy 400.349974 -305.799998) (xy 383.350008 -305.799998)
				(xy 383.350008 -295.800018) (xy 368.800126 -295.800018) (xy 368.800126 -305.799998) (xy 351.799906 -305.799998)
				(xy 351.799906 -295.800018) (xy 337.250024 -295.800018) (xy 337.250024 -305.799998) (xy 320.250058 -305.799998)
				(xy 320.250058 -295.800018) (xy 305.699922 -295.800018) (xy 305.699922 -305.799998) (xy 298.200064 -305.799998)
				(xy 298.200064 -259.199888) (xy 312.699908 -259.199888)
			)
		)
	)
	(zone
		(layer "F.Cu")
		(hatch none 0.5)
		(connect_pads
			(clearance 0)
		)
		(min_thickness 0.25)
		(keepout
			(tracks not_allowed)
			(vias allowed)
			(pads allowed)
			(copperpour not_allowed)
			(footprints allowed)
		)
		(placement
			(enabled no)
			(sheetname "")
		)
		(fill
			(thermal_gap 0.5)
			(thermal_bridge_width 0.5)
			(island_removal_mode 0)
		)
		(polygon
			(pts
				(arc
					(start 195.300092 -183.799988)
					(mid 202.300078 -176.800002)
					(end 209.300064 -183.799988)
				)
				(arc
					(start 209.300064 -189.799976)
					(mid 202.300078 -196.799962)
					(end 195.300092 -189.799976)
				)
			)
		)
	)
	(zone
		(layer "F.Cu")
		(hatch none 0.5)
		(connect_pads
			(clearance 0)
		)
		(min_thickness 0.25)
		(keepout
			(tracks allowed)
			(vias allowed)
			(pads allowed)
			(copperpour allowed)
			(footprints not_allowed)
		)
		(placement
			(enabled no)
			(sheetname "")
		)
		(fill
			(thermal_gap 0.5)
			(thermal_bridge_width 0.5)
			(island_removal_mode 0)
		)
		(polygon
			(pts
				(xy 452.67499 -20.200112) (xy 474.674946 -20.200112) (xy 474.674946 0) (xy 452.67499 0)
			)
		)
	)
	(zone
		(net "P12V_HDD9")
		(layer "F.Cu")
		(hatch none 0.5)
		(connect_pads
			(clearance 0.5)
		)
		(min_thickness 0.25)
		(fill yes
			(thermal_gap 0.5)
			(thermal_bridge_width 0.5)
			(island_removal_mode 0)
		)
		(polygon
			(pts
				(xy 429.295052 -293.540942) (xy 429.041052 -293.794942) (xy 429.041052 -297.858942) (xy 428.582328 -298.317666)
				(xy 428.582328 -301.13986) (xy 427.748446 -301.973742) (xy 420.82847 -301.973742) (xy 420.659052 -302.14316)
				(xy 420.659052 -303.954942) (xy 420.913052 -304.208942) (xy 424.850052 -304.208942) (xy 425.358052 -303.700942)
				(xy 433.105052 -303.700942) (xy 433.994052 -302.811942) (xy 433.994052 -293.794942) (xy 433.740052 -293.540942)
			)
		)
		(polygon
			(pts
				(xy 425.002452 -303.091342) (xy 424.799252 -303.091342) (xy 424.799252 -303.294542) (xy 425.002452 -303.294542)
			)
		)
		(polygon
			(pts
				(xy 424.138852 -303.091342) (xy 423.935652 -303.091342) (xy 423.935652 -303.294542) (xy 424.138852 -303.294542)
			)
		)
	)
	(zone
		(layer "F.Cu")
		(hatch none 0.5)
		(connect_pads
			(clearance 0)
		)
		(min_thickness 0.25)
		(keepout
			(tracks not_allowed)
			(vias allowed)
			(pads allowed)
			(copperpour not_allowed)
			(footprints allowed)
		)
		(placement
			(enabled no)
			(sheetname "")
		)
		(fill
			(thermal_gap 0.5)
			(thermal_bridge_width 0.5)
			(island_removal_mode 0)
		)
		(polygon
			(pts
				(arc
					(start 127.53975 -47.178722)
					(mid 127.158877 -46.797468)
					(end 126.77775 -47.178468)
				)
				(xy 126.77775 -47.527718)
				(arc
					(start 127.03175 -47.527718)
					(mid 127.067671 -47.512839)
					(end 127.08255 -47.476918)
				)
				(arc
					(start 127.08255 -47.433992)
					(mid 127.15875 -46.911824)
					(end 127.23495 -47.433992)
				)
				(xy 127.23495 -47.508414)
				(arc
					(start 127.231902 -47.511462)
					(mid 127.175371 -47.620539)
					(end 127.066294 -47.67707)
				)
				(xy 127.063246 -47.680118) (xy 126.77775 -47.680118) (xy 126.77775 -47.819818) (xy 127.063246 -47.819818)
				(arc
					(start 127.066294 -47.822866)
					(mid 127.175371 -47.879397)
					(end 127.231902 -47.988474)
				)
				(xy 127.23495 -47.991522)
				(arc
					(start 127.23495 -48.065944)
					(mid 127.15875 -48.588112)
					(end 127.08255 -48.065944)
				)
				(arc
					(start 127.08255 -48.023018)
					(mid 127.067671 -47.987097)
					(end 127.03175 -47.972218)
				)
				(xy 126.77775 -47.972218)
				(arc
					(start 126.77775 -48.321468)
					(mid 127.15875 -48.702468)
					(end 127.53975 -48.321468)
				)
			)
		)
	)
	(zone
		(layer "F.Cu")
		(hatch none 0.5)
		(connect_pads
			(clearance 0)
		)
		(min_thickness 0.25)
		(keepout
			(tracks allowed)
			(vias allowed)
			(pads allowed)
			(copperpour allowed)
			(footprints allowed)
		)
		(placement
			(enabled no)
			(sheetname "")
		)
		(fill
			(thermal_gap 0.5)
			(thermal_bridge_width 0.5)
			(island_removal_mode 0)
		)
		(polygon
			(pts
				(xy 94.2594 -163.5252) (xy 95.8342 -163.5252) (xy 96.0882 -163.2712) (xy 96.0882 -162.2552) (xy 95.6818 -161.8488)
				(xy 94.5134 -161.8488) (xy 94.1578 -162.2044) (xy 94.1578 -163.4236)
			)
		)
	)
	(zone
		(layer "F.Cu")
		(hatch none 0.5)
		(connect_pads
			(clearance 0)
		)
		(min_thickness 0.25)
		(keepout
			(tracks not_allowed)
			(vias allowed)
			(pads allowed)
			(copperpour not_allowed)
			(footprints allowed)
		)
		(placement
			(enabled no)
			(sheetname "")
		)
		(fill
			(thermal_gap 0.5)
			(thermal_bridge_width 0.5)
			(island_removal_mode 0)
		)
		(polygon
			(pts
				(arc
					(start 271.970754 -315.92139)
					(mid 271.58696 -316.304803)
					(end 271.9705 -316.68847)
				)
				(arc
					(start 273.1135 -316.68847)
					(mid 273.49704 -316.30493)
					(end 273.1135 -315.92139)
				)
				(xy 272.76425 -315.92139)
				(arc
					(start 272.76425 -316.17793)
					(mid 272.779129 -316.213851)
					(end 272.81505 -316.22873)
				)
				(arc
					(start 272.857976 -316.22873)
					(mid 273.380144 -316.30493)
					(end 272.857976 -316.38113)
				)
				(xy 272.783554 -316.38113)
				(arc
					(start 272.780506 -316.378082)
					(mid 272.671429 -316.321551)
					(end 272.614898 -316.212474)
				)
				(xy 272.61185 -316.209426) (xy 272.61185 -315.92139) (xy 272.47215 -315.92139) (xy 272.47215 -316.209426)
				(arc
					(start 272.469102 -316.212474)
					(mid 272.412571 -316.321551)
					(end 272.303494 -316.378082)
				)
				(xy 272.300446 -316.38113)
				(arc
					(start 272.226024 -316.38113)
					(mid 271.703856 -316.30493)
					(end 272.226024 -316.22873)
				)
				(arc
					(start 272.26895 -316.22873)
					(mid 272.304871 -316.213851)
					(end 272.31975 -316.17793)
				)
				(xy 272.31975 -315.92139)
			)
		)
	)
	(zone
		(layer "F.Cu")
		(hatch none 0.5)
		(connect_pads
			(clearance 0)
		)
		(min_thickness 0.25)
		(keepout
			(tracks allowed)
			(vias allowed)
			(pads allowed)
			(copperpour allowed)
			(footprints not_allowed)
		)
		(placement
			(enabled no)
			(sheetname "")
		)
		(fill
			(thermal_gap 0.5)
			(thermal_bridge_width 0.5)
			(island_removal_mode 0)
		)
		(polygon
			(pts
				(arc
					(start 293.200074 -138.199876)
					(mid 300.20006 -131.19989)
					(end 307.200046 -138.199876)
				)
				(arc
					(start 307.200046 -144.200118)
					(mid 300.20006 -151.200104)
					(end 293.200074 -144.200118)
				)
			)
		)
	)
	(zone
		(layer "F.Cu")
		(hatch none 0.5)
		(connect_pads
			(clearance 0)
		)
		(min_thickness 0.25)
		(keepout
			(tracks allowed)
			(vias allowed)
			(pads allowed)
			(copperpour allowed)
			(footprints allowed)
		)
		(placement
			(enabled no)
			(sheetname "")
		)
		(fill
			(thermal_gap 0.5)
			(thermal_bridge_width 0.5)
			(island_removal_mode 0)
		)
		(polygon
			(pts
				(xy 370.7384 -141.4526) (xy 370.7384 -143.8148) (xy 368.5286 -143.8148) (xy 368.5286 -141.4526)
			)
		)
	)
	(zone
		(net "GND")
		(layer "F.Cu")
		(hatch none 0.5)
		(connect_pads
			(clearance 0.5)
		)
		(min_thickness 0.25)
		(fill yes
			(thermal_gap 0.5)
			(thermal_bridge_width 0.5)
			(island_removal_mode 0)
		)
		(polygon
			(pts
				(xy 97.897442 -347.167962) (xy 56.877712 -322.199) (xy 54.093618 -322.199) (xy 54.093618 -329.373484)
				(xy 52.300886 -329.373484) (xy 50.21961 -331.45476)
				(arc
					(start 43.813984 -331.45476)
					(mid 34.628883 -339.536589)
					(end 23.77694 -333.88681)
				)
				(arc
					(start 23.77694 -333.88681)
					(mid 21.883047 -335.236321)
					(end 19.580352 -335.561432)
				)
				(arc
					(start 19.580352 -335.561432)
					(mid 18.086007 -337.768498)
					(end 15.580614 -338.678012)
				)
				(arc
					(start 15.580614 -338.678012)
					(mid 15.053471 -341.5666)
					(end 12.72667 -343.357708)
				)
				(arc
					(start 12.767818 -343.357708)
					(mid 11.561572 -343.539069)
					(end 10.355326 -343.357708)
				)
				(arc
					(start 10.396474 -343.357708)
					(mid 10.331661 -343.337798)
					(end 10.267188 -343.316814)
				)
				(arc
					(start 10.267188 -343.316814)
					(mid 6.446967 -338.76929)
					(end 11.195304 -335.201514)
				)
				(arc
					(start 11.195304 -335.201514)
					(mid 11.270921 -333.204173)
					(end 12.23772 -331.45476)
				)
				(xy 11.321034 -331.45476) (xy 7.238238 -327.371964)
				(arc
					(start 7.238238 -315.882782)
					(mid 6.549384 -315.323973)
					(end 5.997194 -314.6298)
				)
				(xy 5.842254 -314.6298) (xy 5.842254 -314.633356) (xy 2.032 -314.633356) (xy 2.032 -279.383744)
				(arc
					(start 6.820154 -279.383744)
					(mid 6.987071 -279.388469)
					(end 7.153656 -279.4)
				)
				(xy 9.398 -279.4)
				(arc
					(start 9.398 -276.01418)
					(mid 9.753519 -273.896034)
					(end 11.133074 -272.2499)
				)
				(xy 11.133074 -271.517618) (xy 12.555474 -271.517618) (xy 12.555474 -271.187418) (xy 14.409674 -271.187418)
				(xy 14.409674 -271.111218) (xy 18.473674 -271.111218) (xy 18.473674 -270.781018) (xy 23.093934 -270.781018)
				(xy 23.093934 -260.928866)
				(arc
					(start 32.04591 -260.928866)
					(mid 31.246583 -260.429866)
					(end 30.582616 -259.761228)
				)
				(arc
					(start 30.582616 -259.761228)
					(mid 30.462917 -259.784456)
					(end 30.342586 -259.804154)
				)
				(arc
					(start 30.342586 -259.804154)
					(mid 29.91394 -259.875867)
					(end 29.480002 -259.899912)
				)
				(arc
					(start 25.771602 -259.899912)
					(mid 24.393645 -259.650927)
					(end 23.189946 -258.935474)
				)
				(xy 21.858478 -258.935474)
				(arc
					(start 21.858478 -257.561334)
					(mid 21.315113 -256.56214)
					(end 21.079968 -255.449324)
				)
				(arc
					(start 19.9644 -255.449324)
					(mid 17.746139 -254.80984)
					(end 16.208756 -253.087632)
				)
				(arc
					(start 16.208756 -253.087632)
					(mid 11.036798 -250.912959)
					(end 12.901676 -245.621302)
				)
				(xy 12.901676 -237.299246)
				(arc
					(start 13.172948 -237.299246)
					(mid 13.194384 -236.414504)
					(end 13.403326 -235.55452)
				)
				(xy 13.403326 -231.2416)
				(arc
					(start 8.534908 -231.2416)
					(mid 7.675895 -231.254417)
					(end 6.821678 -231.16286)
				)
				(xy 2.032 -231.16286) (xy 2.032 -217.13825)
				(arc
					(start 8.052562 -217.13825)
					(mid 8.17832 -217.140306)
					(end 8.304022 -217.1446)
				)
				(xy 13.403326 -217.1446) (xy 13.403326 -214.37346) (xy 13.056362 -214.37346) (xy 13.056362 -205.58125)
				(xy 2.032 -194.556888) (xy 2.032 -164.329872) (xy 6.864096 -164.329872)
				(arc
					(start 6.86435 -164.330126)
					(mid 7.502334 -164.375421)
					(end 8.12546 -164.51961)
				)
				(arc
					(start 8.12546 -164.51961)
					(mid 8.653894 -164.597911)
					(end 9.167622 -164.7444)
				)
				(xy 10.3124 -164.7444)
				(arc
					(start 10.3124 -163.19246)
					(mid 9.612616 -159.286379)
					(end 12.555474 -156.624274)
				)
				(xy 12.555474 -156.187394) (xy 14.409674 -156.187394) (xy 14.409674 -156.111194) (xy 17.54886 -156.111194)
				(xy 17.54886 -155.83535)
				(arc
					(start 18.09369 -155.83535)
					(mid 20.270603 -154.037006)
					(end 23.093934 -154.07767)
				)
				(xy 23.093934 -145.928842) (xy 28.1686 -145.928842)
				(arc
					(start 28.1686 -144.533874)
					(mid 26.762885 -143.025144)
					(end 26.252678 -141.02715)
				)
				(arc
					(start 26.252678 -138.74115)
					(mid 27.4732 -135.794548)
					(end 30.419802 -134.574026)
				)
				(arc
					(start 31.562802 -134.574026)
					(mid 34.509404 -135.794548)
					(end 35.729926 -138.74115)
				)
				(xy 35.729926 -140.365226) (xy 36.978082 -140.365226) (xy 36.978082 -139.87526) (xy 38.644576 -138.208766)
				(xy 38.644576 -136.688576) (xy 40.164766 -136.688576) (xy 40.265604 -136.587738)
				(arc
					(start 40.50411 -136.587738)
					(mid 39.874526 -135.543922)
					(end 39.580566 -134.36092)
				)
				(xy 38.68547 -134.36092) (xy 38.68547 -133.133592) (xy 37.300154 -133.133592) (xy 37.300154 -124.367544)
				(xy 38.771068 -124.367544)
				(arc
					(start 38.771068 -108.145072)
					(mid 29.299256 -108.83865)
					(end 22.928326 -101.795326)
				)
				(xy 22.6314 -101.4984) (xy 22.3266 -101.4984) (xy 22.196806 -101.628194)
				(arc
					(start 22.196806 -106.34472)
					(mid 22.441394 -107.7468)
					(end 22.196806 -109.14888)
				)
				(xy 22.196806 -122.299476) (xy 22.658324 -122.299476) (xy 22.658324 -132.208524)
				(arc
					(start 21.170138 -132.208524)
					(mid 20.658135 -132.60551)
					(end 20.089876 -132.916676)
				)
				(xy 20.089876 -133.134862) (xy 19.78406 -133.134862)
				(arc
					(start 19.78406 -133.676644)
					(mid 19.79599 -133.98881)
					(end 19.78406 -134.300976)
				)
				(xy 19.78406 -134.398004)
				(arc
					(start 19.775424 -134.398004)
					(mid 17.689564 -137.565654)
					(end 13.897864 -137.65784)
				)
				(arc
					(start 13.897864 -137.65784)
					(mid 10.107313 -137.564112)
					(end 8.02259 -134.396988)
				)
				(xy 7.124954 -134.396988) (xy 7.124954 -133.14426) (xy 2.032 -133.14426)
				(arc
					(start 2.032 -124.134626)
					(mid 1.347921 -123.70242)
					(end 0.763016 -123.143264)
				)
				(xy 0.763016 -241.199924) (xy 0.762254 -241.199924) (xy 0.762254 -261.199884) (xy 0.763016 -261.199884)
				(arc
					(start 0.763016 -348.199964)
					(mid 0.832426 -348.367536)
					(end 0.999998 -348.436946)
				)
				(arc
					(start 189.6999 -348.436946)
					(mid 190.946539 -348.953321)
					(end 191.462914 -350.19996)
				)
				(arc
					(start 191.462914 -372.000018)
					(mid 191.532324 -372.16759)
					(end 191.699896 -372.237)
				)
				(arc
					(start 199.00011 -372.237)
					(mid 200.246749 -372.753375)
					(end 200.763124 -374.000014)
				)
				(arc
					(start 200.763124 -420.200074)
					(mid 200.832534 -420.367646)
					(end 201.000106 -420.437056)
				)
				(xy 203.040488 -420.437056) (xy 203.040488 -419.168072) (xy 202.032108 -419.168072)
				(arc
					(start 202.032108 -374.000014)
					(mid 201.144056 -371.856068)
					(end 199.00011 -370.968016)
				)
				(xy 197.65645 -370.968016) (xy 197.65645 -367.157762)
				(arc
					(start 199.00011 -367.157762)
					(mid 200.398569 -367.302252)
					(end 201.737976 -367.729516)
				)
				(arc
					(start 201.737976 -367.729516)
					(mid 202.546982 -367.363574)
					(end 203.4159 -367.180876)
				)
				(arc
					(start 203.4159 -367.180876)
					(mid 204.652366 -366.887947)
					(end 205.91907 -366.988598)
				)
				(xy 207.253078 -365.65459) (xy 216.508076 -365.65459) (xy 216.508076 -360.602276)
				(arc
					(start 217.265758 -360.602276)
					(mid 217.464132 -359.62114)
					(end 217.894916 -358.717596)
				)
				(arc
					(start 217.894916 -358.717596)
					(mid 217.890301 -358.22395)
					(end 217.945208 -357.733346)
				)
				(arc
					(start 217.945208 -357.733346)
					(mid 217.934179 -355.836512)
					(end 218.780106 -354.138738)
				)
				(xy 218.780106 -353.438714) (xy 218.898724 -353.438714)
				(arc
					(start 218.898724 -353.414838)
					(mid 217.967015 -351.790048)
					(end 217.857324 -349.920306)
				)
				(arc
					(start 217.857324 -349.920306)
					(mid 217.831895 -349.593648)
					(end 217.832686 -349.266002)
				)
				(arc
					(start 217.832686 -349.266002)
					(mid 217.781278 -349.211968)
					(end 217.730832 -349.157036)
				)
				(xy 216.551764 -349.157036) (xy 216.551764 -340.817454) (xy 209.611976 -339.428074) (xy 209.43316 -339.5472)
				(xy 205.912466 -338.843366) (xy 205.912212 -338.843112) (xy 204.86497 -338.633816) (xy 204.864462 -338.633308)
				(arc
					(start 204.65161 -338.590636)
					(mid 202.916807 -340.87499)
					(end 200.108312 -341.458296)
				)
				(arc
					(start 200.108312 -341.458296)
					(mid 199.610517 -341.495755)
					(end 199.11187 -341.472266)
				)
				(arc
					(start 199.11187 -341.472266)
					(mid 198.256924 -341.522215)
					(end 197.410324 -341.393018)
				)
				(arc
					(start 197.410324 -341.393018)
					(mid 195.13749 -341.368321)
					(end 193.228722 -340.134194)
				)
				(arc
					(start 193.228722 -340.134194)
					(mid 193.140011 -340.072744)
					(end 193.052954 -340.008972)
				)
				(xy 176.50968 -343.357708) (xy 176.50968 -347.167962)
			)
		)
		(polygon
			(pts
				(arc
					(start 45.259498 -343.357708)
					(mid 41.529 -337.590735)
					(end 37.798502 -343.357708)
				)
				(arc
					(start 37.785294 -343.357708)
					(mid 41.529 -345.782916)
					(end 45.272706 -343.357708)
				)
			)
		)
		(polygon
			(pts
				(arc
					(start 75.40244 -335.02981)
					(mid 73.942268 -333.756181)
					(end 72.0598 -333.297276)
				)
				(arc
					(start 71.0946 -333.297276)
					(mid 67.144329 -336.324708)
					(end 69.040756 -340.926166)
				)
				(arc
					(start 69.040756 -340.926166)
					(mid 68.640351 -342.109096)
					(end 68.61556 -343.357708)
				)
				(arc
					(start 68.603622 -343.357708)
					(mid 72.266232 -346.895578)
					(end 76.550266 -344.142568)
				)
				(arc
					(start 76.550266 -344.142568)
					(mid 77.249716 -343.812831)
					(end 77.874876 -343.357708)
				)
				(arc
					(start 77.856842 -343.357708)
					(mid 78.964251 -341.782614)
					(end 79.228442 -339.875368)
				)
				(arc
					(start 79.228442 -339.875368)
					(mid 78.419627 -336.580702)
					(end 75.40244 -335.02981)
				)
			)
		)
	)
	(zone
		(net "GND")
		(layer "F.Cu")
		(hatch none 0.5)
		(connect_pads
			(clearance 0.5)
		)
		(min_thickness 0.25)
		(fill yes
			(thermal_gap 0.5)
			(thermal_bridge_width 0.5)
			(island_removal_mode 0)
		)
		(polygon
			(pts
				(arc
					(start 131.382008 -270.227552)
					(mid 132.666978 -267.958526)
					(end 132.319776 -265.37412)
				)
				(arc
					(start 132.897372 -264.796524)
					(mid 134.541641 -265.268585)
					(end 136.235186 -265.026902)
				)
				(arc
					(start 136.235186 -265.026902)
					(mid 137.543396 -267.798036)
					(end 140.409422 -268.882622)
				)
				(arc
					(start 140.409422 -268.882622)
					(mid 145.303264 -265.242563)
					(end 141.13891 -260.786372)
				)
				(arc
					(start 141.13891 -260.786372)
					(mid 140.011086 -260.714885)
					(end 138.906758 -260.954774)
				)
				(arc
					(start 138.906758 -260.954774)
					(mid 136.871688 -257.647913)
					(end 132.99059 -257.531616)
				)
				(arc
					(start 132.99059 -257.531616)
					(mid 130.13055 -257.118236)
					(end 127.7112 -258.698492)
				)
				(arc
					(start 122.2502 -258.698492)
					(mid 120.303857 -255.139091)
					(end 116.249196 -255.006856)
				)
				(arc
					(start 116.249196 -255.006856)
					(mid 116.22307 -252.061843)
					(end 114.225324 -249.8979)
				)
				(arc
					(start 114.225324 -249.8979)
					(mid 117.786576 -247.541391)
					(end 117.308376 -243.297964)
				)
				(xy 117.308376 -237.299246)
				(arc
					(start 117.034818 -237.299246)
					(mid 116.962152 -237.043378)
					(end 116.87302 -236.79277)
				)
				(arc
					(start 116.87302 -236.79277)
					(mid 117.234465 -235.561942)
					(end 117.19687 -234.279694)
				)
				(xy 139.101576 -238.663734) (xy 139.101576 -247.208294)
				(arc
					(start 140.589762 -247.208294)
					(mid 141.867671 -247.999075)
					(end 143.3449 -248.275094)
				)
				(arc
					(start 144.6149 -248.275094)
					(mid 146.092133 -247.999086)
					(end 147.370038 -247.208294)
				)
				(xy 148.858224 -247.208294) (xy 148.858224 -243.664232)
				(arc
					(start 167.20693 -253.961392)
					(mid 167.182131 -254.383769)
					(end 167.201088 -254.80645)
				)
				(arc
					(start 167.201088 -254.80645)
					(mid 164.52803 -258.3207)
					(end 166.605966 -262.216392)
				)
				(arc
					(start 166.605966 -262.216392)
					(mid 163.70178 -264.407662)
					(end 161.967926 -267.606018)
				)
				(arc
					(start 161.967926 -267.606018)
					(mid 161.57856 -267.840544)
					(end 161.21761 -268.116812)
				)
				(xy 161.21761 -267.042392)
				(arc
					(start 160.247076 -267.042392)
					(mid 160.285624 -265.193793)
					(end 159.506158 -263.517126)
				)
				(xy 159.506158 -260.928866) (xy 149.293834 -260.928866) (xy 149.293834 -270.781018) (xy 144.673574 -270.781018)
				(xy 144.673574 -271.111218) (xy 140.609574 -271.111218) (xy 140.609574 -271.187418) (xy 138.755374 -271.187418)
				(arc
					(start 138.755374 -271.6403)
					(mid 137.024317 -272.490403)
					(end 135.875014 -274.039076)
				)
				(xy 131.382008 -271.173448)
			)
		)
		(polygon
			(pts
				(arc
					(start 145.1356 -249.9106)
					(mid 145.1356 -258.1402)
					(end 145.1356 -249.9106)
				)
			)
		)
	)
	(zone
		(net "GND")
		(layer "F.Cu")
		(hatch none 0.5)
		(connect_pads
			(clearance 0.5)
		)
		(min_thickness 0.25)
		(fill yes
			(thermal_gap 0.5)
			(thermal_bridge_width 0.5)
			(island_removal_mode 0)
		)
		(polygon
			(pts
				(xy 220.801692 -141.861794)
				(arc
					(start 221.225364 -141.861794)
					(mid 221.725864 -142.391006)
					(end 222.309944 -142.826232)
				)
				(arc
					(start 222.309944 -142.826232)
					(mid 222.30646 -144.133236)
					(end 222.527876 -145.42135)
				)
				(arc
					(start 222.527876 -145.42135)
					(mid 220.734217 -147.332118)
					(end 220.415612 -149.933406)
				)
				(arc
					(start 220.415612 -149.933406)
					(mid 220.369758 -150.289733)
					(end 220.354398 -150.64867)
				)
				(arc
					(start 220.354398 -152.19807)
					(mid 220.370577 -152.56664)
					(end 220.418914 -152.932384)
				)
				(arc
					(start 220.418914 -152.932384)
					(mid 220.351545 -153.363)
					(end 220.328998 -153.79827)
				)
				(arc
					(start 220.328998 -155.42387)
					(mid 222.204151 -158.931334)
					(end 226.162362 -159.32023)
				)
				(xy 231.70515 -159.32023) (xy 231.70515 -173.61154) (xy 229.057454 -173.61154) (xy 229.057454 -172.043344)
				(xy 226.393756 -169.379646) (xy 219.96527 -169.379646) (xy 217.339164 -158.87446)
			)
		)
	)
	(zone
		(net "MB1_CM_GATE")
		(layer "F.Cu")
		(hatch none 0.5)
		(connect_pads
			(clearance 0.5)
		)
		(min_thickness 0.25)
		(fill yes
			(thermal_gap 0.5)
			(thermal_bridge_width 0.5)
			(island_removal_mode 0)
		)
		(polygon
			(pts
				(xy 367.974118 -141.6812) (xy 365.375698 -144.27962) (xy 365.375698 -146.302984) (xy 365.535972 -146.463258)
				(xy 367.02238 -146.463258) (xy 367.129314 -146.356324) (xy 367.129314 -144.934686) (xy 368.6048 -143.4592)
				(xy 368.6048 -141.7574) (xy 368.5286 -141.6812)
			)
		)
	)
	(zone
		(layer "F.Cu")
		(hatch none 0.5)
		(connect_pads
			(clearance 0)
		)
		(min_thickness 0.25)
		(keepout
			(tracks allowed)
			(vias allowed)
			(pads allowed)
			(copperpour allowed)
			(footprints not_allowed)
		)
		(placement
			(enabled no)
			(sheetname "")
		)
		(fill
			(thermal_gap 0.5)
			(thermal_bridge_width 0.5)
			(island_removal_mode 0)
		)
		(polygon
			(pts
				(arc
					(start 113.82502 -210.799934)
					(mid 127.824992 -196.799962)
					(end 141.824964 -210.799934)
				)
				(arc
					(start 141.824964 -210.799934)
					(mid 127.824992 -224.799906)
					(end 113.82502 -210.799934)
				)
			)
		)
	)
	(zone
		(layer "F.Cu")
		(hatch none 0.5)
		(connect_pads
			(clearance 0)
		)
		(min_thickness 0.25)
		(keepout
			(tracks not_allowed)
			(vias allowed)
			(pads allowed)
			(copperpour not_allowed)
			(footprints allowed)
		)
		(placement
			(enabled no)
			(sheetname "")
		)
		(fill
			(thermal_gap 0.5)
			(thermal_bridge_width 0.5)
			(island_removal_mode 0)
		)
		(polygon
			(pts
				(arc
					(start 411.174946 -210.799934)
					(mid 425.174918 -196.799962)
					(end 439.17489 -210.799934)
				)
				(arc
					(start 439.17489 -210.799934)
					(mid 425.174918 -224.799906)
					(end 411.174946 -210.799934)
				)
			)
		)
	)
	(zone
		(layer "F.Cu")
		(hatch none 0.5)
		(connect_pads
			(clearance 0)
		)
		(min_thickness 0.25)
		(keepout
			(tracks not_allowed)
			(vias allowed)
			(pads allowed)
			(copperpour not_allowed)
			(footprints allowed)
		)
		(placement
			(enabled no)
			(sheetname "")
		)
		(fill
			(thermal_gap 0.5)
			(thermal_bridge_width 0.5)
			(island_removal_mode 0)
		)
		(polygon
			(pts
				(arc
					(start 388.21995 -162.178746)
					(mid 387.839077 -161.797492)
					(end 387.45795 -162.178492)
				)
				(arc
					(start 387.45795 -163.321492)
					(mid 387.83895 -163.702492)
					(end 388.21995 -163.321492)
				)
				(xy 388.21995 -162.972242)
				(arc
					(start 387.966204 -162.972242)
					(mid 387.930103 -162.987195)
					(end 387.91515 -163.023296)
				)
				(arc
					(start 387.91515 -163.065968)
					(mid 387.83895 -163.588136)
					(end 387.76275 -163.065968)
				)
				(xy 387.76275 -162.9918)
				(arc
					(start 387.765798 -162.988752)
					(mid 387.822406 -162.879498)
					(end 387.93166 -162.82289)
				)
				(xy 387.934708 -162.819842) (xy 388.21995 -162.819842) (xy 388.21995 -162.680142) (xy 387.934708 -162.680142)
				(arc
					(start 387.93166 -162.677094)
					(mid 387.822406 -162.620486)
					(end 387.765798 -162.511232)
				)
				(xy 387.76275 -162.508184)
				(arc
					(start 387.76275 -162.434016)
					(mid 387.83895 -161.911848)
					(end 387.91515 -162.434016)
				)
				(arc
					(start 387.91515 -162.476688)
					(mid 387.930103 -162.512789)
					(end 387.966204 -162.527742)
				)
				(xy 388.21995 -162.527742)
			)
		)
	)
	(zone
		(layer "F.Cu")
		(hatch none 0.5)
		(connect_pads
			(clearance 0)
		)
		(min_thickness 0.25)
		(keepout
			(tracks allowed)
			(vias allowed)
			(pads allowed)
			(copperpour allowed)
			(footprints not_allowed)
		)
		(placement
			(enabled no)
			(sheetname "")
		)
		(fill
			(thermal_gap 0.5)
			(thermal_bridge_width 0.5)
			(island_removal_mode 0)
		)
		(polygon
			(pts
				(xy 231.70007 -263.19988) (xy 231.70007 -289.200082) (xy 256.70002 -289.200082) (xy 256.70002 -263.19988)
			)
		)
	)
	(zone
		(net "GND")
		(layer "F.Cu")
		(hatch none 0.5)
		(connect_pads
			(clearance 0.5)
		)
		(min_thickness 0.25)
		(fill yes
			(thermal_gap 0.5)
			(thermal_bridge_width 0.5)
			(island_removal_mode 0)
		)
		(polygon
			(pts
				(xy 319.9892 -218.8972) (xy 319.546732 -219.339668) (xy 319.546732 -222.596456)
				(arc
					(start 325.015606 -228.06533)
					(mid 325.860229 -229.329398)
					(end 326.156828 -230.820468)
				)
				(arc
					(start 326.156828 -232.836212)
					(mid 326.401416 -234.238292)
					(end 326.156828 -235.640372)
				)
				(xy 326.156828 -237.25632) (xy 326.503792 -237.25632)
				(arc
					(start 326.503792 -238.887254)
					(mid 330.186045 -241.659637)
					(end 328.94905 -246.099838)
				)
				(arc
					(start 328.94905 -246.099838)
					(mid 330.43516 -251.014294)
					(end 325.94804 -253.509272)
				)
				(arc
					(start 325.94804 -253.509272)
					(mid 325.832519 -253.582471)
					(end 325.714614 -253.651766)
				)
				(arc
					(start 325.714614 -253.651766)
					(mid 323.948171 -255.296843)
					(end 321.561714 -255.659382)
				)
				(arc
					(start 321.561714 -255.659382)
					(mid 318.870223 -255.130479)
					(end 317.117984 -253.020068)
				)
				(arc
					(start 317.117984 -253.020068)
					(mid 317.017462 -252.986947)
					(end 316.917832 -252.951234)
				)
				(arc
					(start 316.917832 -252.951234)
					(mid 315.810937 -252.5686)
					(end 314.867798 -251.874274)
				)
				(xy 314.325 -251.331476) (xy 314.325 -251.333) (xy 311.98058 -251.333) (xy 311.98058 -256.159)
				(arc
					(start 313.825636 -256.159)
					(mid 316.145497 -256.189147)
					(end 318.075818 -257.476244)
				)
				(arc
					(start 318.075818 -257.476244)
					(mid 321.371161 -258.071556)
					(end 323.117464 -260.928866)
				)
				(xy 330.656184 -260.928866)
				(arc
					(start 330.656184 -263.830054)
					(mid 331.400941 -265.350544)
					(end 331.46619 -267.042392)
				)
				(xy 332.367636 -267.042392) (xy 332.367636 -267.225018)
				(arc
					(start 332.6384 -267.225018)
					(mid 332.907845 -267.233935)
					(end 333.176118 -267.260578)
				)
				(arc
					(start 333.176118 -267.260578)
					(mid 336.191593 -263.11475)
					(end 341.033608 -261.43077)
				)
				(arc
					(start 341.033608 -261.43077)
					(mid 340.419201 -254.484798)
					(end 346.88907 -257.085592)
				)
				(arc
					(start 346.88907 -257.085592)
					(mid 347.952921 -257.236929)
					(end 348.940628 -257.66014)
				)
				(arc
					(start 348.940628 -257.66014)
					(mid 347.69454 -254.068164)
					(end 349.943166 -251.002546)
				)
				(arc
					(start 349.943166 -251.002546)
					(mid 348.173222 -250.553995)
					(end 346.77477 -249.379994)
				)
				(arc
					(start 346.604082 -249.379994)
					(mid 344.87064 -250.313186)
					(end 342.902032 -250.32843)
				)
				(arc
					(start 342.902032 -250.32843)
					(mid 342.168232 -250.317837)
					(end 341.448136 -250.176284)
				)
				(arc
					(start 341.448136 -250.176284)
					(mid 339.445494 -250.296675)
					(end 337.626452 -249.450352)
				)
				(arc
					(start 337.626452 -249.450352)
					(mid 337.491372 -249.43266)
					(end 337.356958 -249.410474)
				)
				(xy 334.949546 -249.410474) (xy 334.949546 -248.134886) (xy 334.63992 -248.134886)
				(arc
					(start 334.63992 -247.580912)
					(mid 334.001645 -245.38686)
					(end 334.63992 -243.192808)
				)
				(xy 334.63992 -239.368838) (xy 336.110834 -239.368838)
				(arc
					(start 336.110834 -236.699806)
					(mid 336.407427 -235.208734)
					(end 337.252056 -233.944668)
				)
				(arc
					(start 338.0867 -233.110024)
					(mid 338.24267 -232.810822)
					(end 338.422488 -232.525316)
				)
				(arc
					(start 338.422488 -232.525316)
					(mid 337.892485 -229.582186)
					(end 339.507068 -227.065078)
				)
				(arc
					(start 339.507068 -220.046804)
					(mid 338.296738 -221.476046)
					(end 336.858102 -222.675196)
				)
				(arc
					(start 336.858102 -222.675196)
					(mid 334.429762 -228.895239)
					(end 329.371198 -224.536762)
				)
				(arc
					(start 329.371198 -224.536762)
					(mid 324.562547 -222.723933)
					(end 321.132454 -218.8972)
				)
			)
		)
	)
	(zone
		(net "P12V_A_COMP")
		(layer "F.Cu")
		(hatch none 0.5)
		(connect_pads
			(clearance 0.5)
		)
		(min_thickness 0.25)
		(fill yes
			(thermal_gap 0.5)
			(thermal_bridge_width 0.5)
			(island_removal_mode 0)
		)
		(polygon
			(pts
				(xy 220.43136 -12.943078) (xy 220.283786 -13.090652) (xy 220.283786 -22.877526) (xy 220.62186 -23.2156)
				(xy 225.285808 -23.2156) (xy 226.131374 -22.370034) (xy 226.131374 -13.329158) (xy 225.745294 -12.943078)
			)
		)
	)
	(zone
		(net "P5V_A_4")
		(layer "F.Cu")
		(hatch none 0.5)
		(connect_pads
			(clearance 0.5)
		)
		(min_thickness 0.25)
		(fill yes
			(thermal_gap 0.5)
			(thermal_bridge_width 0.5)
			(island_removal_mode 0)
		)
		(polygon
			(pts
				(xy 431.454052 -50.332894) (xy 431.200052 -50.586894) (xy 431.200052 -55.285894) (xy 431.454052 -55.539894)
				(xy 433.740052 -55.539894) (xy 433.994052 -55.285894) (xy 433.994052 -50.586894) (xy 433.740052 -50.332894)
			)
		)
	)
	(zone
		(layer "F.Cu")
		(hatch none 0.5)
		(connect_pads
			(clearance 0)
		)
		(min_thickness 0.25)
		(keepout
			(tracks not_allowed)
			(vias allowed)
			(pads allowed)
			(copperpour not_allowed)
			(footprints allowed)
		)
		(placement
			(enabled no)
			(sheetname "")
		)
		(fill
			(thermal_gap 0.5)
			(thermal_bridge_width 0.5)
			(island_removal_mode 0)
		)
		(polygon
			(pts
				(arc
					(start 356.675182 -47.178722)
					(mid 356.289229 -46.792388)
					(end 355.903022 -47.178468)
				)
				(arc
					(start 355.903022 -48.321468)
					(mid 356.289102 -48.707548)
					(end 356.675182 -48.321468)
				)
				(xy 356.675182 -47.972218)
				(arc
					(start 356.416102 -47.972218)
					(mid 356.380181 -47.987097)
					(end 356.365302 -48.023018)
				)
				(arc
					(start 356.365302 -48.065944)
					(mid 356.289102 -48.588112)
					(end 356.212902 -48.065944)
				)
				(xy 356.212902 -47.991522)
				(arc
					(start 356.21595 -47.988474)
					(mid 356.272481 -47.879397)
					(end 356.381558 -47.822866)
				)
				(xy 356.384606 -47.819818) (xy 356.675182 -47.819818) (xy 356.675182 -47.680118) (xy 356.384606 -47.680118)
				(arc
					(start 356.381558 -47.67707)
					(mid 356.272481 -47.620539)
					(end 356.21595 -47.511462)
				)
				(xy 356.212902 -47.508414)
				(arc
					(start 356.212902 -47.433992)
					(mid 356.289102 -46.911824)
					(end 356.365302 -47.433992)
				)
				(arc
					(start 356.365302 -47.476918)
					(mid 356.380181 -47.512839)
					(end 356.416102 -47.527718)
				)
				(xy 356.675182 -47.527718)
			)
		)
	)
	(zone
		(layer "F.Cu")
		(hatch none 0.5)
		(connect_pads
			(clearance 0)
		)
		(min_thickness 0.25)
		(keepout
			(tracks allowed)
			(vias allowed)
			(pads allowed)
			(copperpour allowed)
			(footprints not_allowed)
		)
		(placement
			(enabled no)
			(sheetname "")
		)
		(fill
			(thermal_gap 0.5)
			(thermal_bridge_width 0.5)
			(island_removal_mode 0)
		)
		(polygon
			(pts
				(arc
					(start 89.324942 -322.799964)
					(mid 96.324928 -315.799978)
					(end 103.324914 -322.799964)
				)
				(arc
					(start 103.324914 -328.799952)
					(mid 96.324928 -335.799938)
					(end 89.324942 -328.799952)
				)
			)
		)
	)
	(zone
		(net "P3V3_STBY_A")
		(layer "F.Cu")
		(hatch none 0.5)
		(connect_pads
			(clearance 0.5)
		)
		(min_thickness 0.25)
		(fill yes
			(thermal_gap 0.5)
			(thermal_bridge_width 0.5)
			(island_removal_mode 0)
		)
		(polygon
			(pts
				(xy 261.041896 -208.6864) (xy 258.6228 -211.105496) (xy 258.6228 -224.3582) (xy 253.336044 -229.644956)
				(xy 253.336044 -236.391704) (xy 254.367284 -237.422944) (xy 254.367284 -238.814864) (xy 257.8735 -242.32108)
				(xy 257.8735 -243.8781) (xy 258.6736 -244.6782) (xy 260.0452 -244.6782) (xy 260.1976 -244.5258)
				(xy 260.1976 -243.5352) (xy 260.1214 -243.459) (xy 259.461 -243.459) (xy 259.207 -243.205) (xy 259.207 -242.419378)
				(xy 255.684782 -238.89716) (xy 255.684782 -234.07878) (xy 256.296414 -233.467148) (xy 256.296414 -231.734614)
				(xy 256.662174 -231.368854) (xy 258.158742 -231.368854) (xy 258.2926 -231.234996) (xy 258.2926 -230.4542)
				(xy 258.2418 -230.4034) (xy 256.5654 -230.4034) (xy 256.2098 -230.0478) (xy 256.2098 -229.4128)
				(xy 258.2164 -227.4062) (xy 260.5786 -227.4062) (xy 260.985 -227.8126) (xy 260.985 -230.020368)
				(xy 261.112 -230.147368) (xy 263.040368 -230.147368) (xy 263.101074 -230.086408) (xy 263.101074 -228.515926)
				(xy 263.4234 -228.1936) (xy 265.5824 -228.1936) (xy 265.938 -228.5492) (xy 265.938 -230.0732) (xy 266.011406 -230.146606)
				(xy 266.570206 -230.146606) (xy 266.680188 -230.036624) (xy 266.680188 -228.543612) (xy 266.9794 -228.2444)
				(xy 267.8684 -228.2444) (xy 268.3256 -228.7016) (xy 268.3256 -230.0732) (xy 268.4018 -230.1494)
				(xy 269.494 -230.1494) (xy 269.7226 -230.378) (xy 269.7226 -238.47806) (xy 270.002 -238.75746) (xy 272.31086 -238.75746)
				(xy 272.572226 -238.496348) (xy 272.572226 -230.687626) (xy 266.2936 -224.409) (xy 266.2936 -222.377)
				(xy 266.192 -222.2754) (xy 265.557 -222.2754) (xy 265.3792 -222.4532) (xy 265.3792 -223.0882) (xy 265.049 -223.4184)
				(xy 262.4074 -223.4184) (xy 262.1026 -223.1136) (xy 262.1026 -221.044262) (xy 263.6774 -219.469462)
				(xy 263.6774 -218.2368) (xy 263.6266 -218.186) (xy 260.4262 -218.186) (xy 260.0706 -217.8304) (xy 260.0706 -212.007958)
				(xy 261.614158 -210.4644) (xy 264.7188 -210.4644) (xy 265.2776 -209.9056) (xy 267.0556 -209.9056)
				(xy 267.5382 -210.3882) (xy 267.5382 -211.6074) (xy 267.589 -211.6582) (xy 268.097 -211.6582) (xy 268.1986 -211.5566)
				(xy 268.1986 -209.4484) (xy 267.4366 -208.6864)
			)
		)
		(polygon
			(pts
				(xy 259.6896 -243.8781) (xy 259.4864 -243.8781) (xy 259.4864 -244.0813) (xy 259.6896 -244.0813)
			)
		)
		(polygon
			(pts
				(xy 272.140172 -238.112046) (xy 271.936972 -238.112046) (xy 271.936972 -238.315246) (xy 272.140172 -238.315246)
			)
		)
		(polygon
			(pts
				(xy 271.581372 -238.112046) (xy 271.378172 -238.112046) (xy 271.378172 -238.315246) (xy 271.581372 -238.315246)
			)
		)
		(polygon
			(pts
				(xy 270.870172 -238.112046) (xy 270.666972 -238.112046) (xy 270.666972 -238.315246) (xy 270.870172 -238.315246)
			)
		)
		(polygon
			(pts
				(xy 270.311372 -238.112046) (xy 270.108172 -238.112046) (xy 270.108172 -238.315246) (xy 270.311372 -238.315246)
			)
		)
		(polygon
			(pts
				(xy 257.817112 -230.8606) (xy 257.613912 -230.8606) (xy 257.613912 -231.0638) (xy 257.817112 -231.0638)
			)
		)
		(polygon
			(pts
				(xy 269.0368 -229.489) (xy 268.8336 -229.489) (xy 268.8336 -229.6922) (xy 269.0368 -229.6922)
			)
		)
		(polygon
			(pts
				(xy 262.5598 -229.489) (xy 262.3566 -229.489) (xy 262.3566 -229.6922) (xy 262.5598 -229.6922)
			)
		)
		(polygon
			(pts
				(xy 261.6454 -229.2858) (xy 261.4422 -229.2858) (xy 261.4422 -229.489) (xy 261.6454 -229.489)
			)
		)
		(polygon
			(pts
				(xy 265.074654 -223.860614) (xy 264.871454 -223.860614) (xy 264.871454 -224.063814) (xy 265.074654 -224.063814)
			)
		)
		(polygon
			(pts
				(xy 264.515854 -223.860614) (xy 264.312654 -223.860614) (xy 264.312654 -224.063814) (xy 264.515854 -224.063814)
			)
		)
		(polygon
			(pts
				(xy 265.710162 -222.714058) (xy 265.506962 -222.714058) (xy 265.506962 -222.917258) (xy 265.710162 -222.917258)
			)
		)
		(polygon
			(pts
				(xy 261.648956 -221.854014) (xy 261.445756 -221.854014) (xy 261.445756 -222.057214) (xy 261.648956 -222.057214)
			)
		)
		(polygon
			(pts
				(xy 261.648956 -221.295214) (xy 261.445756 -221.295214) (xy 261.445756 -221.498414) (xy 261.648956 -221.498414)
			)
		)
		(polygon
			(pts
				(xy 261.407402 -218.936062) (xy 261.204202 -218.936062) (xy 261.204202 -219.139262) (xy 261.407402 -219.139262)
			)
		)
		(polygon
			(pts
				(xy 260.543802 -218.936062) (xy 260.340602 -218.936062) (xy 260.340602 -219.139262) (xy 260.543802 -219.139262)
			)
		)
		(polygon
			(pts
				(xy 262.423402 -218.682062) (xy 262.220202 -218.682062) (xy 262.220202 -218.885262) (xy 262.423402 -218.885262)
			)
		)
		(polygon
			(pts
				(xy 261.813802 -218.682062) (xy 261.610602 -218.682062) (xy 261.610602 -218.885262) (xy 261.813802 -218.885262)
			)
		)
		(polygon
			(pts
				(xy 264.737342 -209.804762) (xy 264.534142 -209.804762) (xy 264.534142 -210.007962) (xy 264.737342 -210.007962)
			)
		)
		(polygon
			(pts
				(xy 264.178542 -209.804762) (xy 263.975342 -209.804762) (xy 263.975342 -210.007962) (xy 264.178542 -210.007962)
			)
		)
		(polygon
			(pts
				(xy 263.518142 -209.804762) (xy 263.314942 -209.804762) (xy 263.314942 -210.007962) (xy 263.518142 -210.007962)
			)
		)
		(polygon
			(pts
				(xy 262.959342 -209.804762) (xy 262.756142 -209.804762) (xy 262.756142 -210.007962) (xy 262.959342 -210.007962)
			)
		)
	)
	(zone
		(layer "F.Cu")
		(hatch none 0.5)
		(connect_pads
			(clearance 0)
		)
		(min_thickness 0.25)
		(keepout
			(tracks not_allowed)
			(vias allowed)
			(pads allowed)
			(copperpour not_allowed)
			(footprints allowed)
		)
		(placement
			(enabled no)
			(sheetname "")
		)
		(fill
			(thermal_gap 0.5)
			(thermal_bridge_width 0.5)
			(island_removal_mode 0)
		)
		(polygon
			(pts
				(arc
					(start 283.574744 -106.85018)
					(mid 282.600146 -107.175046)
					(end 282.925012 -108.149644)
				)
				(xy 282.923742 -108.15193) (xy 284.923738 -109.151928) (xy 284.923992 -109.151674)
				(arc
					(start 284.925008 -109.149642)
					(mid 285.899606 -108.824776)
					(end 285.57474 -107.850178)
				)
				(xy 285.57601 -107.847892) (xy 285.36265 -107.741212)
				(arc
					(start 284.715966 -107.741212)
					(mid 284.701608 -107.744644)
					(end 284.690312 -107.754166)
				)
				(xy 284.549596 -107.947968) (xy 284.549596 -107.956604)
				(arc
					(start 284.535118 -107.971336)
					(mid 284.538001 -108.018885)
					(end 284.570678 -108.053632)
				)
				(arc
					(start 284.811724 -108.174028)
					(mid 285.738175 -108.744321)
					(end 284.72638 -108.344462)
				)
				(xy 284.485334 -108.223812) (xy 284.450028 -108.206286)
				(arc
					(start 284.448504 -108.20146)
					(mid 284.353439 -108.068768)
					(end 284.356048 -107.90555)
				)
				(xy 284.354016 -107.89285) (xy 284.359096 -107.885992) (xy 284.359096 -107.87761) (xy 284.381702 -107.855004)
				(xy 284.536388 -107.642406) (xy 284.536388 -107.642152) (xy 284.559502 -107.610402)
				(arc
					(start 284.565598 -107.609386)
					(mid 284.615333 -107.57487)
					(end 284.672532 -107.55503)
				)
				(xy 284.67685 -107.550712) (xy 284.98165 -107.550712) (xy 284.77845 -107.449112)
				(arc
					(start 284.715458 -107.449112)
					(mid 284.56866 -107.484424)
					(end 284.453838 -107.582462)
				)
				(xy 284.257496 -107.852972) (xy 284.257496 -107.86872) (xy 284.22981 -107.89666) (xy 284.228286 -107.89793)
				(xy 284.201616 -107.9246)
				(arc
					(start 284.19679 -107.9246)
					(mid 284.087149 -107.970071)
					(end 283.968698 -107.962192)
				)
				(xy 283.963872 -107.963716)
				(arc
					(start 283.688028 -107.825794)
					(mid 282.761577 -107.255501)
					(end 283.773372 -107.65536)
				)
				(arc
					(start 284.01391 -107.775756)
					(mid 284.042679 -107.782983)
					(end 284.071822 -107.777534)
				)
				(xy 284.089602 -107.760008) (xy 284.323028 -107.438444)
				(arc
					(start 284.325314 -107.43819)
					(mid 284.403783 -107.364033)
					(end 284.496002 -107.307888)
				)
				(xy 283.576014 -106.847894)
			)
		)
	)
	(zone
		(layer "F.Cu")
		(hatch none 0.5)
		(connect_pads
			(clearance 0)
		)
		(min_thickness 0.25)
		(keepout
			(tracks not_allowed)
			(vias allowed)
			(pads allowed)
			(copperpour not_allowed)
			(footprints allowed)
		)
		(placement
			(enabled no)
			(sheetname "")
		)
		(fill
			(thermal_gap 0.5)
			(thermal_bridge_width 0.5)
			(island_removal_mode 0)
		)
		(polygon
			(pts
				(arc
					(start 388.21995 -277.17877)
					(mid 387.839077 -276.797516)
					(end 387.45795 -277.178516)
				)
				(arc
					(start 387.45795 -278.321516)
					(mid 387.83895 -278.702516)
					(end 388.21995 -278.321516)
				)
				(xy 388.21995 -277.972266)
				(arc
					(start 387.966204 -277.972266)
					(mid 387.930103 -277.987219)
					(end 387.91515 -278.02332)
				)
				(arc
					(start 387.91515 -278.065992)
					(mid 387.83895 -278.58816)
					(end 387.76275 -278.065992)
				)
				(xy 387.76275 -277.991824)
				(arc
					(start 387.765798 -277.988776)
					(mid 387.822406 -277.879522)
					(end 387.93166 -277.822914)
				)
				(xy 387.934708 -277.819866) (xy 388.21995 -277.819866) (xy 388.21995 -277.680166) (xy 387.934708 -277.680166)
				(arc
					(start 387.93166 -277.677118)
					(mid 387.822406 -277.62051)
					(end 387.765798 -277.511256)
				)
				(xy 387.76275 -277.508208)
				(arc
					(start 387.76275 -277.43404)
					(mid 387.83895 -276.911872)
					(end 387.91515 -277.43404)
				)
				(arc
					(start 387.91515 -277.476712)
					(mid 387.930103 -277.512813)
					(end 387.966204 -277.527766)
				)
				(xy 388.21995 -277.527766)
			)
		)
	)
	(zone
		(net "P5V_B")
		(layer "F.Cu")
		(hatch none 0.5)
		(connect_pads
			(clearance 0.5)
		)
		(min_thickness 0.25)
		(fill yes
			(thermal_gap 0.5)
			(thermal_bridge_width 0.5)
			(island_removal_mode 0)
		)
		(polygon
			(pts
				(xy 267.404088 15.406116) (xy 267.236194 15.238222) (xy 267.236194 11.828526) (xy 267.372338 11.692382)
				(xy 268.295882 11.692382) (xy 268.420088 11.816588) (xy 268.420088 15.279116) (xy 268.293088 15.406116)
			)
		)
		(polygon
			(pts
				(xy 268.28115 12.4079) (xy 268.07795 12.4079) (xy 268.07795 12.2047) (xy 268.28115 12.2047)
			)
		)
		(polygon
			(pts
				(xy 267.67155 12.4079) (xy 267.46835 12.4079) (xy 267.46835 12.2047) (xy 267.67155 12.2047)
			)
		)
	)
	(zone
		(layer "F.Cu")
		(hatch none 0.5)
		(connect_pads
			(clearance 0)
		)
		(min_thickness 0.25)
		(keepout
			(tracks allowed)
			(vias allowed)
			(pads allowed)
			(copperpour allowed)
			(footprints not_allowed)
		)
		(placement
			(enabled no)
			(sheetname "")
		)
		(fill
			(thermal_gap 0.5)
			(thermal_bridge_width 0.5)
			(island_removal_mode 0)
		)
		(polygon
			(pts
				(xy 189.799976 -79.799942) (xy 214.799926 -79.799942) (xy 214.799926 -53.799994) (xy 189.799976 -53.799994)
			)
		)
	)
	(zone
		(net "12V_PRE_18")
		(layer "F.Cu")
		(hatch none 0.5)
		(connect_pads
			(clearance 0.5)
		)
		(min_thickness 0.25)
		(fill yes
			(thermal_gap 0.5)
			(thermal_bridge_width 0.5)
			(island_removal_mode 0)
		)
		(polygon
			(pts
				(xy 331.268578 -183.31434) (xy 328.803 -185.779918) (xy 326.263 -185.779918) (xy 326.009 -186.033918)
				(xy 326.009 -186.414918) (xy 326.263 -186.668918) (xy 332.961234 -186.668918) (xy 333.621634 -186.008518)
				(xy 333.621634 -183.43499) (xy 333.500984 -183.31434)
			)
		)
	)
	(zone
		(layer "F.Cu")
		(hatch none 0.5)
		(connect_pads
			(clearance 0)
		)
		(min_thickness 0.25)
		(keepout
			(tracks not_allowed)
			(vias allowed)
			(pads allowed)
			(copperpour not_allowed)
			(footprints allowed)
		)
		(placement
			(enabled no)
			(sheetname "")
		)
		(fill
			(thermal_gap 0.5)
			(thermal_bridge_width 0.5)
			(island_removal_mode 0)
		)
		(polygon
			(pts
				(arc
					(start 282.83662 -263.153652)
					(mid 282.28798 -263.702292)
					(end 282.83662 -264.250932)
				)
				(arc
					(start 284.236668 -264.250932)
					(mid 284.785308 -263.702292)
					(end 284.236668 -263.153652)
				)
				(xy 283.777944 -263.153652)
				(arc
					(start 283.777944 -263.575292)
					(mid 283.787243 -263.597743)
					(end 283.809694 -263.607042)
				)
				(arc
					(start 283.854652 -263.607042)
					(mid 284.63038 -263.702292)
					(end 283.854652 -263.797542)
				)
				(xy 283.770324 -263.797542)
				(arc
					(start 283.765752 -263.793224)
					(mid 283.652491 -263.732495)
					(end 283.591762 -263.619234)
				)
				(xy 283.587444 -263.614662) (xy 283.587444 -263.153652) (xy 283.485844 -263.153652) (xy 283.485844 -263.614662)
				(arc
					(start 283.481526 -263.619234)
					(mid 283.420797 -263.732495)
					(end 283.307536 -263.793224)
				)
				(xy 283.302964 -263.797542)
				(arc
					(start 283.218636 -263.797542)
					(mid 282.442908 -263.702292)
					(end 283.218636 -263.607042)
				)
				(arc
					(start 283.263594 -263.607042)
					(mid 283.286045 -263.597743)
					(end 283.295344 -263.575292)
				)
				(xy 283.295344 -263.153652)
			)
		)
	)
	(zone
		(net "P5V_HDD24")
		(layer "F.Cu")
		(hatch none 0.5)
		(connect_pads
			(clearance 0.5)
		)
		(min_thickness 0.25)
		(fill yes
			(thermal_gap 0.5)
			(thermal_bridge_width 0.5)
			(island_removal_mode 0)
		)
		(polygon
			(pts
				(xy 19.668998 -56.682894) (xy 19.414998 -56.936894) (xy 19.414998 -59.222894) (xy 19.668998 -59.476894)
				(xy 19.668998 -61.508894) (xy 20.430998 -62.270894) (xy 20.430998 -63.032894) (xy 20.811998 -63.413894)
				(xy 21.192998 -63.413894) (xy 24.367998 -66.588894) (xy 31.225998 -66.588894) (xy 31.352998 -66.461894)
				(xy 31.352998 -64.683894) (xy 31.225998 -64.556894) (xy 26.145998 -64.556894) (xy 24.240998 -62.651894)
				(xy 23.351998 -62.651894) (xy 22.462998 -61.762894) (xy 22.462998 -59.222894) (xy 23.097998 -58.587894)
				(xy 23.097998 -56.936894) (xy 22.843998 -56.682894)
			)
		)
		(polygon
			(pts
				(xy 21.675598 -63.109094) (xy 21.472398 -63.109094) (xy 21.472398 -63.312294) (xy 21.675598 -63.312294)
			)
		)
		(polygon
			(pts
				(xy 21.675598 -62.245494) (xy 21.472398 -62.245494) (xy 21.472398 -62.448694) (xy 21.675598 -62.448694)
			)
		)
		(polygon
			(pts
				(xy 20.811998 -62.245494) (xy 20.608798 -62.245494) (xy 20.608798 -62.448694) (xy 20.811998 -62.448694)
			)
		)
	)
	(zone
		(net "P5V_A_2")
		(layer "F.Cu")
		(hatch none 0.5)
		(connect_pads
			(clearance 0.5)
		)
		(min_thickness 0.25)
		(fill yes
			(thermal_gap 0.5)
			(thermal_bridge_width 0.5)
			(island_removal_mode 0)
		)
		(polygon
			(pts
				(xy 113.017554 -51.855624) (xy 112.763554 -52.109624) (xy 112.763554 -54.395624) (xy 113.017554 -54.649624)
				(xy 117.716554 -54.649624) (xy 117.970554 -54.395624) (xy 117.970554 -52.109624) (xy 117.716554 -51.855624)
			)
		)
	)
	(zone
		(net "12V_PRE_14")
		(layer "F.Cu")
		(hatch none 0.5)
		(connect_pads
			(clearance 0.5)
		)
		(min_thickness 0.25)
		(fill yes
			(thermal_gap 0.5)
			(thermal_bridge_width 0.5)
			(island_removal_mode 0)
		)
		(polygon
			(pts
				(xy 82.768948 -178.794918) (xy 82.641948 -178.921918) (xy 82.641948 -180.445918) (xy 84.038948 -181.842918)
				(xy 85.435948 -181.842918) (xy 90.388948 -186.795918) (xy 94.325948 -186.795918) (xy 94.452948 -186.668918)
				(xy 94.452948 -185.906918) (xy 94.325948 -185.779918) (xy 91.023948 -185.779918) (xy 84.038948 -178.794918)
			)
		)
	)
	(zone
		(net "P12V_A")
		(layer "F.Cu")
		(hatch none 0.5)
		(connect_pads
			(clearance 0.5)
		)
		(min_thickness 0.25)
		(fill yes
			(thermal_gap 0.5)
			(thermal_bridge_width 0.5)
			(island_removal_mode 0)
		)
		(polygon
			(pts
				(xy 469.307926 -169.142918) (xy 468.291926 -170.158918) (xy 467.656926 -170.158918) (xy 467.275926 -170.539918)
				(xy 467.275926 -173.079918) (xy 467.529926 -173.333918) (xy 470.831926 -173.333918) (xy 471.085926 -173.079918)
				(xy 471.085926 -170.793918) (xy 470.450926 -170.158918) (xy 470.069926 -170.158918) (xy 469.815926 -169.904918)
				(xy 469.815926 -169.269918) (xy 469.688926 -169.142918)
			)
		)
		(polygon
			(pts
				(xy 469.282526 -169.727118) (xy 469.079326 -169.727118) (xy 469.079326 -169.930318) (xy 469.282526 -169.930318)
			)
		)
	)
	(zone
		(net "GND")
		(layer "F.Cu")
		(hatch none 0.5)
		(connect_pads
			(clearance 0.5)
		)
		(min_thickness 0.25)
		(fill yes
			(thermal_gap 0.5)
			(thermal_bridge_width 0.5)
			(island_removal_mode 0)
		)
		(polygon
			(pts
				(xy 374.704356 -69.193918) (xy 374.896126 -69.193918)
				(arc
					(start 374.896126 -57.8358)
					(mid 375.196541 -56.996753)
					(end 375.298462 -56.111394)
				)
				(arc
					(start 375.298462 -49.824894)
					(mid 375.230262 -49.098821)
					(end 375.027952 -48.398176)
				)
				(arc
					(start 375.027952 -48.398176)
					(mid 374.747603 -47.638061)
					(end 374.324626 -46.947074)
				)
				(xy 374.324626 -43.47337)
				(arc
					(start 373.971058 -43.47337)
					(mid 373.554155 -41.044396)
					(end 371.817392 -39.295832)
				)
				(arc
					(start 371.817392 -39.295832)
					(mid 373.701062 -38.830461)
					(end 375.158254 -37.549328)
				)
				(arc
					(start 383.363724 -37.549328)
					(mid 383.369225 -38.383298)
					(end 383.54381 -39.198804)
				)
				(xy 383.54381 -39.671244) (xy 380.465838 -39.671244) (xy 380.465838 -41.352724)
				(arc
					(start 380.45136 -41.367202)
					(mid 379.942054 -41.996026)
					(end 379.574552 -42.716958)
				)
				(arc
					(start 379.574552 -42.716958)
					(mid 377.739716 -46.823296)
					(end 380.812294 -50.10785)
				)
				(arc
					(start 380.812294 -55.804054)
					(mid 379.207573 -56.093164)
					(end 377.843288 -56.98617)
				)
				(xy 376.813826 -56.98617)
				(arc
					(start 376.813826 -58.682128)
					(mid 376.63353 -59.733717)
					(end 376.731276 -60.79617)
				)
				(xy 376.051826 -60.79617) (xy 376.051826 -69.282818)
				(arc
					(start 376.106436 -69.282818)
					(mid 376.151919 -70.075886)
					(end 376.34799 -70.84568)
				)
				(xy 376.34799 -78.735174) (xy 369.562126 -78.735174) (xy 369.562126 -77.524102) (xy 369.565174 -77.511148)
				(xy 371.583458 -77.511148) (xy 374.704356 -74.39025)
			)
		)
	)
	(zone
		(net "12V_PRE_16")
		(layer "F.Cu")
		(hatch none 0.5)
		(connect_pads
			(clearance 0.5)
		)
		(min_thickness 0.25)
		(fill yes
			(thermal_gap 0.5)
			(thermal_bridge_width 0.5)
			(island_removal_mode 0)
		)
		(polygon
			(pts
				(xy 145.868898 -178.794918) (xy 145.741898 -178.921918) (xy 145.741898 -180.445918) (xy 147.138898 -181.842918)
				(xy 148.535898 -181.842918) (xy 153.488898 -186.795918) (xy 157.425898 -186.795918) (xy 157.552898 -186.668918)
				(xy 157.552898 -185.906918) (xy 157.425898 -185.779918) (xy 154.123898 -185.779918) (xy 147.138898 -178.794918)
			)
		)
	)
	(zone
		(layer "F.Cu")
		(hatch none 0.5)
		(connect_pads
			(clearance 0)
		)
		(min_thickness 0.25)
		(keepout
			(tracks allowed)
			(vias allowed)
			(pads allowed)
			(copperpour allowed)
			(footprints not_allowed)
		)
		(placement
			(enabled no)
			(sheetname "")
		)
		(fill
			(thermal_gap 0.5)
			(thermal_bridge_width 0.5)
			(island_removal_mode 0)
		)
		(polygon
			(pts
				(arc
					(start 449.674996 -92.799916)
					(mid 456.674982 -85.79993)
					(end 463.674968 -92.799916)
				)
				(arc
					(start 463.674968 -98.799904)
					(mid 456.674982 -105.79989)
					(end 449.674996 -98.799904)
				)
			)
		)
	)
	(zone
		(layer "F.Cu")
		(hatch none 0.5)
		(connect_pads
			(clearance 0)
		)
		(min_thickness 0.25)
		(keepout
			(tracks allowed)
			(vias allowed)
			(pads allowed)
			(copperpour allowed)
			(footprints not_allowed)
		)
		(placement
			(enabled no)
			(sheetname "")
		)
		(fill
			(thermal_gap 0.5)
			(thermal_bridge_width 0.5)
			(island_removal_mode 0)
		)
		(polygon
			(pts
				(xy 0 -9.99998) (xy 15.32509 -9.99998) (xy 15.32509 0)
				(arc
					(start 0.999998 0)
					(mid 0.292893 -0.292893)
					(end 0 -0.999998)
				)
			)
		)
	)
	(zone
		(net "GND")
		(layer "F.Cu")
		(hatch none 0.5)
		(connect_pads
			(clearance 0.5)
		)
		(min_thickness 0.25)
		(fill yes
			(thermal_gap 0.5)
			(thermal_bridge_width 0.5)
			(island_removal_mode 0)
		)
		(polygon
			(pts
				(arc
					(start 396.999968 -0.763016)
					(mid 396.832396 -0.832426)
					(end 396.762986 -0.999998)
				)
				(arc
					(start 396.762986 -13.999972)
					(mid 396.246611 -15.246611)
					(end 394.999972 -15.762986)
				)
				(xy 394.734796 -15.762986) (xy 394.734796 -20.842224)
				(arc
					(start 393.541758 -20.842224)
					(mid 393.530105 -21.162543)
					(end 393.494006 -21.481034)
				)
				(xy 393.494006 -21.653754) (xy 401.585684 -21.653754) (xy 407.52776 -27.59583)
				(arc
					(start 407.52776 -35.743134)
					(mid 407.772348 -37.145214)
					(end 407.52776 -38.547294)
				)
				(xy 407.52776 -59.40044) (xy 411.9118 -55.0164) (xy 411.9118 -51.9176) (xy 409.3718 -49.3776) (xy 409.3718 -42.3164)
				(xy 410.6418 -41.0464) (xy 410.6418 -39.7764) (xy 411.9372 -38.481) (xy 411.9372 -37.211) (xy 413.1818 -35.9664)
				(xy 413.1818 -34.6964) (xy 414.4772 -33.401) (xy 414.4772 -30.7594) (xy 416.5092 -28.7274) (xy 421.1828 -28.7274)
				(xy 427.1264 -34.671) (xy 427.1264 -35.941) (xy 427.5328 -36.3474) (xy 432.6128 -36.3474) (xy 438.5564 -42.291)
				(xy 438.5564 -73.533) (xy 431.3428 -80.7466) (xy 427.5328 -80.7466) (xy 427.1264 -81.153) (xy 427.1264 -82.423)
				(xy 423.7228 -85.8266) (xy 416.1028 -85.8266) (xy 414.4518 -84.1756) (xy 414.4518 -73.5076) (xy 414.0708 -73.1266)
				(xy 411.2768 -73.1266) (xy 407.52776 -69.37756) (xy 407.52776 -74.448416)
				(arc
					(start 398.739106 -83.23707)
					(mid 401.860621 -85.722636)
					(end 403.869144 -89.17051)
				)
				(arc
					(start 404.964392 -88.075262)
					(mid 406.22846 -87.230639)
					(end 407.71953 -86.93404)
				)
				(arc
					(start 409.122626 -86.93404)
					(mid 410.613698 -87.230633)
					(end 411.877764 -88.075262)
				)
				(arc
					(start 412.839916 -89.037414)
					(mid 413.01668 -89.226325)
					(end 413.18053 -89.426542)
				)
				(xy 414.543748 -89.426542) (xy 414.543748 -99.37369) (xy 414.196784 -99.37369) (xy 414.196784 -122.299476)
				(xy 414.658302 -122.299476) (xy 414.658302 -132.208524)
				(arc
					(start 413.170116 -132.208524)
					(mid 412.638451 -132.61835)
					(end 412.046928 -132.935726)
				)
				(xy 412.046928 -133.124194)
				(arc
					(start 411.516576 -133.124194)
					(mid 411.329508 -133.17181)
					(end 411.140402 -133.210554)
				)
				(arc
					(start 411.140402 -133.210554)
					(mid 410.912518 -133.439752)
					(end 410.667454 -133.650482)
				)
				(xy 410.667454 -134.499096)
				(arc
					(start 409.327096 -134.499096)
					(mid 407.340621 -135.480994)
					(end 405.133556 -135.28294)
				)
				(arc
					(start 405.079708 -135.275066)
					(mid 403.34216 -135.83124)
					(end 401.535646 -135.576564)
				)
				(arc
					(start 401.535646 -135.576564)
					(mid 402.387994 -137.297458)
					(end 402.360892 -139.217654)
				)
				(arc
					(start 402.360892 -139.217654)
					(mid 397.81016 -143.38299)
					(end 394.310108 -138.302746)
				)
				(arc
					(start 394.310108 -138.302746)
					(mid 395.345642 -135.479945)
					(end 398.031208 -134.127748)
				)
				(xy 398.031208 -133.124448) (xy 397.728694 -133.124448) (xy 397.728694 -124.3584)
				(arc
					(start 399.503392 -124.3584)
					(mid 400.403057 -123.33989)
					(end 401.591018 -122.679968)
				)
				(arc
					(start 401.591018 -121.46788)
					(mid 401.34643 -120.0658)
					(end 401.591018 -118.66372)
				)
				(arc
					(start 401.591018 -113.936526)
					(mid 396.199783 -114.827675)
					(end 394.73378 -109.563662)
				)
				(arc
					(start 394.73378 -109.563662)
					(mid 388.593704 -108.34848)
					(end 384.153664 -103.9368)
				)
				(xy 383.286 -103.9368) (xy 382.646682 -104.576118)
				(arc
					(start 382.646682 -105.30332)
					(mid 382.89127 -106.7054)
					(end 382.646682 -108.10748)
				)
				(xy 382.646682 -122.299476) (xy 383.1082 -122.299476)
				(arc
					(start 383.1082 -127.017018)
					(mid 385.222212 -127.384521)
					(end 386.859272 -128.77165)
				)
				(arc
					(start 386.859272 -128.77165)
					(mid 388.33117 -131.054187)
					(end 388.048754 -133.755384)
				)
				(arc
					(start 388.048754 -133.755384)
					(mid 388.119755 -133.869682)
					(end 388.18693 -133.98627)
				)
				(xy 388.950962 -133.98627) (xy 388.950962 -145.928842) (xy 393.756134 -145.928842)
				(arc
					(start 393.756134 -148.517102)
					(mid 394.535569 -150.193775)
					(end 394.497052 -152.042368)
				)
				(xy 395.467586 -152.042368) (xy 395.467586 -152.224994)
				(arc
					(start 396.34795 -152.224994)
					(mid 397.657371 -152.4402)
					(end 398.829022 -153.063194)
				)
				(arc
					(start 399.34642 -153.063194)
					(mid 400.0521 -153.000437)
					(end 400.758152 -153.058876)
				)
				(arc
					(start 400.758152 -153.058876)
					(mid 401.074719 -153.048782)
					(end 401.39112 -153.063194)
				)
				(xy 402.978874 -153.063194)
				(arc
					(start 402.978874 -153.533602)
					(mid 404.626429 -155.159355)
					(end 405.127714 -157.41904)
				)
				(arc
					(start 405.127714 -157.41904)
					(mid 407.914612 -157.18517)
					(end 410.573728 -158.0515)
				)
				(arc
					(start 410.573728 -157.352492)
					(mid 411.929999 -154.321249)
					(end 415.093912 -153.312368)
				)
				(xy 415.093912 -145.928842) (xy 425.306236 -145.928842)
				(arc
					(start 425.306236 -148.517102)
					(mid 426.085671 -150.193775)
					(end 426.047154 -152.042368)
				)
				(xy 427.017688 -152.042368) (xy 427.017688 -152.224994)
				(arc
					(start 427.898052 -152.224994)
					(mid 429.207473 -152.4402)
					(end 430.379124 -153.063194)
				)
				(arc
					(start 431.028094 -153.063194)
					(mid 431.746152 -153.000462)
					(end 432.46421 -153.063194)
				)
				(arc
					(start 432.757834 -153.063194)
					(mid 433.07 -153.051264)
					(end 433.382166 -153.063194)
				)
				(xy 434.528976 -153.063194)
				(arc
					(start 434.528976 -153.320242)
					(mid 435.669962 -153.983857)
					(end 436.540148 -154.976322)
				)
				(arc
					(start 436.540148 -154.976322)
					(mid 439.644149 -153.291548)
					(end 442.895228 -154.671268)
				)
				(xy 445.753236 -154.671268) (xy 445.753236 -154.91968) (xy 446.64376 -154.91968) (xy 446.64376 -145.928842)
				(xy 456.856084 -145.928842)
				(arc
					(start 456.856084 -148.517102)
					(mid 457.635519 -150.193775)
					(end 457.597002 -152.042368)
				)
				(xy 458.567536 -152.042368) (xy 458.567536 -152.224994)
				(arc
					(start 459.4479 -152.224994)
					(mid 460.757321 -152.4402)
					(end 461.928972 -153.063194)
				)
				(arc
					(start 462.461864 -153.063194)
					(mid 462.980342 -153.00521)
					(end 463.501994 -153.012902)
				)
				(xy 463.501994 -151.99995)
				(arc
					(start 463.995262 -151.99995)
					(mid 467.534968 -149.884774)
					(end 471.117422 -151.926544)
				)
				(xy 471.21699 -151.99995)
				(arc
					(start 471.852752 -151.99995)
					(mid 472.164918 -151.98802)
					(end 472.477084 -151.99995)
				)
				(xy 475.366842 -151.99995)
				(arc
					(start 475.366842 -153.533094)
					(mid 475.496707 -153.705554)
					(end 475.617286 -153.88463)
				)
				(arc
					(start 475.617286 -153.88463)
					(mid 476.857842 -153.383559)
					(end 478.193862 -153.312368)
				)
				(xy 478.193862 -145.928842) (xy 489.418122 -145.928842) (xy 489.418122 -314.9092) (xy 477.296734 -314.9092)
				(xy 477.296734 -319.426336) (xy 477.643698 -319.426336) (xy 477.643698 -329.373484)
				(arc
					(start 476.281496 -329.373484)
					(mid 476.101955 -329.597966)
					(end 475.906338 -329.808586)
				)
				(arc
					(start 475.121986 -330.592938)
					(mid 473.857918 -331.437561)
					(end 472.366848 -331.73416)
				)
				(arc
					(start 470.760552 -331.73416)
					(mid 469.26948 -331.437567)
					(end 468.005414 -330.592938)
				)
				(arc
					(start 467.427056 -330.01458)
					(mid 456.353317 -339.610674)
					(end 445.869314 -329.373484)
				)
				(arc
					(start 445.05372 -329.373484)
					(mid 444.742248 -329.871251)
					(end 444.359538 -330.316586)
				)
				(arc
					(start 443.498986 -331.177138)
					(mid 442.234918 -332.021761)
					(end 440.743848 -332.31836)
				)
				(arc
					(start 437.66994 -332.31836)
					(mid 436.178868 -332.021767)
					(end 434.914802 -331.177138)
				)
				(arc
					(start 433.64658 -329.908916)
					(mid 432.801957 -328.644848)
					(end 432.505358 -327.153778)
				)
				(arc
					(start 432.505358 -325.20636)
					(mid 432.26077 -323.80428)
					(end 432.505358 -322.4022)
				)
				(arc
					(start 432.505358 -316.35573)
					(mid 430.83357 -314.60272)
					(end 430.446688 -312.211466)
				)
				(arc
					(start 430.446688 -312.211466)
					(mid 429.40495 -311.335882)
					(end 428.708058 -310.16702)
				)
				(arc
					(start 428.708058 -310.16702)
					(mid 428.431587 -310.195366)
					(end 428.15383 -310.204866)
				)
				(arc
					(start 426.151548 -310.204866)
					(mid 425.876825 -311.313492)
					(end 425.306236 -312.302906)
				)
				(xy 425.306236 -314.891166) (xy 416.13836 -314.891166) (xy 416.13836 -316.624716)
				(arc
					(start 414.367218 -318.395858)
					(mid 414.432741 -318.909014)
					(end 414.433766 -319.426336)
				)
				(xy 414.543748 -319.426336) (xy 414.543748 -329.373484)
				(arc
					(start 413.503872 -329.373484)
					(mid 413.1924 -329.871251)
					(end 412.80969 -330.316586)
				)
				(arc
					(start 411.949138 -331.177138)
					(mid 410.68507 -332.021761)
					(end 409.194 -332.31836)
				)
				(arc
					(start 407.638504 -332.31836)
					(mid 406.147432 -332.021767)
					(end 404.883366 -331.177138)
				)
				(arc
					(start 404.33879 -330.632562)
					(mid 393.041338 -339.59701)
					(end 382.869186 -329.373484)
				)
				(arc
					(start 381.95377 -329.373484)
					(mid 381.642298 -329.871251)
					(end 381.259588 -330.316586)
				)
				(arc
					(start 380.399036 -331.177138)
					(mid 379.134968 -332.021761)
					(end 377.643898 -332.31836)
				)
				(arc
					(start 376.088402 -332.31836)
					(mid 374.59733 -332.021767)
					(end 373.333264 -331.177138)
				)
				(arc
					(start 372.193312 -330.037186)
					(mid 371.348689 -328.773118)
					(end 371.05209 -327.282048)
				)
				(arc
					(start 371.05209 -322.86448)
					(mid 370.807502 -321.4624)
					(end 371.05209 -320.06032)
				)
				(arc
					(start 371.05209 -318.158622)
					(mid 370.282267 -316.460174)
					(end 370.346478 -314.596526)
				)
				(xy 369.725702 -313.97575)
				(arc
					(start 369.725702 -313.229244)
					(mid 368.688123 -311.470944)
					(end 368.629692 -309.430166)
				)
				(arc
					(start 367.447576 -309.430166)
					(mid 366.310916 -310.006374)
					(end 365.052102 -310.204866)
				)
				(arc
					(start 363.051598 -310.204866)
					(mid 362.776875 -311.313492)
					(end 362.206286 -312.302906)
				)
				(xy 362.206286 -314.891166)
				(arc
					(start 354.273612 -314.891166)
					(mid 352.685741 -315.214704)
					(end 351.096834 -314.896246)
				)
				(xy 351.096834 -319.426336) (xy 351.443798 -319.426336) (xy 351.443798 -329.373484) (xy 350.652842 -329.373484)
				(xy 347.707966 -332.31836) (xy 343.317576 -332.31836) (xy 343.317322 -332.318614)
				(arc
					(start 340.906354 -332.318614)
					(mid 329.174673 -339.511364)
					(end 319.869312 -329.373484)
				)
				(arc
					(start 318.85382 -329.373484)
					(mid 318.542348 -329.871251)
					(end 318.159638 -330.316586)
				)
				(arc
					(start 317.299086 -331.177138)
					(mid 316.035018 -332.021761)
					(end 314.543948 -332.31836)
				)
				(xy 306.809902 -332.31836) (xy 306.809902 -338.54898) (xy 298.19092 -347.167962) (xy 296.847006 -347.167962)
				(xy 296.847006 -348.436946) (xy 297.413172 -348.436946) (xy 297.413172 -348.437708) (xy 311.722516 -348.437708)
				(xy 311.722516 -348.436946)
				(arc
					(start 490.450124 -348.436946)
					(mid 490.617696 -348.367536)
					(end 490.687106 -348.199964)
				)
				(arc
					(start 490.687106 -0.999998)
					(mid 490.617696 -0.832426)
					(end 490.450124 -0.763016)
				)
			)
		)
		(polygon
			(pts
				(xy 456.856084 -30.928818) (xy 446.64376 -30.928818)
				(arc
					(start 446.64376 -38.312344)
					(mid 443.479779 -39.321149)
					(end 442.123576 -42.352468)
				)
				(arc
					(start 442.123576 -45.527468)
					(mid 442.598486 -47.434229)
					(end 443.912244 -48.895508)
				)
				(arc
					(start 443.912244 -52.74818)
					(mid 443.09538 -54.804977)
					(end 443.469522 -56.98617)
				)
				(xy 440.447176 -56.98617)
				(arc
					(start 440.447176 -58.541666)
					(mid 439.730078 -59.890208)
					(end 439.557668 -61.407802)
				)
				(arc
					(start 439.557668 -61.407802)
					(mid 439.504243 -62.386535)
					(end 439.685176 -63.349886)
				)
				(xy 439.685176 -69.282818)
				(arc
					(start 440.294776 -69.282818)
					(mid 440.469725 -69.571702)
					(end 440.667902 -69.845174)
				)
				(arc
					(start 440.667902 -69.845174)
					(mid 442.887262 -72.500967)
					(end 446.346834 -72.601328)
				)
				(xy 448.398646 -72.601328)
				(arc
					(start 448.398646 -73.80605)
					(mid 448.069166 -74.224371)
					(end 447.791586 -74.678794)
				)
				(xy 446.64376 -74.678794) (xy 446.64376 -84.891118)
				(arc
					(start 449.28917 -84.891118)
					(mid 447.25864 -87.467768)
					(end 446.093596 -90.53449)
				)
				(xy 446.093596 -89.426542) (xy 444.778892 -89.426542) (xy 442.28639 -86.93404) (xy 437.655462 -86.93404)
				(xy 433.902866 -90.686636)
				(arc
					(start 433.902866 -109.51972)
					(mid 433.658278 -110.9218)
					(end 433.902866 -112.32388)
				)
				(xy 433.902866 -119.386858)
				(arc
					(start 431.95494 -121.334784)
					(mid 431.110317 -122.598852)
					(end 430.813718 -124.089922)
				)
				(xy 430.813718 -124.294138) (xy 429.342804 -124.294138) (xy 429.342804 -133.060186) (xy 429.645318 -133.060186)
				(xy 429.645318 -134.42696)
				(arc
					(start 431.001424 -134.42696)
					(mid 431.819567 -134.987016)
					(end 432.748436 -135.33374)
				)
				(arc
					(start 432.748436 -135.33374)
					(mid 434.446955 -135.778315)
					(end 436.175404 -135.469884)
				)
				(arc
					(start 436.175404 -135.469884)
					(mid 438.97232 -135.914019)
					(end 441.38723 -134.434834)
				)
				(xy 442.281564 -134.434834)
				(arc
					(start 442.281564 -133.58622)
					(mid 442.494558 -133.404863)
					(end 442.694822 -133.209538)
				)
				(arc
					(start 442.694822 -133.209538)
					(mid 442.987505 -133.145364)
					(end 443.274704 -133.059932)
				)
				(xy 443.661038 -133.059932)
				(arc
					(start 443.661038 -132.907024)
					(mid 444.217734 -132.599061)
					(end 444.719964 -132.208524)
				)
				(xy 446.20815 -132.208524) (xy 446.20815 -122.299476) (xy 445.746632 -122.299476)
				(arc
					(start 445.746632 -116.59108)
					(mid 445.99122 -115.189)
					(end 445.746632 -113.78692)
				)
				(xy 445.746632 -105.763568) (xy 446.3796 -105.1306)
				(arc
					(start 447.902838 -105.1306)
					(mid 454.907284 -109.470188)
					(end 462.93659 -107.6198)
				)
				(xy 464.0072 -107.6198) (xy 464.690968 -108.303568)
				(arc
					(start 464.690968 -111.98352)
					(mid 464.44638 -113.3856)
					(end 464.690968 -114.78768)
				)
				(xy 464.690968 -121.618756)
				(arc
					(start 463.40903 -122.900694)
					(mid 462.877184 -123.563776)
					(end 462.501742 -124.326396)
				)
				(xy 460.796894 -124.326396) (xy 460.796894 -133.092444) (xy 461.099408 -133.092444) (xy 461.099408 -134.459218)
				(arc
					(start 462.455514 -134.459218)
					(mid 463.273657 -135.019274)
					(end 464.202526 -135.365998)
				)
				(arc
					(start 464.202526 -135.365998)
					(mid 466.19102 -135.811924)
					(end 468.147908 -135.243062)
				)
				(arc
					(start 468.201756 -135.250936)
					(mid 470.408845 -135.449119)
					(end 472.395296 -134.467092)
				)
				(xy 473.735654 -134.467092)
				(arc
					(start 473.735654 -133.536944)
					(mid 473.903996 -133.391998)
					(end 474.06433 -133.23824)
				)
				(arc
					(start 474.06433 -133.23824)
					(mid 474.397812 -133.178915)
					(end 474.725238 -133.09219)
				)
				(xy 475.115128 -133.09219)
				(arc
					(start 475.115128 -132.949442)
					(mid 475.723885 -132.627754)
					(end 476.270066 -132.208524)
				)
				(xy 477.758252 -132.208524)
				(arc
					(start 477.758252 -127.216662)
					(mid 481.756926 -128.052784)
					(end 485.607868 -126.689358)
				)
				(xy 489.418122 -126.689358) (xy 489.418122 -114.310414)
				(arc
					(start 485.607868 -114.310414)
					(mid 481.492144 -112.933764)
					(end 477.296734 -114.043968)
				)
				(arc
					(start 477.296734 -110.41888)
					(mid 477.541322 -109.0168)
					(end 477.296734 -107.61472)
				)
				(xy 477.296734 -99.37369) (xy 477.643698 -99.37369) (xy 477.643698 -89.426542)
				(arc
					(start 476.28048 -89.426542)
					(mid 476.116641 -89.226316)
					(end 475.939866 -89.037414)
				)
				(arc
					(start 474.977714 -88.075262)
					(mid 473.713646 -87.230639)
					(end 472.222576 -86.93404)
				)
				(arc
					(start 470.81948 -86.93404)
					(mid 469.328408 -87.230633)
					(end 468.064342 -88.075262)
				)
				(arc
					(start 466.895434 -89.24417)
					(mid 463.108882 -84.099113)
					(end 457.080112 -81.986374)
				)
				(arc
					(start 457.080112 -81.986374)
					(mid 457.494913 -81.131916)
					(end 457.701396 -80.204818)
				)
				(arc
					(start 459.7019 -80.204818)
					(mid 460.960715 -80.006328)
					(end 462.097374 -79.430118)
				)
				(xy 464.211924 -79.430118) (xy 464.211924 -77.511148) (xy 466.233256 -77.511148) (xy 469.354154 -74.39025)
				(xy 469.354154 -73.143364) (xy 474.229938 -78.019148)
				(arc
					(start 474.803978 -78.019148)
					(mid 474.947227 -78.165312)
					(end 475.097602 -78.304136)
				)
				(xy 475.097602 -79.417418) (xy 478.193862 -79.417418) (xy 478.193862 -84.891118) (xy 489.418122 -84.891118)
				(xy 489.418122 -30.928818) (xy 478.193862 -30.928818)
				(arc
					(start 478.193862 -38.312344)
					(mid 476.868291 -38.381217)
					(end 475.635574 -38.87343)
				)
				(arc
					(start 475.635574 -38.87343)
					(mid 475.518266 -38.700134)
					(end 475.392242 -38.53307)
				)
				(xy 475.392242 -36.999926)
				(arc
					(start 472.502484 -36.999926)
					(mid 472.190318 -36.987996)
					(end 471.878152 -36.999926)
				)
				(arc
					(start 471.26525 -36.999926)
					(mid 467.619334 -34.763662)
					(end 463.973418 -36.999926)
				)
				(xy 463.527394 -36.999926)
				(arc
					(start 463.527394 -38.008306)
					(mid 463.038856 -38.006976)
					(end 462.553558 -38.06317)
				)
				(arc
					(start 461.928972 -38.06317)
					(mid 460.757315 -37.440194)
					(end 459.4479 -37.22497)
				)
				(xy 458.567536 -37.22497) (xy 458.567536 -37.042344)
				(arc
					(start 457.597002 -37.042344)
					(mid 457.63555 -35.193745)
					(end 456.856084 -33.517078)
				)
			)
		)
		(polygon
			(pts
				(arc
					(start 318.926464 -343.357708)
					(mid 315.030104 -340.511643)
					(end 311.133744 -343.357708)
				)
				(arc
					(start 311.131712 -343.357708)
					(mid 310.990477 -345.254975)
					(end 311.722516 -347.01099)
				)
				(xy 311.722516 -347.167962)
				(arc
					(start 318.217296 -347.167962)
					(mid 319.052656 -345.352383)
					(end 318.928496 -343.357708)
				)
			)
		)
		(polygon
			(pts
				(arc
					(start 416.65525 -343.357708)
					(mid 412.623 -338.581161)
					(end 408.59075 -343.357708)
				)
				(arc
					(start 408.588972 -343.357708)
					(mid 412.623 -346.763392)
					(end 416.657028 -343.357708)
				)
			)
		)
		(polygon
			(pts
				(arc
					(start 445.856106 -343.357708)
					(mid 441.96 -338.022376)
					(end 438.063894 -343.357708)
				)
				(arc
					(start 438.062116 -343.357708)
					(mid 441.96 -346.204518)
					(end 445.857884 -343.357708)
				)
			)
		)
		(polygon
			(pts
				(arc
					(start 471.538808 -343.357708)
					(mid 467.868 -337.4637)
					(end 464.197192 -343.357708)
				)
				(arc
					(start 464.19516 -343.357708)
					(mid 467.868 -345.645723)
					(end 471.54084 -343.357708)
				)
			)
		)
		(polygon
			(pts
				(arc
					(start 485.604058 -337.257644)
					(mid 481.141484 -338.777772)
					(end 480.023424 -343.357708)
				)
				(xy 480.023424 -347.167962) (xy 489.418122 -347.167962) (xy 489.418122 -337.258406) (xy 485.60482 -337.258406)
			)
		)
		(polygon
			(pts
				(arc
					(start 383.155952 -337.246976)
					(mid 377.957603 -335.617517)
					(end 375.75109 -340.598506)
				)
				(arc
					(start 375.75109 -340.598506)
					(mid 375.017877 -341.889772)
					(end 374.794018 -343.357708)
				)
				(arc
					(start 374.79224 -343.357708)
					(mid 375.657896 -345.749685)
					(end 377.769628 -347.167962)
				)
				(arc
					(start 379.994668 -347.167962)
					(mid 381.580961 -346.305924)
					(end 382.641856 -344.845132)
				)
				(arc
					(start 382.641856 -344.845132)
					(mid 383.795013 -344.266571)
					(end 384.710686 -343.357708)
				)
				(arc
					(start 384.708654 -343.357708)
					(mid 385.370642 -339.936883)
					(end 383.155952 -337.246976)
				)
			)
		)
		(polygon
			(pts
				(arc
					(start 350.406208 -341.76843)
					(mid 355.053563 -337.383681)
					(end 349.753174 -333.81569)
				)
				(arc
					(start 349.753174 -333.81569)
					(mid 349.028462 -333.731332)
					(end 348.300294 -333.777082)
				)
				(arc
					(start 348.300294 -333.777082)
					(mid 344.305101 -335.855239)
					(end 344.641678 -340.34603)
				)
				(arc
					(start 344.641678 -340.34603)
					(mid 343.36954 -341.640376)
					(end 342.782652 -343.357708)
				)
				(arc
					(start 342.780874 -343.357708)
					(mid 343.13569 -345.505878)
					(end 344.54211 -347.167962)
				)
				(arc
					(start 349.157798 -347.167962)
					(mid 350.564229 -345.505883)
					(end 350.919034 -343.357708)
				)
				(arc
					(start 350.917256 -343.357708)
					(mid 350.743687 -342.536715)
					(end 350.406208 -341.76843)
				)
			)
		)
		(polygon
			(pts
				(arc
					(start 475.869 -333.47406)
					(mid 475.869 -341.65794)
					(end 475.869 -333.47406)
				)
			)
		)
		(polygon
			(pts
				(arc
					(start 483.368604 -2.032)
					(mid 481.24999 -1.436084)
					(end 479.131376 -2.032)
				)
				(xy 455.78649 -2.032)
				(arc
					(start 455.78649 -5.842254)
					(mid 455.294028 -7.393895)
					(end 455.103738 -9.01065)
				)
				(arc
					(start 455.103738 -9.01065)
					(mid 453.276845 -15.395439)
					(end 459.477618 -17.773396)
				)
				(arc
					(start 459.477618 -17.773396)
					(mid 464.610937 -24.572892)
					(end 467.844632 -16.690848)
				)
				(arc
					(start 467.844632 -16.690848)
					(mid 471.017251 -13.626118)
					(end 472.246198 -9.389618)
				)
				(arc
					(start 472.246198 -9.389618)
					(mid 473.22603 -8.59902)
					(end 473.97289 -7.585456)
				)
				(arc
					(start 473.97289 -7.585456)
					(mid 478.731654 -12.63894)
					(end 485.607868 -11.689842)
				)
				(xy 489.418122 -11.689842) (xy 489.418122 -2.032)
			)
		)
	)
	(zone
		(layer "F.Cu")
		(hatch none 0.5)
		(connect_pads
			(clearance 0)
		)
		(min_thickness 0.25)
		(keepout
			(tracks not_allowed)
			(vias allowed)
			(pads allowed)
			(copperpour not_allowed)
			(footprints allowed)
		)
		(placement
			(enabled no)
			(sheetname "")
		)
		(fill
			(thermal_gap 0.5)
			(thermal_bridge_width 0.5)
			(island_removal_mode 0)
		)
		(polygon
			(pts
				(arc
					(start 438.6199 -162.178746)
					(mid 438.239027 -161.797492)
					(end 437.8579 -162.178492)
				)
				(arc
					(start 437.8579 -163.321492)
					(mid 438.2389 -163.702492)
					(end 438.6199 -163.321492)
				)
				(xy 438.6199 -162.972242)
				(arc
					(start 438.387236 -162.972242)
					(mid 438.336228 -162.99337)
					(end 438.3151 -163.044378)
				)
				(arc
					(start 438.3151 -163.065968)
					(mid 438.2389 -163.588136)
					(end 438.1627 -163.065968)
				)
				(xy 438.1627 -163.012882)
				(arc
					(start 438.16524 -163.010088)
					(mid 438.2284 -162.885542)
					(end 438.352946 -162.822382)
				)
				(xy 438.35574 -162.819842) (xy 438.6199 -162.819842) (xy 438.6199 -162.680142) (xy 438.35574 -162.680142)
				(arc
					(start 438.352946 -162.677602)
					(mid 438.2284 -162.614442)
					(end 438.16524 -162.489896)
				)
				(xy 438.1627 -162.487102)
				(arc
					(start 438.1627 -162.434016)
					(mid 438.2389 -161.911848)
					(end 438.3151 -162.434016)
				)
				(arc
					(start 438.3151 -162.455606)
					(mid 438.336228 -162.506614)
					(end 438.387236 -162.527742)
				)
				(xy 438.6199 -162.527742)
			)
		)
	)
	(zone
		(net "GND")
		(layer "F.Cu")
		(hatch none 0.5)
		(connect_pads
			(clearance 0.5)
		)
		(min_thickness 0.25)
		(fill yes
			(thermal_gap 0.5)
			(thermal_bridge_width 0.5)
			(island_removal_mode 0)
		)
		(polygon
			(pts
				(xy 198.755 -323.005704) (xy 187.198 -318.532256)
				(arc
					(start 187.198 -320.382392)
					(mid 187.437078 -320.639942)
					(end 187.653168 -320.917062)
				)
				(arc
					(start 187.653168 -320.917062)
					(mid 189.785797 -323.640937)
					(end 189.067948 -327.025)
				)
				(xy 189.103 -327.025) (xy 189.103 -327.80986) (xy 198.755 -325.855838)
			)
		)
	)
	(zone
		(layer "F.Cu")
		(hatch none 0.5)
		(connect_pads
			(clearance 0)
		)
		(min_thickness 0.25)
		(keepout
			(tracks allowed)
			(vias allowed)
			(pads allowed)
			(copperpour allowed)
			(footprints allowed)
		)
		(placement
			(enabled no)
			(sheetname "")
		)
		(fill
			(thermal_gap 0.5)
			(thermal_bridge_width 0.5)
			(island_removal_mode 0)
		)
		(polygon
			(pts
				(xy 240.7412 -390.2964) (xy 240.7412 -393.446) (xy 237.744 -393.446) (xy 237.744 -390.2964)
			)
		)
	)
	(zone
		(net "P5V_A_4")
		(layer "F.Cu")
		(hatch none 0.5)
		(connect_pads
			(clearance 0.5)
		)
		(min_thickness 0.25)
		(fill yes
			(thermal_gap 0.5)
			(thermal_bridge_width 0.5)
			(island_removal_mode 0)
		)
		(polygon
			(pts
				(xy 399.90395 -50.332894) (xy 399.64995 -50.586894) (xy 399.64995 -55.285894) (xy 399.90395 -55.539894)
				(xy 402.18995 -55.539894) (xy 402.44395 -55.285894) (xy 402.44395 -50.586894) (xy 402.18995 -50.332894)
			)
		)
	)
	(zone
		(layer "F.Cu")
		(hatch none 0.5)
		(connect_pads
			(clearance 0)
		)
		(min_thickness 0.25)
		(keepout
			(tracks allowed)
			(vias allowed)
			(pads allowed)
			(copperpour allowed)
			(footprints not_allowed)
		)
		(placement
			(enabled no)
			(sheetname "")
		)
		(fill
			(thermal_gap 0.5)
			(thermal_bridge_width 0.5)
			(island_removal_mode 0)
		)
		(polygon
			(pts
				(xy 198.399908 -130.350006) (xy 198.399908 -79.799942) (xy 214.799926 -79.799942) (xy 214.799926 -53.799994)
				(xy 198.399908 -53.799994) (xy 198.399908 -48.150018) (xy 291.599874 -48.150018) (xy 291.599874 -128.199896)
				(xy 287.699958 -128.199896) (xy 287.699958 -130.350006)
			)
		)
	)
	(zone
		(layer "F.Cu")
		(hatch none 0.5)
		(connect_pads
			(clearance 0)
		)
		(min_thickness 0.25)
		(keepout
			(tracks not_allowed)
			(vias allowed)
			(pads allowed)
			(copperpour not_allowed)
			(footprints allowed)
		)
		(placement
			(enabled no)
			(sheetname "")
		)
		(fill
			(thermal_gap 0.5)
			(thermal_bridge_width 0.5)
			(island_removal_mode 0)
		)
		(polygon
			(pts
				(arc
					(start 271.970754 -355.524054)
					(mid 271.5895 -355.904927)
					(end 271.9705 -356.286054)
				)
				(arc
					(start 273.1135 -356.286054)
					(mid 273.4945 -355.905054)
					(end 273.1135 -355.524054)
				)
				(xy 272.76425 -355.524054)
				(arc
					(start 272.76425 -355.778054)
					(mid 272.779129 -355.813975)
					(end 272.81505 -355.828854)
				)
				(arc
					(start 272.857976 -355.828854)
					(mid 273.380144 -355.905054)
					(end 272.857976 -355.981254)
				)
				(xy 272.783554 -355.981254)
				(arc
					(start 272.780506 -355.978206)
					(mid 272.671429 -355.921675)
					(end 272.614898 -355.812598)
				)
				(xy 272.61185 -355.80955) (xy 272.61185 -355.524054) (xy 272.47215 -355.524054) (xy 272.47215 -355.80955)
				(arc
					(start 272.469102 -355.812598)
					(mid 272.412571 -355.921675)
					(end 272.303494 -355.978206)
				)
				(xy 272.300446 -355.981254)
				(arc
					(start 272.226024 -355.981254)
					(mid 271.703856 -355.905054)
					(end 272.226024 -355.828854)
				)
				(arc
					(start 272.26895 -355.828854)
					(mid 272.304871 -355.813975)
					(end 272.31975 -355.778054)
				)
				(xy 272.31975 -355.524054)
			)
		)
	)
	(zone
		(layer "F.Cu")
		(hatch none 0.5)
		(connect_pads
			(clearance 0)
		)
		(min_thickness 0.25)
		(keepout
			(tracks allowed)
			(vias allowed)
			(pads allowed)
			(copperpour allowed)
			(footprints allowed)
		)
		(placement
			(enabled no)
			(sheetname "")
		)
		(fill
			(thermal_gap 0.5)
			(thermal_bridge_width 0.5)
			(island_removal_mode 0)
		)
		(polygon
			(pts
				(xy 482.2952 -48.5648) (xy 483.743 -48.5648) (xy 483.9462 -48.3616) (xy 483.9462 -47.2186) (xy 483.6922 -46.9646)
				(xy 482.2698 -46.9646) (xy 482.1682 -47.0662) (xy 482.1682 -48.4378)
			)
		)
	)
	(zone
		(net "12V_PRE_20")
		(layer "F.Cu")
		(hatch none 0.5)
		(connect_pads
			(clearance 0.5)
		)
		(min_thickness 0.25)
		(fill yes
			(thermal_gap 0.5)
			(thermal_bridge_width 0.5)
			(island_removal_mode 0)
		)
		(polygon
			(pts
				(xy 394.368528 -183.31434) (xy 391.90295 -185.779918) (xy 389.36295 -185.779918) (xy 389.10895 -186.033918)
				(xy 389.10895 -186.414918) (xy 389.36295 -186.668918) (xy 396.061184 -186.668918) (xy 396.721584 -186.008518)
				(xy 396.721584 -183.43499) (xy 396.600934 -183.31434)
			)
		)
	)
	(zone
		(layer "F.Cu")
		(hatch none 0.5)
		(connect_pads
			(clearance 0)
		)
		(min_thickness 0.25)
		(keepout
			(tracks allowed)
			(vias allowed)
			(pads allowed)
			(copperpour allowed)
			(footprints not_allowed)
		)
		(placement
			(enabled no)
			(sheetname "")
		)
		(fill
			(thermal_gap 0.5)
			(thermal_bridge_width 0.5)
			(island_removal_mode 0)
		)
		(polygon
			(pts
				(arc
					(start 4.249928 -224.199958)
					(mid 7.999984 -220.449902)
					(end 11.75004 -224.199958)
				)
				(arc
					(start 11.75004 -224.199958)
					(mid 7.999984 -227.950014)
					(end 4.249928 -224.199958)
				)
			)
		)
	)
	(zone
		(net "P12V_A")
		(layer "F.Cu")
		(hatch none 0.5)
		(connect_pads
			(clearance 0.5)
		)
		(min_thickness 0.25)
		(fill yes
			(thermal_gap 0.5)
			(thermal_bridge_width 0.5)
			(island_removal_mode 0)
		)
		(polygon
			(pts
				(xy 397.74495 -56.428894) (xy 397.23695 -56.936894) (xy 397.23695 -60.365894) (xy 397.49095 -60.619894)
				(xy 400.79295 -60.619894) (xy 401.04695 -60.365894) (xy 401.04695 -58.333894) (xy 401.17395 -58.206894)
				(xy 401.55495 -58.206894) (xy 401.68195 -58.079894) (xy 401.68195 -56.555894) (xy 401.55495 -56.428894)
			)
		)
		(polygon
			(pts
				(xy 401.14855 -57.444894) (xy 400.94535 -57.444894) (xy 400.94535 -57.648094) (xy 401.14855 -57.648094)
			)
		)
		(polygon
			(pts
				(xy 401.19935 -56.987694) (xy 400.99615 -56.987694) (xy 400.99615 -57.190894) (xy 401.19935 -57.190894)
			)
		)
	)
	(zone
		(layer "F.Cu")
		(hatch none 0.5)
		(connect_pads
			(clearance 0)
		)
		(min_thickness 0.25)
		(keepout
			(tracks not_allowed)
			(vias allowed)
			(pads allowed)
			(copperpour not_allowed)
			(footprints allowed)
		)
		(placement
			(enabled no)
			(sheetname "")
		)
		(fill
			(thermal_gap 0.5)
			(thermal_bridge_width 0.5)
			(island_removal_mode 0)
		)
		(polygon
			(pts
				(arc
					(start 362.89869 -28.150312)
					(mid 362.350177 -27.601418)
					(end 361.80141 -28.150058)
				)
				(arc
					(start 361.80141 -28.62707)
					(mid 361.863661 -28.615827)
					(end 361.926632 -28.609798)
				)
				(xy 361.927902 -28.608782)
				(arc
					(start 362.22305 -28.608782)
					(mid 362.245501 -28.599483)
					(end 362.2548 -28.577032)
				)
				(arc
					(start 362.2548 -28.532074)
					(mid 362.35005 -27.756346)
					(end 362.4453 -28.532074)
				)
				(xy 362.4453 -28.616402)
				(arc
					(start 362.440982 -28.620974)
					(mid 362.380253 -28.734235)
					(end 362.266992 -28.794964)
				)
				(xy 362.26242 -28.799282)
				(arc
					(start 361.967272 -28.799282)
					(mid 361.88343 -28.805464)
					(end 361.80141 -28.82392)
				)
				(arc
					(start 361.80141 -28.931362)
					(mid 361.862653 -28.912733)
					(end 361.92587 -28.90266)
				)
				(xy 361.927902 -28.900882) (xy 362.26242 -28.900882)
				(arc
					(start 362.266992 -28.9052)
					(mid 362.380253 -28.965929)
					(end 362.440982 -29.07919)
				)
				(xy 362.4453 -29.083762)
				(arc
					(start 362.4453 -29.16809)
					(mid 362.35005 -29.943818)
					(end 362.2548 -29.16809)
				)
				(arc
					(start 362.2548 -29.123132)
					(mid 362.245501 -29.100681)
					(end 362.22305 -29.091382)
				)
				(arc
					(start 361.967272 -29.091382)
					(mid 361.879842 -29.105591)
					(end 361.80141 -29.146754)
				)
				(arc
					(start 361.80141 -29.550106)
					(mid 362.35005 -30.098746)
					(end 362.89869 -29.550106)
				)
			)
		)
	)
	(zone
		(net "GND")
		(layer "F.Cu")
		(hatch none 0.5)
		(connect_pads
			(clearance 0.5)
		)
		(min_thickness 0.25)
		(fill yes
			(thermal_gap 0.5)
			(thermal_bridge_width 0.5)
			(island_removal_mode 0)
		)
		(polygon
			(pts
				(arc
					(start 383.54381 -191.445134)
					(mid 381.777209 -192.604942)
					(end 379.667516 -192.728088)
				)
				(arc
					(start 379.667516 -192.728088)
					(mid 379.686626 -194.408444)
					(end 379.028452 -195.95465)
				)
				(arc
					(start 379.028452 -195.95465)
					(mid 381.634493 -199.135056)
					(end 380.159768 -202.973178)
				)
				(arc
					(start 380.159768 -202.973178)
					(mid 380.396743 -203.160627)
					(end 380.618492 -203.365862)
				)
				(arc
					(start 381.289814 -204.037184)
					(mid 381.463685 -204.222723)
					(end 381.625094 -204.4192)
				)
				(arc
					(start 383.39522 -204.4192)
					(mid 384.556566 -201.972667)
					(end 386.289042 -199.891142)
				)
				(xy 383.54381 -199.891142)
			)
		)
	)
	(zone
		(net "5V_PRE_0")
		(layer "F.Cu")
		(hatch none 0.5)
		(connect_pads
			(clearance 0.5)
		)
		(min_thickness 0.25)
		(fill yes
			(thermal_gap 0.5)
			(thermal_bridge_width 0.5)
			(island_removal_mode 0)
		)
		(polygon
			(pts
				(xy 23.021798 -289.8902) (xy 22.843998 -290.068) (xy 22.843998 -291.508942) (xy 22.970998 -291.635942)
				(xy 24.240998 -291.635942) (xy 26.780998 -294.175942) (xy 31.225998 -294.175942) (xy 31.352998 -294.048942)
				(xy 31.352998 -293.286942) (xy 31.225998 -293.159942) (xy 28.321 -293.159942) (xy 25.051258 -289.8902)
			)
		)
	)
	(zone
		(net "P12V_A")
		(layer "F.Cu")
		(hatch none 0.5)
		(connect_pads
			(clearance 0.5)
		)
		(min_thickness 0.25)
		(fill yes
			(thermal_gap 0.5)
			(thermal_bridge_width 0.5)
			(island_removal_mode 0)
		)
		(polygon
			(pts
				(xy 469.749124 -282.1686) (xy 469.300052 -282.617672) (xy 469.300052 -283.688282) (xy 468.127334 -284.861)
				(xy 467.453726 -284.861) (xy 467.174326 -285.1404) (xy 467.174326 -287.419542) (xy 467.428326 -287.673542)
				(xy 471.109294 -287.673542) (xy 471.481658 -287.301178) (xy 471.481658 -282.510992) (xy 471.139266 -282.1686)
			)
		)
		(polygon
			(pts
				(xy 470.942924 -284.021276) (xy 470.739724 -284.021276) (xy 470.739724 -284.224476) (xy 470.942924 -284.224476)
			)
		)
		(polygon
			(pts
				(xy 470.942924 -283.411676) (xy 470.739724 -283.411676) (xy 470.739724 -283.614876) (xy 470.942924 -283.614876)
			)
		)
		(polygon
			(pts
				(xy 470.993724 -282.954476) (xy 470.790524 -282.954476) (xy 470.790524 -283.157676) (xy 470.993724 -283.157676)
			)
		)
	)
	(zone
		(layer "F.Cu")
		(hatch none 0.5)
		(connect_pads
			(clearance 0)
		)
		(min_thickness 0.25)
		(keepout
			(tracks not_allowed)
			(vias allowed)
			(pads allowed)
			(copperpour not_allowed)
			(footprints allowed)
		)
		(placement
			(enabled no)
			(sheetname "")
		)
		(fill
			(thermal_gap 0.5)
			(thermal_bridge_width 0.5)
			(island_removal_mode 0)
		)
		(polygon
			(pts
				(arc
					(start 271.970754 -332.12151)
					(mid 271.58696 -332.504923)
					(end 271.9705 -332.88859)
				)
				(arc
					(start 273.1135 -332.88859)
					(mid 273.49704 -332.50505)
					(end 273.1135 -332.12151)
				)
				(xy 272.76425 -332.12151)
				(arc
					(start 272.76425 -332.37805)
					(mid 272.779129 -332.413971)
					(end 272.81505 -332.42885)
				)
				(arc
					(start 272.857976 -332.42885)
					(mid 273.380144 -332.50505)
					(end 272.857976 -332.58125)
				)
				(xy 272.783554 -332.58125)
				(arc
					(start 272.780506 -332.578202)
					(mid 272.671429 -332.521671)
					(end 272.614898 -332.412594)
				)
				(xy 272.61185 -332.409546) (xy 272.61185 -332.12151) (xy 272.47215 -332.12151) (xy 272.47215 -332.409546)
				(arc
					(start 272.469102 -332.412594)
					(mid 272.412571 -332.521671)
					(end 272.303494 -332.578202)
				)
				(xy 272.300446 -332.58125)
				(arc
					(start 272.226024 -332.58125)
					(mid 271.703856 -332.50505)
					(end 272.226024 -332.42885)
				)
				(arc
					(start 272.26895 -332.42885)
					(mid 272.304871 -332.413971)
					(end 272.31975 -332.37805)
				)
				(xy 272.31975 -332.12151)
			)
		)
	)
	(zone
		(net "P12V_HDD28")
		(layer "F.Cu")
		(hatch none 0.5)
		(connect_pads
			(clearance 0.5)
		)
		(min_thickness 0.25)
		(fill yes
			(thermal_gap 0.5)
			(thermal_bridge_width 0.5)
			(island_removal_mode 0)
		)
		(polygon
			(pts
				(xy 138.502898 -61.254894) (xy 138.248898 -61.508894) (xy 138.248898 -63.159894) (xy 138.502898 -63.413894)
				(xy 140.661898 -63.413894) (xy 141.169898 -63.921894) (xy 141.169898 -66.461894) (xy 148.916898 -74.208894)
				(xy 157.425898 -74.208894) (xy 157.552898 -74.081894) (xy 157.552898 -72.303894) (xy 157.425898 -72.176894)
				(xy 151.456898 -72.176894) (xy 150.821898 -71.541894) (xy 149.170898 -71.541894) (xy 144.852898 -67.223894)
				(xy 144.852898 -63.667894) (xy 143.709898 -62.524894) (xy 143.709898 -61.508894) (xy 143.455898 -61.254894)
			)
		)
		(polygon
			(pts
				(xy 150.974298 -73.218294) (xy 150.771098 -73.218294) (xy 150.771098 -73.421494) (xy 150.974298 -73.421494)
			)
		)
		(polygon
			(pts
				(xy 150.110698 -73.218294) (xy 149.907498 -73.218294) (xy 149.907498 -73.421494) (xy 150.110698 -73.421494)
			)
		)
	)
	(zone
		(layer "F.Cu")
		(hatch none 0.5)
		(connect_pads
			(clearance 0)
		)
		(min_thickness 0.25)
		(keepout
			(tracks allowed)
			(vias allowed)
			(pads allowed)
			(copperpour allowed)
			(footprints allowed)
		)
		(placement
			(enabled no)
			(sheetname "")
		)
		(fill
			(thermal_gap 0.5)
			(thermal_bridge_width 0.5)
			(island_removal_mode 0)
		)
		(polygon
			(pts
				(xy 443.682374 -251.774706) (xy 443.682374 -247.676416) (xy 444.933324 -247.676416) (xy 444.933324 -251.774706)
			)
		)
	)
	(zone
		(layer "F.Cu")
		(hatch none 0.5)
		(connect_pads
			(clearance 0)
		)
		(min_thickness 0.25)
		(keepout
			(tracks allowed)
			(vias allowed)
			(pads allowed)
			(copperpour allowed)
			(footprints allowed)
		)
		(placement
			(enabled no)
			(sheetname "")
		)
		(fill
			(thermal_gap 0.5)
			(thermal_bridge_width 0.5)
			(island_removal_mode 0)
		)
		(polygon
			(pts
				(xy 368.6048 -137.3886) (xy 368.6048 -135.382) (xy 370.2558 -135.382) (xy 370.2558 -137.3886)
			)
		)
	)
	(zone
		(layer "F.Cu")
		(hatch none 0.5)
		(connect_pads
			(clearance 0)
		)
		(min_thickness 0.25)
		(keepout
			(tracks allowed)
			(vias allowed)
			(pads allowed)
			(copperpour allowed)
			(footprints allowed)
		)
		(placement
			(enabled no)
			(sheetname "")
		)
		(fill
			(thermal_gap 0.5)
			(thermal_bridge_width 0.5)
			(island_removal_mode 0)
		)
		(polygon
			(pts
				(xy 147.004024 -129.977134) (xy 147.93849 -129.977134) (xy 147.93849 -131.511294) (xy 147.004024 -131.511294)
			)
		)
	)
	(zone
		(net "GND")
		(layer "F.Cu")
		(hatch none 0.5)
		(connect_pads
			(clearance 0.5)
		)
		(min_thickness 0.25)
		(fill yes
			(thermal_gap 0.5)
			(thermal_bridge_width 0.5)
			(island_removal_mode 0)
		)
		(polygon
			(pts
				(xy 27.677364 -244.63375) (xy 27.394662 -244.916452) (xy 27.394662 -250.355862) (xy 27.7368 -250.698)
				(xy 27.7368 -250.735084) (xy 28.02636 -251.024644) (xy 30.850078 -251.024644) (xy 31.0388 -250.835922)
				(xy 31.0388 -244.81155) (xy 30.861 -244.63375)
			)
		)
	)
	(zone
		(layer "F.Cu")
		(hatch none 0.5)
		(connect_pads
			(clearance 0)
		)
		(min_thickness 0.25)
		(keepout
			(tracks allowed)
			(vias allowed)
			(pads allowed)
			(copperpour allowed)
			(footprints allowed)
		)
		(placement
			(enabled no)
			(sheetname "")
		)
		(fill
			(thermal_gap 0.5)
			(thermal_bridge_width 0.5)
			(island_removal_mode 0)
		)
		(polygon
			(pts
				(xy 300.470824 -66.014092) (xy 300.470824 -65.079626) (xy 302.004984 -65.079626) (xy 302.004984 -66.014092)
			)
		)
	)
	(zone
		(net "GND")
		(layer "F.Cu")
		(hatch none 0.5)
		(connect_pads
			(clearance 0.5)
		)
		(min_thickness 0.25)
		(fill yes
			(thermal_gap 0.5)
			(thermal_bridge_width 0.5)
			(island_removal_mode 0)
		)
		(polygon
			(pts
				(xy 56.261508 -88.757252) (xy 41.133522 -69.234812) (xy 41.133522 -69.308218)
				(arc
					(start 40.585898 -69.308218)
					(mid 39.988861 -70.180045)
					(end 39.18839 -70.86981)
				)
				(arc
					(start 39.18839 -70.86981)
					(mid 37.478513 -72.495129)
					(end 35.163252 -72.947784)
				)
				(xy 35.163252 -75.66025) (xy 35.01771 -75.805792) (xy 35.01771 -78.777592)
				(arc
					(start 34.047176 -78.777592)
					(mid 34.121625 -80.432246)
					(end 33.533842 -81.980786)
				)
				(arc
					(start 33.533842 -81.980786)
					(mid 39.616075 -83.995359)
					(end 43.492928 -89.096596)
				)
				(xy 45.655484 -86.93404) (xy 49.950116 -86.93404) (xy 52.442618 -89.426542) (xy 54.093618 -89.426542)
				(xy 54.093618 -99.37369) (xy 53.746654 -99.37369)
				(arc
					(start 53.746654 -99.56292)
					(mid 53.991242 -100.965)
					(end 53.746654 -102.36708)
				)
				(xy 53.746654 -122.299476) (xy 54.208172 -122.299476) (xy 54.208172 -132.208524)
				(arc
					(start 52.719986 -132.208524)
					(mid 52.212862 -132.602269)
					(end 51.650392 -132.91185)
				)
				(xy 51.650392 -133.124194) (xy 51.344576 -133.124194)
				(arc
					(start 51.344576 -133.665976)
					(mid 51.356506 -133.978142)
					(end 51.344576 -134.290308)
				)
				(xy 51.344576 -134.361936)
				(arc
					(start 51.33848 -134.361936)
					(mid 51.238744 -134.952783)
					(end 51.053746 -135.522716)
				)
				(arc
					(start 51.053746 -135.522716)
					(mid 54.267058 -134.869555)
					(end 56.927496 -136.786366)
				)
				(xy 57.133236 -136.786366)
				(arc
					(start 57.133236 -137.182098)
					(mid 57.434121 -138.154156)
					(end 57.485788 -139.17041)
				)
				(arc
					(start 57.485788 -139.17041)
					(mid 57.547433 -139.936358)
					(end 57.466484 -140.700506)
				)
				(xy 57.465976 -140.708888)
				(arc
					(start 57.962546 -140.708888)
					(mid 58.771184 -140.577221)
					(end 59.589924 -140.607288)
				)
				(arc
					(start 59.589924 -140.607288)
					(mid 59.820715 -139.869576)
					(end 60.183776 -139.187174)
				)
				(arc
					(start 60.183776 -139.187174)
					(mid 59.717545 -138.144055)
					(end 59.55792 -137.01268)
				)
				(arc
					(start 59.55792 -135.61568)
					(mid 60.037522 -133.693762)
					(end 61.36386 -132.222494)
				)
				(arc
					(start 61.36386 -132.222494)
					(mid 62.847737 -130.825405)
					(end 64.821562 -130.317748)
				)
				(arc
					(start 66.218562 -130.317748)
					(mid 67.6125 -130.562558)
					(end 68.839588 -131.267708)
				)
				(xy 68.839588 -124.367544)
				(arc
					(start 70.103746 -124.367544)
					(mid 70.12859 -124.208123)
					(end 70.159626 -124.04979)
				)
				(arc
					(start 70.159626 -124.04979)
					(mid 71.796329 -120.154671)
					(end 76.005182 -119.785384)
				)
				(arc
					(start 76.005182 -119.785384)
					(mid 77.361154 -119.385558)
					(end 78.772258 -119.471186)
				)
				(arc
					(start 78.772258 -119.471186)
					(mid 79.495943 -119.266065)
					(end 80.24495 -119.196866)
				)
				(arc
					(start 81.51495 -119.196866)
					(mid 84.034132 -120.064534)
					(end 85.484716 -122.299476)
				)
				(xy 85.758274 -122.299476) (xy 85.758274 -132.208524)
				(arc
					(start 84.270088 -132.208524)
					(mid 83.758085 -132.60551)
					(end 83.189826 -132.916676)
				)
				(xy 83.189826 -133.124194) (xy 82.88401 -133.124194)
				(arc
					(start 82.88401 -133.665976)
					(mid 82.89594 -133.978142)
					(end 82.88401 -134.290308)
				)
				(xy 82.88401 -134.361936)
				(arc
					(start 82.877914 -134.361936)
					(mid 80.800698 -137.548835)
					(end 76.997814 -137.647172)
				)
				(arc
					(start 76.997814 -137.647172)
					(mid 73.850353 -137.840981)
					(end 71.500492 -135.738108)
				)
				(arc
					(start 71.500492 -136.96315)
					(mid 71.347933 -138.069667)
					(end 70.901814 -139.093702)
				)
				(arc
					(start 70.901814 -139.093702)
					(mid 70.960234 -139.182634)
					(end 71.016368 -139.273026)
				)
				(arc
					(start 74.234802 -139.273026)
					(mid 77.181404 -140.493548)
					(end 78.401926 -143.44015)
				)
				(arc
					(start 78.401926 -144.71015)
					(mid 78.345776 -145.391669)
					(end 78.178914 -146.054826)
				)
				(arc
					(start 78.178914 -146.054826)
					(mid 78.681299 -148.510233)
					(end 77.657198 -150.797768)
				)
				(arc
					(start 77.657198 -150.797768)
					(mid 76.185844 -152.932475)
					(end 73.726802 -153.754074)
				)
				(arc
					(start 71.402194 -153.754074)
					(mid 70.890822 -155.108127)
					(end 69.939916 -156.199332)
				)
				(arc
					(start 69.939916 -156.199332)
					(mid 69.781054 -156.491117)
					(end 69.599048 -156.769054)
				)
				(arc
					(start 69.599048 -156.769054)
					(mid 69.943095 -157.130466)
					(end 70.237858 -157.533086)
				)
				(xy 71.552054 -159.595058)
				(arc
					(start 72.652636 -159.595058)
					(mid 73.747827 -157.710441)
					(end 75.655424 -156.65577)
				)
				(xy 75.655424 -156.187394) (xy 77.509624 -156.187394) (xy 77.509624 -156.111194) (xy 80.677004 -156.111194)
				(xy 80.677004 -155.784042)
				(arc
					(start 81.286858 -155.784042)
					(mid 83.443899 -154.07769)
					(end 86.193884 -154.123136)
				)
				(xy 86.193884 -145.928842) (xy 96.406208 -145.928842)
				(arc
					(start 96.406208 -148.517102)
					(mid 97.185643 -150.193775)
					(end 97.147126 -152.042368)
				)
				(xy 98.11766 -152.042368) (xy 98.11766 -154.671268) (xy 99.83216 -154.671268) (xy 99.83216 -155.778708)
				(xy 101.459284 -156.81452) (xy 103.015288 -159.253428) (xy 103.029766 -159.319214)
				(arc
					(start 104.276906 -159.319214)
					(mid 105.392517 -157.595182)
					(end 107.205272 -156.63037)
				)
				(xy 107.205272 -156.187394) (xy 109.059472 -156.187394) (xy 109.059472 -156.111194) (xy 112.216438 -156.111194)
				(xy 112.216438 -155.848304)
				(arc
					(start 112.82299 -155.848304)
					(mid 114.98568 -154.13596)
					(end 117.743732 -154.186128)
				)
				(arc
					(start 117.743732 -151.323294)
					(mid 117.098755 -144.857441)
					(end 123.507754 -145.928842)
				)
				(xy 126.113794 -145.928842) (xy 126.113794 -139.93495) (xy 126.717806 -139.93495)
				(arc
					(start 126.720346 -139.929362)
					(mid 125.233015 -139.427586)
					(end 124.044202 -138.402568)
				)
				(arc
					(start 124.044202 -138.402568)
					(mid 122.240493 -134.840852)
					(end 124.33046 -131.439158)
				)
				(arc
					(start 124.33046 -125.69825)
					(mid 121.181668 -126.073936)
					(end 118.71071 -124.086366)
				)
				(arc
					(start 118.71071 -124.086366)
					(mid 118.019216 -124.258303)
					(end 117.308376 -124.3076)
				)
				(xy 117.308376 -132.208524)
				(arc
					(start 115.82019 -132.208524)
					(mid 115.300844 -132.610274)
					(end 114.723926 -132.923788)
				)
				(xy 114.723926 -133.114796) (xy 114.41811 -133.114796)
				(arc
					(start 114.41811 -133.656578)
					(mid 114.43004 -133.968744)
					(end 114.41811 -134.28091)
				)
				(xy 114.41811 -134.352538)
				(arc
					(start 114.412014 -134.352538)
					(mid 112.334798 -137.539437)
					(end 108.531914 -137.637774)
				)
				(arc
					(start 108.531914 -137.637774)
					(mid 104.730212 -137.537835)
					(end 102.6541 -134.351522)
				)
				(xy 101.759004 -134.351522) (xy 101.759004 -133.124194) (xy 100.373688 -133.124194) (xy 100.373688 -124.611892)
				(xy 89.533222 -124.611892) (xy 89.533222 -110.081568) (xy 89.73439 -110.081568) (xy 88.632284 -109.379258)
			)
		)
		(polygon
			(pts
				(arc
					(start 74.066654 -102.207822)
					(mid 74.066654 -110.391702)
					(end 74.066654 -102.207822)
				)
			)
		)
	)
	(zone
		(net "P12V_A")
		(layer "F.Cu")
		(hatch none 0.5)
		(connect_pads
			(clearance 0.5)
		)
		(min_thickness 0.25)
		(fill yes
			(thermal_gap 0.5)
			(thermal_bridge_width 0.5)
			(island_removal_mode 0)
		)
		(polygon
			(pts
				(xy 256.8448 -366.9792) (xy 252.598682 -371.225318) (xy 252.598682 -377.096782) (xy 252.8189 -377.317)
				(xy 257.37312 -377.317) (xy 257.475482 -377.214638) (xy 257.475482 -369.079018) (xy 257.7592 -368.7953)
				(xy 259.64642 -368.7953) (xy 260.015482 -369.164362) (xy 260.015482 -377.063762) (xy 260.27634 -377.32462)
				(xy 264.483342 -377.32462) (xy 264.587482 -377.22048) (xy 264.587482 -369.048538) (xy 264.8077 -368.82832)
				(xy 266.76096 -368.82832) (xy 267.000482 -369.067842) (xy 267.000482 -376.80138) (xy 267.523722 -377.32462)
				(xy 271.58188 -377.32462) (xy 271.653 -377.2535) (xy 271.653 -367.32718) (xy 271.30502 -366.9792)
			)
		)
	)
	(zone
		(layer "F.Cu")
		(hatch none 0.5)
		(connect_pads
			(clearance 0)
		)
		(min_thickness 0.25)
		(keepout
			(tracks allowed)
			(vias allowed)
			(pads allowed)
			(copperpour allowed)
			(footprints not_allowed)
		)
		(placement
			(enabled no)
			(sheetname "")
		)
		(fill
			(thermal_gap 0.5)
			(thermal_bridge_width 0.5)
			(island_removal_mode 0)
		)
		(polygon
			(pts
				(arc
					(start 7.599934 -5.500116)
					(mid 3.850132 -9.249918)
					(end 0.100076 -5.500116)
				)
				(arc
					(start 0.100076 -5.500116)
					(mid 3.850132 -1.75006)
					(end 7.599934 -5.500116)
				)
			)
		)
	)
	(zone
		(net "P12V_A")
		(layer "F.Cu")
		(hatch none 0.5)
		(connect_pads
			(clearance 0.5)
		)
		(min_thickness 0.25)
		(fill yes
			(thermal_gap 0.5)
			(thermal_bridge_width 0.5)
			(island_removal_mode 0)
		)
		(polygon
			(pts
				(xy 251.629926 -30.555946) (xy 250.923552 -31.26232) (xy 250.923552 -35.039554) (xy 251.64923 -35.765232)
				(xy 265.28395 -35.765232) (xy 265.53795 -35.511232) (xy 265.53795 -30.913832) (xy 265.18235 -30.558232)
				(xy 262.52297 -30.558232) (xy 262.520684 -30.555946)
			)
		)
	)
	(zone
		(net "P12V_HDD6")
		(layer "F.Cu")
		(hatch none 0.5)
		(connect_pads
			(clearance 0.5)
		)
		(min_thickness 0.25)
		(fill yes
			(thermal_gap 0.5)
			(thermal_bridge_width 0.5)
			(island_removal_mode 0)
		)
		(polygon
			(pts
				(xy 334.645 -293.540942) (xy 334.391 -293.794942) (xy 334.391 -297.858942) (xy 333.932276 -298.317666)
				(xy 333.932276 -301.13986) (xy 333.098394 -301.973742) (xy 326.178418 -301.973742) (xy 326.009 -302.14316)
				(xy 326.009 -303.954942) (xy 326.263 -304.208942) (xy 330.2 -304.208942) (xy 330.708 -303.700942)
				(xy 338.455 -303.700942) (xy 339.344 -302.811942) (xy 339.344 -293.794942) (xy 339.09 -293.540942)
			)
		)
		(polygon
			(pts
				(xy 330.3524 -303.091342) (xy 330.1492 -303.091342) (xy 330.1492 -303.294542) (xy 330.3524 -303.294542)
			)
		)
		(polygon
			(pts
				(xy 329.4888 -303.091342) (xy 329.2856 -303.091342) (xy 329.2856 -303.294542) (xy 329.4888 -303.294542)
			)
		)
	)
	(zone
		(layer "F.Cu")
		(hatch none 0.5)
		(connect_pads
			(clearance 0)
		)
		(min_thickness 0.25)
		(keepout
			(tracks allowed)
			(vias allowed)
			(pads allowed)
			(copperpour allowed)
			(footprints allowed)
		)
		(placement
			(enabled no)
			(sheetname "")
		)
		(fill
			(thermal_gap 0.5)
			(thermal_bridge_width 0.5)
			(island_removal_mode 0)
		)
		(polygon
			(pts
				(xy 340.8426 -29.9974) (xy 340.8426 -32.5882) (xy 339.032596 -32.5882) (xy 339.032596 -29.9974)
			)
		)
	)
	(zone
		(net "MB3_12V_CTRL_GATE2")
		(layer "F.Cu")
		(hatch none 0.5)
		(connect_pads
			(clearance 0.5)
		)
		(min_thickness 0.25)
		(fill yes
			(thermal_gap 0.5)
			(thermal_bridge_width 0.5)
			(island_removal_mode 0)
		)
		(polygon
			(pts
				(xy 265.03884 -372.10238) (xy 264.892282 -372.248938) (xy 264.892282 -377.14936) (xy 265.067542 -377.32462)
				(xy 266.492482 -377.32462) (xy 266.644882 -377.17222) (xy 266.644882 -372.268242) (xy 266.47902 -372.10238)
			)
		)
	)
	(zone
		(net "GND")
		(layer "F.Cu")
		(hatch none 0.5)
		(connect_pads
			(clearance 0.5)
		)
		(min_thickness 0.25)
		(fill yes
			(thermal_gap 0.5)
			(thermal_bridge_width 0.5)
			(island_removal_mode 0)
		)
		(polygon
			(pts
				(xy 283.018992 -387.148578)
				(arc
					(start 283.018992 -399.3007)
					(mid 283.700193 -399.135313)
					(end 284.398974 -399.07972)
				)
				(arc
					(start 286.101282 -399.07972)
					(mid 287.961316 -399.49011)
					(end 289.475926 -400.645122)
				)
				(arc
					(start 289.475926 -400.645122)
					(mid 289.403216 -399.924244)
					(end 289.378898 -399.200116)
				)
				(arc
					(start 289.378898 -393.205716)
					(mid 294.099235 -384.268296)
					(end 304.14214 -383.128012)
				)
				(xy 304.148236 -383.134108) (xy 307.967888 -383.134108) (xy 307.967888 -409.271724)
				(arc
					(start 304.157634 -409.271724)
					(mid 296.295589 -409.292429)
					(end 290.49472 -403.98573)
				)
				(arc
					(start 290.49472 -403.98573)
					(mid 290.394515 -404.55178)
					(end 290.22167 -405.100028)
				)
				(arc
					(start 290.22167 -405.100028)
					(mid 290.072189 -408.641469)
					(end 287.36925 -410.934662)
				)
				(arc
					(start 287.36925 -410.934662)
					(mid 288.035724 -413.096024)
					(end 288.033968 -415.357818)
				)
				(xy 288.033968 -419.134544) (xy 288.00044 -419.168072) (xy 272.183606 -419.168072) (xy 272.183606 -420.437056)
				(arc
					(start 308.99989 -420.437056)
					(mid 309.167462 -420.367646)
					(end 309.236872 -420.200074)
				)
				(arc
					(start 309.236872 -375.000012)
					(mid 309.167462 -374.83244)
					(end 308.99989 -374.76303)
				)
				(arc
					(start 296.69994 -374.76303)
					(mid 295.453301 -374.246655)
					(end 294.936926 -373.000016)
				)
				(xy 294.936926 -365.742474) (xy 293.667942 -365.742474) (xy 293.667942 -369.98656) (xy 283.44495 -369.98656)
				(xy 281.7876 -368.32921) (xy 277.65121 -368.32921) (xy 277.65121 -372.851934) (xy 277.598886 -372.904258)
				(xy 277.598886 -375.819416) (xy 278.274526 -376.495056) (xy 278.274526 -380.140972) (xy 278.275796 -380.142242)
				(xy 278.275796 -384.713226) (xy 280.58364 -384.713226)
			)
		)
	)
	(zone
		(net "P12V_HDD26")
		(layer "F.Cu")
		(hatch none 0.5)
		(connect_pads
			(clearance 0.5)
		)
		(min_thickness 0.25)
		(fill yes
			(thermal_gap 0.5)
			(thermal_bridge_width 0.5)
			(island_removal_mode 0)
		)
		(polygon
			(pts
				(xy 75.402948 -61.254894) (xy 75.148948 -61.508894) (xy 75.148948 -63.159894) (xy 75.402948 -63.413894)
				(xy 77.561948 -63.413894) (xy 78.069948 -63.921894) (xy 78.069948 -66.461894) (xy 85.816948 -74.208894)
				(xy 94.325948 -74.208894) (xy 94.452948 -74.081894) (xy 94.452948 -72.303894) (xy 94.325948 -72.176894)
				(xy 88.356948 -72.176894) (xy 87.721948 -71.541894) (xy 86.070948 -71.541894) (xy 81.752948 -67.223894)
				(xy 81.752948 -63.667894) (xy 80.609948 -62.524894) (xy 80.609948 -61.508894) (xy 80.355948 -61.254894)
			)
		)
		(polygon
			(pts
				(xy 87.874348 -73.218294) (xy 87.671148 -73.218294) (xy 87.671148 -73.421494) (xy 87.874348 -73.421494)
			)
		)
		(polygon
			(pts
				(xy 87.010748 -73.218294) (xy 86.807548 -73.218294) (xy 86.807548 -73.421494) (xy 87.010748 -73.421494)
			)
		)
	)
	(zone
		(net "P12V_A")
		(layer "F.Cu")
		(hatch none 0.5)
		(connect_pads
			(clearance 0.5)
		)
		(min_thickness 0.25)
		(fill yes
			(thermal_gap 0.5)
			(thermal_bridge_width 0.5)
			(island_removal_mode 0)
		)
		(polygon
			(pts
				(xy 140.407898 -284.142942) (xy 139.391898 -285.158942) (xy 138.756898 -285.158942) (xy 138.375898 -285.539942)
				(xy 138.375898 -288.079942) (xy 138.629898 -288.333942) (xy 141.931898 -288.333942) (xy 142.185898 -288.079942)
				(xy 142.185898 -285.793942) (xy 141.550898 -285.158942) (xy 141.169898 -285.158942) (xy 140.915898 -284.904942)
				(xy 140.915898 -284.269942) (xy 140.788898 -284.142942)
			)
		)
		(polygon
			(pts
				(xy 140.382498 -284.727142) (xy 140.179298 -284.727142) (xy 140.179298 -284.930342) (xy 140.382498 -284.930342)
			)
		)
	)
	(zone
		(net "P5V_A_1")
		(layer "F.Cu")
		(hatch none 0.5)
		(connect_pads
			(clearance 0.5)
		)
		(min_thickness 0.25)
		(fill yes
			(thermal_gap 0.5)
			(thermal_bridge_width 0.5)
			(island_removal_mode 0)
		)
		(polygon
			(pts
				(xy 81.498948 -165.840918) (xy 81.244948 -166.094918) (xy 81.244948 -168.380918) (xy 81.498948 -168.634918)
				(xy 86.197948 -168.634918) (xy 86.451948 -168.380918) (xy 86.451948 -166.094918) (xy 86.197948 -165.840918)
			)
		)
	)
	(zone
		(net "P12V_A")
		(layer "F.Cu")
		(hatch none 0.5)
		(connect_pads
			(clearance 0.5)
		)
		(min_thickness 0.25)
		(fill yes
			(thermal_gap 0.5)
			(thermal_bridge_width 0.5)
			(island_removal_mode 0)
		)
		(polygon
			(pts
				(xy 460.8449 -171.428918) (xy 460.3369 -171.936918) (xy 460.3369 -175.365918) (xy 460.5909 -175.619918)
				(xy 463.8929 -175.619918) (xy 464.1469 -175.365918) (xy 464.1469 -173.333918) (xy 464.2739 -173.206918)
				(xy 464.6549 -173.206918) (xy 464.7819 -173.079918) (xy 464.7819 -171.555918) (xy 464.6549 -171.428918)
			)
		)
		(polygon
			(pts
				(xy 464.2485 -172.444918) (xy 464.0453 -172.444918) (xy 464.0453 -172.648118) (xy 464.2485 -172.648118)
			)
		)
		(polygon
			(pts
				(xy 464.2993 -171.987718) (xy 464.0961 -171.987718) (xy 464.0961 -172.190918) (xy 464.2993 -172.190918)
			)
		)
	)
	(zone
		(net "GND")
		(layer "F.Cu")
		(hatch none 0.5)
		(connect_pads
			(clearance 0.5)
		)
		(min_thickness 0.25)
		(fill yes
			(thermal_gap 0.5)
			(thermal_bridge_width 0.5)
			(island_removal_mode 0)
		)
		(polygon
			(pts
				(xy 358.067102 -126.936754) (xy 358.067102 -127.241554) (xy 357.089202 -127.241554) (xy 357.089202 -128.105154)
				(xy 355.158802 -128.105154) (xy 355.158802 -131.69519) (xy 353.88042 -130.416808) (xy 350.923352 -130.416808)
				(xy 350.923352 -126.120398) (xy 351.096834 -125.946916)
				(arc
					(start 351.096834 -113.782602)
					(mid 355.94403 -115.169024)
					(end 358.454706 -110.797086)
				)
				(arc
					(start 358.454706 -110.797086)
					(mid 362.8004 -110.292784)
					(end 364.204504 -106.149394)
				)
				(arc
					(start 364.204504 -106.149394)
					(mid 366.47761 -106.697853)
					(end 368.67973 -105.911396)
				)
				(arc
					(start 368.67973 -105.911396)
					(mid 369.328055 -106.318651)
					(end 370.040916 -106.597958)
				)
				(arc
					(start 370.040916 -112.51692)
					(mid 369.796328 -113.919)
					(end 370.040916 -115.32108)
				)
				(xy 370.040916 -118.886224)
				(arc
					(start 366.981486 -121.945654)
					(mid 365.431852 -122.834338)
					(end 364.40872 -124.29871)
				)
				(xy 363.80928 -124.29871) (xy 363.80928 -125.884686) (xy 362.992162 -125.884686) (xy 361.940094 -126.936754)
			)
		)
	)
	(zone
		(net "GND")
		(layer "F.Cu")
		(hatch none 0.5)
		(connect_pads
			(clearance 0.5)
		)
		(min_thickness 0.25)
		(fill yes
			(thermal_gap 0.5)
			(thermal_bridge_width 0.5)
			(island_removal_mode 0)
		)
		(polygon
			(pts
				(xy 215.630506 -99.0092) (xy 215.151208 -99.488498) (xy 215.151208 -108.34243) (xy 215.553798 -108.74502)
				(xy 219.574364 -108.74502) (xy 219.819728 -108.499656) (xy 219.819728 -99.2632) (xy 219.565728 -99.0092)
			)
		)
	)
	(zone
		(layer "F.Cu")
		(hatch none 0.5)
		(connect_pads
			(clearance 0)
		)
		(min_thickness 0.25)
		(keepout
			(tracks not_allowed)
			(vias allowed)
			(pads allowed)
			(copperpour not_allowed)
			(footprints allowed)
		)
		(placement
			(enabled no)
			(sheetname "")
		)
		(fill
			(thermal_gap 0.5)
			(thermal_bridge_width 0.5)
			(island_removal_mode 0)
		)
		(polygon
			(pts
				(arc
					(start 325.12 -277.17877)
					(mid 324.739127 -276.797516)
					(end 324.358 -277.178516)
				)
				(arc
					(start 324.358 -278.321516)
					(mid 324.739 -278.702516)
					(end 325.12 -278.321516)
				)
				(xy 325.12 -277.972266)
				(arc
					(start 324.866254 -277.972266)
					(mid 324.830153 -277.987219)
					(end 324.8152 -278.02332)
				)
				(arc
					(start 324.8152 -278.065992)
					(mid 324.739 -278.58816)
					(end 324.6628 -278.065992)
				)
				(xy 324.6628 -277.991824)
				(arc
					(start 324.665848 -277.988776)
					(mid 324.722456 -277.879522)
					(end 324.83171 -277.822914)
				)
				(xy 324.834758 -277.819866) (xy 325.12 -277.819866) (xy 325.12 -277.680166) (xy 324.834758 -277.680166)
				(arc
					(start 324.83171 -277.677118)
					(mid 324.722456 -277.62051)
					(end 324.665848 -277.511256)
				)
				(xy 324.6628 -277.508208)
				(arc
					(start 324.6628 -277.43404)
					(mid 324.739 -276.911872)
					(end 324.8152 -277.43404)
				)
				(arc
					(start 324.8152 -277.476712)
					(mid 324.830153 -277.512813)
					(end 324.866254 -277.527766)
				)
				(xy 325.12 -277.527766)
			)
		)
	)
	(zone
		(net "P5V_HDD10")
		(layer "F.Cu")
		(hatch none 0.5)
		(connect_pads
			(clearance 0.5)
		)
		(min_thickness 0.25)
		(fill yes
			(thermal_gap 0.5)
			(thermal_bridge_width 0.5)
			(island_removal_mode 0)
		)
		(polygon
			(pts
				(xy 457.091288 -281.729942) (xy 456.996546 -281.824684) (xy 456.996546 -285.493206) (xy 457.5429 -286.03956)
				(xy 457.5429 -292.778942) (xy 455.8919 -294.429942) (xy 452.4629 -294.429942) (xy 452.2089 -294.683942)
				(xy 452.2089 -296.334942) (xy 452.4629 -296.588942) (xy 457.0349 -296.588942) (xy 457.6699 -295.953942)
				(xy 459.4479 -295.953942) (xy 459.9559 -295.445942) (xy 459.9559 -281.983942) (xy 459.7019 -281.729942)
			)
		)
		(polygon
			(pts
				(xy 456.5523 -295.598342) (xy 456.3491 -295.598342) (xy 456.3491 -295.801542) (xy 456.5523 -295.801542)
			)
		)
		(polygon
			(pts
				(xy 455.6887 -295.598342) (xy 455.4855 -295.598342) (xy 455.4855 -295.801542) (xy 455.6887 -295.801542)
			)
		)
	)
	(zone
		(layer "F.Cu")
		(hatch none 0.5)
		(connect_pads
			(clearance 0)
		)
		(min_thickness 0.25)
		(keepout
			(tracks allowed)
			(vias allowed)
			(pads allowed)
			(copperpour allowed)
			(footprints not_allowed)
		)
		(placement
			(enabled no)
			(sheetname "")
		)
		(fill
			(thermal_gap 0.5)
			(thermal_bridge_width 0.5)
			(island_removal_mode 0)
		)
		(polygon
			(pts
				(arc
					(start 251.199904 -279.200102)
					(mid 244.199918 -286.200088)
					(end 237.199932 -279.200102)
				)
				(arc
					(start 237.199932 -273.200114)
					(mid 244.199918 -266.200128)
					(end 251.199904 -273.200114)
				)
			)
		)
	)
	(zone
		(net "P5V_A_3")
		(layer "F.Cu")
		(hatch none 0.5)
		(connect_pads
			(clearance 0.5)
		)
		(min_thickness 0.25)
		(fill yes
			(thermal_gap 0.5)
			(thermal_bridge_width 0.5)
			(island_removal_mode 0)
		)
		(polygon
			(pts
				(xy 473.45219 -276.948392) (xy 473.333064 -277.067264) (xy 473.333064 -279.623266) (xy 473.45219 -279.742392)
				(xy 478.15119 -279.742392) (xy 478.40519 -279.488392) (xy 478.40519 -277.202392) (xy 478.15119 -276.948392)
			)
		)
	)
	(zone
		(layer "F.Cu")
		(hatch none 0.5)
		(connect_pads
			(clearance 0)
		)
		(min_thickness 0.25)
		(keepout
			(tracks allowed)
			(vias allowed)
			(pads allowed)
			(copperpour allowed)
			(footprints not_allowed)
		)
		(placement
			(enabled no)
			(sheetname "")
		)
		(fill
			(thermal_gap 0.5)
			(thermal_bridge_width 0.5)
			(island_removal_mode 0)
		)
		(polygon
			(pts
				(xy 149.999954 -9.99998) (xy 155.325064 -9.99998) (xy 155.325064 0)
				(arc
					(start 150.999952 0)
					(mid 150.292847 -0.292893)
					(end 149.999954 -0.999998)
				)
			)
		)
	)
	(zone
		(layer "F.Cu")
		(hatch none 0.5)
		(connect_pads
			(clearance 0)
		)
		(min_thickness 0.25)
		(keepout
			(tracks not_allowed)
			(vias allowed)
			(pads allowed)
			(copperpour not_allowed)
			(footprints allowed)
		)
		(placement
			(enabled no)
			(sheetname "")
		)
		(fill
			(thermal_gap 0.5)
			(thermal_bridge_width 0.5)
			(island_removal_mode 0)
		)
		(polygon
			(pts
				(arc
					(start 271.970754 -306.921408)
					(mid 271.58696 -307.304821)
					(end 271.9705 -307.688488)
				)
				(arc
					(start 273.1135 -307.688488)
					(mid 273.49704 -307.304948)
					(end 273.1135 -306.921408)
				)
				(xy 272.76425 -306.921408)
				(arc
					(start 272.76425 -307.177948)
					(mid 272.779129 -307.213869)
					(end 272.81505 -307.228748)
				)
				(arc
					(start 272.857976 -307.228748)
					(mid 273.380144 -307.304948)
					(end 272.857976 -307.381148)
				)
				(xy 272.783554 -307.381148)
				(arc
					(start 272.780506 -307.3781)
					(mid 272.671429 -307.321569)
					(end 272.614898 -307.212492)
				)
				(xy 272.61185 -307.209444) (xy 272.61185 -306.921408) (xy 272.47215 -306.921408) (xy 272.47215 -307.209444)
				(arc
					(start 272.469102 -307.212492)
					(mid 272.412571 -307.321569)
					(end 272.303494 -307.3781)
				)
				(xy 272.300446 -307.381148)
				(arc
					(start 272.226024 -307.381148)
					(mid 271.703856 -307.304948)
					(end 272.226024 -307.228748)
				)
				(arc
					(start 272.26895 -307.228748)
					(mid 272.304871 -307.213869)
					(end 272.31975 -307.177948)
				)
				(xy 272.31975 -306.921408)
			)
		)
	)
	(zone
		(net "P5V_HDD7")
		(layer "F.Cu")
		(hatch none 0.5)
		(connect_pads
			(clearance 0.5)
		)
		(min_thickness 0.25)
		(fill yes
			(thermal_gap 0.5)
			(thermal_bridge_width 0.5)
			(island_removal_mode 0)
		)
		(polygon
			(pts
				(xy 363.147102 -281.729942) (xy 362.893102 -281.983942) (xy 362.893102 -292.778942) (xy 361.242102 -294.429942)
				(xy 357.813102 -294.429942) (xy 357.559102 -294.683942) (xy 357.559102 -296.334942) (xy 357.813102 -296.588942)
				(xy 362.385102 -296.588942) (xy 363.020102 -295.953942) (xy 364.798102 -295.953942) (xy 365.306102 -295.445942)
				(xy 365.306102 -281.983942) (xy 365.052102 -281.729942)
			)
		)
		(polygon
			(pts
				(xy 361.902502 -295.598342) (xy 361.699302 -295.598342) (xy 361.699302 -295.801542) (xy 361.902502 -295.801542)
			)
		)
		(polygon
			(pts
				(xy 361.038902 -295.598342) (xy 360.835702 -295.598342) (xy 360.835702 -295.801542) (xy 361.038902 -295.801542)
			)
		)
	)
	(zone
		(net "GND")
		(layer "F.Cu")
		(hatch none 0.5)
		(connect_pads
			(clearance 0.5)
		)
		(min_thickness 0.25)
		(fill yes
			(thermal_gap 0.5)
			(thermal_bridge_width 0.5)
			(island_removal_mode 0)
		)
		(polygon
			(pts
				(xy 440.600084 -195.18757) (xy 441.11164 -195.699126) (xy 441.11164 -202.25893) (xy 440.212988 -202.25893)
				(xy 438.045606 -204.426312)
				(arc
					(start 437.640476 -204.426312)
					(mid 432.67837 -198.979976)
					(end 425.638214 -196.807074)
				)
				(arc
					(start 425.638214 -196.807074)
					(mid 425.978144 -196.032635)
					(end 426.151548 -195.204842)
				)
				(arc
					(start 428.152052 -195.204842)
					(mid 429.410867 -195.006352)
					(end 430.547526 -194.430142)
				)
				(xy 432.662076 -194.430142) (xy 432.662076 -192.511172) (xy 434.683408 -192.511172) (xy 437.804306 -189.390274)
				(xy 437.804306 -184.193942) (xy 437.996076 -184.193942)
				(arc
					(start 437.996076 -172.643038)
					(mid 438.18584 -171.963063)
					(end 438.249822 -171.260008)
				)
				(arc
					(start 438.249822 -168.403016)
					(mid 440.065579 -167.969551)
					(end 441.496196 -166.770304)
				)
				(xy 443.912244 -166.770304) (xy 443.912244 -175.115982)
				(arc
					(start 443.131448 -175.896778)
					(mid 442.286825 -177.160846)
					(end 441.990226 -178.651916)
				)
				(arc
					(start 441.990226 -179.23256)
					(mid 441.745796 -180.670805)
					(end 442.015372 -182.104538)
				)
				(arc
					(start 442.015372 -182.104538)
					(mid 442.290012 -183.162056)
					(end 442.847476 -184.10174)
				)
				(xy 442.847476 -186.107324) (xy 442.898276 -186.107324) (xy 442.898276 -187.097924) (xy 442.923676 -187.097924)
				(xy 442.923676 -187.099956) (xy 440.600084 -189.423548)
			)
		)
	)
	(zone
		(net "MB3_CM_GATE_C")
		(layer "F.Cu")
		(hatch none 0.5)
		(connect_pads
			(clearance 0.5)
		)
		(min_thickness 0.25)
		(fill yes
			(thermal_gap 0.5)
			(thermal_bridge_width 0.5)
			(island_removal_mode 0)
		)
		(polygon
			(pts
				(xy 242.764818 -379.235462) (xy 242.631214 -379.369066) (xy 242.631214 -380.492254) (xy 242.823492 -380.684532)
				(xy 246.790718 -380.684532) (xy 247.015254 -380.459996) (xy 247.015254 -379.44933) (xy 246.801386 -379.235462)
			)
		)
		(polygon
			(pts
				(xy 243.767102 -380.167896) (xy 243.563902 -380.167896) (xy 243.563902 -380.371096) (xy 243.767102 -380.371096)
			)
		)
	)
	(zone
		(layer "F.Cu")
		(hatch none 0.5)
		(connect_pads
			(clearance 0)
		)
		(min_thickness 0.25)
		(keepout
			(tracks allowed)
			(vias allowed)
			(pads allowed)
			(copperpour allowed)
			(footprints allowed)
		)
		(placement
			(enabled no)
			(sheetname "")
		)
		(fill
			(thermal_gap 0.5)
			(thermal_bridge_width 0.5)
			(island_removal_mode 0)
		)
		(polygon
			(pts
				(xy 278.1554 -277.4188) (xy 278.1554 -275.0312) (xy 279.1714 -275.0312) (xy 279.1714 -277.4188)
			)
		)
	)
	(zone
		(layer "F.Cu")
		(hatch none 0.5)
		(connect_pads
			(clearance 0)
		)
		(min_thickness 0.25)
		(keepout
			(tracks allowed)
			(vias allowed)
			(pads allowed)
			(copperpour allowed)
			(footprints allowed)
		)
		(placement
			(enabled no)
			(sheetname "")
		)
		(fill
			(thermal_gap 0.5)
			(thermal_bridge_width 0.5)
			(island_removal_mode 0)
		)
		(polygon
			(pts
				(xy 242.8748 -136.7282) (xy 242.8748 -133.858) (xy 239.6236 -133.858) (xy 239.6236 -136.7282)
			)
		)
	)
	(zone
		(net "12V_PRE_7")
		(layer "F.Cu")
		(hatch none 0.5)
		(connect_pads
			(clearance 0.5)
		)
		(min_thickness 0.25)
		(fill yes
			(thermal_gap 0.5)
			(thermal_bridge_width 0.5)
			(island_removal_mode 0)
		)
		(polygon
			(pts
				(xy 362.81868 -298.314364) (xy 360.353102 -300.779942) (xy 357.813102 -300.779942) (xy 357.559102 -301.033942)
				(xy 357.559102 -301.414942) (xy 357.813102 -301.668942) (xy 364.511336 -301.668942) (xy 365.171736 -301.008542)
				(xy 365.171736 -298.435014) (xy 365.051086 -298.314364)
			)
		)
	)
	(zone
		(net "GND")
		(layer "F.Cu")
		(hatch none 0.5)
		(connect_pads
			(clearance 0.5)
		)
		(min_thickness 0.25)
		(fill yes
			(thermal_gap 0.5)
			(thermal_bridge_width 0.5)
			(island_removal_mode 0)
		)
		(polygon
			(pts
				(xy 320.167 -104.0638) (xy 319.546732 -104.684068) (xy 319.546732 -108.296456)
				(arc
					(start 322.184776 -110.9345)
					(mid 323.349068 -111.752932)
					(end 324.1675 -112.917224)
				)
				(arc
					(start 325.30415 -114.053874)
					(mid 326.148773 -115.317942)
					(end 326.445372 -116.809012)
				)
				(xy 326.445372 -122.40641) (xy 326.792336 -122.40641) (xy 326.792336 -132.315458) (xy 323.849492 -132.315458)
				(xy 323.849492 -133.135624)
				(arc
					(start 323.019928 -133.135624)
					(mid 322.757094 -133.411434)
					(end 322.470018 -133.661912)
				)
				(xy 322.470018 -134.510526)
				(arc
					(start 321.12966 -134.510526)
					(mid 319.721215 -135.339954)
					(end 318.100456 -135.551672)
				)
				(arc
					(start 318.100456 -135.551672)
					(mid 314.20491 -137.185576)
					(end 310.941974 -134.502652)
				)
				(arc
					(start 310.367934 -134.502652)
					(mid 310.856654 -136.325464)
					(end 311.021222 -138.205464)
				)
				(arc
					(start 311.021222 -144.200118)
					(mid 308.787023 -150.785071)
					(end 303.007014 -154.650948)
				)
				(arc
					(start 303.007014 -157.209236)
					(mid 299.025222 -161.298704)
					(end 294.831008 -157.427422)
				)
				(xy 292.521386 -155.1178) (xy 290.4998 -155.1178) (xy 289.594798 -156.022802) (xy 289.594798 -175.742346)
				(xy 301.399956 -175.742346)
				(arc
					(start 302.500792 -176.843182)
					(mid 302.642946 -176.835755)
					(end 302.785272 -176.833276)
				)
				(arc
					(start 303.699672 -176.833276)
					(mid 304.422236 -176.897593)
					(end 305.122072 -177.088546)
				)
				(xy 305.641756 -177.088546) (xy 306.084986 -177.531776) (xy 306.177696 -177.531776) (xy 306.177696 -177.624486)
				(arc
					(start 306.4383 -177.885344)
					(mid 306.592312 -178.03156)
					(end 306.738528 -178.185572)
				)
				(xy 308.280054 -179.726844)
				(arc
					(start 308.280054 -182.917338)
					(mid 308.332029 -183.290769)
					(end 308.349396 -183.6674)
				)
				(arc
					(start 308.349396 -185.4962)
					(mid 308.332022 -185.87283)
					(end 308.280054 -186.246262)
				)
				(xy 308.280054 -187.811156) (xy 305.387756 -190.703454) (xy 304.134266 -190.703454) (xy 304.134266 -192.490344)
				(xy 301.323756 -195.300854) (xy 284.7594 -195.300854) (xy 284.7594 -199.872854) (xy 295.1734 -210.286854)
				(xy 295.1734 -228.601524) (xy 298.006516 -231.43464) (xy 305.916076 -231.43464) (xy 306.764436 -232.283)
				(arc
					(start 310.928004 -232.283)
					(mid 310.893377 -231.241227)
					(end 311.120028 -230.223822)
				)
				(xy 311.120028 -228.618796) (xy 307.956966 -225.455734)
				(arc
					(start 307.956966 -207.046322)
					(mid 308.253559 -205.55525)
					(end 309.098188 -204.291184)
				)
				(arc
					(start 310.31434 -203.075032)
					(mid 311.578408 -202.230409)
					(end 313.069478 -201.93381)
				)
				(arc
					(start 314.472574 -201.93381)
					(mid 315.963646 -202.230403)
					(end 317.227712 -203.075032)
				)
				(arc
					(start 318.189864 -204.037184)
					(mid 318.363735 -204.222723)
					(end 318.525144 -204.4192)
				)
				(arc
					(start 320.3956 -204.4192)
					(mid 321.556852 -201.972709)
					(end 323.289168 -199.891142)
				)
				(xy 320.44386 -199.891142) (xy 320.44386 -189.678818)
				(arc
					(start 321.591686 -189.678818)
					(mid 321.869252 -189.224386)
					(end 322.198746 -188.806074)
				)
				(xy 322.198746 -187.601352)
				(arc
					(start 319.908936 -187.601352)
					(mid 316.365109 -187.248285)
					(end 314.355226 -184.308242)
				)
				(xy 312.926476 -184.308242) (xy 312.926476 -175.821594) (xy 313.688476 -175.821594) (xy 313.688476 -172.011594)
				(arc
					(start 315.852302 -172.011594)
					(mid 316.726574 -171.45613)
					(end 317.712344 -171.138088)
				)
				(arc
					(start 317.712344 -163.895532)
					(mid 316.398565 -162.434264)
					(end 315.923676 -160.527492)
				)
				(arc
					(start 315.923676 -157.352492)
					(mid 317.279947 -154.321249)
					(end 320.44386 -153.312368)
				)
				(xy 320.44386 -145.928842) (xy 330.656184 -145.928842)
				(arc
					(start 330.656184 -148.517102)
					(mid 331.435619 -150.193775)
					(end 331.397102 -152.042368)
				)
				(xy 332.367636 -152.042368) (xy 332.367636 -152.224994)
				(arc
					(start 333.248 -152.224994)
					(mid 334.557421 -152.4402)
					(end 335.729072 -153.063194)
				)
				(arc
					(start 336.193384 -153.063194)
					(mid 336.818168 -153.001512)
					(end 337.445096 -153.035)
				)
				(xy 340.207346 -153.035) (xy 340.207346 -147.418044) (xy 341.38489 -146.2405) (xy 341.121746 -145.977356)
				(arc
					(start 341.121746 -139.620752)
					(mid 340.889745 -139.077225)
					(end 340.73846 -138.505946)
				)
				(arc
					(start 340.73846 -138.505946)
					(mid 339.021215 -137.490771)
					(end 337.988402 -135.784082)
				)
				(arc
					(start 337.988402 -135.784082)
					(mid 337.649067 -135.586163)
					(end 337.330288 -135.3566)
				)
				(arc
					(start 337.330288 -135.3566)
					(mid 336.444927 -135.010742)
					(end 335.663286 -134.469886)
				)
				(xy 334.30718 -134.469886) (xy 334.30718 -133.103112) (xy 334.004666 -133.103112) (xy 334.004666 -124.337064)
				(arc
					(start 335.643474 -124.337064)
					(mid 336.030089 -123.465422)
					(end 336.616802 -122.71375)
				)
				(xy 338.491068 -120.839484) (xy 338.491068 -109.256068) (xy 337.439 -108.204)
				(arc
					(start 336.018886 -108.204)
					(mid 327.758892 -109.215252)
					(end 321.223386 -104.0638)
				)
			)
		)
	)
	(zone
		(net "P12V_HDD23")
		(layer "F.Cu")
		(hatch none 0.5)
		(connect_pads
			(clearance 0.5)
		)
		(min_thickness 0.25)
		(fill yes
			(thermal_gap 0.5)
			(thermal_bridge_width 0.5)
			(island_removal_mode 0)
		)
		(polygon
			(pts
				(xy 467.402926 -176.254918) (xy 467.148926 -176.508918) (xy 467.148926 -178.159918) (xy 467.402926 -178.413918)
				(xy 468.70874 -178.413918) (xy 469.157558 -178.862736) (xy 469.157558 -181.692042) (xy 476.674434 -189.208918)
				(xy 486.325926 -189.208918) (xy 486.452926 -189.081918) (xy 486.452926 -187.303918) (xy 486.325926 -187.176918)
				(xy 480.356926 -187.176918) (xy 479.721926 -186.541918) (xy 478.070926 -186.541918) (xy 473.206826 -181.677818)
				(xy 473.206826 -181.66207) (xy 472.609926 -181.06517) (xy 472.609926 -176.508918) (xy 472.355926 -176.254918)
			)
		)
		(polygon
			(pts
				(xy 479.874326 -188.218318) (xy 479.671126 -188.218318) (xy 479.671126 -188.421518) (xy 479.874326 -188.421518)
			)
		)
		(polygon
			(pts
				(xy 479.010726 -188.218318) (xy 478.807526 -188.218318) (xy 478.807526 -188.421518) (xy 479.010726 -188.421518)
			)
		)
	)
	(zone
		(layer "F.Cu")
		(hatch none 0.5)
		(connect_pads
			(clearance 0)
		)
		(min_thickness 0.25)
		(keepout
			(tracks allowed)
			(vias allowed)
			(pads allowed)
			(copperpour allowed)
			(footprints allowed)
		)
		(placement
			(enabled no)
			(sheetname "")
		)
		(fill
			(thermal_gap 0.5)
			(thermal_bridge_width 0.5)
			(island_removal_mode 0)
		)
		(polygon
			(pts
				(xy 232.029 -234.3404) (xy 232.029 -231.6734) (xy 235.0516 -231.6734) (xy 235.0516 -234.3404)
			)
		)
	)
	(zone
		(layer "F.Cu")
		(hatch none 0.5)
		(connect_pads
			(clearance 0)
		)
		(min_thickness 0.25)
		(keepout
			(tracks not_allowed)
			(vias allowed)
			(pads allowed)
			(copperpour not_allowed)
			(footprints allowed)
		)
		(placement
			(enabled no)
			(sheetname "")
		)
		(fill
			(thermal_gap 0.5)
			(thermal_bridge_width 0.5)
			(island_removal_mode 0)
		)
		(polygon
			(pts
				(arc
					(start 409.150058 -289.999928)
					(mid 404.400004 -294.749982)
					(end 399.64995 -289.999928)
				)
				(arc
					(start 399.64995 -289.999928)
					(mid 404.400004 -285.249874)
					(end 409.150058 -289.999928)
				)
			)
		)
	)
	(zone
		(net "P5V_A_3")
		(layer "F.Cu")
		(hatch none 0.5)
		(connect_pads
			(clearance 0.5)
		)
		(min_thickness 0.25)
		(fill yes
			(thermal_gap 0.5)
			(thermal_bridge_width 0.5)
			(island_removal_mode 0)
		)
		(polygon
			(pts
				(xy 397.405606 -165.332918) (xy 397.216122 -165.522402) (xy 397.216122 -170.338242) (xy 397.417798 -170.539918)
				(xy 400.033998 -170.539918) (xy 400.28876 -170.285156) (xy 400.28876 -165.50005) (xy 400.121628 -165.332918)
			)
		)
	)
	(zone
		(layer "F.Cu")
		(hatch none 0.5)
		(connect_pads
			(clearance 0)
		)
		(min_thickness 0.25)
		(keepout
			(tracks not_allowed)
			(vias allowed)
			(pads allowed)
			(copperpour not_allowed)
			(footprints allowed)
		)
		(placement
			(enabled no)
			(sheetname "")
		)
		(fill
			(thermal_gap 0.5)
			(thermal_bridge_width 0.5)
			(island_removal_mode 0)
		)
		(polygon
			(pts
				(arc
					(start 240.874804 -106.85018)
					(mid 239.900206 -107.175046)
					(end 240.225072 -108.149644)
				)
				(xy 240.223802 -108.15193)
				(arc
					(start 240.997994 -108.539026)
					(mid 241.044571 -108.355508)
					(end 241.145568 -108.195364)
				)
				(arc
					(start 241.262916 -108.034328)
					(mid 241.263172 -107.983678)
					(end 241.229134 -107.94619)
				)
				(arc
					(start 240.988088 -107.825794)
					(mid 240.061637 -107.255501)
					(end 241.073432 -107.65536)
				)
				(xy 241.314478 -107.77601) (xy 241.349784 -107.793536)
				(arc
					(start 241.351308 -107.798362)
					(mid 241.446373 -107.931054)
					(end 241.443764 -108.094272)
				)
				(xy 241.445796 -108.106718) (xy 241.273838 -108.342938)
				(arc
					(start 241.270536 -108.343446)
					(mid 241.201899 -108.48096)
					(end 241.187986 -108.634022)
				)
				(arc
					(start 241.303556 -108.69168)
					(mid 241.295597 -108.525504)
					(end 241.373914 -108.378752)
				)
				(xy 241.542316 -108.14685) (xy 241.542316 -108.131102) (xy 241.570002 -108.103162) (xy 241.571526 -108.101892)
				(xy 241.598196 -108.075222)
				(arc
					(start 241.603022 -108.075222)
					(mid 241.712663 -108.029751)
					(end 241.831114 -108.03763)
				)
				(xy 241.83594 -108.036106)
				(arc
					(start 242.111784 -108.174028)
					(mid 243.038235 -108.744321)
					(end 242.02644 -108.344462)
				)
				(arc
					(start 241.785902 -108.224066)
					(mid 241.757133 -108.216839)
					(end 241.72799 -108.222288)
				)
				(xy 241.71021 -108.239814) (xy 241.500914 -108.528104)
				(arc
					(start 241.497612 -108.528612)
					(mid 241.479235 -108.60786)
					(end 241.514376 -108.681266)
				)
				(xy 241.746532 -108.913168) (xy 242.223798 -109.151928)
				(arc
					(start 242.225068 -109.149642)
					(mid 243.199666 -108.824776)
					(end 242.8748 -107.850178)
				)
				(xy 242.87607 -107.847892) (xy 240.876074 -106.847894) (xy 240.87582 -106.848148)
			)
		)
	)
	(zone
		(net "GND")
		(layer "F.Cu")
		(hatch none 0.5)
		(connect_pads
			(clearance 0.5)
		)
		(min_thickness 0.25)
		(fill yes
			(thermal_gap 0.5)
			(thermal_bridge_width 0.5)
			(island_removal_mode 0)
		)
		(polygon
			(pts
				(xy 129.667 -150.876) (xy 129.667 -152.042368) (xy 129.667508 -152.042368) (xy 129.667508 -154.671268)
				(xy 131.382008 -154.671268) (xy 131.382008 -155.948126)
				(arc
					(start 132.051552 -156.374846)
					(mid 132.709008 -156.902694)
					(end 133.236716 -157.560264)
				)
				(xy 134.22122 -159.1056)
				(arc
					(start 135.879078 -159.1056)
					(mid 137.011775 -157.510873)
					(end 138.755374 -156.624274)
				)
				(xy 138.755374 -156.187394) (xy 140.609574 -156.187394) (xy 140.609574 -156.111194) (xy 144.673574 -156.111194)
				(xy 144.673574 -155.780994) (xy 149.293834 -155.780994) (xy 149.293834 -151.637238) (xy 137.739882 -151.637238)
				(xy 136.978644 -150.876)
			)
		)
	)
	(zone
		(net "P5V_A_3")
		(layer "F.Cu")
		(hatch none 0.5)
		(connect_pads
			(clearance 0.5)
		)
		(min_thickness 0.25)
		(fill yes
			(thermal_gap 0.5)
			(thermal_bridge_width 0.5)
			(island_removal_mode 0)
		)
		(polygon
			(pts
				(xy 368.354102 -165.332918) (xy 368.100102 -165.586918) (xy 368.100102 -170.285918) (xy 368.354102 -170.539918)
				(xy 370.640102 -170.539918) (xy 370.894102 -170.285918) (xy 370.894102 -165.586918) (xy 370.640102 -165.332918)
			)
		)
	)
	(zone
		(layer "F.Cu")
		(hatch none 0.5)
		(connect_pads
			(clearance 0)
		)
		(min_thickness 0.25)
		(keepout
			(tracks not_allowed)
			(vias allowed)
			(pads allowed)
			(copperpour not_allowed)
			(footprints allowed)
		)
		(placement
			(enabled no)
			(sheetname "")
		)
		(fill
			(thermal_gap 0.5)
			(thermal_bridge_width 0.5)
			(island_removal_mode 0)
		)
		(polygon
			(pts
				(arc
					(start 271.970754 -337.52155)
					(mid 271.58696 -337.904963)
					(end 271.9705 -338.28863)
				)
				(arc
					(start 273.1135 -338.28863)
					(mid 273.49704 -337.90509)
					(end 273.1135 -337.52155)
				)
				(xy 272.76425 -337.52155)
				(arc
					(start 272.76425 -337.77809)
					(mid 272.779129 -337.814011)
					(end 272.81505 -337.82889)
				)
				(arc
					(start 272.857976 -337.82889)
					(mid 273.380144 -337.90509)
					(end 272.857976 -337.98129)
				)
				(xy 272.783554 -337.98129)
				(arc
					(start 272.780506 -337.978242)
					(mid 272.671429 -337.921711)
					(end 272.614898 -337.812634)
				)
				(xy 272.61185 -337.809586) (xy 272.61185 -337.52155) (xy 272.47215 -337.52155) (xy 272.47215 -337.809586)
				(arc
					(start 272.469102 -337.812634)
					(mid 272.412571 -337.921711)
					(end 272.303494 -337.978242)
				)
				(xy 272.300446 -337.98129)
				(arc
					(start 272.226024 -337.98129)
					(mid 271.703856 -337.90509)
					(end 272.226024 -337.82889)
				)
				(arc
					(start 272.26895 -337.82889)
					(mid 272.304871 -337.814011)
					(end 272.31975 -337.77809)
				)
				(xy 272.31975 -337.52155)
			)
		)
	)
	(zone
		(layer "F.Cu")
		(hatch none 0.5)
		(connect_pads
			(clearance 0)
		)
		(min_thickness 0.25)
		(keepout
			(tracks allowed)
			(vias allowed)
			(pads allowed)
			(copperpour allowed)
			(footprints allowed)
		)
		(placement
			(enabled no)
			(sheetname "")
		)
		(fill
			(thermal_gap 0.5)
			(thermal_bridge_width 0.5)
			(island_removal_mode 0)
		)
		(polygon
			(pts
				(xy 157.951678 -141.321536) (xy 157.017212 -141.321536) (xy 157.017212 -138.672062) (xy 157.951678 -138.672062)
			)
		)
	)
	(zone
		(net "GND")
		(layer "F.Cu")
		(hatch none 0.5)
		(connect_pads
			(clearance 0.5)
		)
		(min_thickness 0.25)
		(fill yes
			(thermal_gap 0.5)
			(thermal_bridge_width 0.5)
			(island_removal_mode 0)
		)
		(polygon
			(pts
				(xy 301.5234 -180.8988) (xy 301.0662 -181.356) (xy 301.0662 -182.77459) (xy 301.342806 -183.051196)
				(xy 301.342806 -186.509406) (xy 301.7266 -186.8932) (xy 303.8094 -186.8932) (xy 304.4698 -186.2328)
				(xy 304.4698 -181.3052) (xy 304.0634 -180.8988)
			)
		)
	)
	(zone
		(net "12V_PRE_35")
		(layer "F.Cu")
		(hatch none 0.5)
		(connect_pads
			(clearance 0.5)
		)
		(min_thickness 0.25)
		(fill yes
			(thermal_gap 0.5)
			(thermal_bridge_width 0.5)
			(island_removal_mode 0)
		)
		(polygon
			(pts
				(xy 474.768926 -63.794894) (xy 474.641926 -63.921894) (xy 474.641926 -67.860926) (xy 476.184976 -69.403976)
				(xy 479.997008 -69.403976) (xy 482.388926 -71.795894) (xy 486.325926 -71.795894) (xy 486.452926 -71.668894)
				(xy 486.452926 -70.906894) (xy 486.325926 -70.779894) (xy 483.023926 -70.779894) (xy 480.378008 -68.133976)
				(xy 476.489776 -68.133976) (xy 476.123 -67.7672) (xy 476.123 -63.9318) (xy 475.986094 -63.794894)
			)
		)
	)
	(zone
		(net "5V_PRE_21")
		(layer "F.Cu")
		(hatch none 0.5)
		(connect_pads
			(clearance 0.5)
		)
		(min_thickness 0.25)
		(fill yes
			(thermal_gap 0.5)
			(thermal_bridge_width 0.5)
			(island_removal_mode 0)
		)
		(polygon
			(pts
				(xy 424.088052 -174.984918) (xy 423.834052 -175.238918) (xy 423.834052 -177.778918) (xy 423.453052 -178.159918)
				(xy 420.913052 -178.159918) (xy 420.659052 -178.413918) (xy 420.659052 -178.794918) (xy 420.913052 -179.048918)
				(xy 424.215052 -179.048918) (xy 425.485052 -177.778918) (xy 425.485052 -175.238918) (xy 425.231052 -174.984918)
			)
		)
	)
	(zone
		(layer "F.Cu")
		(hatch none 0.5)
		(connect_pads
			(clearance 0)
		)
		(min_thickness 0.25)
		(keepout
			(tracks not_allowed)
			(vias allowed)
			(pads allowed)
			(copperpour not_allowed)
			(footprints allowed)
		)
		(placement
			(enabled no)
			(sheetname "")
		)
		(fill
			(thermal_gap 0.5)
			(thermal_bridge_width 0.5)
			(island_removal_mode 0)
		)
		(polygon
			(pts
				(arc
					(start 467.499954 -274.877022)
					(mid 467.499954 -265.122914)
					(end 467.499954 -274.877022)
				)
			)
		)
	)
	(zone
		(net "P5V_A_2")
		(layer "F.Cu")
		(hatch none 0.5)
		(connect_pads
			(clearance 0.5)
		)
		(min_thickness 0.25)
		(fill yes
			(thermal_gap 0.5)
			(thermal_bridge_width 0.5)
			(island_removal_mode 0)
		)
		(polygon
			(pts
				(xy 176.149 -165.840918) (xy 175.895 -166.094918) (xy 175.895 -168.380918) (xy 176.149 -168.634918)
				(xy 180.848 -168.634918) (xy 181.102 -168.380918) (xy 181.102 -166.094918) (xy 180.848 -165.840918)
			)
		)
	)
	(zone
		(net "P12V_HDD25")
		(layer "F.Cu")
		(hatch none 0.5)
		(connect_pads
			(clearance 0.5)
		)
		(min_thickness 0.25)
		(fill yes
			(thermal_gap 0.5)
			(thermal_bridge_width 0.5)
			(island_removal_mode 0)
		)
		(polygon
			(pts
				(xy 43.852846 -61.254894) (xy 43.598846 -61.508894) (xy 43.598846 -63.159894) (xy 43.852846 -63.413894)
				(xy 46.011846 -63.413894) (xy 46.519846 -63.921894) (xy 46.519846 -66.461894) (xy 54.266846 -74.208894)
				(xy 62.775846 -74.208894) (xy 62.902846 -74.081894) (xy 62.902846 -72.303894) (xy 62.775846 -72.176894)
				(xy 56.806846 -72.176894) (xy 56.171846 -71.541894) (xy 54.520846 -71.541894) (xy 50.202846 -67.223894)
				(xy 50.202846 -63.667894) (xy 49.059846 -62.524894) (xy 49.059846 -61.508894) (xy 48.805846 -61.254894)
			)
		)
		(polygon
			(pts
				(xy 56.324246 -73.218294) (xy 56.121046 -73.218294) (xy 56.121046 -73.421494) (xy 56.324246 -73.421494)
			)
		)
		(polygon
			(pts
				(xy 55.460646 -73.218294) (xy 55.257446 -73.218294) (xy 55.257446 -73.421494) (xy 55.460646 -73.421494)
			)
		)
	)
	(zone
		(net "MB3_CM_GATE_R")
		(layer "F.Cu")
		(hatch none 0.5)
		(connect_pads
			(clearance 0.5)
		)
		(min_thickness 0.25)
		(fill yes
			(thermal_gap 0.5)
			(thermal_bridge_width 0.5)
			(island_removal_mode 0)
		)
		(polygon
			(pts
				(xy 257.93573 -369.147598) (xy 257.766566 -369.316508) (xy 257.766566 -371.310154) (xy 258.038854 -371.582442)
				(xy 259.333492 -371.582442) (xy 259.642356 -371.273578) (xy 259.642356 -369.273582) (xy 259.516372 -369.147598)
			)
		)
	)
	(zone
		(layer "F.Cu")
		(hatch none 0.5)
		(connect_pads
			(clearance 0)
		)
		(min_thickness 0.25)
		(keepout
			(tracks not_allowed)
			(vias allowed)
			(pads allowed)
			(copperpour not_allowed)
			(footprints allowed)
		)
		(placement
			(enabled no)
			(sheetname "")
		)
		(fill
			(thermal_gap 0.5)
			(thermal_bridge_width 0.5)
			(island_removal_mode 0)
		)
		(polygon
			(pts
				(arc
					(start 320.3702 -158.368492)
					(mid 319.9892 -157.987492)
					(end 319.6082 -158.368492)
				)
				(arc
					(start 319.6082 -159.511238)
					(mid 319.989073 -159.892492)
					(end 320.3702 -159.511492)
				)
				(xy 320.3702 -159.162242) (xy 320.14795 -159.162242) (xy 320.0654 -159.244792)
				(arc
					(start 320.0654 -159.255968)
					(mid 319.9892 -159.778136)
					(end 319.913 -159.255968)
				)
				(xy 319.913 -159.1818) (xy 320.084958 -159.009842) (xy 320.3702 -159.009842) (xy 320.3702 -158.870142)
				(xy 320.084958 -158.870142) (xy 319.913 -158.698184)
				(arc
					(start 319.913 -158.624016)
					(mid 319.9892 -158.101848)
					(end 320.0654 -158.624016)
				)
				(xy 320.0654 -158.635192) (xy 320.14795 -158.717742) (xy 320.3702 -158.717742)
			)
		)
	)
	(zone
		(layer "F.Cu")
		(hatch none 0.5)
		(connect_pads
			(clearance 0)
		)
		(min_thickness 0.25)
		(keepout
			(tracks allowed)
			(vias allowed)
			(pads allowed)
			(copperpour allowed)
			(footprints not_allowed)
		)
		(placement
			(enabled no)
			(sheetname "")
		)
		(fill
			(thermal_gap 0.5)
			(thermal_bridge_width 0.5)
			(island_removal_mode 0)
		)
		(polygon
			(pts
				(xy 191.799972 -79.799942) (xy 198.399908 -79.799942) (xy 198.399908 -173.800008) (xy 191.799972 -173.800008)
			)
		)
	)
	(zone
		(layer "F.Cu")
		(hatch none 0.5)
		(connect_pads
			(clearance 0)
		)
		(min_thickness 0.25)
		(keepout
			(tracks allowed)
			(vias allowed)
			(pads allowed)
			(copperpour allowed)
			(footprints not_allowed)
		)
		(placement
			(enabled no)
			(sheetname "")
		)
		(fill
			(thermal_gap 0.5)
			(thermal_bridge_width 0.5)
			(island_removal_mode 0)
		)
		(polygon
			(pts
				(arc
					(start 102.350062 -289.999928)
					(mid 107.100116 -285.249874)
					(end 111.849916 -289.999928)
				)
				(arc
					(start 111.849916 -289.999928)
					(mid 107.100116 -294.749728)
					(end 102.350062 -289.999928)
				)
			)
		)
	)
	(zone
		(net "12V_PRE_27")
		(layer "F.Cu")
		(hatch none 0.5)
		(connect_pads
			(clearance 0.5)
		)
		(min_thickness 0.25)
		(fill yes
			(thermal_gap 0.5)
			(thermal_bridge_width 0.5)
			(island_removal_mode 0)
		)
		(polygon
			(pts
				(xy 114.318796 -63.794894) (xy 114.191796 -63.921894) (xy 114.191796 -65.445894) (xy 115.588796 -66.842894)
				(xy 116.985796 -66.842894) (xy 121.938796 -71.795894) (xy 125.875796 -71.795894) (xy 126.002796 -71.668894)
				(xy 126.002796 -70.906894) (xy 125.875796 -70.779894) (xy 122.573796 -70.779894) (xy 115.588796 -63.794894)
			)
		)
	)
	(zone
		(layer "F.Cu")
		(hatch none 0.5)
		(connect_pads
			(clearance 0)
		)
		(min_thickness 0.25)
		(keepout
			(tracks allowed)
			(vias allowed)
			(pads allowed)
			(copperpour allowed)
			(footprints not_allowed)
		)
		(placement
			(enabled no)
			(sheetname "")
		)
		(fill
			(thermal_gap 0.5)
			(thermal_bridge_width 0.5)
			(island_removal_mode 0)
		)
		(polygon
			(pts
				(arc
					(start 410.85008 -164.200078)
					(mid 407.100024 -167.950134)
					(end 403.349968 -164.200078)
				)
				(arc
					(start 403.349968 -164.200078)
					(mid 407.100024 -160.450022)
					(end 410.85008 -164.200078)
				)
			)
		)
	)
	(zone
		(net "12V_PRE_2")
		(layer "F.Cu")
		(hatch none 0.5)
		(connect_pads
			(clearance 0.5)
		)
		(min_thickness 0.25)
		(fill yes
			(thermal_gap 0.5)
			(thermal_bridge_width 0.5)
			(island_removal_mode 0)
		)
		(polygon
			(pts
				(xy 82.768948 -293.794942) (xy 82.641948 -293.921942) (xy 82.641948 -295.445942) (xy 84.038948 -296.842942)
				(xy 85.435948 -296.842942) (xy 90.388948 -301.795942) (xy 94.325948 -301.795942) (xy 94.452948 -301.668942)
				(xy 94.452948 -300.906942) (xy 94.325948 -300.779942) (xy 91.023948 -300.779942) (xy 84.038948 -293.794942)
			)
		)
	)
	(zone
		(layer "F.Cu")
		(hatch none 0.5)
		(connect_pads
			(clearance 0)
		)
		(min_thickness 0.25)
		(keepout
			(tracks allowed)
			(vias allowed)
			(pads allowed)
			(copperpour allowed)
			(footprints allowed)
		)
		(placement
			(enabled no)
			(sheetname "")
		)
		(fill
			(thermal_gap 0.5)
			(thermal_bridge_width 0.5)
			(island_removal_mode 0)
		)
		(polygon
			(pts
				(xy 237.0074 -387.4008) (xy 237.0074 -386.1054) (xy 234.7214 -386.1054) (xy 234.7214 -387.4008)
			)
		)
	)
	(zone
		(layer "F.Cu")
		(hatch none 0.5)
		(connect_pads
			(clearance 0)
		)
		(min_thickness 0.25)
		(keepout
			(tracks allowed)
			(vias allowed)
			(pads allowed)
			(copperpour allowed)
			(footprints not_allowed)
		)
		(placement
			(enabled no)
			(sheetname "")
		)
		(fill
			(thermal_gap 0.5)
			(thermal_bridge_width 0.5)
			(island_removal_mode 0)
		)
		(polygon
			(pts
				(arc
					(start 375.150126 -28.079954)
					(mid 372.150132 -31.079948)
					(end 369.149884 -28.079954)
				)
				(arc
					(start 369.149884 -28.079954)
					(mid 372.150132 -25.079706)
					(end 375.150126 -28.079954)
				)
			)
		)
	)
	(zone
		(net "GND")
		(layer "F.Cu")
		(hatch none 0.5)
		(connect_pads
			(clearance 0.5)
		)
		(min_thickness 0.25)
		(fill yes
			(thermal_gap 0.5)
			(thermal_bridge_width 0.5)
			(island_removal_mode 0)
		)
		(polygon
			(pts
				(arc
					(start 140.550138 -89.426542)
					(mid 141.035852 -88.995498)
					(end 141.583664 -88.646762)
				)
				(xy 136.09574 -73.76414) (xy 134.366 -72.0344) (xy 133.602476 -72.0344)
				(arc
					(start 133.35254 -72.284336)
					(mid 131.886452 -73.87664)
					(end 129.81305 -74.497946)
				)
				(xy 129.81305 -75.66025) (xy 129.667508 -75.805792) (xy 129.667508 -78.777592)
				(arc
					(start 128.696974 -78.777592)
					(mid 128.735522 -80.626191)
					(end 127.956056 -82.302858)
				)
				(xy 127.956056 -84.891118) (xy 123.424442 -84.891118)
				(arc
					(start 131.839716 -90.663522)
					(mid 135.247176 -85.899557)
					(end 139.923266 -89.426542)
				)
			)
		)
	)
	(zone
		(net "GND")
		(layer "F.Cu")
		(hatch none 0.5)
		(connect_pads
			(clearance 0.5)
		)
		(min_thickness 0.25)
		(fill yes
			(thermal_gap 0.5)
			(thermal_bridge_width 0.5)
			(island_removal_mode 0)
		)
		(polygon
			(pts
				(xy 98.1202 -266.573508) (xy 98.1202 -269.671292) (xy 99.83216 -269.671292)
				(arc
					(start 99.83216 -271.169638)
					(mid 100.499219 -271.902683)
					(end 100.958396 -272.781014)
				)
				(arc
					(start 104.318562 -281.890216)
					(mid 106.224267 -281.471478)
					(end 108.175298 -281.494484)
				)
				(arc
					(start 108.175298 -281.494484)
					(mid 108.280088 -280.389183)
					(end 108.678218 -279.352756)
				)
				(xy 108.678218 -277.249128) (xy 108.297218 -277.249128)
				(arc
					(start 108.297218 -270.047466)
					(mid 103.145922 -271.460732)
					(end 100.989638 -266.573508)
				)
			)
		)
	)
	(zone
		(layer "F.Cu")
		(hatch none 0.5)
		(connect_pads
			(clearance 0)
		)
		(min_thickness 0.25)
		(keepout
			(tracks not_allowed)
			(vias allowed)
			(pads allowed)
			(copperpour not_allowed)
			(footprints allowed)
		)
		(placement
			(enabled no)
			(sheetname "")
		)
		(fill
			(thermal_gap 0.5)
			(thermal_bridge_width 0.5)
			(island_removal_mode 0)
		)
		(polygon
			(pts
				(arc
					(start 383.47015 -273.368516)
					(mid 383.08915 -272.987516)
					(end 382.70815 -273.368516)
				)
				(arc
					(start 382.70815 -274.511262)
					(mid 383.089023 -274.892516)
					(end 383.47015 -274.511516)
				)
				(xy 383.47015 -274.162266)
				(arc
					(start 383.230628 -274.162266)
					(mid 383.211271 -274.166099)
					(end 383.194814 -274.176998)
				)
				(arc
					(start 383.180082 -274.19173)
					(mid 383.169156 -274.208176)
					(end 383.16535 -274.227544)
				)
				(arc
					(start 383.16535 -274.255992)
					(mid 383.08915 -274.77816)
					(end 383.01295 -274.255992)
				)
				(xy 383.01295 -274.196048)
				(arc
					(start 383.015998 -274.193)
					(mid 383.028433 -274.149837)
					(end 383.050034 -274.11045)
				)
				(xy 383.050034 -274.106386) (xy 383.10947 -274.04695)
				(arc
					(start 383.113534 -274.04695)
					(mid 383.152912 -274.025328)
					(end 383.196084 -274.012914)
				)
				(xy 383.199132 -274.009866) (xy 383.47015 -274.009866) (xy 383.47015 -273.870166) (xy 383.194306 -273.870166)
				(arc
					(start 383.191258 -273.867118)
					(mid 383.148095 -273.854683)
					(end 383.108708 -273.833082)
				)
				(xy 383.104644 -273.833082) (xy 383.050034 -273.778472)
				(arc
					(start 383.050034 -273.774408)
					(mid 383.028412 -273.73503)
					(end 383.015998 -273.691858)
				)
				(xy 383.01295 -273.68881)
				(arc
					(start 383.01295 -273.62404)
					(mid 383.08915 -273.101872)
					(end 383.16535 -273.62404)
				)
				(arc
					(start 383.16535 -273.657314)
					(mid 383.169183 -273.676671)
					(end 383.180082 -273.693128)
				)
				(arc
					(start 383.189988 -273.703034)
					(mid 383.206434 -273.71396)
					(end 383.225802 -273.717766)
				)
				(xy 383.47015 -273.717766)
			)
		)
	)
	(zone
		(layer "F.Cu")
		(hatch none 0.5)
		(connect_pads
			(clearance 0)
		)
		(min_thickness 0.25)
		(keepout
			(tracks allowed)
			(vias allowed)
			(pads allowed)
			(copperpour allowed)
			(footprints allowed)
		)
		(placement
			(enabled no)
			(sheetname "")
		)
		(fill
			(thermal_gap 0.5)
			(thermal_bridge_width 0.5)
			(island_removal_mode 0)
		)
		(polygon
			(pts
				(xy 260.104382 -234.78109) (xy 260.104382 -231.27589) (xy 257.894582 -231.27589) (xy 257.894582 -234.78109)
			)
		)
	)
	(zone
		(net "P5V_A_3")
		(layer "F.Cu")
		(hatch none 0.5)
		(connect_pads
			(clearance 0.5)
		)
		(min_thickness 0.25)
		(fill yes
			(thermal_gap 0.5)
			(thermal_bridge_width 0.5)
			(island_removal_mode 0)
		)
		(polygon
			(pts
				(xy 462.254346 -280.332942) (xy 462.076546 -280.510742) (xy 462.076546 -285.3563) (xy 462.260188 -285.539942)
				(xy 464.754214 -285.539942) (xy 464.991958 -285.302198) (xy 464.991958 -280.53411) (xy 464.79079 -280.332942)
			)
		)
	)
	(zone
		(layer "F.Cu")
		(hatch none 0.5)
		(connect_pads
			(clearance 0)
		)
		(min_thickness 0.25)
		(keepout
			(tracks not_allowed)
			(vias allowed)
			(pads allowed)
			(copperpour not_allowed)
			(footprints allowed)
		)
		(placement
			(enabled no)
			(sheetname "")
		)
		(fill
			(thermal_gap 0.5)
			(thermal_bridge_width 0.5)
			(island_removal_mode 0)
		)
		(polygon
			(pts
				(arc
					(start 190.639954 -162.178746)
					(mid 190.259081 -161.797492)
					(end 189.877954 -162.178492)
				)
				(xy 189.877954 -162.527742)
				(arc
					(start 190.131954 -162.527742)
					(mid 190.167875 -162.512863)
					(end 190.182754 -162.476942)
				)
				(arc
					(start 190.182754 -162.434016)
					(mid 190.258954 -161.911848)
					(end 190.335154 -162.434016)
				)
				(xy 190.335154 -162.508438)
				(arc
					(start 190.332106 -162.511486)
					(mid 190.275575 -162.620563)
					(end 190.166498 -162.677094)
				)
				(xy 190.16345 -162.680142) (xy 189.877954 -162.680142) (xy 189.877954 -162.819842) (xy 190.16345 -162.819842)
				(arc
					(start 190.166498 -162.82289)
					(mid 190.275575 -162.879421)
					(end 190.332106 -162.988498)
				)
				(xy 190.335154 -162.991546)
				(arc
					(start 190.335154 -163.065968)
					(mid 190.258954 -163.588136)
					(end 190.182754 -163.065968)
				)
				(arc
					(start 190.182754 -163.023042)
					(mid 190.167875 -162.987121)
					(end 190.131954 -162.972242)
				)
				(xy 189.877954 -162.972242)
				(arc
					(start 189.877954 -163.321492)
					(mid 190.258954 -163.702492)
					(end 190.639954 -163.321492)
				)
			)
		)
	)
	(zone
		(net "GND")
		(layer "F.Cu")
		(hatch none 0.5)
		(connect_pads
			(clearance 0.5)
		)
		(min_thickness 0.25)
		(fill yes
			(thermal_gap 0.5)
			(thermal_bridge_width 0.5)
			(island_removal_mode 0)
		)
		(polygon
			(pts
				(xy 80.22717 -81.719928)
				(arc
					(start 72.198738 -69.356732)
					(mid 71.512701 -70.38664)
					(end 70.550024 -71.164196)
				)
				(arc
					(start 70.550024 -71.164196)
					(mid 68.871438 -72.572008)
					(end 66.7131 -72.947784)
				)
				(xy 66.7131 -75.66025) (xy 66.567558 -75.805792) (xy 66.567558 -78.777592)
				(arc
					(start 65.597024 -78.777592)
					(mid 65.635572 -80.626191)
					(end 64.856106 -82.302858)
				)
				(xy 64.856106 -84.699094) (xy 76.156312 -91.897962) (xy 76.156312 -89.426542)
				(arc
					(start 77.450188 -89.426542)
					(mid 78.796754 -88.497577)
					(end 80.399636 -88.170512)
				)
				(arc
					(start 81.400396 -88.170512)
					(mid 82.991346 -88.492567)
					(end 84.33181 -89.408)
				)
				(arc
					(start 86.049104 -89.408)
					(mid 86.749293 -87.759592)
					(end 87.711788 -86.249256)
				)
				(xy 86.371938 -85.955886)
			)
		)
	)
	(zone
		(net "P12V_HDD21")
		(layer "F.Cu")
		(hatch none 0.5)
		(connect_pads
			(clearance 0.5)
		)
		(min_thickness 0.25)
		(fill yes
			(thermal_gap 0.5)
			(thermal_bridge_width 0.5)
			(island_removal_mode 0)
		)
		(polygon
			(pts
				(xy 429.295052 -178.540918) (xy 429.041052 -178.794918) (xy 429.041052 -182.858918) (xy 428.582328 -183.317642)
				(xy 428.582328 -186.139836) (xy 427.748446 -186.973718) (xy 420.82847 -186.973718) (xy 420.659052 -187.143136)
				(xy 420.659052 -188.954918) (xy 420.913052 -189.208918) (xy 424.850052 -189.208918) (xy 425.358052 -188.700918)
				(xy 433.105052 -188.700918) (xy 433.994052 -187.811918) (xy 433.994052 -178.794918) (xy 433.740052 -178.540918)
			)
		)
		(polygon
			(pts
				(xy 425.002452 -188.091318) (xy 424.799252 -188.091318) (xy 424.799252 -188.294518) (xy 425.002452 -188.294518)
			)
		)
		(polygon
			(pts
				(xy 424.138852 -188.091318) (xy 423.935652 -188.091318) (xy 423.935652 -188.294518) (xy 424.138852 -188.294518)
			)
		)
	)
	(zone
		(net "12V_PRE_17")
		(layer "F.Cu")
		(hatch none 0.5)
		(connect_pads
			(clearance 0.5)
		)
		(min_thickness 0.25)
		(fill yes
			(thermal_gap 0.5)
			(thermal_bridge_width 0.5)
			(island_removal_mode 0)
		)
		(polygon
			(pts
				(xy 177.419 -178.794918) (xy 177.292 -178.921918) (xy 177.292 -180.445918) (xy 178.689 -181.842918)
				(xy 180.086 -181.842918) (xy 185.039 -186.795918) (xy 188.976 -186.795918) (xy 189.103 -186.668918)
				(xy 189.103 -185.906918) (xy 188.976 -185.779918) (xy 185.674 -185.779918) (xy 178.689 -178.794918)
			)
		)
	)
	(zone
		(net "GND")
		(layer "F.Cu")
		(hatch none 0.5)
		(connect_pads
			(clearance 0.5)
		)
		(min_thickness 0.25)
		(fill yes
			(thermal_gap 0.5)
			(thermal_bridge_width 0.5)
			(island_removal_mode 0)
		)
		(polygon
			(pts
				(xy 44.619164 -139.98575) (xy 44.336462 -140.268452) (xy 44.336462 -144.158462) (xy 44.6786 -144.5006)
				(xy 44.6786 -146.087084) (xy 44.96816 -146.376644) (xy 47.791878 -146.376644) (xy 47.9806 -146.187922)
				(xy 47.9806 -140.16355) (xy 47.8028 -139.98575)
			)
		)
	)
	(zone
		(net "GND")
		(layer "F.Cu")
		(hatch none 0.5)
		(connect_pads
			(clearance 0.5)
		)
		(min_thickness 0.25)
		(fill yes
			(thermal_gap 0.5)
			(thermal_bridge_width 0.5)
			(island_removal_mode 0)
		)
		(polygon
			(pts
				(arc
					(start 191.509142 -311.578244)
					(mid 191.901733 -310.203505)
					(end 191.797178 -308.77764)
				)
				(xy 192.767712 -308.77764) (xy 192.767712 -305.80584) (xy 192.913254 -305.660298)
				(arc
					(start 192.913254 -302.906176)
					(mid 193.387462 -302.919527)
					(end 193.860166 -302.879506)
				)
				(arc
					(start 193.860166 -303.141126)
					(mid 194.192718 -304.766937)
					(end 195.13677 -306.131722)
				)
				(arc
					(start 195.13677 -306.131722)
					(mid 195.133561 -306.225043)
					(end 195.132452 -306.318412)
				)
				(arc
					(start 195.132452 -307.385212)
					(mid 196.44186 -310.407109)
					(end 199.542146 -311.5183)
				)
				(xy 199.542146 -314.687966)
			)
		)
	)
	(zone
		(layer "F.Cu")
		(hatch none 0.5)
		(connect_pads
			(clearance 0)
		)
		(min_thickness 0.25)
		(keepout
			(tracks allowed)
			(vias allowed)
			(pads allowed)
			(copperpour allowed)
			(footprints allowed)
		)
		(placement
			(enabled no)
			(sheetname "")
		)
		(fill
			(thermal_gap 0.5)
			(thermal_bridge_width 0.5)
			(island_removal_mode 0)
		)
		(polygon
			(pts
				(xy 368.1984 -141.6304) (xy 368.1984 -137.414) (xy 365.633 -137.414) (xy 365.633 -141.6304)
			)
		)
	)
	(zone
		(layer "F.Cu")
		(hatch none 0.5)
		(connect_pads
			(clearance 0)
		)
		(min_thickness 0.25)
		(keepout
			(tracks not_allowed)
			(vias allowed)
			(pads allowed)
			(copperpour not_allowed)
			(footprints allowed)
		)
		(placement
			(enabled no)
			(sheetname "")
		)
		(fill
			(thermal_gap 0.5)
			(thermal_bridge_width 0.5)
			(island_removal_mode 0)
		)
		(polygon
			(pts
				(arc
					(start 32.889952 -277.17877)
					(mid 32.509079 -276.797516)
					(end 32.127952 -277.178516)
				)
				(xy 32.127952 -277.527766)
				(arc
					(start 32.381952 -277.527766)
					(mid 32.417873 -277.512887)
					(end 32.432752 -277.476966)
				)
				(arc
					(start 32.432752 -277.43404)
					(mid 32.508952 -276.911872)
					(end 32.585152 -277.43404)
				)
				(xy 32.585152 -277.508462)
				(arc
					(start 32.582104 -277.51151)
					(mid 32.525573 -277.620587)
					(end 32.416496 -277.677118)
				)
				(xy 32.413448 -277.680166) (xy 32.127952 -277.680166) (xy 32.127952 -277.819866) (xy 32.413448 -277.819866)
				(arc
					(start 32.416496 -277.822914)
					(mid 32.525573 -277.879445)
					(end 32.582104 -277.988522)
				)
				(xy 32.585152 -277.99157)
				(arc
					(start 32.585152 -278.065992)
					(mid 32.508952 -278.58816)
					(end 32.432752 -278.065992)
				)
				(arc
					(start 32.432752 -278.023066)
					(mid 32.417873 -277.987145)
					(end 32.381952 -277.972266)
				)
				(xy 32.127952 -277.972266)
				(arc
					(start 32.127952 -278.321516)
					(mid 32.508952 -278.702516)
					(end 32.889952 -278.321516)
				)
			)
		)
	)
	(zone
		(layer "F.Cu")
		(hatch none 0.5)
		(connect_pads
			(clearance 0)
		)
		(min_thickness 0.25)
		(keepout
			(tracks allowed)
			(vias allowed)
			(pads allowed)
			(copperpour allowed)
			(footprints not_allowed)
		)
		(placement
			(enabled no)
			(sheetname "")
		)
		(fill
			(thermal_gap 0.5)
			(thermal_bridge_width 0.5)
			(island_removal_mode 0)
		)
		(polygon
			(pts
				(xy 0 -9.99998) (xy 15.32509 -9.99998) (xy 15.32509 -20.200112) (xy 37.325046 -20.200112) (xy 37.325046 -9.99998)
				(xy 102.00005 -9.99998)
				(arc
					(start 102.00005 -13.999972)
					(mid 102.292943 -14.707077)
					(end 103.000048 -14.99997)
				)
				(arc
					(start 148.999956 -14.99997)
					(mid 149.707061 -14.707077)
					(end 149.999954 -13.999972)
				)
				(xy 149.999954 -9.99998) (xy 155.325064 -9.99998) (xy 155.325064 -20.200112) (xy 177.32502 -20.200112)
				(xy 177.32502 -9.99998) (xy 191.799972 -9.99998) (xy 191.799972 -53.799994) (xy 189.799976 -53.799994)
				(xy 189.799976 -79.799942) (xy 180.64988 -79.799942) (xy 180.64988 -65.79997) (xy 166.099998 -65.79997)
				(xy 166.099998 -75.79995) (xy 149.100032 -75.79995) (xy 149.100032 -65.79997) (xy 134.549896 -65.79997)
				(xy 134.549896 -75.79995) (xy 117.54993 -75.79995) (xy 117.54993 -65.79997) (xy 103.000048 -65.79997)
				(xy 103.000048 -75.79995) (xy 86.000082 -75.79995) (xy 86.000082 -65.79997) (xy 71.449946 -65.79997)
				(xy 71.449946 -75.79995) (xy 54.44998 -75.79995) (xy 54.44998 -65.79997) (xy 39.900098 -65.79997)
				(xy 39.900098 -75.79995) (xy 22.899878 -75.79995) (xy 22.899878 -65.79997) (xy 8.349996 -65.79997)
				(xy 8.349996 -75.79995) (xy 0 -75.79995)
			)
		)
	)
	(zone
		(layer "F.Cu")
		(hatch none 0.5)
		(connect_pads
			(clearance 0)
		)
		(min_thickness 0.25)
		(keepout
			(tracks allowed)
			(vias allowed)
			(pads allowed)
			(copperpour allowed)
			(footprints not_allowed)
		)
		(placement
			(enabled no)
			(sheetname "")
		)
		(fill
			(thermal_gap 0.5)
			(thermal_bridge_width 0.5)
			(island_removal_mode 0)
		)
		(polygon
			(pts
				(arc
					(start 39.250112 -269.999968)
					(mid 44.000166 -265.249914)
					(end 48.749966 -269.999968)
				)
				(arc
					(start 48.749966 -269.999968)
					(mid 44.000166 -274.749768)
					(end 39.250112 -269.999968)
				)
			)
		)
	)
	(zone
		(layer "F.Cu")
		(hatch none 0.5)
		(connect_pads
			(clearance 0)
		)
		(min_thickness 0.25)
		(keepout
			(tracks not_allowed)
			(vias allowed)
			(pads allowed)
			(copperpour not_allowed)
			(footprints allowed)
		)
		(placement
			(enabled no)
			(sheetname "")
		)
		(fill
			(thermal_gap 0.5)
			(thermal_bridge_width 0.5)
			(island_removal_mode 0)
		)
		(polygon
			(pts
				(arc
					(start 485.000046 -120.499886)
					(mid 481.24999 -124.249942)
					(end 477.499934 -120.499886)
				)
				(arc
					(start 477.499934 -120.499886)
					(mid 481.24999 -116.74983)
					(end 485.000046 -120.499886)
				)
			)
		)
	)
	(zone
		(net "P5V_HDD1")
		(layer "F.Cu")
		(hatch none 0.5)
		(connect_pads
			(clearance 0.5)
		)
		(min_thickness 0.25)
		(fill yes
			(thermal_gap 0.5)
			(thermal_bridge_width 0.5)
			(island_removal_mode 0)
		)
		(polygon
			(pts
				(xy 51.218846 -286.682942) (xy 50.964846 -286.936942) (xy 50.964846 -289.222942) (xy 51.218846 -289.476942)
				(xy 51.218846 -291.508942) (xy 51.980846 -292.270942) (xy 51.980846 -293.032942) (xy 52.361846 -293.413942)
				(xy 52.742846 -293.413942) (xy 55.917846 -296.588942) (xy 62.775846 -296.588942) (xy 62.902846 -296.461942)
				(xy 62.902846 -294.683942) (xy 62.775846 -294.556942) (xy 57.695846 -294.556942) (xy 55.790846 -292.651942)
				(xy 54.901846 -292.651942) (xy 54.012846 -291.762942) (xy 54.012846 -289.222942) (xy 54.647846 -288.587942)
				(xy 54.647846 -286.936942) (xy 54.393846 -286.682942)
			)
		)
		(polygon
			(pts
				(xy 53.225446 -293.109142) (xy 53.022246 -293.109142) (xy 53.022246 -293.312342) (xy 53.225446 -293.312342)
			)
		)
		(polygon
			(pts
				(xy 53.225446 -292.245542) (xy 53.022246 -292.245542) (xy 53.022246 -292.448742) (xy 53.225446 -292.448742)
			)
		)
		(polygon
			(pts
				(xy 52.361846 -292.245542) (xy 52.158646 -292.245542) (xy 52.158646 -292.448742) (xy 52.361846 -292.448742)
			)
		)
	)
	(zone
		(net "5V_PRE_6")
		(layer "F.Cu")
		(hatch none 0.5)
		(connect_pads
			(clearance 0.5)
		)
		(min_thickness 0.25)
		(fill yes
			(thermal_gap 0.5)
			(thermal_bridge_width 0.5)
			(island_removal_mode 0)
		)
		(polygon
			(pts
				(xy 329.438 -289.984942) (xy 329.184 -290.238942) (xy 329.184 -292.778942) (xy 328.803 -293.159942)
				(xy 326.263 -293.159942) (xy 326.009 -293.413942) (xy 326.009 -293.794942) (xy 326.263 -294.048942)
				(xy 329.565 -294.048942) (xy 330.835 -292.778942) (xy 330.835 -290.238942) (xy 330.581 -289.984942)
			)
		)
	)
	(zone
		(layer "F.Cu")
		(hatch none 0.5)
		(connect_pads
			(clearance 0)
		)
		(min_thickness 0.25)
		(keepout
			(tracks allowed)
			(vias allowed)
			(pads allowed)
			(copperpour allowed)
			(footprints allowed)
		)
		(placement
			(enabled no)
			(sheetname "")
		)
		(fill
			(thermal_gap 0.5)
			(thermal_bridge_width 0.5)
			(island_removal_mode 0)
		)
		(polygon
			(pts
				(xy 265.8364 -218.7321) (xy 265.8364 -220.7895) (xy 263.8552 -220.7895) (xy 263.8552 -218.7321)
			)
		)
	)
	(zone
		(layer "F.Cu")
		(hatch none 0.5)
		(connect_pads
			(clearance 0)
		)
		(min_thickness 0.25)
		(keepout
			(tracks allowed)
			(vias allowed)
			(pads allowed)
			(copperpour allowed)
			(footprints allowed)
		)
		(placement
			(enabled no)
			(sheetname "")
		)
		(fill
			(thermal_gap 0.5)
			(thermal_bridge_width 0.5)
			(island_removal_mode 0)
		)
		(polygon
			(pts
				(xy 301.879 -67.809872) (xy 301.879 -65.78854) (xy 299.590968 -65.78854) (xy 299.590968 -67.809872)
			)
		)
	)
	(zone
		(layer "F.Cu")
		(hatch none 0.5)
		(connect_pads
			(clearance 0)
		)
		(min_thickness 0.25)
		(keepout
			(tracks not_allowed)
			(vias allowed)
			(pads allowed)
			(copperpour not_allowed)
			(footprints allowed)
		)
		(placement
			(enabled no)
			(sheetname "")
		)
		(fill
			(thermal_gap 0.5)
			(thermal_bridge_width 0.5)
			(island_removal_mode 0)
		)
		(polygon
			(pts
				(arc
					(start 320.41084 -273.36877)
					(mid 319.989327 -272.946876)
					(end 319.56756 -273.368516)
				)
				(arc
					(start 319.56756 -274.511516)
					(mid 319.9892 -274.933156)
					(end 320.41084 -274.511516)
				)
				(xy 320.41084 -274.162266)
				(arc
					(start 320.133472 -274.162266)
					(mid 320.114115 -274.166099)
					(end 320.097658 -274.176998)
				)
				(arc
					(start 320.080132 -274.194524)
					(mid 320.069206 -274.21097)
					(end 320.0654 -274.230338)
				)
				(arc
					(start 320.0654 -274.255992)
					(mid 319.9892 -274.77816)
					(end 319.913 -274.255992)
				)
				(xy 319.913 -274.198842)
				(arc
					(start 319.916048 -274.195794)
					(mid 319.928483 -274.152631)
					(end 319.950084 -274.113244)
				)
				(xy 319.950084 -274.10918) (xy 320.012314 -274.04695)
				(arc
					(start 320.016378 -274.04695)
					(mid 320.055756 -274.025328)
					(end 320.098928 -274.012914)
				)
				(xy 320.101976 -274.009866) (xy 320.41084 -274.009866) (xy 320.41084 -273.870166) (xy 320.101722 -273.870166)
				(arc
					(start 320.098674 -273.867118)
					(mid 320.055511 -273.854683)
					(end 320.016124 -273.833082)
				)
				(xy 320.01206 -273.833082) (xy 319.950084 -273.771106)
				(arc
					(start 319.950084 -273.767042)
					(mid 319.928462 -273.727664)
					(end 319.916048 -273.684492)
				)
				(xy 319.913 -273.681444)
				(arc
					(start 319.913 -273.62404)
					(mid 319.9892 -273.101872)
					(end 320.0654 -273.62404)
				)
				(arc
					(start 320.0654 -273.649948)
					(mid 320.069233 -273.669305)
					(end 320.080132 -273.685762)
				)
				(arc
					(start 320.097404 -273.703034)
					(mid 320.11385 -273.71396)
					(end 320.133218 -273.717766)
				)
				(xy 320.41084 -273.717766)
			)
		)
	)
	(zone
		(layer "F.Cu")
		(hatch none 0.5)
		(connect_pads
			(clearance 0)
		)
		(min_thickness 0.25)
		(keepout
			(tracks allowed)
			(vias allowed)
			(pads allowed)
			(copperpour allowed)
			(footprints not_allowed)
		)
		(placement
			(enabled no)
			(sheetname "")
		)
		(fill
			(thermal_gap 0.5)
			(thermal_bridge_width 0.5)
			(island_removal_mode 0)
		)
		(polygon
			(pts
				(arc
					(start 233.59999 -143.500094)
					(mid 229.849934 -147.25015)
					(end 226.099878 -143.500094)
				)
				(arc
					(start 226.099878 -143.500094)
					(mid 229.849934 -139.750038)
					(end 233.59999 -143.500094)
				)
			)
		)
	)
	(zone
		(layer "F.Cu")
		(hatch none 0.5)
		(connect_pads
			(clearance 0)
		)
		(min_thickness 0.25)
		(keepout
			(tracks allowed)
			(vias allowed)
			(pads allowed)
			(copperpour allowed)
			(footprints not_allowed)
		)
		(placement
			(enabled no)
			(sheetname "")
		)
		(fill
			(thermal_gap 0.5)
			(thermal_bridge_width 0.5)
			(island_removal_mode 0)
		)
		(polygon
			(pts
				(xy 209.099912 -303.600104) (xy 209.099912 -312.999882) (xy 201.399902 -312.999882) (xy 201.399902 -303.600104)
			)
		)
	)
	(zone
		(layer "F.Cu")
		(hatch none 0.5)
		(connect_pads
			(clearance 0)
		)
		(min_thickness 0.25)
		(keepout
			(tracks allowed)
			(vias allowed)
			(pads allowed)
			(copperpour allowed)
			(footprints allowed)
		)
		(placement
			(enabled no)
			(sheetname "")
		)
		(fill
			(thermal_gap 0.5)
			(thermal_bridge_width 0.5)
			(island_removal_mode 0)
		)
		(polygon
			(pts
				(xy 243.1034 -257.4036) (xy 243.1034 -259.9436) (xy 243.089684 -259.9436) (xy 243.089684 -260.339078)
				(xy 242.935506 -260.493256) (xy 240.225326 -260.493256) (xy 239.936528 -260.493256) (xy 238.889286 -259.446014)
				(xy 238.889286 -256.851404) (xy 239.056164 -256.684526) (xy 239.159034 -256.581656) (xy 239.159034 -256.036064)
				(xy 239.92332 -255.271778) (xy 240.48847 -255.271778) (xy 240.681002 -255.46431) (xy 240.681002 -255.715008)
				(xy 240.430558 -255.965452) (xy 240.237772 -255.965452) (xy 240.019586 -256.183638) (xy 240.019586 -256.639568)
				(xy 240.064544 -256.684526) (xy 240.520728 -256.684526) (xy 240.669064 -256.832862) (xy 240.669064 -256.890266)
				(xy 242.967256 -256.890266) (xy 243.1034 -257.02641)
			)
		)
	)
	(zone
		(layer "F.Cu")
		(hatch none 0.5)
		(connect_pads
			(clearance 0)
		)
		(min_thickness 0.25)
		(keepout
			(tracks allowed)
			(vias allowed)
			(pads allowed)
			(copperpour allowed)
			(footprints not_allowed)
		)
		(placement
			(enabled no)
			(sheetname "")
		)
		(fill
			(thermal_gap 0.5)
			(thermal_bridge_width 0.5)
			(island_removal_mode 0)
		)
		(polygon
			(pts
				(arc
					(start 244.100096 6.500114)
					(mid 247.850152 10.25017)
					(end 251.599954 6.500114)
				)
				(arc
					(start 251.599954 6.500114)
					(mid 247.850152 2.750312)
					(end 244.100096 6.500114)
				)
			)
		)
	)
	(zone
		(layer "F.Cu")
		(hatch none 0.5)
		(connect_pads
			(clearance 0)
		)
		(min_thickness 0.25)
		(keepout
			(tracks allowed)
			(vias allowed)
			(pads allowed)
			(copperpour allowed)
			(footprints not_allowed)
		)
		(placement
			(enabled no)
			(sheetname "")
		)
		(fill
			(thermal_gap 0.5)
			(thermal_bridge_width 0.5)
			(island_removal_mode 0)
		)
		(polygon
			(pts
				(xy 86.000082 -295.800018) (xy 71.449946 -295.800018) (xy 71.449946 -305.799998) (xy 54.44998 -305.799998)
				(xy 54.44998 -295.800018) (xy 39.900098 -295.800018) (xy 39.900098 -305.799998) (xy 22.899878 -305.799998)
				(xy 22.899878 -295.800018) (xy 8.349996 -295.800018) (xy 8.349996 -305.799998) (xy 0 -305.799998)
				(arc
					(start 0 -348.199964)
					(mid 0.292893 -348.907069)
					(end 0.999998 -349.199962)
				)
				(arc
					(start 189.6999 -349.199962)
					(mid 190.407005 -349.492855)
					(end 190.699898 -350.19996)
				)
				(arc
					(start 190.699898 -372.000018)
					(mid 190.992791 -372.707123)
					(end 191.699896 -373.000016)
				)
				(xy 191.799972 -373.000016) (xy 191.799972 -305.799998) (xy 180.64988 -305.799998) (xy 180.64988 -295.800018)
				(xy 166.099998 -295.800018) (xy 166.099998 -305.799998) (xy 149.100032 -305.799998) (xy 149.100032 -295.800018)
				(xy 134.549896 -295.800018) (xy 134.549896 -305.799998) (xy 117.54993 -305.799998) (xy 117.54993 -295.800018)
				(xy 103.000048 -295.800018) (xy 103.000048 -305.799998) (xy 86.000082 -305.799998)
			)
		)
	)
	(zone
		(layer "F.Cu")
		(hatch none 0.5)
		(connect_pads
			(clearance 0)
		)
		(min_thickness 0.25)
		(keepout
			(tracks allowed)
			(vias allowed)
			(pads allowed)
			(copperpour allowed)
			(footprints allowed)
		)
		(placement
			(enabled no)
			(sheetname "")
		)
		(fill
			(thermal_gap 0.5)
			(thermal_bridge_width 0.5)
			(island_removal_mode 0)
		)
		(polygon
			(pts
				(xy 143.027654 -136.903968) (xy 143.027654 -135.989568) (xy 141.198854 -135.989568) (xy 141.198854 -136.903968)
			)
		)
	)
	(zone
		(layer "F.Cu")
		(hatch none 0.5)
		(connect_pads
			(clearance 0)
		)
		(min_thickness 0.25)
		(keepout
			(tracks allowed)
			(vias allowed)
			(pads allowed)
			(copperpour allowed)
			(footprints not_allowed)
		)
		(placement
			(enabled no)
			(sheetname "")
		)
		(fill
			(thermal_gap 0.5)
			(thermal_bridge_width 0.5)
			(island_removal_mode 0)
		)
		(polygon
			(pts
				(arc
					(start 477.499934 -120.499886)
					(mid 481.24999 -116.74983)
					(end 485.000046 -120.499886)
				)
				(arc
					(start 485.000046 -120.499886)
					(mid 481.24999 -124.249942)
					(end 477.499934 -120.499886)
				)
			)
		)
	)
	(zone
		(net "P5V_A_2")
		(layer "F.Cu")
		(hatch none 0.5)
		(connect_pads
			(clearance 0.5)
		)
		(min_thickness 0.25)
		(fill yes
			(thermal_gap 0.5)
			(thermal_bridge_width 0.5)
			(island_removal_mode 0)
		)
		(polygon
			(pts
				(xy 18.398998 -50.840894) (xy 18.144998 -51.094894) (xy 18.144998 -53.380894) (xy 18.398998 -53.634894)
				(xy 23.097998 -53.634894) (xy 23.351998 -53.380894) (xy 23.351998 -51.094894) (xy 23.097998 -50.840894)
			)
		)
	)
	(zone
		(layer "F.Cu")
		(hatch none 0.5)
		(connect_pads
			(clearance 0)
		)
		(min_thickness 0.25)
		(keepout
			(tracks not_allowed)
			(vias allowed)
			(pads allowed)
			(copperpour not_allowed)
			(footprints allowed)
		)
		(placement
			(enabled no)
			(sheetname "")
		)
		(fill
			(thermal_gap 0.5)
			(thermal_bridge_width 0.5)
			(island_removal_mode 0)
		)
		(polygon
			(pts
				(arc
					(start 113.82502 -210.799934)
					(mid 127.824992 -196.799962)
					(end 141.824964 -210.799934)
				)
				(arc
					(start 141.824964 -210.799934)
					(mid 127.824992 -224.799906)
					(end 113.82502 -210.799934)
				)
			)
		)
	)
	(zone
		(layer "F.Cu")
		(hatch none 0.5)
		(connect_pads
			(clearance 0)
		)
		(min_thickness 0.25)
		(keepout
			(tracks allowed)
			(vias allowed)
			(pads allowed)
			(copperpour allowed)
			(footprints not_allowed)
		)
		(placement
			(enabled no)
			(sheetname "")
		)
		(fill
			(thermal_gap 0.5)
			(thermal_bridge_width 0.5)
			(island_removal_mode 0)
		)
		(polygon
			(pts
				(arc
					(start 163.949888 -164.200078)
					(mid 167.699944 -160.450022)
					(end 171.45 -164.200078)
				)
				(arc
					(start 171.45 -164.200078)
					(mid 167.699944 -167.950134)
					(end 163.949888 -164.200078)
				)
			)
		)
	)
	(zone
		(layer "F.Cu")
		(hatch none 0.5)
		(connect_pads
			(clearance 0)
		)
		(min_thickness 0.25)
		(keepout
			(tracks allowed)
			(vias allowed)
			(pads allowed)
			(copperpour allowed)
			(footprints not_allowed)
		)
		(placement
			(enabled no)
			(sheetname "")
		)
		(fill
			(thermal_gap 0.5)
			(thermal_bridge_width 0.5)
			(island_removal_mode 0)
		)
		(polygon
			(pts
				(xy 225.03003 -21.299932) (xy 215.629998 -21.299932) (xy 215.629998 -13.599922) (xy 225.03003 -13.599922)
			)
		)
	)
	(zone
		(net "P5V_HDD4")
		(layer "F.Cu")
		(hatch none 0.5)
		(connect_pads
			(clearance 0.5)
		)
		(min_thickness 0.25)
		(fill yes
			(thermal_gap 0.5)
			(thermal_bridge_width 0.5)
			(island_removal_mode 0)
		)
		(polygon
			(pts
				(xy 145.868898 -286.682942) (xy 145.614898 -286.936942) (xy 145.614898 -289.222942) (xy 145.868898 -289.476942)
				(xy 145.868898 -291.508942) (xy 146.630898 -292.270942) (xy 146.630898 -293.032942) (xy 147.011898 -293.413942)
				(xy 147.392898 -293.413942) (xy 150.567898 -296.588942) (xy 157.425898 -296.588942) (xy 157.552898 -296.461942)
				(xy 157.552898 -294.683942) (xy 157.425898 -294.556942) (xy 152.345898 -294.556942) (xy 150.440898 -292.651942)
				(xy 149.551898 -292.651942) (xy 148.662898 -291.762942) (xy 148.662898 -289.222942) (xy 149.297898 -288.587942)
				(xy 149.297898 -286.936942) (xy 149.043898 -286.682942)
			)
		)
		(polygon
			(pts
				(xy 147.875498 -293.109142) (xy 147.672298 -293.109142) (xy 147.672298 -293.312342) (xy 147.875498 -293.312342)
			)
		)
		(polygon
			(pts
				(xy 147.875498 -292.245542) (xy 147.672298 -292.245542) (xy 147.672298 -292.448742) (xy 147.875498 -292.448742)
			)
		)
		(polygon
			(pts
				(xy 147.011898 -292.245542) (xy 146.808698 -292.245542) (xy 146.808698 -292.448742) (xy 147.011898 -292.448742)
			)
		)
	)
	(zone
		(layer "F.Cu")
		(hatch none 0.5)
		(connect_pads
			(clearance 0)
		)
		(min_thickness 0.25)
		(keepout
			(tracks allowed)
			(vias allowed)
			(pads allowed)
			(copperpour allowed)
			(footprints not_allowed)
		)
		(placement
			(enabled no)
			(sheetname "")
		)
		(fill
			(thermal_gap 0.5)
			(thermal_bridge_width 0.5)
			(island_removal_mode 0)
		)
		(polygon
			(pts
				(arc
					(start 26.325068 -322.799964)
					(mid 33.325054 -315.799978)
					(end 40.32504 -322.799964)
				)
				(arc
					(start 40.32504 -328.799952)
					(mid 33.325054 -335.799938)
					(end 26.325068 -328.799952)
				)
			)
		)
	)
	(zone
		(net "P5V_A_4")
		(layer "F.Cu")
		(hatch none 0.5)
		(connect_pads
			(clearance 0.5)
		)
		(min_thickness 0.25)
		(fill yes
			(thermal_gap 0.5)
			(thermal_bridge_width 0.5)
			(island_removal_mode 0)
		)
		(polygon
			(pts
				(xy 368.354102 -50.332894) (xy 368.100102 -50.586894) (xy 368.100102 -55.285894) (xy 368.354102 -55.539894)
				(xy 370.640102 -55.539894) (xy 370.894102 -55.285894) (xy 370.894102 -50.586894) (xy 370.640102 -50.332894)
			)
		)
	)
	(zone
		(layer "F.Cu")
		(hatch none 0.5)
		(connect_pads
			(clearance 0)
		)
		(min_thickness 0.25)
		(keepout
			(tracks not_allowed)
			(vias allowed)
			(pads allowed)
			(copperpour not_allowed)
			(footprints allowed)
		)
		(placement
			(enabled no)
			(sheetname "")
		)
		(fill
			(thermal_gap 0.5)
			(thermal_bridge_width 0.5)
			(island_removal_mode 0)
		)
		(polygon
			(pts
				(arc
					(start 271.970754 -359.123996)
					(mid 271.5895 -359.504869)
					(end 271.9705 -359.885996)
				)
				(arc
					(start 273.1135 -359.885996)
					(mid 273.4945 -359.504996)
					(end 273.1135 -359.123996)
				)
				(xy 272.76425 -359.123996)
				(arc
					(start 272.76425 -359.377996)
					(mid 272.779129 -359.413917)
					(end 272.81505 -359.428796)
				)
				(arc
					(start 272.857976 -359.428796)
					(mid 273.380144 -359.504996)
					(end 272.857976 -359.581196)
				)
				(xy 272.783554 -359.581196)
				(arc
					(start 272.780506 -359.578148)
					(mid 272.671429 -359.521617)
					(end 272.614898 -359.41254)
				)
				(xy 272.61185 -359.409492) (xy 272.61185 -359.123996) (xy 272.47215 -359.123996) (xy 272.47215 -359.409492)
				(arc
					(start 272.469102 -359.41254)
					(mid 272.412571 -359.521617)
					(end 272.303494 -359.578148)
				)
				(xy 272.300446 -359.581196)
				(arc
					(start 272.226024 -359.581196)
					(mid 271.703856 -359.504996)
					(end 272.226024 -359.428796)
				)
				(arc
					(start 272.26895 -359.428796)
					(mid 272.304871 -359.413917)
					(end 272.31975 -359.377996)
				)
				(xy 272.31975 -359.123996)
			)
		)
	)
	(zone
		(layer "F.Cu")
		(hatch none 0.5)
		(connect_pads
			(clearance 0)
		)
		(min_thickness 0.25)
		(keepout
			(tracks allowed)
			(vias allowed)
			(pads allowed)
			(copperpour allowed)
			(footprints allowed)
		)
		(placement
			(enabled no)
			(sheetname "")
		)
		(fill
			(thermal_gap 0.5)
			(thermal_bridge_width 0.5)
			(island_removal_mode 0)
		)
		(polygon
			(pts
				(xy 302.1076 -70.739) (xy 302.1076 -68.62318) (xy 299.49394 -68.62318) (xy 299.49394 -70.739)
			)
		)
	)
	(zone
		(layer "F.Cu")
		(hatch none 0.5)
		(connect_pads
			(clearance 0)
		)
		(min_thickness 0.25)
		(keepout
			(tracks allowed)
			(vias allowed)
			(pads allowed)
			(copperpour allowed)
			(footprints allowed)
		)
		(placement
			(enabled no)
			(sheetname "")
		)
		(fill
			(thermal_gap 0.5)
			(thermal_bridge_width 0.5)
			(island_removal_mode 0)
		)
		(polygon
			(pts
				(xy 253.5428 -260.9342) (xy 253.5428 -257.556) (xy 256.4892 -257.556) (xy 256.4892 -260.9342)
			)
		)
	)
	(zone
		(layer "F.Cu")
		(hatch none 0.5)
		(connect_pads
			(clearance 0)
		)
		(min_thickness 0.25)
		(keepout
			(tracks allowed)
			(vias allowed)
			(pads allowed)
			(copperpour allowed)
			(footprints allowed)
		)
		(placement
			(enabled no)
			(sheetname "")
		)
		(fill
			(thermal_gap 0.5)
			(thermal_bridge_width 0.5)
			(island_removal_mode 0)
		)
		(polygon
			(pts
				(xy 26.665174 -248.726706) (xy 26.665174 -244.628416) (xy 27.916124 -244.628416) (xy 27.916124 -248.726706)
			)
		)
	)
	(zone
		(net "5V_PRE_8")
		(layer "F.Cu")
		(hatch none 0.5)
		(connect_pads
			(clearance 0.5)
		)
		(min_thickness 0.25)
		(fill yes
			(thermal_gap 0.5)
			(thermal_bridge_width 0.5)
			(island_removal_mode 0)
		)
		(polygon
			(pts
				(xy 392.53795 -289.984942) (xy 392.28395 -290.238942) (xy 392.28395 -292.778942) (xy 391.90295 -293.159942)
				(xy 389.36295 -293.159942) (xy 389.10895 -293.413942) (xy 389.10895 -293.794942) (xy 389.36295 -294.048942)
				(xy 392.66495 -294.048942) (xy 393.93495 -292.778942) (xy 393.93495 -290.238942) (xy 393.68095 -289.984942)
			)
		)
	)
	(zone
		(net "12V_PRE_25")
		(layer "F.Cu")
		(hatch none 0.5)
		(connect_pads
			(clearance 0.5)
		)
		(min_thickness 0.25)
		(fill yes
			(thermal_gap 0.5)
			(thermal_bridge_width 0.5)
			(island_removal_mode 0)
		)
		(polygon
			(pts
				(xy 51.218846 -63.794894) (xy 51.091846 -63.921894) (xy 51.091846 -65.445894) (xy 52.488846 -66.842894)
				(xy 53.885846 -66.842894) (xy 58.838846 -71.795894) (xy 62.775846 -71.795894) (xy 62.902846 -71.668894)
				(xy 62.902846 -70.906894) (xy 62.775846 -70.779894) (xy 59.473846 -70.779894) (xy 52.488846 -63.794894)
			)
		)
	)
	(zone
		(net "5V_PRE_18")
		(layer "F.Cu")
		(hatch none 0.5)
		(connect_pads
			(clearance 0.5)
		)
		(min_thickness 0.25)
		(fill yes
			(thermal_gap 0.5)
			(thermal_bridge_width 0.5)
			(island_removal_mode 0)
		)
		(polygon
			(pts
				(xy 329.438 -174.984918) (xy 329.184 -175.238918) (xy 329.184 -177.778918) (xy 328.803 -178.159918)
				(xy 326.263 -178.159918) (xy 326.009 -178.413918) (xy 326.009 -178.794918) (xy 326.263 -179.048918)
				(xy 329.565 -179.048918) (xy 330.835 -177.778918) (xy 330.835 -175.238918) (xy 330.581 -174.984918)
			)
		)
	)
	(zone
		(layer "F.Cu")
		(hatch none 0.5)
		(connect_pads
			(clearance 0)
		)
		(min_thickness 0.25)
		(keepout
			(tracks allowed)
			(vias allowed)
			(pads allowed)
			(copperpour allowed)
			(footprints not_allowed)
		)
		(placement
			(enabled no)
			(sheetname "")
		)
		(fill
			(thermal_gap 0.5)
			(thermal_bridge_width 0.5)
			(island_removal_mode 0)
		)
		(polygon
			(pts
				(xy 312.675016 0) (xy 312.675016 -9.99998) (xy 298.200064 -9.99998) (xy 298.200064 38.800024)
				(arc
					(start 298.99991 38.800024)
					(mid 299.707015 38.507131)
					(end 299.999908 37.800026)
				)
				(arc
					(start 299.999908 0.999998)
					(mid 300.292801 0.292893)
					(end 300.999906 0)
				)
			)
		)
	)
	(zone
		(layer "F.Cu")
		(hatch none 0.5)
		(connect_pads
			(clearance 0)
		)
		(min_thickness 0.25)
		(keepout
			(tracks allowed)
			(vias allowed)
			(pads allowed)
			(copperpour allowed)
			(footprints not_allowed)
		)
		(placement
			(enabled no)
			(sheetname "")
		)
		(fill
			(thermal_gap 0.5)
			(thermal_bridge_width 0.5)
			(island_removal_mode 0)
		)
		(polygon
			(pts
				(arc
					(start 251.599954 -143.500094)
					(mid 247.850152 -147.249896)
					(end 244.100096 -143.500094)
				)
				(arc
					(start 244.100096 -143.500094)
					(mid 247.850152 -139.750038)
					(end 251.599954 -143.500094)
				)
			)
		)
	)
	(zone
		(net "12V_PRE_29")
		(layer "F.Cu")
		(hatch none 0.5)
		(connect_pads
			(clearance 0.5)
		)
		(min_thickness 0.25)
		(fill yes
			(thermal_gap 0.5)
			(thermal_bridge_width 0.5)
			(island_removal_mode 0)
		)
		(polygon
			(pts
				(xy 177.419 -63.794894) (xy 177.292 -63.921894) (xy 177.292 -65.445894) (xy 178.689 -66.842894)
				(xy 180.086 -66.842894) (xy 185.039 -71.795894) (xy 188.976 -71.795894) (xy 189.103 -71.668894)
				(xy 189.103 -70.906894) (xy 188.976 -70.779894) (xy 185.674 -70.779894) (xy 178.689 -63.794894)
			)
		)
	)
	(zone
		(layer "F.Cu")
		(hatch none 0.5)
		(connect_pads
			(clearance 0)
		)
		(min_thickness 0.25)
		(keepout
			(tracks allowed)
			(vias allowed)
			(pads allowed)
			(copperpour allowed)
			(footprints not_allowed)
		)
		(placement
			(enabled no)
			(sheetname "")
		)
		(fill
			(thermal_gap 0.5)
			(thermal_bridge_width 0.5)
			(island_removal_mode 0)
		)
		(polygon
			(pts
				(xy 0 -125.800104) (xy 191.799972 -125.800104) (xy 191.799972 -173.800008) (xy 189.799976 -173.800008)
				(xy 189.799976 -190.799974) (xy 180.64988 -190.799974) (xy 180.64988 -180.799994) (xy 166.099998 -180.799994)
				(xy 166.099998 -190.799974) (xy 149.100032 -190.799974) (xy 149.100032 -180.799994) (xy 134.549896 -180.799994)
				(xy 134.549896 -190.799974) (xy 117.54993 -190.799974) (xy 117.54993 -180.799994) (xy 103.000048 -180.799994)
				(xy 103.000048 -190.799974) (xy 86.000082 -190.799974) (xy 86.000082 -180.799994) (xy 71.449946 -180.799994)
				(xy 71.449946 -190.799974) (xy 54.44998 -190.799974) (xy 54.44998 -180.799994) (xy 39.900098 -180.799994)
				(xy 39.900098 -190.799974) (xy 22.899878 -190.799974) (xy 22.899878 -180.799994) (xy 8.349996 -180.799994)
				(xy 8.349996 -190.799974) (xy 0 -190.799974)
			)
		)
	)
	(zone
		(layer "F.Cu")
		(hatch none 0.5)
		(connect_pads
			(clearance 0)
		)
		(min_thickness 0.25)
		(keepout
			(tracks allowed)
			(vias allowed)
			(pads allowed)
			(copperpour allowed)
			(footprints allowed)
		)
		(placement
			(enabled no)
			(sheetname "")
		)
		(fill
			(thermal_gap 0.5)
			(thermal_bridge_width 0.5)
			(island_removal_mode 0)
		)
		(polygon
			(pts
				(xy 237.0328 -386.588) (xy 237.0328 -384.1242) (xy 240.912142 -384.1242) (xy 242.12169 -382.914652)
				(xy 243.59235 -382.914652) (xy 243.746274 -383.068576) (xy 243.746274 -385.366768) (xy 242.840764 -386.272278)
				(xy 241.2238 -386.272278) (xy 241.2238 -386.588)
			)
		)
	)
	(zone
		(net "MB0_CM_GATE")
		(layer "F.Cu")
		(hatch none 0.5)
		(connect_pads
			(clearance 0.5)
		)
		(min_thickness 0.25)
		(fill yes
			(thermal_gap 0.5)
			(thermal_bridge_width 0.5)
			(island_removal_mode 0)
		)
		(polygon
			(pts
				(xy 148.69287 -131.77647) (xy 146.591274 -133.878066) (xy 146.591274 -134.772908) (xy 146.566636 -134.797546)
				(xy 146.566636 -135.830056) (xy 146.591274 -135.854694) (xy 147.840446 -135.854694) (xy 148.991066 -134.704074)
				(xy 148.991066 -134.701026) (xy 150.104856 -133.587236) (xy 150.104856 -131.910074) (xy 149.971252 -131.77647)
			)
		)
	)
	(zone
		(net "MB1_CM_GATE_C")
		(layer "F.Cu")
		(hatch none 0.5)
		(connect_pads
			(clearance 0.5)
		)
		(min_thickness 0.25)
		(fill yes
			(thermal_gap 0.5)
			(thermal_bridge_width 0.5)
			(island_removal_mode 0)
		)
		(polygon
			(pts
				(xy 367.289588 -148.671788) (xy 367.231168 -148.730208) (xy 367.231168 -151.13635) (xy 367.47704 -151.382222)
				(xy 369.829588 -151.382222) (xy 370.016786 -151.195024) (xy 370.016786 -148.826728) (xy 369.861846 -148.671788)
			)
		)
		(polygon
			(pts
				(xy 369.102894 -149.747224) (xy 368.899694 -149.747224) (xy 368.899694 -149.950424) (xy 369.102894 -149.950424)
			)
		)
		(polygon
			(pts
				(xy 369.102894 -148.883624) (xy 368.899694 -148.883624) (xy 368.899694 -149.086824) (xy 369.102894 -149.086824)
			)
		)
	)
	(zone
		(net "P12V_HDD5")
		(layer "F.Cu")
		(hatch none 0.5)
		(connect_pads
			(clearance 0.5)
		)
		(min_thickness 0.25)
		(fill yes
			(thermal_gap 0.5)
			(thermal_bridge_width 0.5)
			(island_removal_mode 0)
		)
		(polygon
			(pts
				(xy 170.053 -291.254942) (xy 169.799 -291.508942) (xy 169.799 -293.159942) (xy 170.053 -293.413942)
				(xy 172.212 -293.413942) (xy 172.72 -293.921942) (xy 172.72 -296.461942) (xy 180.467 -304.208942)
				(xy 188.976 -304.208942) (xy 189.103 -304.081942) (xy 189.103 -302.303942) (xy 188.976 -302.176942)
				(xy 183.007 -302.176942) (xy 182.372 -301.541942) (xy 180.721 -301.541942) (xy 176.403 -297.223942)
				(xy 176.403 -293.667942) (xy 175.26 -292.524942) (xy 175.26 -291.508942) (xy 175.006 -291.254942)
			)
		)
		(polygon
			(pts
				(xy 182.5244 -303.218342) (xy 182.3212 -303.218342) (xy 182.3212 -303.421542) (xy 182.5244 -303.421542)
			)
		)
		(polygon
			(pts
				(xy 181.6608 -303.218342) (xy 181.4576 -303.218342) (xy 181.4576 -303.421542) (xy 181.6608 -303.421542)
			)
		)
	)
	(zone
		(layer "F.Cu")
		(hatch none 0.5)
		(connect_pads
			(clearance 0)
		)
		(min_thickness 0.25)
		(keepout
			(tracks not_allowed)
			(vias allowed)
			(pads allowed)
			(copperpour not_allowed)
			(footprints allowed)
		)
		(placement
			(enabled no)
			(sheetname "")
		)
		(fill
			(thermal_gap 0.5)
			(thermal_bridge_width 0.5)
			(island_removal_mode 0)
		)
		(polygon
			(pts
				(arc
					(start 388.21995 -47.178722)
					(mid 387.839077 -46.797468)
					(end 387.45795 -47.178468)
				)
				(arc
					(start 387.45795 -48.321468)
					(mid 387.83895 -48.702468)
					(end 388.21995 -48.321468)
				)
				(xy 388.21995 -47.972218)
				(arc
					(start 387.966204 -47.972218)
					(mid 387.930103 -47.987171)
					(end 387.91515 -48.023272)
				)
				(arc
					(start 387.91515 -48.065944)
					(mid 387.83895 -48.588112)
					(end 387.76275 -48.065944)
				)
				(xy 387.76275 -47.991776)
				(arc
					(start 387.765798 -47.988728)
					(mid 387.822406 -47.879474)
					(end 387.93166 -47.822866)
				)
				(xy 387.934708 -47.819818) (xy 388.21995 -47.819818) (xy 388.21995 -47.680118) (xy 387.934708 -47.680118)
				(arc
					(start 387.93166 -47.67707)
					(mid 387.822406 -47.620462)
					(end 387.765798 -47.511208)
				)
				(xy 387.76275 -47.50816)
				(arc
					(start 387.76275 -47.433992)
					(mid 387.83895 -46.911824)
					(end 387.91515 -47.433992)
				)
				(arc
					(start 387.91515 -47.476664)
					(mid 387.930103 -47.512765)
					(end 387.966204 -47.527718)
				)
				(xy 388.21995 -47.527718)
			)
		)
	)
	(zone
		(layer "F.Cu")
		(hatch none 0.5)
		(connect_pads
			(clearance 0)
		)
		(min_thickness 0.25)
		(keepout
			(tracks not_allowed)
			(vias allowed)
			(pads allowed)
			(copperpour not_allowed)
			(footprints allowed)
		)
		(placement
			(enabled no)
			(sheetname "")
		)
		(fill
			(thermal_gap 0.5)
			(thermal_bridge_width 0.5)
			(island_removal_mode 0)
		)
		(polygon
			(pts
				(arc
					(start 48.749966 -269.999968)
					(mid 44.000166 -274.749768)
					(end 39.250112 -269.999968)
				)
				(arc
					(start 39.250112 -269.999968)
					(mid 44.000166 -265.249914)
					(end 48.749966 -269.999968)
				)
			)
		)
	)
	(zone
		(layer "F.Cu")
		(hatch none 0.5)
		(connect_pads
			(clearance 0)
		)
		(min_thickness 0.25)
		(keepout
			(tracks allowed)
			(vias allowed)
			(pads allowed)
			(copperpour allowed)
			(footprints allowed)
		)
		(placement
			(enabled no)
			(sheetname "")
		)
		(fill
			(thermal_gap 0.5)
			(thermal_bridge_width 0.5)
			(island_removal_mode 0)
		)
		(polygon
			(pts
				(xy 140.060172 -130.052064) (xy 140.994638 -130.052064) (xy 140.994638 -131.586224) (xy 140.060172 -131.586224)
			)
		)
	)
	(zone
		(layer "F.Cu")
		(hatch none 0.5)
		(connect_pads
			(clearance 0)
		)
		(min_thickness 0.25)
		(keepout
			(tracks allowed)
			(vias allowed)
			(pads allowed)
			(copperpour allowed)
			(footprints not_allowed)
		)
		(placement
			(enabled no)
			(sheetname "")
		)
		(fill
			(thermal_gap 0.5)
			(thermal_bridge_width 0.5)
			(island_removal_mode 0)
		)
		(polygon
			(pts
				(arc
					(start 342.700102 -282.999942)
					(mid 341.300054 -284.39999)
					(end 339.900006 -282.999942)
				)
				(arc
					(start 339.900006 -282.999942)
					(mid 341.300054 -281.599894)
					(end 342.700102 -282.999942)
				)
			)
		)
	)
	(zone
		(net "P12V_B_COMP")
		(layer "F.Cu")
		(hatch none 0.5)
		(connect_pads
			(clearance 0.5)
		)
		(min_thickness 0.25)
		(fill yes
			(thermal_gap 0.5)
			(thermal_bridge_width 0.5)
			(island_removal_mode 0)
		)
		(polygon
			(pts
				(xy 346.359226 -134.227062) (xy 346.1512 -134.435088) (xy 346.1512 -138.079226) (xy 346.324174 -138.2522)
				(xy 352.298 -138.2522) (xy 352.552 -137.9982) (xy 352.552 -134.476998) (xy 352.302064 -134.227062)
			)
		)
		(polygon
			(pts
				(xy 346.818712 -137.924794) (xy 346.615512 -137.924794) (xy 346.615512 -138.127994) (xy 346.818712 -138.127994)
			)
		)
		(polygon
			(pts
				(xy 346.818712 -137.365994) (xy 346.615512 -137.365994) (xy 346.615512 -137.569194) (xy 346.818712 -137.569194)
			)
		)
	)
	(zone
		(layer "F.Cu")
		(hatch none 0.5)
		(connect_pads
			(clearance 0)
		)
		(min_thickness 0.25)
		(keepout
			(tracks allowed)
			(vias allowed)
			(pads allowed)
			(copperpour allowed)
			(footprints allowed)
		)
		(placement
			(enabled no)
			(sheetname "")
		)
		(fill
			(thermal_gap 0.5)
			(thermal_bridge_width 0.5)
			(island_removal_mode 0)
		)
		(polygon
			(pts
				(xy 337.82 -16.7132) (xy 337.82 -15.0368) (xy 338.5058 -15.0368) (xy 338.5058 -16.7132)
			)
		)
	)
	(zone
		(layer "F.Cu")
		(hatch none 0.5)
		(connect_pads
			(clearance 0)
		)
		(min_thickness 0.25)
		(keepout
			(tracks not_allowed)
			(vias allowed)
			(pads allowed)
			(copperpour not_allowed)
			(footprints allowed)
		)
		(placement
			(enabled no)
			(sheetname "")
		)
		(fill
			(thermal_gap 0.5)
			(thermal_bridge_width 0.5)
			(island_removal_mode 0)
		)
		(polygon
			(pts
				(arc
					(start 319.214754 -42.246042)
					(mid 318.8335 -42.626915)
					(end 319.2145 -43.008042)
				)
				(xy 319.56375 -43.008042)
				(arc
					(start 319.56375 -42.851832)
					(mid 319.537188 -42.767049)
					(end 319.466976 -42.71264)
				)
				(arc
					(start 319.466976 -42.71264)
					(mid 318.94802 -42.61933)
					(end 319.471548 -42.556176)
				)
				(arc
					(start 319.471548 -42.556176)
					(mid 319.636009 -42.647339)
					(end 319.714372 -42.818304)
				)
				(xy 319.71615 -42.820336) (xy 319.71615 -43.008042) (xy 319.85585 -43.008042) (xy 319.85585 -42.820336)
				(arc
					(start 319.857628 -42.818304)
					(mid 319.935918 -42.647271)
					(end 320.100452 -42.556176)
				)
				(arc
					(start 320.100452 -42.556176)
					(mid 320.624026 -42.619329)
					(end 320.105024 -42.71264)
				)
				(arc
					(start 320.105024 -42.71264)
					(mid 320.034866 -42.767087)
					(end 320.00825 -42.851832)
				)
				(xy 320.00825 -43.008042)
				(arc
					(start 320.3575 -43.008042)
					(mid 320.7385 -42.627042)
					(end 320.3575 -42.246042)
				)
			)
		)
	)
	(zone
		(net "GND")
		(layer "F.Cu")
		(hatch none 0.5)
		(connect_pads
			(clearance 0.5)
		)
		(min_thickness 0.25)
		(fill yes
			(thermal_gap 0.5)
			(thermal_bridge_width 0.5)
			(island_removal_mode 0)
		)
		(polygon
			(pts
				(arc
					(start 171.055284 -89.426542)
					(mid 171.662109 -87.964469)
					(end 172.778674 -86.842346)
				)
				(arc
					(start 166.547546 -69.944488)
					(mid 165.893095 -70.706707)
					(end 165.072568 -71.28637)
				)
				(arc
					(start 165.072568 -71.28637)
					(mid 163.423514 -72.565334)
					(end 161.363152 -72.896984)
				)
				(xy 161.363152 -75.66025) (xy 161.21761 -75.805792) (xy 161.21761 -78.777592)
				(arc
					(start 160.247076 -78.777592)
					(mid 160.320999 -80.435516)
					(end 159.730186 -81.986374)
				)
				(arc
					(start 159.730186 -81.986374)
					(mid 167.118509 -85.292909)
					(end 170.145964 -92.799916)
				)
				(arc
					(start 170.145964 -98.794316)
					(mid 168.204082 -104.979454)
					(end 163.075366 -108.944664)
				)
				(arc
					(start 176.672494 -118.271798)
					(mid 181.472174 -118.14703)
					(end 183.083708 -122.669808)
				)
				(xy 185.693558 -124.46) (xy 186.1566 -124.46) (xy 186.517026 -124.099574)
				(arc
					(start 178.192176 -101.523292)
					(mid 177.163287 -101.974532)
					(end 176.050448 -102.128828)
				)
				(arc
					(start 175.049688 -102.128828)
					(mid 172.675768 -101.369595)
					(end 171.183046 -99.37369)
				)
				(xy 170.806364 -99.37369) (xy 170.806364 -89.426542)
			)
		)
	)
	(zone
		(layer "F.Cu")
		(hatch none 0.5)
		(connect_pads
			(clearance 0)
		)
		(min_thickness 0.25)
		(keepout
			(tracks allowed)
			(vias allowed)
			(pads allowed)
			(copperpour allowed)
			(footprints not_allowed)
		)
		(placement
			(enabled no)
			(sheetname "")
		)
		(fill
			(thermal_gap 0.5)
			(thermal_bridge_width 0.5)
			(island_removal_mode 0)
		)
		(polygon
			(pts
				(arc
					(start 399.64995 -289.999928)
					(mid 404.400004 -285.249874)
					(end 409.150058 -289.999928)
				)
				(arc
					(start 409.150058 -289.999928)
					(mid 404.400004 -294.749982)
					(end 399.64995 -289.999928)
				)
			)
		)
	)
	(zone
		(layer "F.Cu")
		(hatch none 0.5)
		(connect_pads
			(clearance 0)
		)
		(min_thickness 0.25)
		(keepout
			(tracks allowed)
			(vias allowed)
			(pads allowed)
			(copperpour allowed)
			(footprints allowed)
		)
		(placement
			(enabled no)
			(sheetname "")
		)
		(fill
			(thermal_gap 0.5)
			(thermal_bridge_width 0.5)
			(island_removal_mode 0)
		)
		(polygon
			(pts
				(xy 281.0256 18.0848) (xy 281.0256 19.9136) (xy 281.5844 19.9136) (xy 281.5844 18.0848)
			)
		)
	)
	(zone
		(net "P5V_A_4")
		(layer "F.Cu")
		(hatch none 0.5)
		(connect_pads
			(clearance 0.5)
		)
		(min_thickness 0.25)
		(fill yes
			(thermal_gap 0.5)
			(thermal_bridge_width 0.5)
			(island_removal_mode 0)
		)
		(polygon
			(pts
				(xy 336.804 -50.332894) (xy 336.55 -50.586894) (xy 336.55 -55.285894) (xy 336.804 -55.539894) (xy 339.09 -55.539894)
				(xy 339.344 -55.285894) (xy 339.344 -50.586894) (xy 339.09 -50.332894)
			)
		)
	)
	(zone
		(layer "F.Cu")
		(hatch none 0.5)
		(connect_pads
			(clearance 0)
		)
		(min_thickness 0.25)
		(keepout
			(tracks allowed)
			(vias allowed)
			(pads allowed)
			(copperpour allowed)
			(footprints allowed)
		)
		(placement
			(enabled no)
			(sheetname "")
		)
		(fill
			(thermal_gap 0.5)
			(thermal_bridge_width 0.5)
			(island_removal_mode 0)
		)
		(polygon
			(pts
				(xy 321.1576 -44.4246) (xy 322.3006 -44.4246) (xy 322.5546 -44.1706) (xy 322.5546 -43.7134) (xy 322.4022 -43.561)
				(xy 321.1322 -43.561) (xy 321.0052 -43.688) (xy 321.0052 -44.1198) (xy 321.1576 -44.2722)
			)
		)
	)
	(zone
		(net "GND")
		(layer "F.Cu")
		(hatch none 0.5)
		(connect_pads
			(clearance 0.5)
		)
		(min_thickness 0.25)
		(fill yes
			(thermal_gap 0.5)
			(thermal_bridge_width 0.5)
			(island_removal_mode 0)
		)
		(polygon
			(pts
				(xy 283.609542 -219.676726) (xy 283.13888 -220.147388) (xy 283.13888 -223.271334) (xy 283.61005 -223.742504)
				(xy 287.24225 -223.742504) (xy 287.717738 -223.267016) (xy 287.717738 -220.147388) (xy 287.247076 -219.676726)
			)
		)
	)
	(zone
		(layer "F.Cu")
		(hatch none 0.5)
		(connect_pads
			(clearance 0)
		)
		(min_thickness 0.25)
		(keepout
			(tracks allowed)
			(vias allowed)
			(pads allowed)
			(copperpour allowed)
			(footprints not_allowed)
		)
		(placement
			(enabled no)
			(sheetname "")
		)
		(fill
			(thermal_gap 0.5)
			(thermal_bridge_width 0.5)
			(island_removal_mode 0)
		)
		(polygon
			(pts
				(arc
					(start 48.749966 -269.999968)
					(mid 44.000166 -274.749768)
					(end 39.250112 -269.999968)
				)
				(arc
					(start 39.250112 -269.999968)
					(mid 44.000166 -265.249914)
					(end 48.749966 -269.999968)
				)
			)
		)
	)
	(zone
		(net "P12V_A")
		(layer "F.Cu")
		(hatch none 0.5)
		(connect_pads
			(clearance 0.5)
		)
		(min_thickness 0.25)
		(fill yes
			(thermal_gap 0.5)
			(thermal_bridge_width 0.5)
			(island_removal_mode 0)
		)
		(polygon
			(pts
				(xy 334.645 -171.428918) (xy 334.137 -171.936918) (xy 334.137 -175.365918) (xy 334.391 -175.619918)
				(xy 337.693 -175.619918) (xy 337.947 -175.365918) (xy 337.947 -173.333918) (xy 338.074 -173.206918)
				(xy 338.455 -173.206918) (xy 338.582 -173.079918) (xy 338.582 -171.555918) (xy 338.455 -171.428918)
			)
		)
		(polygon
			(pts
				(xy 338.0486 -172.444918) (xy 337.8454 -172.444918) (xy 337.8454 -172.648118) (xy 338.0486 -172.648118)
			)
		)
		(polygon
			(pts
				(xy 338.0994 -171.987718) (xy 337.8962 -171.987718) (xy 337.8962 -172.190918) (xy 338.0994 -172.190918)
			)
		)
	)
	(zone
		(layer "F.Cu")
		(hatch none 0.5)
		(connect_pads
			(clearance 0)
		)
		(min_thickness 0.25)
		(keepout
			(tracks allowed)
			(vias allowed)
			(pads allowed)
			(copperpour allowed)
			(footprints allowed)
		)
		(placement
			(enabled no)
			(sheetname "")
		)
		(fill
			(thermal_gap 0.5)
			(thermal_bridge_width 0.5)
			(island_removal_mode 0)
		)
		(polygon
			(pts
				(xy 372.0846 -141.5288) (xy 372.0846 -140.6398) (xy 374.9802 -140.6398) (xy 374.9802 -141.5288)
			)
		)
	)
	(zone
		(net "12V_PRE_34")
		(layer "F.Cu")
		(hatch none 0.5)
		(connect_pads
			(clearance 0.5)
		)
		(min_thickness 0.25)
		(fill yes
			(thermal_gap 0.5)
			(thermal_bridge_width 0.5)
			(island_removal_mode 0)
		)
		(polygon
			(pts
				(xy 457.468478 -68.314316) (xy 455.0029 -70.779894) (xy 452.4629 -70.779894) (xy 452.2089 -71.033894)
				(xy 452.2089 -71.414894) (xy 452.4629 -71.668894) (xy 459.161134 -71.668894) (xy 459.821534 -71.008494)
				(xy 459.821534 -68.434966) (xy 459.700884 -68.314316)
			)
		)
	)
	(zone
		(net "AGND_P5V_A")
		(layer "F.Cu")
		(hatch none 0.5)
		(connect_pads
			(clearance 0.5)
		)
		(min_thickness 0.25)
		(fill yes
			(thermal_gap 0.5)
			(thermal_bridge_width 0.5)
			(island_removal_mode 0)
		)
		(polygon
			(pts
				(xy 27.092402 -253.42215) (xy 26.584402 -253.93015) (xy 26.584402 -255.14935) (xy 26.736802 -255.30175)
				(xy 29.099002 -255.30175) (xy 29.530802 -254.86995) (xy 29.530802 -254.41275) (xy 29.962602 -253.98095)
				(xy 29.962602 -253.52375) (xy 29.861002 -253.42215)
			)
		)
		(polygon
			(pts
				(xy 27.194002 -254.46355) (xy 26.990802 -254.46355) (xy 26.990802 -254.66675) (xy 27.194002 -254.66675)
			)
		)
		(polygon
			(pts
				(xy 29.53893 -253.940818) (xy 29.33573 -253.940818) (xy 29.33573 -254.144018) (xy 29.53893 -254.144018)
			)
		)
		(polygon
			(pts
				(xy 28.956 -253.91872) (xy 28.7528 -253.91872) (xy 28.7528 -254.12192) (xy 28.956 -254.12192)
			)
		)
		(polygon
			(pts
				(xy 28.3972 -253.91872) (xy 28.194 -253.91872) (xy 28.194 -254.12192) (xy 28.3972 -254.12192)
			)
		)
		(polygon
			(pts
				(xy 27.905202 -253.90475) (xy 27.702002 -253.90475) (xy 27.702002 -254.10795) (xy 27.905202 -254.10795)
			)
		)
		(polygon
			(pts
				(xy 27.346402 -253.90475) (xy 27.143202 -253.90475) (xy 27.143202 -254.10795) (xy 27.346402 -254.10795)
			)
		)
	)
	(zone
		(layer "F.Cu")
		(hatch none 0.5)
		(connect_pads
			(clearance 0)
		)
		(min_thickness 0.25)
		(keepout
			(tracks allowed)
			(vias allowed)
			(pads allowed)
			(copperpour allowed)
			(footprints allowed)
		)
		(placement
			(enabled no)
			(sheetname "")
		)
		(fill
			(thermal_gap 0.5)
			(thermal_bridge_width 0.5)
			(island_removal_mode 0)
		)
		(polygon
			(pts
				(xy 239.871504 -382.062228) (xy 238.932466 -382.062228) (xy 238.932466 -380.528068) (xy 239.871504 -380.528068)
			)
		)
	)
	(zone
		(layer "F.Cu")
		(hatch none 0.5)
		(connect_pads
			(clearance 0)
		)
		(min_thickness 0.25)
		(keepout
			(tracks not_allowed)
			(vias allowed)
			(pads allowed)
			(copperpour not_allowed)
			(footprints allowed)
		)
		(placement
			(enabled no)
			(sheetname "")
		)
		(fill
			(thermal_gap 0.5)
			(thermal_bridge_width 0.5)
			(island_removal_mode 0)
		)
		(polygon
			(pts
				(arc
					(start 95.989902 -47.178722)
					(mid 95.609029 -46.797468)
					(end 95.227902 -47.178468)
				)
				(xy 95.227902 -47.527718)
				(arc
					(start 95.481902 -47.527718)
					(mid 95.517823 -47.512839)
					(end 95.532702 -47.476918)
				)
				(arc
					(start 95.532702 -47.433992)
					(mid 95.608902 -46.911824)
					(end 95.685102 -47.433992)
				)
				(xy 95.685102 -47.508414)
				(arc
					(start 95.682054 -47.511462)
					(mid 95.625523 -47.620539)
					(end 95.516446 -47.67707)
				)
				(xy 95.513398 -47.680118) (xy 95.227902 -47.680118) (xy 95.227902 -47.819818) (xy 95.513398 -47.819818)
				(arc
					(start 95.516446 -47.822866)
					(mid 95.625523 -47.879397)
					(end 95.682054 -47.988474)
				)
				(xy 95.685102 -47.991522)
				(arc
					(start 95.685102 -48.065944)
					(mid 95.608902 -48.588112)
					(end 95.532702 -48.065944)
				)
				(arc
					(start 95.532702 -48.023018)
					(mid 95.517823 -47.987097)
					(end 95.481902 -47.972218)
				)
				(xy 95.227902 -47.972218)
				(arc
					(start 95.227902 -48.321468)
					(mid 95.608902 -48.702468)
					(end 95.989902 -48.321468)
				)
			)
		)
	)
	(zone
		(net "P5V_HDD17")
		(layer "F.Cu")
		(hatch none 0.5)
		(connect_pads
			(clearance 0.5)
		)
		(min_thickness 0.25)
		(fill yes
			(thermal_gap 0.5)
			(thermal_bridge_width 0.5)
			(island_removal_mode 0)
		)
		(polygon
			(pts
				(xy 177.419 -171.682918) (xy 177.165 -171.936918) (xy 177.165 -174.222918) (xy 177.419 -174.476918)
				(xy 177.419 -176.508918) (xy 178.181 -177.270918) (xy 178.181 -178.032918) (xy 178.562 -178.413918)
				(xy 178.943 -178.413918) (xy 182.118 -181.588918) (xy 188.976 -181.588918) (xy 189.103 -181.461918)
				(xy 189.103 -179.683918) (xy 188.976 -179.556918) (xy 183.896 -179.556918) (xy 181.991 -177.651918)
				(xy 181.102 -177.651918) (xy 180.213 -176.762918) (xy 180.213 -174.222918) (xy 180.848 -173.587918)
				(xy 180.848 -171.936918) (xy 180.594 -171.682918)
			)
		)
		(polygon
			(pts
				(xy 179.4256 -178.109118) (xy 179.2224 -178.109118) (xy 179.2224 -178.312318) (xy 179.4256 -178.312318)
			)
		)
		(polygon
			(pts
				(xy 179.4256 -177.245518) (xy 179.2224 -177.245518) (xy 179.2224 -177.448718) (xy 179.4256 -177.448718)
			)
		)
		(polygon
			(pts
				(xy 178.562 -177.245518) (xy 178.3588 -177.245518) (xy 178.3588 -177.448718) (xy 178.562 -177.448718)
			)
		)
	)
	(zone
		(layer "F.Cu")
		(hatch none 0.5)
		(connect_pads
			(clearance 0)
		)
		(min_thickness 0.25)
		(keepout
			(tracks allowed)
			(vias allowed)
			(pads allowed)
			(copperpour allowed)
			(footprints allowed)
		)
		(placement
			(enabled no)
			(sheetname "")
		)
		(fill
			(thermal_gap 0.5)
			(thermal_bridge_width 0.5)
			(island_removal_mode 0)
		)
		(polygon
			(pts
				(xy 230.759 -388.0104) (xy 230.759 -384.683) (xy 227.3046 -384.683) (xy 227.3046 -388.0104)
			)
		)
	)
	(zone
		(net "GND")
		(layer "F.Cu")
		(hatch none 0.5)
		(connect_pads
			(clearance 0.5)
		)
		(min_thickness 0.25)
		(fill yes
			(thermal_gap 0.5)
			(thermal_bridge_width 0.5)
			(island_removal_mode 0)
		)
		(polygon
			(pts
				(xy 262.784336 23.618698) (xy 262.606536 23.440898) (xy 262.606536 20.222464) (xy 262.900668 19.928332)
				(xy 264.932668 19.928332) (xy 265.197336 20.193) (xy 265.197336 23.390098) (xy 264.968736 23.618698)
			)
		)
	)
	(zone
		(net "P5V_A_1")
		(layer "F.Cu")
		(hatch none 0.5)
		(connect_pads
			(clearance 0.5)
		)
		(min_thickness 0.25)
		(fill yes
			(thermal_gap 0.5)
			(thermal_bridge_width 0.5)
			(island_removal_mode 0)
		)
		(polygon
			(pts
				(xy 49.948846 -165.840918) (xy 49.694846 -166.094918) (xy 49.694846 -168.380918) (xy 49.948846 -168.634918)
				(xy 54.647846 -168.634918) (xy 54.901846 -168.380918) (xy 54.901846 -166.094918) (xy 54.647846 -165.840918)
			)
		)
	)
	(zone
		(net "P12V_A_VIN_U20")
		(layer "F.Cu")
		(hatch none 0.5)
		(connect_pads
			(clearance 0.5)
		)
		(min_thickness 0.25)
		(fill yes
			(thermal_gap 0.5)
			(thermal_bridge_width 0.5)
			(island_removal_mode 0)
		)
		(polygon
			(pts
				(xy 24.90216 -245.045992) (xy 23.846536 -246.101616) (xy 23.846536 -248.421906) (xy 24.047704 -248.623074)
				(xy 26.726642 -248.623074) (xy 26.835608 -248.514108) (xy 26.835608 -245.150132) (xy 26.731468 -245.045992)
			)
		)
	)
	(zone
		(layer "F.Cu")
		(hatch none 0.5)
		(connect_pads
			(clearance 0)
		)
		(min_thickness 0.25)
		(keepout
			(tracks allowed)
			(vias allowed)
			(pads allowed)
			(copperpour allowed)
			(footprints not_allowed)
		)
		(placement
			(enabled no)
			(sheetname "")
		)
		(fill
			(thermal_gap 0.5)
			(thermal_bridge_width 0.5)
			(island_removal_mode 0)
		)
		(polygon
			(pts
				(xy 191.799972 -79.799942) (xy 191.799972 -125.800104) (xy 0 -125.800104) (xy 0 -75.79995) (xy 8.349996 -75.79995)
				(xy 8.349996 -65.79997) (xy 22.899878 -65.79997) (xy 22.899878 -75.79995) (xy 39.900098 -75.79995)
				(xy 39.900098 -65.79997) (xy 54.44998 -65.79997) (xy 54.44998 -75.79995) (xy 71.449946 -75.79995)
				(xy 71.449946 -65.79997) (xy 86.000082 -65.79997) (xy 86.000082 -75.79995) (xy 103.000048 -75.79995)
				(xy 103.000048 -65.79997) (xy 117.54993 -65.79997) (xy 117.54993 -75.79995) (xy 134.549896 -75.79995)
				(xy 134.549896 -65.79997) (xy 149.100032 -65.79997) (xy 149.100032 -75.79995) (xy 166.099998 -75.79995)
				(xy 166.099998 -65.79997) (xy 180.64988 -65.79997) (xy 180.64988 -79.799942)
			)
		)
	)
	(zone
		(layer "F.Cu")
		(hatch none 0.5)
		(connect_pads
			(clearance 0)
		)
		(min_thickness 0.25)
		(keepout
			(tracks allowed)
			(vias allowed)
			(pads allowed)
			(copperpour allowed)
			(footprints allowed)
		)
		(placement
			(enabled no)
			(sheetname "")
		)
		(fill
			(thermal_gap 0.5)
			(thermal_bridge_width 0.5)
			(island_removal_mode 0)
		)
		(polygon
			(pts
				(xy 43.606974 -144.078706) (xy 43.606974 -139.980416) (xy 44.857924 -139.980416) (xy 44.857924 -144.078706)
			)
		)
	)
	(zone
		(net "AGND_CURRENT_MONOA")
		(layer "F.Cu")
		(hatch none 0.5)
		(connect_pads
			(clearance 0.5)
		)
		(min_thickness 0.25)
		(fill yes
			(thermal_gap 0.5)
			(thermal_bridge_width 0.5)
			(island_removal_mode 0)
		)
		(polygon
			(pts
				(xy 136.893554 -142.089886) (xy 136.722104 -142.261336) (xy 136.722104 -145.23085) (xy 139.318238 -147.826984)
				(xy 150.898352 -147.826984) (xy 151.200358 -147.524978) (xy 151.200358 -145.6563) (xy 151.08174 -145.537682)
				(xy 149.000464 -145.537682) (xy 148.879052 -145.41627) (xy 148.879052 -145.12798) (xy 148.770848 -145.019776)
				(xy 148.067268 -145.019776) (xy 147.936458 -145.150586) (xy 147.936458 -145.425414) (xy 147.82419 -145.537682)
				(xy 142.263622 -145.537682) (xy 141.920722 -145.194782) (xy 141.920722 -143.921734) (xy 141.749526 -143.750538)
				(xy 141.300454 -143.750538) (xy 141.169898 -143.881094) (xy 141.169898 -144.746218) (xy 140.722096 -145.19402)
				(xy 139.500102 -145.19402) (xy 138.493246 -144.187164) (xy 138.493246 -142.220188) (xy 138.362944 -142.089886)
			)
		)
		(polygon
			(pts
				(xy 149.956266 -146.032474) (xy 149.753066 -146.032474) (xy 149.753066 -146.235674) (xy 149.956266 -146.235674)
			)
		)
		(polygon
			(pts
				(xy 149.346666 -146.032474) (xy 149.143466 -146.032474) (xy 149.143466 -146.235674) (xy 149.346666 -146.235674)
			)
		)
		(polygon
			(pts
				(xy 146.654266 -146.032474) (xy 146.451066 -146.032474) (xy 146.451066 -146.235674) (xy 146.654266 -146.235674)
			)
		)
		(polygon
			(pts
				(xy 146.044666 -146.032474) (xy 145.841466 -146.032474) (xy 145.841466 -146.235674) (xy 146.044666 -146.235674)
			)
		)
		(polygon
			(pts
				(xy 144.622266 -146.032474) (xy 144.419066 -146.032474) (xy 144.419066 -146.235674) (xy 144.622266 -146.235674)
			)
		)
		(polygon
			(pts
				(xy 144.012666 -146.032474) (xy 143.809466 -146.032474) (xy 143.809466 -146.235674) (xy 144.012666 -146.235674)
			)
		)
		(polygon
			(pts
				(xy 143.225266 -146.032474) (xy 143.022066 -146.032474) (xy 143.022066 -146.235674) (xy 143.225266 -146.235674)
			)
		)
		(polygon
			(pts
				(xy 142.615666 -146.032474) (xy 142.412466 -146.032474) (xy 142.412466 -146.235674) (xy 142.615666 -146.235674)
			)
		)
		(polygon
			(pts
				(xy 147.629372 -145.998438) (xy 147.426172 -145.998438) (xy 147.426172 -146.201638) (xy 147.629372 -146.201638)
			)
		)
		(polygon
			(pts
				(xy 147.070572 -145.998438) (xy 146.867372 -145.998438) (xy 146.867372 -146.201638) (xy 147.070572 -146.201638)
			)
		)
		(polygon
			(pts
				(xy 145.55216 -145.99031) (xy 145.34896 -145.99031) (xy 145.34896 -146.19351) (xy 145.55216 -146.19351)
			)
		)
		(polygon
			(pts
				(xy 144.99336 -145.99031) (xy 144.79016 -145.99031) (xy 144.79016 -146.19351) (xy 144.99336 -146.19351)
			)
		)
		(polygon
			(pts
				(xy 150.946866 -145.981674) (xy 150.743666 -145.981674) (xy 150.743666 -146.184874) (xy 150.946866 -146.184874)
			)
		)
		(polygon
			(pts
				(xy 150.388066 -145.981674) (xy 150.184866 -145.981674) (xy 150.184866 -146.184874) (xy 150.388066 -146.184874)
			)
		)
		(polygon
			(pts
				(xy 148.940266 -145.778474) (xy 148.737066 -145.778474) (xy 148.737066 -145.981674) (xy 148.940266 -145.981674)
			)
		)
		(polygon
			(pts
				(xy 148.076666 -145.778474) (xy 147.873466 -145.778474) (xy 147.873466 -145.981674) (xy 148.076666 -145.981674)
			)
		)
		(polygon
			(pts
				(xy 138.043666 -144.076674) (xy 137.840466 -144.076674) (xy 137.840466 -144.279874) (xy 138.043666 -144.279874)
			)
		)
		(polygon
			(pts
				(xy 138.043666 -143.517874) (xy 137.840466 -143.517874) (xy 137.840466 -143.721074) (xy 138.043666 -143.721074)
			)
		)
		(polygon
			(pts
				(xy 138.043666 -142.806674) (xy 137.840466 -142.806674) (xy 137.840466 -143.009874) (xy 138.043666 -143.009874)
			)
		)
		(polygon
			(pts
				(xy 138.043666 -142.247874) (xy 137.840466 -142.247874) (xy 137.840466 -142.451074) (xy 138.043666 -142.451074)
			)
		)
	)
	(zone
		(net "P5V_USB_B")
		(layer "F.Cu")
		(hatch none 0.5)
		(connect_pads
			(clearance 0.5)
		)
		(min_thickness 0.25)
		(fill yes
			(thermal_gap 0.5)
			(thermal_bridge_width 0.5)
			(island_removal_mode 0)
		)
		(polygon
			(pts
				(xy 259.1816 32.2326) (xy 259.08 32.131) (xy 259.08 29.3116) (xy 264.4394 23.9522) (xy 265.43 23.9522)
				(xy 266.2428 23.1394) (xy 266.2428 16.51) (xy 266.5984 16.1544) (xy 268.0462 16.1544) (xy 268.1224 16.2306)
				(xy 268.1224 23.8506) (xy 265.7602 26.2128) (xy 263.525 26.2128) (xy 259.9436 29.7942) (xy 259.9436 32.0548)
				(xy 259.7658 32.2326)
			)
		)
		(polygon
			(pts
				(xy 267.571982 19.163538) (xy 267.368782 19.163538) (xy 267.368782 18.960338) (xy 267.571982 18.960338)
			)
		)
		(polygon
			(pts
				(xy 267.571982 19.773138) (xy 267.368782 19.773138) (xy 267.368782 19.569938) (xy 267.571982 19.569938)
			)
		)
	)
	(zone
		(layer "F.Cu")
		(hatch none 0.5)
		(connect_pads
			(clearance 0)
		)
		(min_thickness 0.25)
		(keepout
			(tracks allowed)
			(vias allowed)
			(pads allowed)
			(copperpour allowed)
			(footprints allowed)
		)
		(placement
			(enabled no)
			(sheetname "")
		)
		(fill
			(thermal_gap 0.5)
			(thermal_bridge_width 0.5)
			(island_removal_mode 0)
		)
		(polygon
			(pts
				(xy 301.3075 -70.987666) (xy 301.3075 -71.922132) (xy 299.77334 -71.922132) (xy 299.77334 -70.987666)
			)
		)
	)
	(zone
		(net "5V_PRE_4")
		(layer "F.Cu")
		(hatch none 0.5)
		(connect_pads
			(clearance 0.5)
		)
		(min_thickness 0.25)
		(fill yes
			(thermal_gap 0.5)
			(thermal_bridge_width 0.5)
			(island_removal_mode 0)
		)
		(polygon
			(pts
				(xy 149.247098 -289.7886) (xy 149.043898 -289.9918) (xy 149.043898 -291.508942) (xy 149.170898 -291.635942)
				(xy 150.440898 -291.635942) (xy 152.980898 -294.175942) (xy 157.425898 -294.175942) (xy 157.552898 -294.048942)
				(xy 157.552898 -293.286942) (xy 157.425898 -293.159942) (xy 154.4828 -293.159942) (xy 151.111458 -289.7886)
			)
		)
	)
	(zone
		(layer "F.Cu")
		(hatch none 0.5)
		(connect_pads
			(clearance 0)
		)
		(min_thickness 0.25)
		(keepout
			(tracks allowed)
			(vias allowed)
			(pads allowed)
			(copperpour allowed)
			(footprints allowed)
		)
		(placement
			(enabled no)
			(sheetname "")
		)
		(fill
			(thermal_gap 0.5)
			(thermal_bridge_width 0.5)
			(island_removal_mode 0)
		)
		(polygon
			(pts
				(xy 275.8948 19.2278) (xy 275.8948 20.574) (xy 276.8854 20.574) (xy 276.8854 19.2278)
			)
		)
	)
	(zone
		(net "P5V_A_2")
		(layer "F.Cu")
		(hatch none 0.5)
		(connect_pads
			(clearance 0.5)
		)
		(min_thickness 0.25)
		(fill yes
			(thermal_gap 0.5)
			(thermal_bridge_width 0.5)
			(island_removal_mode 0)
		)
		(polygon
			(pts
				(xy 49.948846 -50.840894) (xy 49.694846 -51.094894) (xy 49.694846 -53.380894) (xy 49.948846 -53.634894)
				(xy 54.647846 -53.634894) (xy 54.901846 -53.380894) (xy 54.901846 -51.094894) (xy 54.647846 -50.840894)
			)
		)
	)
	(zone
		(net "P5V_HDD33")
		(layer "F.Cu")
		(hatch none 0.5)
		(connect_pads
			(clearance 0.5)
		)
		(min_thickness 0.25)
		(fill yes
			(thermal_gap 0.5)
			(thermal_bridge_width 0.5)
			(island_removal_mode 0)
		)
		(polygon
			(pts
				(xy 426.247052 -51.729894) (xy 425.993052 -51.983894) (xy 425.993052 -62.778894) (xy 424.342052 -64.429894)
				(xy 420.913052 -64.429894) (xy 420.659052 -64.683894) (xy 420.659052 -66.334894) (xy 420.913052 -66.588894)
				(xy 425.485052 -66.588894) (xy 426.120052 -65.953894) (xy 427.898052 -65.953894) (xy 428.406052 -65.445894)
				(xy 428.406052 -51.983894) (xy 428.152052 -51.729894)
			)
		)
		(polygon
			(pts
				(xy 425.002452 -65.598294) (xy 424.799252 -65.598294) (xy 424.799252 -65.801494) (xy 425.002452 -65.801494)
			)
		)
		(polygon
			(pts
				(xy 424.138852 -65.598294) (xy 423.935652 -65.598294) (xy 423.935652 -65.801494) (xy 424.138852 -65.801494)
			)
		)
	)
	(zone
		(layer "F.Cu")
		(hatch none 0.5)
		(connect_pads
			(clearance 0)
		)
		(min_thickness 0.25)
		(keepout
			(tracks not_allowed)
			(vias allowed)
			(pads allowed)
			(copperpour not_allowed)
			(footprints allowed)
		)
		(placement
			(enabled no)
			(sheetname "")
		)
		(fill
			(thermal_gap 0.5)
			(thermal_bridge_width 0.5)
			(island_removal_mode 0)
		)
		(polygon
			(pts
				(arc
					(start 346.050108 -269.999968)
					(mid 341.300054 -274.750022)
					(end 336.55 -269.999968)
				)
				(arc
					(start 336.55 -269.999968)
					(mid 341.300054 -265.249914)
					(end 346.050108 -269.999968)
				)
			)
		)
	)
	(zone
		(net "P5V_A_1")
		(layer "F.Cu")
		(hatch none 0.5)
		(connect_pads
			(clearance 0.5)
		)
		(min_thickness 0.25)
		(fill yes
			(thermal_gap 0.5)
			(thermal_bridge_width 0.5)
			(island_removal_mode 0)
		)
		(polygon
			(pts
				(xy 81.498948 -280.840942) (xy 81.244948 -281.094942) (xy 81.244948 -283.380942) (xy 81.498948 -283.634942)
				(xy 86.197948 -283.634942) (xy 86.451948 -283.380942) (xy 86.451948 -281.094942) (xy 86.197948 -280.840942)
			)
		)
	)
	(zone
		(layer "F.Cu")
		(hatch none 0.5)
		(connect_pads
			(clearance 0)
		)
		(min_thickness 0.25)
		(keepout
			(tracks not_allowed)
			(vias allowed)
			(pads allowed)
			(copperpour not_allowed)
			(footprints allowed)
		)
		(placement
			(enabled no)
			(sheetname "")
		)
		(fill
			(thermal_gap 0.5)
			(thermal_bridge_width 0.5)
			(island_removal_mode 0)
		)
		(polygon
			(pts
				(arc
					(start 351.920302 -158.368492)
					(mid 351.539302 -157.987492)
					(end 351.158302 -158.368492)
				)
				(arc
					(start 351.158302 -159.511238)
					(mid 351.539175 -159.892492)
					(end 351.920302 -159.511492)
				)
				(xy 351.920302 -159.162242)
				(arc
					(start 351.676716 -159.162242)
					(mid 351.657359 -159.166075)
					(end 351.640902 -159.176974)
				)
				(arc
					(start 351.630234 -159.187642)
					(mid 351.619308 -159.204088)
					(end 351.615502 -159.223456)
				)
				(arc
					(start 351.615502 -159.255968)
					(mid 351.539302 -159.778136)
					(end 351.463102 -159.255968)
				)
				(xy 351.463102 -159.19196)
				(arc
					(start 351.46615 -159.188912)
					(mid 351.478585 -159.145749)
					(end 351.500186 -159.106362)
				)
				(xy 351.500186 -159.102298) (xy 351.555558 -159.046926)
				(arc
					(start 351.559622 -159.046926)
					(mid 351.599 -159.025304)
					(end 351.642172 -159.01289)
				)
				(xy 351.64522 -159.009842) (xy 351.920302 -159.009842) (xy 351.920302 -158.870142) (xy 351.648014 -158.870142)
				(arc
					(start 351.644966 -158.867094)
					(mid 351.601803 -158.854659)
					(end 351.562416 -158.833058)
				)
				(xy 351.558352 -158.833058) (xy 351.500186 -158.774892)
				(arc
					(start 351.500186 -158.770828)
					(mid 351.478564 -158.73145)
					(end 351.46615 -158.688278)
				)
				(xy 351.463102 -158.68523)
				(arc
					(start 351.463102 -158.624016)
					(mid 351.539302 -158.101848)
					(end 351.615502 -158.624016)
				)
				(arc
					(start 351.615502 -158.653734)
					(mid 351.619335 -158.673091)
					(end 351.630234 -158.689548)
				)
				(arc
					(start 351.643696 -158.70301)
					(mid 351.660142 -158.713936)
					(end 351.67951 -158.717742)
				)
				(xy 351.920302 -158.717742)
			)
		)
	)
	(zone
		(net "GND")
		(layer "F.Cu")
		(hatch none 0.5)
		(connect_pads
			(clearance 0.5)
		)
		(min_thickness 0.25)
		(fill yes
			(thermal_gap 0.5)
			(thermal_bridge_width 0.5)
			(island_removal_mode 0)
		)
		(polygon
			(pts
				(xy 249.301 -39.575486) (xy 249.301 -81.172812) (xy 255.427988 -87.2998) (xy 255.8288 -87.2998)
				(xy 256.134616 -86.993984) (xy 256.134616 -69.95795) (xy 262.688324 -63.403988) (xy 262.688324 -39.575486)
			)
		)
	)
	(zone
		(net "P12V_A")
		(layer "F.Cu")
		(hatch none 0.5)
		(connect_pads
			(clearance 0.5)
		)
		(min_thickness 0.25)
		(fill yes
			(thermal_gap 0.5)
			(thermal_bridge_width 0.5)
			(island_removal_mode 0)
		)
		(polygon
			(pts
				(xy 366.195102 -286.428942) (xy 365.687102 -286.936942) (xy 365.687102 -290.365942) (xy 365.941102 -290.619942)
				(xy 369.243102 -290.619942) (xy 369.497102 -290.365942) (xy 369.497102 -288.333942) (xy 369.624102 -288.206942)
				(xy 370.005102 -288.206942) (xy 370.132102 -288.079942) (xy 370.132102 -286.555942) (xy 370.005102 -286.428942)
			)
		)
		(polygon
			(pts
				(xy 369.598702 -287.444942) (xy 369.395502 -287.444942) (xy 369.395502 -287.648142) (xy 369.598702 -287.648142)
			)
		)
		(polygon
			(pts
				(xy 369.649502 -286.987742) (xy 369.446302 -286.987742) (xy 369.446302 -287.190942) (xy 369.649502 -287.190942)
			)
		)
	)
	(zone
		(layer "F.Cu")
		(hatch none 0.5)
		(connect_pads
			(clearance 0)
		)
		(min_thickness 0.25)
		(keepout
			(tracks not_allowed)
			(vias allowed)
			(pads allowed)
			(copperpour not_allowed)
			(footprints allowed)
		)
		(placement
			(enabled no)
			(sheetname "")
		)
		(fill
			(thermal_gap 0.5)
			(thermal_bridge_width 0.5)
			(island_removal_mode 0)
		)
		(polygon
			(pts
				(arc
					(start 271.970754 -308.721506)
					(mid 271.58696 -309.104919)
					(end 271.9705 -309.488586)
				)
				(arc
					(start 273.1135 -309.488586)
					(mid 273.49704 -309.105046)
					(end 273.1135 -308.721506)
				)
				(xy 272.76425 -308.721506)
				(arc
					(start 272.76425 -308.978046)
					(mid 272.779129 -309.013967)
					(end 272.81505 -309.028846)
				)
				(arc
					(start 272.857976 -309.028846)
					(mid 273.380144 -309.105046)
					(end 272.857976 -309.181246)
				)
				(xy 272.783554 -309.181246)
				(arc
					(start 272.780506 -309.178198)
					(mid 272.671429 -309.121667)
					(end 272.614898 -309.01259)
				)
				(xy 272.61185 -309.009542) (xy 272.61185 -308.721506) (xy 272.47215 -308.721506) (xy 272.47215 -309.009542)
				(arc
					(start 272.469102 -309.01259)
					(mid 272.412571 -309.121667)
					(end 272.303494 -309.178198)
				)
				(xy 272.300446 -309.181246)
				(arc
					(start 272.226024 -309.181246)
					(mid 271.703856 -309.105046)
					(end 272.226024 -309.028846)
				)
				(arc
					(start 272.26895 -309.028846)
					(mid 272.304871 -309.013967)
					(end 272.31975 -308.978046)
				)
				(xy 272.31975 -308.721506)
			)
		)
	)
	(zone
		(net "P5V_A_3")
		(layer "F.Cu")
		(hatch none 0.5)
		(connect_pads
			(clearance 0.5)
		)
		(min_thickness 0.25)
		(fill yes
			(thermal_gap 0.5)
			(thermal_bridge_width 0.5)
			(island_removal_mode 0)
		)
		(polygon
			(pts
				(xy 368.354102 -280.332942) (xy 368.100102 -280.586942) (xy 368.100102 -285.285942) (xy 368.354102 -285.539942)
				(xy 371.426994 -285.539942) (xy 371.56644 -285.400496) (xy 371.56644 -280.719022) (xy 371.18036 -280.332942)
			)
		)
	)
	(zone
		(net "5V_PRE_9")
		(layer "F.Cu")
		(hatch none 0.5)
		(connect_pads
			(clearance 0.5)
		)
		(min_thickness 0.25)
		(fill yes
			(thermal_gap 0.5)
			(thermal_bridge_width 0.5)
			(island_removal_mode 0)
		)
		(polygon
			(pts
				(xy 424.088052 -289.984942) (xy 423.834052 -290.238942) (xy 423.834052 -292.778942) (xy 423.453052 -293.159942)
				(xy 420.913052 -293.159942) (xy 420.659052 -293.413942) (xy 420.659052 -293.794942) (xy 420.913052 -294.048942)
				(xy 424.215052 -294.048942) (xy 425.485052 -292.778942) (xy 425.485052 -290.238942) (xy 425.231052 -289.984942)
			)
		)
	)
	(zone
		(net "5V_PRE_31")
		(layer "F.Cu")
		(hatch none 0.5)
		(connect_pads
			(clearance 0.5)
		)
		(min_thickness 0.25)
		(fill yes
			(thermal_gap 0.5)
			(thermal_bridge_width 0.5)
			(island_removal_mode 0)
		)
		(polygon
			(pts
				(xy 360.988102 -59.984894) (xy 360.734102 -60.238894) (xy 360.734102 -62.778894) (xy 360.353102 -63.159894)
				(xy 357.813102 -63.159894) (xy 357.559102 -63.413894) (xy 357.559102 -63.794894) (xy 357.813102 -64.048894)
				(xy 361.115102 -64.048894) (xy 362.385102 -62.778894) (xy 362.385102 -60.238894) (xy 362.131102 -59.984894)
			)
		)
	)
	(zone
		(net "GND")
		(layer "F.Cu")
		(hatch none 0.5)
		(connect_pads
			(clearance 0.5)
		)
		(min_thickness 0.25)
		(fill yes
			(thermal_gap 0.5)
			(thermal_bridge_width 0.5)
			(island_removal_mode 0)
		)
		(polygon
			(pts
				(xy 19.426174 -306.306728)
				(arc
					(start 17.41678 -304.29708)
					(mid 17.490825 -305.425707)
					(end 17.25676 -306.53228)
				)
				(xy 17.25676 -308.418484) (xy 21.932646 -313.09437) (xy 21.932646 -319.405)
				(arc
					(start 23.050246 -319.405)
					(mid 24.210878 -316.966398)
					(end 25.939242 -314.891166)
				)
				(xy 23.093934 -314.891166)
				(arc
					(start 23.093934 -310.16702)
					(mid 22.341835 -309.863461)
					(end 21.664422 -309.417466)
				)
				(xy 19.997674 -309.417466) (xy 19.997674 -306.878228) (xy 19.882612 -306.763166) (xy 19.426174 -306.763166)
			)
		)
	)
	(zone
		(net "5V_PRE_25")
		(layer "F.Cu")
		(hatch none 0.5)
		(connect_pads
			(clearance 0.5)
		)
		(min_thickness 0.25)
		(fill yes
			(thermal_gap 0.5)
			(thermal_bridge_width 0.5)
			(island_removal_mode 0)
		)
		(polygon
			(pts
				(xy 54.622446 -59.944) (xy 54.393846 -60.1726) (xy 54.393846 -61.508894) (xy 54.520846 -61.635894)
				(xy 55.790846 -61.635894) (xy 58.330846 -64.175894) (xy 62.775846 -64.175894) (xy 62.902846 -64.048894)
				(xy 62.902846 -63.286894) (xy 62.775846 -63.159894) (xy 59.38774 -63.159894) (xy 56.171846 -59.944)
			)
		)
	)
	(zone
		(layer "F.Cu")
		(hatch none 0.5)
		(connect_pads
			(clearance 0)
		)
		(min_thickness 0.25)
		(keepout
			(tracks allowed)
			(vias allowed)
			(pads allowed)
			(copperpour allowed)
			(footprints allowed)
		)
		(placement
			(enabled no)
			(sheetname "")
		)
		(fill
			(thermal_gap 0.5)
			(thermal_bridge_width 0.5)
			(island_removal_mode 0)
		)
		(polygon
			(pts
				(xy 375.065798 -147.502118) (xy 374.131332 -147.502118) (xy 374.131332 -145.967958) (xy 375.065798 -145.967958)
			)
		)
	)
	(zone
		(net "P5V_HDD2")
		(layer "F.Cu")
		(hatch none 0.5)
		(connect_pads
			(clearance 0.5)
		)
		(min_thickness 0.25)
		(fill yes
			(thermal_gap 0.5)
			(thermal_bridge_width 0.5)
			(island_removal_mode 0)
		)
		(polygon
			(pts
				(xy 82.768948 -286.682942) (xy 82.514948 -286.936942) (xy 82.514948 -289.222942) (xy 82.768948 -289.476942)
				(xy 82.768948 -291.508942) (xy 83.530948 -292.270942) (xy 83.530948 -293.032942) (xy 83.911948 -293.413942)
				(xy 84.292948 -293.413942) (xy 87.467948 -296.588942) (xy 94.325948 -296.588942) (xy 94.452948 -296.461942)
				(xy 94.452948 -294.683942) (xy 94.325948 -294.556942) (xy 89.245948 -294.556942) (xy 87.340948 -292.651942)
				(xy 86.451948 -292.651942) (xy 85.562948 -291.762942) (xy 85.562948 -289.222942) (xy 86.197948 -288.587942)
				(xy 86.197948 -286.936942) (xy 85.943948 -286.682942)
			)
		)
		(polygon
			(pts
				(xy 84.775548 -293.109142) (xy 84.572348 -293.109142) (xy 84.572348 -293.312342) (xy 84.775548 -293.312342)
			)
		)
		(polygon
			(pts
				(xy 84.775548 -292.245542) (xy 84.572348 -292.245542) (xy 84.572348 -292.448742) (xy 84.775548 -292.448742)
			)
		)
		(polygon
			(pts
				(xy 83.911948 -292.245542) (xy 83.708748 -292.245542) (xy 83.708748 -292.448742) (xy 83.911948 -292.448742)
			)
		)
	)
	(zone
		(net "5V_PRE_30")
		(layer "F.Cu")
		(hatch none 0.5)
		(connect_pads
			(clearance 0.5)
		)
		(min_thickness 0.25)
		(fill yes
			(thermal_gap 0.5)
			(thermal_bridge_width 0.5)
			(island_removal_mode 0)
		)
		(polygon
			(pts
				(xy 329.438 -59.984894) (xy 329.184 -60.238894) (xy 329.184 -62.778894) (xy 328.803 -63.159894)
				(xy 326.263 -63.159894) (xy 326.009 -63.413894) (xy 326.009 -63.794894) (xy 326.263 -64.048894)
				(xy 329.565 -64.048894) (xy 330.835 -62.778894) (xy 330.835 -60.238894) (xy 330.581 -59.984894)
			)
		)
	)
	(zone
		(net "5V_PRE_17")
		(layer "F.Cu")
		(hatch none 0.5)
		(connect_pads
			(clearance 0.5)
		)
		(min_thickness 0.25)
		(fill yes
			(thermal_gap 0.5)
			(thermal_bridge_width 0.5)
			(island_removal_mode 0)
		)
		(polygon
			(pts
				(xy 180.721 -174.9552) (xy 180.594 -175.0822) (xy 180.594 -176.508918) (xy 180.721 -176.635918)
				(xy 181.991 -176.635918) (xy 184.531 -179.175918) (xy 188.976 -179.175918) (xy 189.103 -179.048918)
				(xy 189.103 -178.286918) (xy 188.976 -178.159918) (xy 186.0296 -178.159918) (xy 182.824882 -174.9552)
			)
		)
	)
	(zone
		(layer "F.Cu")
		(hatch none 0.5)
		(connect_pads
			(clearance 0)
		)
		(min_thickness 0.25)
		(keepout
			(tracks not_allowed)
			(vias allowed)
			(pads allowed)
			(copperpour not_allowed)
			(footprints allowed)
		)
		(placement
			(enabled no)
			(sheetname "")
		)
		(fill
			(thermal_gap 0.5)
			(thermal_bridge_width 0.5)
			(island_removal_mode 0)
		)
		(polygon
			(pts
				(arc
					(start 415.020252 -158.368492)
					(mid 414.639252 -157.987492)
					(end 414.258252 -158.368492)
				)
				(arc
					(start 414.258252 -159.511238)
					(mid 414.639125 -159.892492)
					(end 415.020252 -159.511492)
				)
				(xy 415.020252 -159.162242)
				(arc
					(start 414.792414 -159.162242)
					(mid 414.773057 -159.166075)
					(end 414.7566 -159.176974)
				)
				(arc
					(start 414.730184 -159.20339)
					(mid 414.719258 -159.219836)
					(end 414.715452 -159.239204)
				)
				(arc
					(start 414.715452 -159.255968)
					(mid 414.639252 -159.778136)
					(end 414.563052 -159.255968)
				)
				(xy 414.563052 -159.207708)
				(arc
					(start 414.5661 -159.20466)
					(mid 414.578535 -159.161497)
					(end 414.600136 -159.12211)
				)
				(xy 414.600136 -159.118046) (xy 414.671256 -159.046926)
				(arc
					(start 414.67532 -159.046926)
					(mid 414.714698 -159.025304)
					(end 414.75787 -159.01289)
				)
				(xy 414.760918 -159.009842) (xy 415.020252 -159.009842) (xy 415.020252 -158.870142) (xy 414.743138 -158.870142)
				(arc
					(start 414.74009 -158.867094)
					(mid 414.696927 -158.854659)
					(end 414.65754 -158.833058)
				)
				(xy 414.653476 -158.833058) (xy 414.600136 -158.779718)
				(arc
					(start 414.600136 -158.775654)
					(mid 414.578514 -158.736276)
					(end 414.5661 -158.693104)
				)
				(xy 414.563052 -158.690056)
				(arc
					(start 414.563052 -158.624016)
					(mid 414.639252 -158.101848)
					(end 414.715452 -158.624016)
				)
				(arc
					(start 414.715452 -158.65856)
					(mid 414.719285 -158.677917)
					(end 414.730184 -158.694374)
				)
				(arc
					(start 414.73882 -158.70301)
					(mid 414.755266 -158.713936)
					(end 414.774634 -158.717742)
				)
				(xy 415.020252 -158.717742)
			)
		)
	)
	(zone
		(layer "F.Cu")
		(hatch none 0.5)
		(connect_pads
			(clearance 0)
		)
		(min_thickness 0.25)
		(keepout
			(tracks not_allowed)
			(vias allowed)
			(pads allowed)
			(copperpour not_allowed)
			(footprints allowed)
		)
		(placement
			(enabled no)
			(sheetname "")
		)
		(fill
			(thermal_gap 0.5)
			(thermal_bridge_width 0.5)
			(island_removal_mode 0)
		)
		(polygon
			(pts
				(arc
					(start 440.2201 -158.368492)
					(mid 439.8391 -157.987492)
					(end 439.4581 -158.368492)
				)
				(arc
					(start 439.4581 -159.511238)
					(mid 439.838973 -159.892492)
					(end 440.2201 -159.511492)
				)
				(xy 440.2201 -159.162242)
				(arc
					(start 439.989976 -159.162242)
					(mid 439.970619 -159.166075)
					(end 439.954162 -159.176974)
				)
				(arc
					(start 439.930032 -159.201104)
					(mid 439.919106 -159.21755)
					(end 439.9153 -159.236918)
				)
				(arc
					(start 439.9153 -159.255968)
					(mid 439.8391 -159.778136)
					(end 439.7629 -159.255968)
				)
				(xy 439.7629 -159.205422)
				(arc
					(start 439.765948 -159.202374)
					(mid 439.778383 -159.159211)
					(end 439.799984 -159.119824)
				)
				(xy 439.799984 -159.11576) (xy 439.868818 -159.046926)
				(arc
					(start 439.872882 -159.046926)
					(mid 439.91226 -159.025304)
					(end 439.955432 -159.01289)
				)
				(xy 439.95848 -159.009842) (xy 440.2201 -159.009842) (xy 440.2201 -158.870142) (xy 439.94832 -158.870142)
				(arc
					(start 439.945272 -158.867094)
					(mid 439.902109 -158.854659)
					(end 439.862722 -158.833058)
				)
				(xy 439.858658 -158.833058) (xy 439.799984 -158.774384)
				(arc
					(start 439.799984 -158.77032)
					(mid 439.778362 -158.730942)
					(end 439.765948 -158.68777)
				)
				(xy 439.7629 -158.684722)
				(arc
					(start 439.7629 -158.624016)
					(mid 439.8391 -158.101848)
					(end 439.9153 -158.624016)
				)
				(arc
					(start 439.9153 -158.653226)
					(mid 439.919133 -158.672583)
					(end 439.930032 -158.68904)
				)
				(arc
					(start 439.944002 -158.70301)
					(mid 439.960448 -158.713936)
					(end 439.979816 -158.717742)
				)
				(xy 440.2201 -158.717742)
			)
		)
	)
	(zone
		(layer "F.Cu")
		(hatch none 0.5)
		(connect_pads
			(clearance 0)
		)
		(min_thickness 0.25)
		(keepout
			(tracks allowed)
			(vias allowed)
			(pads allowed)
			(copperpour allowed)
			(footprints not_allowed)
		)
		(placement
			(enabled no)
			(sheetname "")
		)
		(fill
			(thermal_gap 0.5)
			(thermal_bridge_width 0.5)
			(island_removal_mode 0)
		)
		(polygon
			(pts
				(xy 298.200064 -233.19994) (xy 291.599874 -233.19994) (xy 291.599874 -154.200098) (xy 298.200064 -154.200098)
			)
		)
	)
	(zone
		(net "P12V_A")
		(layer "F.Cu")
		(hatch none 0.5)
		(connect_pads
			(clearance 0.5)
		)
		(min_thickness 0.25)
		(fill yes
			(thermal_gap 0.5)
			(thermal_bridge_width 0.5)
			(island_removal_mode 0)
		)
		(polygon
			(pts
				(xy 283.654246 -225.04908) (xy 283.162502 -225.540824) (xy 283.162502 -228.334062) (xy 283.82976 -229.00132)
				(xy 286.737806 -229.00132) (xy 286.91713 -228.821996) (xy 286.91713 -225.294698) (xy 286.671512 -225.04908)
			)
		)
	)
	(zone
		(layer "F.Cu")
		(hatch none 0.5)
		(connect_pads
			(clearance 0)
		)
		(min_thickness 0.25)
		(keepout
			(tracks allowed)
			(vias allowed)
			(pads allowed)
			(copperpour allowed)
			(footprints not_allowed)
		)
		(placement
			(enabled no)
			(sheetname "")
		)
		(fill
			(thermal_gap 0.5)
			(thermal_bridge_width 0.5)
			(island_removal_mode 0)
		)
		(polygon
			(pts
				(arc
					(start 7.599934 -120.499886)
					(mid 3.850132 -124.249688)
					(end 0.100076 -120.499886)
				)
				(arc
					(start 0.100076 -120.499886)
					(mid 3.850132 -116.74983)
					(end 7.599934 -120.499886)
				)
			)
		)
	)
	(zone
		(layer "F.Cu")
		(hatch none 0.5)
		(connect_pads
			(clearance 0)
		)
		(min_thickness 0.25)
		(keepout
			(tracks allowed)
			(vias allowed)
			(pads allowed)
			(copperpour allowed)
			(footprints allowed)
		)
		(placement
			(enabled no)
			(sheetname "")
		)
		(fill
			(thermal_gap 0.5)
			(thermal_bridge_width 0.5)
			(island_removal_mode 0)
		)
		(polygon
			(pts
				(xy 338.2264 -29.972) (xy 338.2264 -32.893) (xy 336.296 -32.893) (xy 336.296 -29.972)
			)
		)
	)
	(zone
		(layer "F.Cu")
		(hatch none 0.5)
		(connect_pads
			(clearance 0)
		)
		(min_thickness 0.25)
		(keepout
			(tracks allowed)
			(vias allowed)
			(pads allowed)
			(copperpour allowed)
			(footprints not_allowed)
		)
		(placement
			(enabled no)
			(sheetname "")
		)
		(fill
			(thermal_gap 0.5)
			(thermal_bridge_width 0.5)
			(island_removal_mode 0)
		)
		(polygon
			(pts
				(xy 198.399908 -48.150018) (xy 198.399908 -30.31998) (xy 215.629998 -30.31998) (xy 225.03003 -30.31998)
				(xy 225.03003 -22.61997) (xy 215.629998 -22.61997) (xy 215.629998 -30.219904) (xy 198.399908 -30.219904)
				(xy 198.399908 -21.299932) (xy 215.629998 -21.299932) (xy 225.03003 -21.299932) (xy 225.03003 -13.599922)
				(xy 215.629998 -13.599922) (xy 215.629998 -21.20011) (xy 198.399908 -21.20011) (xy 198.399908 -18.999962)
				(xy 201.399902 -18.999962) (xy 209.099912 -18.999962) (xy 209.099912 -9.59993) (xy 201.399902 -9.59993)
				(xy 201.399902 -18.899886) (xy 198.399908 -18.899886) (xy 198.399908 0)
				(arc
					(start 199.00011 0)
					(mid 199.707215 0.292893)
					(end 200.000108 0.999998)
				)
				(arc
					(start 200.000108 0.999998)
					(mid 200.293001 1.707103)
					(end 201.000106 1.999996)
				)
				(arc
					(start 219.00007 1.999996)
					(mid 219.707175 2.292889)
					(end 220.000068 2.999994)
				)
				(arc
					(start 220.000068 37.800026)
					(mid 220.292961 38.507131)
					(end 221.000066 38.800024)
				)
				(xy 291.599874 38.800024) (xy 291.599874 -10.199878) (xy 267.990066 -10.199878) (xy 267.990066 -2.599944)
				(xy 258.590034 -2.599944) (xy 258.590034 -10.299954) (xy 267.990066 -10.299954) (xy 291.599874 -10.299954)
				(xy 291.599874 -20.200112) (xy 267.759942 -20.200112) (xy 267.759942 -12.599924) (xy 258.35991 -12.599924)
				(xy 258.35991 -20.299934) (xy 267.759942 -20.299934) (xy 291.599874 -20.299934) (xy 291.599874 -34.399982)
				(xy 267.670026 -34.399982) (xy 267.670026 -25.100026) (xy 259.970016 -25.100026) (xy 259.970016 -34.500058)
				(xy 267.670026 -34.500058) (xy 291.599874 -34.500058) (xy 291.599874 -48.150018)
			)
		)
	)
	(zone
		(net "P12V_A")
		(layer "F.Cu")
		(hatch none 0.5)
		(connect_pads
			(clearance 0.5)
		)
		(min_thickness 0.25)
		(fill yes
			(thermal_gap 0.5)
			(thermal_bridge_width 0.5)
			(island_removal_mode 0)
		)
		(polygon
			(pts
				(xy 14.207998 -284.142942) (xy 13.191998 -285.158942) (xy 12.556998 -285.158942) (xy 12.175998 -285.539942)
				(xy 12.175998 -288.079942) (xy 12.429998 -288.333942) (xy 15.731998 -288.333942) (xy 15.985998 -288.079942)
				(xy 15.985998 -285.793942) (xy 15.350998 -285.158942) (xy 14.969998 -285.158942) (xy 14.715998 -284.904942)
				(xy 14.715998 -284.269942) (xy 14.588998 -284.142942)
			)
		)
		(polygon
			(pts
				(xy 14.182598 -284.727142) (xy 13.979398 -284.727142) (xy 13.979398 -284.930342) (xy 14.182598 -284.930342)
			)
		)
	)
	(zone
		(layer "F.Cu")
		(hatch none 0.5)
		(connect_pads
			(clearance 0)
		)
		(min_thickness 0.25)
		(keepout
			(tracks allowed)
			(vias allowed)
			(pads allowed)
			(copperpour allowed)
			(footprints allowed)
		)
		(placement
			(enabled no)
			(sheetname "")
		)
		(fill
			(thermal_gap 0.5)
			(thermal_bridge_width 0.5)
			(island_removal_mode 0)
		)
		(polygon
			(pts
				(xy 248.8946 -296.3164) (xy 248.8946 -293.5478) (xy 247.707404 -293.5478) (xy 247.707404 -296.3164)
			)
		)
	)
	(zone
		(layer "F.Cu")
		(hatch none 0.5)
		(connect_pads
			(clearance 0)
		)
		(min_thickness 0.25)
		(keepout
			(tracks not_allowed)
			(vias allowed)
			(pads allowed)
			(copperpour not_allowed)
			(footprints allowed)
		)
		(placement
			(enabled no)
			(sheetname "")
		)
		(fill
			(thermal_gap 0.5)
			(thermal_bridge_width 0.5)
			(island_removal_mode 0)
		)
		(polygon
			(pts
				(arc
					(start 382.7653 -45.7708)
					(mid 382.3843 -46.1518)
					(end 382.7653 -46.5328)
				)
				(arc
					(start 383.908046 -46.5328)
					(mid 384.2893 -46.151927)
					(end 383.9083 -45.7708)
				)
				(xy 383.55905 -45.7708)
				(arc
					(start 383.55905 -46.022768)
					(mid 383.562883 -46.042125)
					(end 383.573782 -46.058582)
				)
				(arc
					(start 383.576068 -46.060868)
					(mid 383.592514 -46.071794)
					(end 383.611882 -46.0756)
				)
				(arc
					(start 383.652776 -46.0756)
					(mid 384.174944 -46.1518)
					(end 383.652776 -46.228)
				)
				(xy 383.580386 -46.228)
				(arc
					(start 383.577338 -46.224952)
					(mid 383.534175 -46.212517)
					(end 383.494788 -46.190916)
				)
				(xy 383.490724 -46.190916) (xy 383.443734 -46.143926)
				(arc
					(start 383.443734 -46.139862)
					(mid 383.422112 -46.100484)
					(end 383.409698 -46.057312)
				)
				(xy 383.40665 -46.054264) (xy 383.40665 -45.7708) (xy 383.26695 -45.7708) (xy 383.26695 -46.046644)
				(arc
					(start 383.263902 -46.049692)
					(mid 383.251467 -46.092855)
					(end 383.229866 -46.132242)
				)
				(xy 383.229866 -46.136306) (xy 383.175256 -46.190916)
				(arc
					(start 383.171192 -46.190916)
					(mid 383.131814 -46.212538)
					(end 383.088642 -46.224952)
				)
				(xy 383.085594 -46.228)
				(arc
					(start 383.020824 -46.228)
					(mid 382.498656 -46.1518)
					(end 383.020824 -46.0756)
				)
				(arc
					(start 383.054098 -46.0756)
					(mid 383.073455 -46.071767)
					(end 383.089912 -46.060868)
				)
				(arc
					(start 383.099818 -46.050962)
					(mid 383.110744 -46.034516)
					(end 383.11455 -46.015148)
				)
				(xy 383.11455 -45.7708)
			)
		)
	)
	(zone
		(layer "F.Cu")
		(hatch none 0.5)
		(connect_pads
			(clearance 0)
		)
		(min_thickness 0.25)
		(keepout
			(tracks allowed)
			(vias allowed)
			(pads allowed)
			(copperpour allowed)
			(footprints not_allowed)
		)
		(placement
			(enabled no)
			(sheetname "")
		)
		(fill
			(thermal_gap 0.5)
			(thermal_bridge_width 0.5)
			(island_removal_mode 0)
		)
		(polygon
			(pts
				(xy 191.799972 -199.799956) (xy 191.799972 -240.799874) (xy 0 -240.799874) (xy 0 -190.799974) (xy 8.349996 -190.799974)
				(xy 8.349996 -180.799994) (xy 22.899878 -180.799994) (xy 22.899878 -190.799974) (xy 39.900098 -190.799974)
				(xy 39.900098 -180.799994) (xy 54.44998 -180.799994) (xy 54.44998 -190.799974) (xy 71.449946 -190.799974)
				(xy 71.449946 -180.799994) (xy 86.000082 -180.799994) (xy 86.000082 -190.799974) (xy 103.000048 -190.799974)
				(xy 103.000048 -180.799994) (xy 117.54993 -180.799994) (xy 117.54993 -190.799974) (xy 134.549896 -190.799974)
				(xy 134.549896 -180.799994) (xy 149.100032 -180.799994) (xy 149.100032 -190.799974) (xy 166.099998 -190.799974)
				(xy 166.099998 -180.799994) (xy 180.64988 -180.799994) (xy 180.64988 -190.799974) (xy 189.799976 -190.799974)
				(xy 189.799976 -199.799956)
			)
		)
	)
	(zone
		(net "P12V_A")
		(layer "F.Cu")
		(hatch none 0.5)
		(connect_pads
			(clearance 0.5)
		)
		(min_thickness 0.25)
		(fill yes
			(thermal_gap 0.5)
			(thermal_bridge_width 0.5)
			(island_removal_mode 0)
		)
		(polygon
			(pts
				(xy 77.307948 -54.142894) (xy 76.291948 -55.158894) (xy 75.656948 -55.158894) (xy 75.275948 -55.539894)
				(xy 75.275948 -58.079894) (xy 75.529948 -58.333894) (xy 78.831948 -58.333894) (xy 79.085948 -58.079894)
				(xy 79.085948 -55.793894) (xy 78.450948 -55.158894) (xy 78.069948 -55.158894) (xy 77.815948 -54.904894)
				(xy 77.815948 -54.269894) (xy 77.688948 -54.142894)
			)
		)
		(polygon
			(pts
				(xy 77.282548 -54.727094) (xy 77.079348 -54.727094) (xy 77.079348 -54.930294) (xy 77.282548 -54.930294)
			)
		)
	)
	(zone
		(net "AGND_CURRENT_MONOB")
		(layer "F.Cu")
		(hatch none 0.5)
		(connect_pads
			(clearance 0.5)
		)
		(min_thickness 0.25)
		(fill yes
			(thermal_gap 0.5)
			(thermal_bridge_width 0.5)
			(island_removal_mode 0)
		)
		(polygon
			(pts
				(xy 364.570518 -129.69494) (xy 364.109 -130.156458) (xy 364.109 -131.8514) (xy 364.2106 -131.953)
				(xy 365.9378 -131.953) (xy 366.141 -132.1562) (xy 366.141 -132.3848) (xy 366.2172 -132.461) (xy 367.1824 -132.461)
				(xy 367.284 -132.3594) (xy 367.284 -132.1308) (xy 367.4618 -131.953) (xy 372.7196 -131.953) (xy 372.8212 -131.8514)
				(xy 372.8212 -130.556) (xy 372.829328 -130.547872) (xy 372.829328 -130.021584) (xy 372.502684 -129.69494)
			)
		)
		(polygon
			(pts
				(xy 367.2332 -131.4958) (xy 367.03 -131.4958) (xy 367.03 -131.699) (xy 367.2332 -131.699)
			)
		)
		(polygon
			(pts
				(xy 366.3696 -131.4958) (xy 366.1664 -131.4958) (xy 366.1664 -131.699) (xy 366.3696 -131.699)
			)
		)
		(polygon
			(pts
				(xy 364.9218 -131.2926) (xy 364.7186 -131.2926) (xy 364.7186 -131.4958) (xy 364.9218 -131.4958)
			)
		)
		(polygon
			(pts
				(xy 370.316506 -131.283964) (xy 370.113306 -131.283964) (xy 370.113306 -131.487164) (xy 370.316506 -131.487164)
			)
		)
		(polygon
			(pts
				(xy 369.757706 -131.283964) (xy 369.554506 -131.283964) (xy 369.554506 -131.487164) (xy 369.757706 -131.487164)
			)
		)
		(polygon
			(pts
				(xy 368.239294 -131.275836) (xy 368.036094 -131.275836) (xy 368.036094 -131.479036) (xy 368.239294 -131.479036)
			)
		)
		(polygon
			(pts
				(xy 367.680494 -131.275836) (xy 367.477294 -131.275836) (xy 367.477294 -131.479036) (xy 367.680494 -131.479036)
			)
		)
		(polygon
			(pts
				(xy 372.6942 -131.2418) (xy 372.491 -131.2418) (xy 372.491 -131.445) (xy 372.6942 -131.445)
			)
		)
		(polygon
			(pts
				(xy 372.0846 -131.2418) (xy 371.8814 -131.2418) (xy 371.8814 -131.445) (xy 372.0846 -131.445)
			)
		)
		(polygon
			(pts
				(xy 371.2972 -131.2418) (xy 371.094 -131.2418) (xy 371.094 -131.445) (xy 371.2972 -131.445)
			)
		)
		(polygon
			(pts
				(xy 370.6876 -131.2418) (xy 370.4844 -131.2418) (xy 370.4844 -131.445) (xy 370.6876 -131.445)
			)
		)
		(polygon
			(pts
				(xy 369.2652 -131.2418) (xy 369.062 -131.2418) (xy 369.062 -131.445) (xy 369.2652 -131.445)
			)
		)
		(polygon
			(pts
				(xy 368.6556 -131.2418) (xy 368.4524 -131.2418) (xy 368.4524 -131.445) (xy 368.6556 -131.445)
			)
		)
		(polygon
			(pts
				(xy 365.9632 -131.2418) (xy 365.76 -131.2418) (xy 365.76 -131.445) (xy 365.9632 -131.445)
			)
		)
		(polygon
			(pts
				(xy 365.3536 -131.2418) (xy 365.1504 -131.2418) (xy 365.1504 -131.445) (xy 365.3536 -131.445)
			)
		)
	)
	(zone
		(layer "F.Cu")
		(hatch none 0.5)
		(connect_pads
			(clearance 0)
		)
		(min_thickness 0.25)
		(keepout
			(tracks allowed)
			(vias allowed)
			(pads allowed)
			(copperpour allowed)
			(footprints not_allowed)
		)
		(placement
			(enabled no)
			(sheetname "")
		)
		(fill
			(thermal_gap 0.5)
			(thermal_bridge_width 0.5)
			(island_removal_mode 0)
		)
		(polygon
			(pts
				(arc
					(start 237.199932 -360.19994)
					(mid 244.199918 -353.199954)
					(end 251.199904 -360.19994)
				)
				(arc
					(start 251.199904 -366.199928)
					(mid 244.199918 -373.199914)
					(end 237.199932 -366.199928)
				)
			)
		)
	)
	(zone
		(net "P12V_HDD4")
		(layer "F.Cu")
		(hatch none 0.5)
		(connect_pads
			(clearance 0.5)
		)
		(min_thickness 0.25)
		(fill yes
			(thermal_gap 0.5)
			(thermal_bridge_width 0.5)
			(island_removal_mode 0)
		)
		(polygon
			(pts
				(xy 138.898122 -291.254942) (xy 138.696954 -291.45611) (xy 138.696954 -293.266368) (xy 138.844528 -293.413942)
				(xy 140.661898 -293.413942) (xy 141.169898 -293.921942) (xy 141.169898 -296.461942) (xy 148.916898 -304.208942)
				(xy 157.425898 -304.208942) (xy 157.552898 -304.081942) (xy 157.552898 -302.303942) (xy 157.425898 -302.176942)
				(xy 151.456898 -302.176942) (xy 150.821898 -301.541942) (xy 149.170898 -301.541942) (xy 144.852898 -297.223942)
				(xy 144.852898 -293.667942) (xy 143.709898 -292.524942) (xy 143.709898 -291.508942) (xy 143.455898 -291.254942)
			)
		)
		(polygon
			(pts
				(xy 150.974298 -303.218342) (xy 150.771098 -303.218342) (xy 150.771098 -303.421542) (xy 150.974298 -303.421542)
			)
		)
		(polygon
			(pts
				(xy 150.110698 -303.218342) (xy 149.907498 -303.218342) (xy 149.907498 -303.421542) (xy 150.110698 -303.421542)
			)
		)
	)
	(zone
		(layer "F.Cu")
		(hatch none 0.5)
		(connect_pads
			(clearance 0)
		)
		(min_thickness 0.25)
		(keepout
			(tracks not_allowed)
			(vias allowed)
			(pads allowed)
			(copperpour not_allowed)
			(footprints allowed)
		)
		(placement
			(enabled no)
			(sheetname "")
		)
		(fill
			(thermal_gap 0.5)
			(thermal_bridge_width 0.5)
			(island_removal_mode 0)
		)
		(polygon
			(pts
				(arc
					(start 350.764856 -42.240962)
					(mid 350.378522 -42.626915)
					(end 350.764602 -43.013122)
				)
				(xy 351.140522 -43.013122)
				(arc
					(start 351.140522 -42.754042)
					(mid 351.125643 -42.718121)
					(end 351.089722 -42.703242)
				)
				(arc
					(start 351.020126 -42.703242)
					(mid 350.497958 -42.627042)
					(end 351.020126 -42.550842)
				)
				(xy 351.121218 -42.550842)
				(arc
					(start 351.124266 -42.55389)
					(mid 351.233343 -42.610421)
					(end 351.289874 -42.719498)
				)
				(xy 351.292922 -42.722546) (xy 351.292922 -43.013122) (xy 351.432622 -43.013122) (xy 351.432622 -42.722546)
				(arc
					(start 351.43567 -42.719498)
					(mid 351.492201 -42.610421)
					(end 351.601278 -42.55389)
				)
				(xy 351.604326 -42.550842)
				(arc
					(start 351.652078 -42.550842)
					(mid 352.174246 -42.627042)
					(end 351.652078 -42.703242)
				)
				(arc
					(start 351.635822 -42.703242)
					(mid 351.599901 -42.718121)
					(end 351.585022 -42.754042)
				)
				(xy 351.585022 -43.013122)
				(arc
					(start 351.907602 -43.013122)
					(mid 352.293682 -42.627042)
					(end 351.907602 -42.240962)
				)
			)
		)
	)
	(zone
		(net "12V_PRE_1")
		(layer "F.Cu")
		(hatch none 0.5)
		(connect_pads
			(clearance 0.5)
		)
		(min_thickness 0.25)
		(fill yes
			(thermal_gap 0.5)
			(thermal_bridge_width 0.5)
			(island_removal_mode 0)
		)
		(polygon
			(pts
				(xy 51.218846 -293.794942) (xy 51.091846 -293.921942) (xy 51.091846 -295.445942) (xy 52.488846 -296.842942)
				(xy 53.885846 -296.842942) (xy 58.838846 -301.795942) (xy 62.775846 -301.795942) (xy 62.902846 -301.668942)
				(xy 62.902846 -300.906942) (xy 62.775846 -300.779942) (xy 59.473846 -300.779942) (xy 52.488846 -293.794942)
			)
		)
	)
	(zone
		(net "P5V_A_3")
		(layer "F.Cu")
		(hatch none 0.5)
		(connect_pads
			(clearance 0.5)
		)
		(min_thickness 0.25)
		(fill yes
			(thermal_gap 0.5)
			(thermal_bridge_width 0.5)
			(island_removal_mode 0)
		)
		(polygon
			(pts
				(xy 336.563716 -165.332918) (xy 336.29473 -165.601904) (xy 336.29473 -170.293284) (xy 336.541364 -170.539918)
				(xy 339.178138 -170.539918) (xy 339.347556 -170.3705) (xy 339.347556 -165.6207) (xy 339.059774 -165.332918)
			)
		)
	)
	(zone
		(layer "F.Cu")
		(hatch none 0.5)
		(connect_pads
			(clearance 0)
		)
		(min_thickness 0.25)
		(keepout
			(tracks not_allowed)
			(vias allowed)
			(pads allowed)
			(copperpour not_allowed)
			(footprints allowed)
		)
		(placement
			(enabled no)
			(sheetname "")
		)
		(fill
			(thermal_gap 0.5)
			(thermal_bridge_width 0.5)
			(island_removal_mode 0)
		)
		(polygon
			(pts
				(arc
					(start 64.4398 -277.17877)
					(mid 64.058927 -276.797516)
					(end 63.6778 -277.178516)
				)
				(xy 63.6778 -277.527766)
				(arc
					(start 63.9318 -277.527766)
					(mid 63.967721 -277.512887)
					(end 63.9826 -277.476966)
				)
				(arc
					(start 63.9826 -277.43404)
					(mid 64.0588 -276.911872)
					(end 64.135 -277.43404)
				)
				(xy 64.135 -277.508462)
				(arc
					(start 64.131952 -277.51151)
					(mid 64.075421 -277.620587)
					(end 63.966344 -277.677118)
				)
				(xy 63.963296 -277.680166) (xy 63.6778 -277.680166) (xy 63.6778 -277.819866) (xy 63.963296 -277.819866)
				(arc
					(start 63.966344 -277.822914)
					(mid 64.075421 -277.879445)
					(end 64.131952 -277.988522)
				)
				(xy 64.135 -277.99157)
				(arc
					(start 64.135 -278.065992)
					(mid 64.0588 -278.58816)
					(end 63.9826 -278.065992)
				)
				(arc
					(start 63.9826 -278.023066)
					(mid 63.967721 -277.987145)
					(end 63.9318 -277.972266)
				)
				(xy 63.6778 -277.972266)
				(arc
					(start 63.6778 -278.321516)
					(mid 64.0588 -278.702516)
					(end 64.4398 -278.321516)
				)
			)
		)
	)
	(zone
		(layer "F.Cu")
		(hatch none 0.5)
		(connect_pads
			(clearance 0)
		)
		(min_thickness 0.25)
		(keepout
			(tracks allowed)
			(vias allowed)
			(pads allowed)
			(copperpour allowed)
			(footprints allowed)
		)
		(placement
			(enabled no)
			(sheetname "")
		)
		(fill
			(thermal_gap 0.5)
			(thermal_bridge_width 0.5)
			(island_removal_mode 0)
		)
		(polygon
			(pts
				(xy 267.335 -275.971) (xy 267.335 -273.4564) (xy 268.351 -273.4564) (xy 268.351 -275.971)
			)
		)
	)
	(zone
		(layer "F.Cu")
		(hatch none 0.5)
		(connect_pads
			(clearance 0)
		)
		(min_thickness 0.25)
		(keepout
			(tracks not_allowed)
			(vias allowed)
			(pads allowed)
			(copperpour not_allowed)
			(footprints allowed)
		)
		(placement
			(enabled no)
			(sheetname "")
		)
		(fill
			(thermal_gap 0.5)
			(thermal_bridge_width 0.5)
			(island_removal_mode 0)
		)
		(polygon
			(pts
				(arc
					(start 123.150122 -28.079954)
					(mid 126.150116 -25.07996)
					(end 129.15011 -28.079954)
				)
				(arc
					(start 129.15011 -28.079954)
					(mid 126.150116 -31.079948)
					(end 123.150122 -28.079954)
				)
			)
		)
	)
	(zone
		(layer "F.Cu")
		(hatch none 0.5)
		(connect_pads
			(clearance 0)
		)
		(min_thickness 0.25)
		(keepout
			(tracks allowed)
			(vias allowed)
			(pads allowed)
			(copperpour allowed)
			(footprints not_allowed)
		)
		(placement
			(enabled no)
			(sheetname "")
		)
		(fill
			(thermal_gap 0.5)
			(thermal_bridge_width 0.5)
			(island_removal_mode 0)
		)
		(polygon
			(pts
				(arc
					(start 477.499934 -5.500116)
					(mid 481.24999 -1.75006)
					(end 485.000046 -5.500116)
				)
				(arc
					(start 485.000046 -5.500116)
					(mid 481.24999 -9.250172)
					(end 477.499934 -5.500116)
				)
			)
		)
	)
	(zone
		(layer "F.Cu")
		(hatch none 0.5)
		(connect_pads
			(clearance 0)
		)
		(min_thickness 0.25)
		(keepout
			(tracks allowed)
			(vias allowed)
			(pads allowed)
			(copperpour allowed)
			(footprints allowed)
		)
		(placement
			(enabled no)
			(sheetname "")
		)
		(fill
			(thermal_gap 0.5)
			(thermal_bridge_width 0.5)
			(island_removal_mode 0)
		)
		(polygon
			(pts
				(xy 364.461298 -279.038558) (xy 364.461298 -278.09952) (xy 365.995458 -278.09952) (xy 365.995458 -279.038558)
			)
		)
	)
	(zone
		(net "GND")
		(layer "F.Cu")
		(hatch none 0.5)
		(connect_pads
			(clearance 0.5)
		)
		(min_thickness 0.25)
		(fill yes
			(thermal_gap 0.5)
			(thermal_bridge_width 0.5)
			(island_removal_mode 0)
		)
		(polygon
			(pts
				(xy 315.753242 -30.997906) (xy 320.597784 -28.161488) (xy 324.746112 -28.161488) (xy 326.009 -26.8986)
				(arc
					(start 326.009 -25.839674)
					(mid 326.001953 -25.701197)
					(end 325.999602 -25.56256)
				)
				(arc
					(start 325.999602 -25.096216)
					(mid 325.948804 -24.449532)
					(end 325.999602 -23.802848)
				)
				(arc
					(start 325.999602 -21.405088)
					(mid 327.443039 -18.286359)
					(end 330.754736 -17.36852)
				)
				(arc
					(start 330.754736 -17.36852)
					(mid 330.822098 -17.358941)
					(end 330.88961 -17.350486)
				)
				(xy 330.88961 -16.928846) (xy 331.177646 -16.928846) (xy 331.177646 -14.077442)
				(arc
					(start 332.164436 -14.077442)
					(mid 332.210175 -13.58275)
					(end 332.315566 -13.097256)
				)
				(xy 332.315566 -12.121642)
				(arc
					(start 332.733396 -12.121642)
					(mid 334.426248 -10.546249)
					(end 336.702908 -10.140696)
				)
				(arc
					(start 336.702908 -10.140696)
					(mid 337.651886 -10.091625)
					(end 338.586572 -10.26287)
				)
				(arc
					(start 338.586572 -10.26287)
					(mid 340.463399 -10.787792)
					(end 341.884254 -12.121642)
				)
				(xy 345.968066 -12.121642)
				(arc
					(start 345.968066 -13.999972)
					(mid 346.856118 -16.143918)
					(end 349.000064 -17.03197)
				)
				(xy 349.743776 -17.03197) (xy 349.743776 -15.762986)
				(arc
					(start 349.000064 -15.762986)
					(mid 347.753425 -15.246611)
					(end 347.23705 -13.999972)
				)
				(arc
					(start 347.23705 -0.999998)
					(mid 347.16764 -0.832426)
					(end 347.000068 -0.763016)
				)
				(arc
					(start 300.999906 -0.763016)
					(mid 299.753267 -0.246641)
					(end 299.236892 0.999998)
				)
				(arc
					(start 299.236892 37.800026)
					(mid 299.167482 37.967598)
					(end 298.99991 38.037008)
				)
				(arc
					(start 221.000066 38.037008)
					(mid 220.832494 37.967598)
					(end 220.763084 37.800026)
				)
				(xy 220.763084 4.156964) (xy 222.032068 4.156964) (xy 222.032068 12.92225)
				(arc
					(start 225.842322 12.92225)
					(mid 227.688394 13.754877)
					(end 229.689152 14.068298)
				)
				(arc
					(start 229.689152 17.799812)
					(mid 230.599269 22.035363)
					(end 233.168952 25.52319)
				)
				(arc
					(start 233.168952 26.184352)
					(mid 231.774171 29.2608)
					(end 233.168952 32.337248)
				)
				(xy 233.168952 36.768024) (xy 287.131252 36.768024)
				(arc
					(start 287.131252 31.696914)
					(mid 287.944011 29.249878)
					(end 287.131252 26.802842)
				)
				(xy 287.131252 25.447244) (xy 288.417508 24.160734)
				(arc
					(start 288.417508 15.671546)
					(mid 288.117817 14.16481)
					(end 287.264348 12.887452)
				)
				(arc
					(start 287.153858 12.776962)
					(mid 287.362243 12.74865)
					(end 287.568894 12.709652)
				)
				(arc
					(start 287.568894 12.709652)
					(mid 289.882715 13.612505)
					(end 292.292278 13.010134)
				)
				(arc
					(start 292.292278 13.010134)
					(mid 293.260903 12.827316)
					(end 294.157654 12.41806)
				)
				(xy 297.967908 12.41806)
				(arc
					(start 297.967908 0.999998)
					(mid 298.85596 -1.143948)
					(end 300.999906 -2.032)
				)
				(xy 303.518316 -2.032) (xy 303.518316 -5.842254) (xy 303.85258 -6.176518) (xy 307.868828 -6.176518)
				(xy 309.01132 -7.31901) (xy 309.01767 -7.31901) (xy 309.01767 -7.32536) (xy 312.234326 -10.542016)
				(xy 312.234326 -23.973028) (xy 309.697628 -26.509726)
				(arc
					(start 308.770274 -26.509726)
					(mid 308.038782 -26.719612)
					(end 307.281072 -26.790396)
				)
				(xy 304.741072 -26.790396)
				(arc
					(start 304.71364 -26.790396)
					(mid 303.772502 -28.511508)
					(end 302.138334 -29.596588)
				)
				(arc
					(start 302.138334 -29.596588)
					(mid 299.565815 -30.663634)
					(end 296.906442 -29.836364)
				)
				(xy 294.828722 -29.836364) (xy 294.828722 -29.6418) (xy 289.594798 -29.6418)
				(arc
					(start 289.594798 -38.60419)
					(mid 290.819817 -39.13791)
					(end 291.807392 -40.03802)
				)
				(arc
					(start 291.807392 -40.03802)
					(mid 292.65179 -40.71795)
					(end 293.287958 -41.595802)
				)
				(arc
					(start 293.287958 -41.595802)
					(mid 294.353434 -44.103205)
					(end 293.607744 -46.723554)
				)
				(arc
					(start 293.607744 -46.723554)
					(mid 292.085593 -48.838934)
					(end 289.594798 -49.605692)
				)
				(xy 289.594798 -78.596998) (xy 290.068 -79.0702) (xy 290.816284 -79.0702)
				(arc
					(start 294.117268 -75.769216)
					(mid 294.044603 -75.34013)
					(end 294.02024 -74.905616)
				)
				(arc
					(start 294.02024 -73.1266)
					(mid 294.046804 -72.672397)
					(end 294.126158 -72.224392)
				)
				(xy 293.727886 -71.82612)
				(arc
					(start 293.727886 -67.071494)
					(mid 293.634213 -64.927947)
					(end 294.638476 -63.031878)
				)
				(xy 294.638476 -62.660276)
				(arc
					(start 295.035986 -62.660276)
					(mid 295.275403 -62.478913)
					(end 295.527476 -62.315598)
				)
				(xy 295.527476 -59.358276)
				(arc
					(start 298.056554 -59.358276)
					(mid 299.647458 -58.346841)
					(end 301.521876 -58.145426)
				)
				(xy 303.208944 -50.700432)
				(arc
					(start 305.093878 -47.740062)
					(mid 305.361699 -43.838775)
					(end 308.783228 -41.945306)
				)
			)
		)
		(polygon
			(pts
				(xy 334.548734 -2.032) (xy 315.786516 -2.032)
				(arc
					(start 315.786516 -5.842254)
					(mid 315.294054 -7.393895)
					(end 315.103764 -9.01065)
				)
				(arc
					(start 315.103764 -9.01065)
					(mid 313.585108 -15.92698)
					(end 320.553588 -17.184624)
				)
				(arc
					(start 320.553588 -17.184624)
					(mid 328.430545 -16.333186)
					(end 332.246224 -9.389618)
				)
				(arc
					(start 332.246224 -9.389618)
					(mid 333.798316 -7.876167)
					(end 334.54848 -5.842254)
				)
				(xy 334.548734 -5.842254)
			)
		)
	)
	(zone
		(layer "F.Cu")
		(hatch none 0.5)
		(connect_pads
			(clearance 0)
		)
		(min_thickness 0.25)
		(keepout
			(tracks not_allowed)
			(vias allowed)
			(pads allowed)
			(copperpour not_allowed)
			(footprints allowed)
		)
		(placement
			(enabled no)
			(sheetname "")
		)
		(fill
			(thermal_gap 0.5)
			(thermal_bridge_width 0.5)
			(island_removal_mode 0)
		)
		(polygon
			(pts
				(arc
					(start 389.898636 -29.15031)
					(mid 389.350123 -28.601416)
					(end 388.801356 -29.150056)
				)
				(arc
					(start 388.801356 -29.627068)
					(mid 388.863607 -29.615825)
					(end 388.926578 -29.609796)
				)
				(xy 388.927848 -29.60878)
				(arc
					(start 389.222996 -29.60878)
					(mid 389.245447 -29.599481)
					(end 389.254746 -29.57703)
				)
				(arc
					(start 389.254746 -29.532072)
					(mid 389.349996 -28.756344)
					(end 389.445246 -29.532072)
				)
				(xy 389.445246 -29.6164)
				(arc
					(start 389.440928 -29.620972)
					(mid 389.380199 -29.734233)
					(end 389.266938 -29.794962)
				)
				(xy 389.262366 -29.79928)
				(arc
					(start 388.967218 -29.79928)
					(mid 388.883376 -29.805462)
					(end 388.801356 -29.823918)
				)
				(arc
					(start 388.801356 -29.93136)
					(mid 388.862599 -29.912731)
					(end 388.925816 -29.902658)
				)
				(xy 388.927848 -29.90088) (xy 389.262366 -29.90088)
				(arc
					(start 389.266938 -29.905198)
					(mid 389.380199 -29.965927)
					(end 389.440928 -30.079188)
				)
				(xy 389.445246 -30.08376)
				(arc
					(start 389.445246 -30.168088)
					(mid 389.349996 -30.943816)
					(end 389.254746 -30.168088)
				)
				(arc
					(start 389.254746 -30.12313)
					(mid 389.245447 -30.100679)
					(end 389.222996 -30.09138)
				)
				(arc
					(start 388.967218 -30.09138)
					(mid 388.879788 -30.105589)
					(end 388.801356 -30.146752)
				)
				(arc
					(start 388.801356 -30.550104)
					(mid 389.349996 -31.098744)
					(end 389.898636 -30.550104)
				)
			)
		)
	)
	(zone
		(net "P12V_A")
		(layer "F.Cu")
		(hatch none 0.5)
		(connect_pads
			(clearance 0.5)
		)
		(min_thickness 0.25)
		(fill yes
			(thermal_gap 0.5)
			(thermal_bridge_width 0.5)
			(island_removal_mode 0)
		)
		(polygon
			(pts
				(xy 429.295052 -286.428942) (xy 428.787052 -286.936942) (xy 428.787052 -290.365942) (xy 429.041052 -290.619942)
				(xy 432.343052 -290.619942) (xy 432.597052 -290.365942) (xy 432.597052 -288.333942) (xy 432.724052 -288.206942)
				(xy 433.105052 -288.206942) (xy 433.232052 -288.079942) (xy 433.232052 -286.555942) (xy 433.105052 -286.428942)
			)
		)
		(polygon
			(pts
				(xy 432.698652 -287.444942) (xy 432.495452 -287.444942) (xy 432.495452 -287.648142) (xy 432.698652 -287.648142)
			)
		)
		(polygon
			(pts
				(xy 432.749452 -286.987742) (xy 432.546252 -286.987742) (xy 432.546252 -287.190942) (xy 432.749452 -287.190942)
			)
		)
	)
	(zone
		(layer "F.Cu")
		(hatch none 0.5)
		(connect_pads
			(clearance 0)
		)
		(min_thickness 0.25)
		(keepout
			(tracks not_allowed)
			(vias allowed)
			(pads allowed)
			(copperpour not_allowed)
			(footprints allowed)
		)
		(placement
			(enabled no)
			(sheetname "")
		)
		(fill
			(thermal_gap 0.5)
			(thermal_bridge_width 0.5)
			(island_removal_mode 0)
		)
		(polygon
			(pts
				(arc
					(start 446.5701 -43.368468)
					(mid 446.1891 -42.987468)
					(end 445.8081 -43.368468)
				)
				(arc
					(start 445.8081 -44.511214)
					(mid 446.188973 -44.892468)
					(end 446.5701 -44.511468)
				)
				(xy 446.5701 -44.162218)
				(arc
					(start 446.357248 -44.162218)
					(mid 446.337891 -44.166051)
					(end 446.321434 -44.17695)
				)
				(arc
					(start 446.280032 -44.218352)
					(mid 446.269106 -44.234798)
					(end 446.2653 -44.254166)
				)
				(arc
					(start 446.2653 -44.255944)
					(mid 446.1891 -44.778112)
					(end 446.1129 -44.255944)
				)
				(xy 446.1129 -44.22267)
				(arc
					(start 446.115948 -44.219622)
					(mid 446.128383 -44.176459)
					(end 446.149984 -44.137072)
				)
				(xy 446.149984 -44.133008) (xy 446.23609 -44.046902)
				(arc
					(start 446.240154 -44.046902)
					(mid 446.279532 -44.02528)
					(end 446.322704 -44.012866)
				)
				(xy 446.325752 -44.009818) (xy 446.5701 -44.009818) (xy 446.5701 -43.870118) (xy 446.29705 -43.870118)
				(arc
					(start 446.294002 -43.86707)
					(mid 446.250839 -43.854635)
					(end 446.211452 -43.833034)
				)
				(xy 446.207388 -43.833034) (xy 446.149984 -43.77563)
				(arc
					(start 446.149984 -43.771566)
					(mid 446.128362 -43.732188)
					(end 446.115948 -43.689016)
				)
				(xy 446.1129 -43.685968)
				(arc
					(start 446.1129 -43.623992)
					(mid 446.1891 -43.101824)
					(end 446.2653 -43.623992)
				)
				(arc
					(start 446.2653 -43.654472)
					(mid 446.269133 -43.673829)
					(end 446.280032 -43.690286)
				)
				(arc
					(start 446.292732 -43.702986)
					(mid 446.309178 -43.713912)
					(end 446.328546 -43.717718)
				)
				(xy 446.5701 -43.717718)
			)
		)
	)
	(zone
		(layer "F.Cu")
		(hatch none 0.5)
		(connect_pads
			(clearance 0)
		)
		(min_thickness 0.25)
		(keepout
			(tracks allowed)
			(vias allowed)
			(pads allowed)
			(copperpour allowed)
			(footprints allowed)
		)
		(placement
			(enabled no)
			(sheetname "")
		)
		(fill
			(thermal_gap 0.5)
			(thermal_bridge_width 0.5)
			(island_removal_mode 0)
		)
		(polygon
			(pts
				(xy 361.67949 -137.646664) (xy 361.67949 -136.712198) (xy 363.21365 -136.712198) (xy 363.21365 -137.646664)
			)
		)
	)
	(zone
		(net "12V_PRE_9")
		(layer "F.Cu")
		(hatch none 0.5)
		(connect_pads
			(clearance 0.5)
		)
		(min_thickness 0.25)
		(fill yes
			(thermal_gap 0.5)
			(thermal_bridge_width 0.5)
			(island_removal_mode 0)
		)
		(polygon
			(pts
				(xy 425.91863 -298.314364) (xy 423.453052 -300.779942) (xy 420.913052 -300.779942) (xy 420.659052 -301.033942)
				(xy 420.659052 -301.414942) (xy 420.913052 -301.668942) (xy 427.611286 -301.668942) (xy 428.271686 -301.008542)
				(xy 428.271686 -298.435014) (xy 428.151036 -298.314364)
			)
		)
	)
	(zone
		(layer "F.Cu")
		(hatch none 0.5)
		(connect_pads
			(clearance 0)
		)
		(min_thickness 0.25)
		(keepout
			(tracks not_allowed)
			(vias allowed)
			(pads allowed)
			(copperpour not_allowed)
			(footprints allowed)
		)
		(placement
			(enabled no)
			(sheetname "")
		)
		(fill
			(thermal_gap 0.5)
			(thermal_bridge_width 0.5)
			(island_removal_mode 0)
		)
		(polygon
			(pts
				(arc
					(start 283.574744 -134.850124)
					(mid 282.600146 -135.17499)
					(end 282.925012 -136.149588)
				)
				(xy 282.923742 -136.151874) (xy 284.923738 -137.151872) (xy 284.923992 -137.151618)
				(arc
					(start 284.925008 -137.149586)
					(mid 285.899606 -136.82472)
					(end 285.57474 -135.850122)
				)
				(xy 285.57601 -135.847836)
				(arc
					(start 284.81655 -135.468106)
					(mid 284.769167 -135.630294)
					(end 284.677358 -135.772144)
				)
				(xy 284.635448 -135.830056) (xy 284.61208 -135.861806) (xy 284.588966 -135.89381) (xy 284.549596 -135.947912)
				(xy 284.549596 -135.956548)
				(arc
					(start 284.535118 -135.97128)
					(mid 284.538001 -136.018829)
					(end 284.570678 -136.053576)
				)
				(arc
					(start 284.811724 -136.173972)
					(mid 285.738175 -136.744265)
					(end 284.72638 -136.344406)
				)
				(xy 284.485334 -136.223756) (xy 284.450028 -136.20623)
				(arc
					(start 284.448504 -136.201404)
					(mid 284.353439 -136.068712)
					(end 284.356048 -135.905494)
				)
				(xy 284.354016 -135.892794) (xy 284.359096 -135.885936) (xy 284.359096 -135.877554) (xy 284.381702 -135.854948)
				(xy 284.458156 -135.750046) (xy 284.549088 -135.62457)
				(arc
					(start 284.55239 -135.624062)
					(mid 284.613038 -135.506584)
					(end 284.631384 -135.37565)
				)
				(arc
					(start 284.522164 -135.320786)
					(mid 284.51966 -135.463318)
					(end 284.450028 -135.58774)
				)
				(xy 284.257496 -135.852916) (xy 284.257496 -135.868664) (xy 284.22981 -135.896604) (xy 284.228286 -135.897874)
				(xy 284.201616 -135.924544)
				(arc
					(start 284.19679 -135.924544)
					(mid 284.087149 -135.970015)
					(end 283.968698 -135.962136)
				)
				(xy 283.963872 -135.96366) (xy 283.928566 -135.94588)
				(arc
					(start 283.688028 -135.825738)
					(mid 282.761577 -135.255445)
					(end 283.773372 -135.655304)
				)
				(arc
					(start 284.01391 -135.7757)
					(mid 284.042679 -135.782927)
					(end 284.071822 -135.777478)
				)
				(xy 284.089602 -135.759952) (xy 284.323028 -135.438388)
				(arc
					(start 284.325568 -135.43788)
					(mid 284.33834 -135.373945)
					(end 284.309566 -135.315452)
				)
				(xy 284.107636 -135.113776) (xy 283.576014 -134.847838)
			)
		)
	)
	(zone
		(net "GND")
		(layer "F.Cu")
		(hatch none 0.5)
		(connect_pads
			(clearance 0.5)
		)
		(min_thickness 0.25)
		(fill yes
			(thermal_gap 0.5)
			(thermal_bridge_width 0.5)
			(island_removal_mode 0)
		)
		(polygon
			(pts
				(xy 469.354154 -188.468) (xy 469.354154 -189.390274) (xy 466.233256 -192.511172) (xy 464.241896 -192.511172)
				(xy 464.241896 -194.4751)
				(arc
					(start 462.127346 -194.4751)
					(mid 460.990686 -195.051308)
					(end 459.731872 -195.2498)
				)
				(arc
					(start 457.69657 -195.2498)
					(mid 457.487415 -196.153269)
					(end 457.080112 -196.986398)
				)
				(arc
					(start 457.080112 -196.986398)
					(mid 462.427389 -198.634427)
					(end 466.236558 -202.733148)
				)
				(arc
					(start 466.236558 -202.733148)
					(mid 466.903749 -202.030099)
					(end 467.717632 -201.503788)
				)
				(arc
					(start 467.717632 -201.503788)
					(mid 469.721122 -199.644387)
					(end 472.448382 -199.462136)
				)
				(xy 478.193862 -199.462136)
				(arc
					(start 478.193862 -195.166996)
					(mid 477.441763 -194.863437)
					(end 476.76435 -194.417442)
				)
				(xy 475.097602 -194.417442) (xy 475.097602 -193.019172) (xy 475.096078 -193.019172) (xy 470.544906 -188.468)
			)
		)
	)
	(zone
		(layer "F.Cu")
		(hatch none 0.5)
		(connect_pads
			(clearance 0)
		)
		(min_thickness 0.25)
		(keepout
			(tracks allowed)
			(vias allowed)
			(pads allowed)
			(copperpour allowed)
			(footprints not_allowed)
		)
		(placement
			(enabled no)
			(sheetname "")
		)
		(fill
			(thermal_gap 0.5)
			(thermal_bridge_width 0.5)
			(island_removal_mode 0)
		)
		(polygon
			(pts
				(xy 312.699908 -125.800104) (xy 491.450122 -125.800104) (xy 491.450122 -190.799974) (xy 478.00006 -190.799974)
				(xy 478.00006 -180.799994) (xy 463.449924 -180.799994) (xy 463.449924 -190.799974) (xy 446.449958 -190.799974)
				(xy 446.449958 -180.799994) (xy 431.900076 -180.799994) (xy 431.900076 -190.799974) (xy 414.90011 -190.799974)
				(xy 414.90011 -180.799994) (xy 400.349974 -180.799994) (xy 400.349974 -190.799974) (xy 383.350008 -190.799974)
				(xy 383.350008 -180.799994) (xy 368.800126 -180.799994) (xy 368.800126 -190.799974) (xy 351.799906 -190.799974)
				(xy 351.799906 -180.799994) (xy 337.250024 -180.799994) (xy 337.250024 -190.799974) (xy 320.250058 -190.799974)
				(xy 320.250058 -180.799994) (xy 305.699922 -180.799994) (xy 305.699922 -190.799974) (xy 298.200064 -190.799974)
				(xy 298.200064 -154.200098) (xy 312.699908 -154.200098)
			)
		)
	)
	(zone
		(layer "F.Cu")
		(hatch none 0.5)
		(connect_pads
			(clearance 0)
		)
		(min_thickness 0.25)
		(keepout
			(tracks allowed)
			(vias allowed)
			(pads allowed)
			(copperpour allowed)
			(footprints allowed)
		)
		(placement
			(enabled no)
			(sheetname "")
		)
		(fill
			(thermal_gap 0.5)
			(thermal_bridge_width 0.5)
			(island_removal_mode 0)
		)
		(polygon
			(pts
				(xy 333.683102 -49.044098) (xy 332.748636 -49.044098) (xy 332.748636 -47.423578) (xy 333.683102 -47.423578)
			)
		)
	)
	(zone
		(net "MB0_CM_GATE_R")
		(layer "F.Cu")
		(hatch none 0.5)
		(connect_pads
			(clearance 0.5)
		)
		(min_thickness 0.25)
		(fill yes
			(thermal_gap 0.5)
			(thermal_bridge_width 0.5)
			(island_removal_mode 0)
		)
		(polygon
			(pts
				(xy 148.640038 -127.888746) (xy 148.474176 -128.054608) (xy 148.474176 -131.26593) (xy 148.66112 -131.452874)
				(xy 151.495252 -131.452874) (xy 151.617934 -131.330192) (xy 151.617934 -127.979678) (xy 151.527002 -127.888746)
			)
		)
	)
	(zone
		(layer "F.Cu")
		(hatch none 0.5)
		(connect_pads
			(clearance 0)
		)
		(min_thickness 0.25)
		(keepout
			(tracks allowed)
			(vias allowed)
			(pads allowed)
			(copperpour allowed)
			(footprints allowed)
		)
		(placement
			(enabled no)
			(sheetname "")
		)
		(fill
			(thermal_gap 0.5)
			(thermal_bridge_width 0.5)
			(island_removal_mode 0)
		)
		(polygon
			(pts
				(xy 151.807672 -140.865606) (xy 151.807672 -139.93114) (xy 153.341832 -139.93114) (xy 153.341832 -140.865606)
			)
		)
	)
	(zone
		(net "P3V3_STBY_A")
		(layer "F.Cu")
		(hatch none 0.5)
		(connect_pads
			(clearance 0.5)
		)
		(min_thickness 0.25)
		(fill yes
			(thermal_gap 0.5)
			(thermal_bridge_width 0.5)
			(island_removal_mode 0)
		)
		(polygon
			(pts
				(xy 225.558096 -393.610592) (xy 225.298 -393.870688) (xy 225.298 -395.7828) (xy 225.746056 -396.230856)
				(xy 229.733856 -396.230856) (xy 233.7562 -400.2532) (xy 233.7562 -405.978614) (xy 233.077766 -406.657048)
				(xy 231.258364 -406.657048) (xy 230.936546 -406.978866) (xy 230.936546 -407.622248) (xy 231.349804 -408.035506)
				(xy 234.877102 -408.035506) (xy 235.751116 -407.161492) (xy 235.751116 -406.255728) (xy 235.7628 -406.255728)
				(xy 235.7628 -399.5674) (xy 229.805992 -393.610592)
			)
		)
	)
	(zone
		(net "P12V_A")
		(layer "F.Cu")
		(hatch none 0.5)
		(connect_pads
			(clearance 0.5)
		)
		(min_thickness 0.25)
		(fill yes
			(thermal_gap 0.5)
			(thermal_bridge_width 0.5)
			(island_removal_mode 0)
		)
		(polygon
			(pts
				(xy 429.038512 -171.017438) (xy 428.787052 -171.268898) (xy 428.787052 -175.365918) (xy 429.041052 -175.619918)
				(xy 432.343052 -175.619918) (xy 432.597052 -175.365918) (xy 432.597052 -173.333918) (xy 432.724052 -173.206918)
				(xy 433.105052 -173.206918) (xy 433.232052 -173.079918) (xy 433.232052 -171.423076) (xy 432.826414 -171.017438)
			)
		)
		(polygon
			(pts
				(xy 432.698652 -172.444918) (xy 432.495452 -172.444918) (xy 432.495452 -172.648118) (xy 432.698652 -172.648118)
			)
		)
		(polygon
			(pts
				(xy 432.749452 -171.987718) (xy 432.546252 -171.987718) (xy 432.546252 -172.190918) (xy 432.749452 -172.190918)
			)
		)
		(polygon
			(pts
				(xy 432.749452 -171.428918) (xy 432.546252 -171.428918) (xy 432.546252 -171.632118) (xy 432.749452 -171.632118)
			)
		)
	)
	(zone
		(net "P12V_HDD7")
		(layer "F.Cu")
		(hatch none 0.5)
		(connect_pads
			(clearance 0.5)
		)
		(min_thickness 0.25)
		(fill yes
			(thermal_gap 0.5)
			(thermal_bridge_width 0.5)
			(island_removal_mode 0)
		)
		(polygon
			(pts
				(xy 366.195102 -293.540942) (xy 365.941102 -293.794942) (xy 365.941102 -297.858942) (xy 365.482378 -298.317666)
				(xy 365.482378 -301.13986) (xy 364.648496 -301.973742) (xy 357.72852 -301.973742) (xy 357.559102 -302.14316)
				(xy 357.559102 -303.954942) (xy 357.813102 -304.208942) (xy 361.750102 -304.208942) (xy 362.258102 -303.700942)
				(xy 370.005102 -303.700942) (xy 370.894102 -302.811942) (xy 370.894102 -293.794942) (xy 370.640102 -293.540942)
			)
		)
		(polygon
			(pts
				(xy 361.902502 -303.091342) (xy 361.699302 -303.091342) (xy 361.699302 -303.294542) (xy 361.902502 -303.294542)
			)
		)
		(polygon
			(pts
				(xy 361.038902 -303.091342) (xy 360.835702 -303.091342) (xy 360.835702 -303.294542) (xy 361.038902 -303.294542)
			)
		)
	)
	(zone
		(net "P12V_A")
		(layer "F.Cu")
		(hatch none 0.5)
		(connect_pads
			(clearance 0.5)
		)
		(min_thickness 0.25)
		(fill yes
			(thermal_gap 0.5)
			(thermal_bridge_width 0.5)
			(island_removal_mode 0)
		)
		(polygon
			(pts
				(xy 171.958 -54.142894) (xy 170.942 -55.158894) (xy 170.307 -55.158894) (xy 169.926 -55.539894)
				(xy 169.926 -58.079894) (xy 170.18 -58.333894) (xy 173.482 -58.333894) (xy 173.736 -58.079894) (xy 173.736 -55.793894)
				(xy 173.101 -55.158894) (xy 172.72 -55.158894) (xy 172.466 -54.904894) (xy 172.466 -54.269894) (xy 172.339 -54.142894)
			)
		)
		(polygon
			(pts
				(xy 171.9326 -54.727094) (xy 171.7294 -54.727094) (xy 171.7294 -54.930294) (xy 171.9326 -54.930294)
			)
		)
	)
	(zone
		(layer "F.Cu")
		(hatch none 0.5)
		(connect_pads
			(clearance 0)
		)
		(min_thickness 0.25)
		(keepout
			(tracks not_allowed)
			(vias allowed)
			(pads allowed)
			(copperpour not_allowed)
			(footprints allowed)
		)
		(placement
			(enabled no)
			(sheetname "")
		)
		(fill
			(thermal_gap 0.5)
			(thermal_bridge_width 0.5)
			(island_removal_mode 0)
		)
		(polygon
			(pts
				(arc
					(start 89.324942 -92.799916)
					(mid 96.324928 -85.79993)
					(end 103.324914 -92.799916)
				)
				(arc
					(start 103.324914 -98.799904)
					(mid 96.324928 -105.79989)
					(end 89.324942 -98.799904)
				)
			)
		)
	)
	(zone
		(net "P12V_HDD2")
		(layer "F.Cu")
		(hatch none 0.5)
		(connect_pads
			(clearance 0.5)
		)
		(min_thickness 0.25)
		(fill yes
			(thermal_gap 0.5)
			(thermal_bridge_width 0.5)
			(island_removal_mode 0)
		)
		(polygon
			(pts
				(xy 75.402948 -291.254942) (xy 75.148948 -291.508942) (xy 75.148948 -293.159942) (xy 75.402948 -293.413942)
				(xy 77.561948 -293.413942) (xy 78.069948 -293.921942) (xy 78.069948 -296.461942) (xy 85.816948 -304.208942)
				(xy 94.325948 -304.208942) (xy 94.452948 -304.081942) (xy 94.452948 -302.303942) (xy 94.325948 -302.176942)
				(xy 88.356948 -302.176942) (xy 87.721948 -301.541942) (xy 86.070948 -301.541942) (xy 81.752948 -297.223942)
				(xy 81.752948 -293.667942) (xy 80.609948 -292.524942) (xy 80.609948 -291.508942) (xy 80.355948 -291.254942)
			)
		)
		(polygon
			(pts
				(xy 87.874348 -303.218342) (xy 87.671148 -303.218342) (xy 87.671148 -303.421542) (xy 87.874348 -303.421542)
			)
		)
		(polygon
			(pts
				(xy 87.010748 -303.218342) (xy 86.807548 -303.218342) (xy 86.807548 -303.421542) (xy 87.010748 -303.421542)
			)
		)
	)
	(zone
		(net "12V_PRE_13")
		(layer "F.Cu")
		(hatch none 0.5)
		(connect_pads
			(clearance 0.5)
		)
		(min_thickness 0.25)
		(fill yes
			(thermal_gap 0.5)
			(thermal_bridge_width 0.5)
			(island_removal_mode 0)
		)
		(polygon
			(pts
				(xy 51.218846 -178.794918) (xy 51.091846 -178.921918) (xy 51.091846 -180.445918) (xy 52.488846 -181.842918)
				(xy 53.885846 -181.842918) (xy 58.838846 -186.795918) (xy 62.775846 -186.795918) (xy 62.902846 -186.668918)
				(xy 62.902846 -185.906918) (xy 62.775846 -185.779918) (xy 59.473846 -185.779918) (xy 52.488846 -178.794918)
			)
		)
	)
	(zone
		(net "P12V_A")
		(layer "F.Cu")
		(hatch none 0.5)
		(connect_pads
			(clearance 0.5)
		)
		(min_thickness 0.25)
		(fill yes
			(thermal_gap 0.5)
			(thermal_bridge_width 0.5)
			(island_removal_mode 0)
		)
		(polygon
			(pts
				(xy 460.8449 -286.428942) (xy 460.3369 -286.936942) (xy 460.3369 -290.365942) (xy 460.5909 -290.619942)
				(xy 463.8929 -290.619942) (xy 464.1469 -290.365942) (xy 464.1469 -288.333942) (xy 464.2739 -288.206942)
				(xy 464.6549 -288.206942) (xy 464.7819 -288.079942) (xy 464.7819 -286.555942) (xy 464.6549 -286.428942)
			)
		)
		(polygon
			(pts
				(xy 464.1469 -287.419542) (xy 463.9437 -287.419542) (xy 463.9437 -287.622742) (xy 464.1469 -287.622742)
			)
		)
		(polygon
			(pts
				(xy 464.1977 -286.936942) (xy 463.9945 -286.936942) (xy 463.9945 -287.140142) (xy 464.1977 -287.140142)
			)
		)
	)
	(zone
		(net "P12V_A")
		(layer "F.Cu")
		(hatch none 0.5)
		(connect_pads
			(clearance 0.5)
		)
		(min_thickness 0.25)
		(fill yes
			(thermal_gap 0.5)
			(thermal_bridge_width 0.5)
			(island_removal_mode 0)
		)
		(polygon
			(pts
				(xy 279.48636 -235.692696) (xy 279.132538 -236.046518) (xy 279.132538 -240.643918) (xy 279.437338 -240.948718)
				(xy 282.332938 -240.948718) (xy 282.586938 -240.694718) (xy 282.586938 -236.097318) (xy 282.182316 -235.692696)
			)
		)
	)
	(zone
		(net "P12V_A")
		(layer "F.Cu")
		(hatch none 0.5)
		(connect_pads
			(clearance 0.5)
		)
		(min_thickness 0.25)
		(fill yes
			(thermal_gap 0.5)
			(thermal_bridge_width 0.5)
			(island_removal_mode 0)
		)
		(polygon
			(pts
				(xy 113.6396 -284.5054) (xy 113.272316 -284.872684) (xy 113.272316 -287.900618) (xy 113.676176 -288.304224)
				(xy 116.368576 -288.304224) (xy 116.6876 -287.9852) (xy 116.6876 -285.0134) (xy 116.1796 -284.5054)
			)
		)
	)
	(zone
		(layer "F.Cu")
		(hatch none 0.5)
		(connect_pads
			(clearance 0)
		)
		(min_thickness 0.25)
		(keepout
			(tracks allowed)
			(vias allowed)
			(pads allowed)
			(copperpour allowed)
			(footprints not_allowed)
		)
		(placement
			(enabled no)
			(sheetname "")
		)
		(fill
			(thermal_gap 0.5)
			(thermal_bridge_width 0.5)
			(island_removal_mode 0)
		)
		(polygon
			(pts
				(arc
					(start 111.849916 -289.999928)
					(mid 107.100116 -294.749728)
					(end 102.350062 -289.999928)
				)
				(arc
					(start 102.350062 -289.999928)
					(mid 107.100116 -285.249874)
					(end 111.849916 -289.999928)
				)
			)
		)
	)
	(zone
		(layer "F.Cu")
		(hatch none 0.5)
		(connect_pads
			(clearance 0)
		)
		(min_thickness 0.25)
		(keepout
			(tracks allowed)
			(vias allowed)
			(pads allowed)
			(copperpour allowed)
			(footprints allowed)
		)
		(placement
			(enabled no)
			(sheetname "")
		)
		(fill
			(thermal_gap 0.5)
			(thermal_bridge_width 0.5)
			(island_removal_mode 0)
		)
		(polygon
			(pts
				(xy 234.811316 -382.078738) (xy 233.872278 -382.078738) (xy 233.872278 -380.544578) (xy 234.811316 -380.544578)
			)
		)
	)
	(zone
		(net "MB3_CM_GATE_R")
		(layer "F.Cu")
		(hatch none 0.5)
		(connect_pads
			(clearance 0.5)
		)
		(min_thickness 0.25)
		(fill yes
			(thermal_gap 0.5)
			(thermal_bridge_width 0.5)
			(island_removal_mode 0)
		)
		(polygon
			(pts
				(xy 242.203224 -380.863856) (xy 242.058698 -381.008382) (xy 242.058698 -382.387602) (xy 242.235228 -382.564132)
				(xy 243.42217 -382.564132) (xy 243.907564 -383.049272) (xy 243.907564 -383.475484) (xy 244.276372 -383.844292)
				(xy 245.55069 -383.844292) (xy 246.577358 -382.817624) (xy 246.577358 -381.10668) (xy 246.334534 -380.863856)
			)
		)
	)
	(zone
		(net "P12V_HDD24")
		(layer "F.Cu")
		(hatch none 0.5)
		(connect_pads
			(clearance 0.5)
		)
		(min_thickness 0.25)
		(fill yes
			(thermal_gap 0.5)
			(thermal_bridge_width 0.5)
			(island_removal_mode 0)
		)
		(polygon
			(pts
				(xy 12.302998 -61.254894) (xy 12.048998 -61.508894) (xy 12.048998 -63.159894) (xy 12.302998 -63.413894)
				(xy 14.461998 -63.413894) (xy 14.969998 -63.921894) (xy 14.969998 -66.461894) (xy 22.716998 -74.208894)
				(xy 31.225998 -74.208894) (xy 31.352998 -74.081894) (xy 31.352998 -72.303894) (xy 31.225998 -72.176894)
				(xy 25.256998 -72.176894) (xy 24.621998 -71.541894) (xy 22.970998 -71.541894) (xy 18.652998 -67.223894)
				(xy 18.652998 -63.667894) (xy 17.509998 -62.524894) (xy 17.509998 -61.508894) (xy 17.255998 -61.254894)
			)
		)
		(polygon
			(pts
				(xy 24.774398 -73.218294) (xy 24.571198 -73.218294) (xy 24.571198 -73.421494) (xy 24.774398 -73.421494)
			)
		)
		(polygon
			(pts
				(xy 23.910798 -73.218294) (xy 23.707598 -73.218294) (xy 23.707598 -73.421494) (xy 23.910798 -73.421494)
			)
		)
	)
	(zone
		(net "MB3_12V_CTRL_GATE1")
		(layer "F.Cu")
		(hatch none 0.5)
		(connect_pads
			(clearance 0.5)
		)
		(min_thickness 0.25)
		(fill yes
			(thermal_gap 0.5)
			(thermal_bridge_width 0.5)
			(island_removal_mode 0)
		)
		(polygon
			(pts
				(xy 272.20164 -372.12016) (xy 272.034762 -372.287038) (xy 272.034762 -377.249182) (xy 272.11782 -377.33224)
				(xy 273.608292 -377.33224) (xy 273.788632 -377.1519) (xy 273.788632 -372.289832) (xy 273.61896 -372.12016)
			)
		)
	)
	(zone
		(layer "F.Cu")
		(hatch none 0.5)
		(connect_pads
			(clearance 0)
		)
		(min_thickness 0.25)
		(keepout
			(tracks not_allowed)
			(vias allowed)
			(pads allowed)
			(copperpour not_allowed)
			(footprints allowed)
		)
		(placement
			(enabled no)
			(sheetname "")
		)
		(fill
			(thermal_gap 0.5)
			(thermal_bridge_width 0.5)
			(island_removal_mode 0)
		)
		(polygon
			(pts
				(arc
					(start 451.3199 -47.178722)
					(mid 450.939027 -46.797468)
					(end 450.5579 -47.178468)
				)
				(arc
					(start 450.5579 -48.321468)
					(mid 450.9389 -48.702468)
					(end 451.3199 -48.321468)
				)
				(xy 451.3199 -47.972218)
				(arc
					(start 451.09892 -47.972218)
					(mid 451.03965 -47.996768)
					(end 451.0151 -48.056038)
				)
				(arc
					(start 451.0151 -48.065944)
					(mid 450.9389 -48.588112)
					(end 450.8627 -48.065944)
				)
				(xy 450.8627 -48.024542)
				(arc
					(start 450.86524 -48.022002)
					(mid 450.93194 -47.889058)
					(end 451.064884 -47.822358)
				)
				(xy 451.067424 -47.819818) (xy 451.3199 -47.819818) (xy 451.3199 -47.680118) (xy 451.067424 -47.680118)
				(arc
					(start 451.064884 -47.677578)
					(mid 450.93194 -47.610878)
					(end 450.86524 -47.477934)
				)
				(xy 450.8627 -47.475394)
				(arc
					(start 450.8627 -47.433992)
					(mid 450.9389 -46.911824)
					(end 451.0151 -47.433992)
				)
				(arc
					(start 451.0151 -47.443898)
					(mid 451.03965 -47.503168)
					(end 451.09892 -47.527718)
				)
				(xy 451.3199 -47.527718)
			)
		)
	)
	(zone
		(layer "F.Cu")
		(hatch none 0.5)
		(connect_pads
			(clearance 0)
		)
		(min_thickness 0.25)
		(keepout
			(tracks allowed)
			(vias allowed)
			(pads allowed)
			(copperpour allowed)
			(footprints not_allowed)
		)
		(placement
			(enabled no)
			(sheetname "")
		)
		(fill
			(thermal_gap 0.5)
			(thermal_bridge_width 0.5)
			(island_removal_mode 0)
		)
		(polygon
			(pts
				(arc
					(start 346.050108 -269.999968)
					(mid 341.300054 -274.750022)
					(end 336.55 -269.999968)
				)
				(arc
					(start 336.55 -269.999968)
					(mid 341.300054 -265.249914)
					(end 346.050108 -269.999968)
				)
			)
		)
	)
	(zone
		(layer "F.Cu")
		(hatch none 0.5)
		(connect_pads
			(clearance 0)
		)
		(min_thickness 0.25)
		(keepout
			(tracks allowed)
			(vias allowed)
			(pads allowed)
			(copperpour allowed)
			(footprints allowed)
		)
		(placement
			(enabled no)
			(sheetname "")
		)
		(fill
			(thermal_gap 0.5)
			(thermal_bridge_width 0.5)
			(island_removal_mode 0)
		)
		(polygon
			(pts
				(xy 272.8849 13.2842) (xy 272.8849 14.859) (xy 273.7231 14.859) (xy 273.7231 13.2842)
			)
		)
	)
	(zone
		(layer "F.Cu")
		(hatch none 0.5)
		(connect_pads
			(clearance 0)
		)
		(min_thickness 0.25)
		(keepout
			(tracks not_allowed)
			(vias allowed)
			(pads allowed)
			(copperpour not_allowed)
			(footprints allowed)
		)
		(placement
			(enabled no)
			(sheetname "")
		)
		(fill
			(thermal_gap 0.5)
			(thermal_bridge_width 0.5)
			(island_removal_mode 0)
		)
		(polygon
			(pts
				(arc
					(start 451.3199 -277.17877)
					(mid 450.939027 -276.797516)
					(end 450.5579 -277.178516)
				)
				(arc
					(start 450.5579 -278.321516)
					(mid 450.9389 -278.702516)
					(end 451.3199 -278.321516)
				)
				(xy 451.3199 -277.972266)
				(arc
					(start 451.099174 -277.972266)
					(mid 451.039725 -277.996891)
					(end 451.0151 -278.05634)
				)
				(arc
					(start 451.0151 -278.065992)
					(mid 450.9389 -278.58816)
					(end 450.8627 -278.065992)
				)
				(xy 450.8627 -278.024844)
				(arc
					(start 450.86524 -278.022304)
					(mid 450.932016 -277.889182)
					(end 451.065138 -277.822406)
				)
				(xy 451.067678 -277.819866) (xy 451.3199 -277.819866) (xy 451.3199 -277.680166) (xy 451.067678 -277.680166)
				(arc
					(start 451.065138 -277.677626)
					(mid 450.932016 -277.61085)
					(end 450.86524 -277.477728)
				)
				(xy 450.8627 -277.475188)
				(arc
					(start 450.8627 -277.43404)
					(mid 450.9389 -276.911872)
					(end 451.0151 -277.43404)
				)
				(arc
					(start 451.0151 -277.443692)
					(mid 451.039725 -277.503141)
					(end 451.099174 -277.527766)
				)
				(xy 451.3199 -277.527766)
			)
		)
	)
	(zone
		(layer "F.Cu")
		(hatch none 0.5)
		(connect_pads
			(clearance 0)
		)
		(min_thickness 0.25)
		(keepout
			(tracks allowed)
			(vias allowed)
			(pads allowed)
			(copperpour allowed)
			(footprints allowed)
		)
		(placement
			(enabled no)
			(sheetname "")
		)
		(fill
			(thermal_gap 0.5)
			(thermal_bridge_width 0.5)
			(island_removal_mode 0)
		)
		(polygon
			(pts
				(xy 365.218218 -49.043844) (xy 364.283752 -49.043844) (xy 364.283752 -46.422818) (xy 365.218218 -46.422818)
			)
		)
	)
	(zone
		(net "5V_PRE_10")
		(layer "F.Cu")
		(hatch none 0.5)
		(connect_pads
			(clearance 0.5)
		)
		(min_thickness 0.25)
		(fill yes
			(thermal_gap 0.5)
			(thermal_bridge_width 0.5)
			(island_removal_mode 0)
		)
		(polygon
			(pts
				(xy 455.6379 -289.984942) (xy 455.3839 -290.238942) (xy 455.3839 -292.778942) (xy 455.0029 -293.159942)
				(xy 452.4629 -293.159942) (xy 452.2089 -293.413942) (xy 452.2089 -293.794942) (xy 452.4629 -294.048942)
				(xy 455.7649 -294.048942) (xy 457.0349 -292.778942) (xy 457.0349 -290.238942) (xy 456.7809 -289.984942)
			)
		)
	)
	(zone
		(layer "F.Cu")
		(hatch none 0.5)
		(connect_pads
			(clearance 0)
		)
		(min_thickness 0.25)
		(keepout
			(tracks allowed)
			(vias allowed)
			(pads allowed)
			(copperpour allowed)
			(footprints not_allowed)
		)
		(placement
			(enabled no)
			(sheetname "")
		)
		(fill
			(thermal_gap 0.5)
			(thermal_bridge_width 0.5)
			(island_removal_mode 0)
		)
		(polygon
			(pts
				(arc
					(start 350.750124 -164.200078)
					(mid 347.000068 -167.950134)
					(end 343.250012 -164.200078)
				)
				(arc
					(start 343.250012 -164.200078)
					(mid 347.000068 -160.450022)
					(end 350.750124 -164.200078)
				)
			)
		)
	)
	(zone
		(net "P12V_A")
		(layer "F.Cu")
		(hatch none 0.5)
		(connect_pads
			(clearance 0.5)
		)
		(min_thickness 0.25)
		(fill yes
			(thermal_gap 0.5)
			(thermal_bridge_width 0.5)
			(island_removal_mode 0)
		)
		(polygon
			(pts
				(xy 108.857796 -54.142894) (xy 107.841796 -55.158894) (xy 107.206796 -55.158894) (xy 106.825796 -55.539894)
				(xy 106.825796 -58.079894) (xy 107.079796 -58.333894) (xy 110.381796 -58.333894) (xy 110.635796 -58.079894)
				(xy 110.635796 -55.793894) (xy 110.000796 -55.158894) (xy 109.619796 -55.158894) (xy 109.365796 -54.904894)
				(xy 109.365796 -54.269894) (xy 109.238796 -54.142894)
			)
		)
		(polygon
			(pts
				(xy 108.832396 -54.727094) (xy 108.629196 -54.727094) (xy 108.629196 -54.930294) (xy 108.832396 -54.930294)
			)
		)
	)
	(zone
		(net "GND")
		(layer "F.Cu")
		(hatch none 0.5)
		(connect_pads
			(clearance 0.5)
		)
		(min_thickness 0.25)
		(fill yes
			(thermal_gap 0.5)
			(thermal_bridge_width 0.5)
			(island_removal_mode 0)
		)
		(polygon
			(pts
				(xy 156.4386 -231.730804)
				(arc
					(start 153.420064 -226.992434)
					(mid 148.402349 -227.601073)
					(end 146.624548 -222.869506)
				)
				(arc
					(start 146.624548 -222.869506)
					(mid 147.137221 -220.86615)
					(end 148.564346 -219.36964)
				)
				(arc
					(start 145.921984 -215.222074)
					(mid 145.22251 -215.412837)
					(end 144.500346 -215.47709)
				)
				(arc
					(start 143.499586 -215.47709)
					(mid 142.320953 -215.303613)
					(end 141.242288 -214.797894)
				)
				(arc
					(start 141.242288 -214.797894)
					(mid 137.931103 -220.488795)
					(end 132.3848 -224.03689)
				)
				(xy 132.3848 -225.091498) (xy 138.522202 -226.400614)
				(arc
					(start 145.371058 -227.863146)
					(mid 145.93063 -228.02743)
					(end 146.459194 -228.273864)
				)
				(xy 146.94535 -228.546914) (xy 147.011644 -228.585014) (xy 155.388818 -233.299) (xy 156.4386 -233.299)
			)
		)
	)
	(zone
		(net "P5V_A_4")
		(layer "F.Cu")
		(hatch none 0.5)
		(connect_pads
			(clearance 0.5)
		)
		(min_thickness 0.25)
		(fill yes
			(thermal_gap 0.5)
			(thermal_bridge_width 0.5)
			(island_removal_mode 0)
		)
		(polygon
			(pts
				(xy 473.498926 -50.840894) (xy 473.244926 -51.094894) (xy 473.244926 -53.380894) (xy 473.498926 -53.634894)
				(xy 478.197926 -53.634894) (xy 478.451926 -53.380894) (xy 478.451926 -51.094894) (xy 478.197926 -50.840894)
			)
		)
	)
	(zone
		(net "P12V_A")
		(layer "F.Cu")
		(hatch none 0.5)
		(connect_pads
			(clearance 0.5)
		)
		(min_thickness 0.25)
		(fill yes
			(thermal_gap 0.5)
			(thermal_bridge_width 0.5)
			(island_removal_mode 0)
		)
		(polygon
			(pts
				(xy 203.182982 -163.8046) (xy 202.633834 -164.353748) (xy 202.633834 -167.171624) (xy 204.47381 -169.0116)
				(xy 205.872588 -169.0116) (xy 206.299562 -168.584626) (xy 206.299562 -164.281104) (xy 205.823058 -163.8046)
			)
		)
	)
	(zone
		(net "5V_PRE_16")
		(layer "F.Cu")
		(hatch none 0.5)
		(connect_pads
			(clearance 0.5)
		)
		(min_thickness 0.25)
		(fill yes
			(thermal_gap 0.5)
			(thermal_bridge_width 0.5)
			(island_removal_mode 0)
		)
		(polygon
			(pts
				(xy 149.272498 -174.9298) (xy 149.043898 -175.1584) (xy 149.043898 -176.508918) (xy 149.170898 -176.635918)
				(xy 150.440898 -176.635918) (xy 152.980898 -179.175918) (xy 157.425898 -179.175918) (xy 157.552898 -179.048918)
				(xy 157.552898 -178.286918) (xy 157.425898 -178.159918) (xy 154.052016 -178.159918) (xy 150.821898 -174.9298)
			)
		)
	)
	(zone
		(net "P5V_A_2")
		(layer "F.Cu")
		(hatch none 0.5)
		(connect_pads
			(clearance 0.5)
		)
		(min_thickness 0.25)
		(fill yes
			(thermal_gap 0.5)
			(thermal_bridge_width 0.5)
			(island_removal_mode 0)
		)
		(polygon
			(pts
				(xy 144.598898 -165.840918) (xy 144.344898 -166.094918) (xy 144.344898 -168.380918) (xy 144.598898 -168.634918)
				(xy 149.297898 -168.634918) (xy 149.551898 -168.380918) (xy 149.551898 -166.094918) (xy 149.297898 -165.840918)
			)
		)
	)
	(zone
		(net "5V_PRE_32")
		(layer "F.Cu")
		(hatch none 0.5)
		(connect_pads
			(clearance 0.5)
		)
		(min_thickness 0.25)
		(fill yes
			(thermal_gap 0.5)
			(thermal_bridge_width 0.5)
			(island_removal_mode 0)
		)
		(polygon
			(pts
				(xy 392.53795 -59.984894) (xy 392.28395 -60.238894) (xy 392.28395 -62.778894) (xy 391.90295 -63.159894)
				(xy 389.36295 -63.159894) (xy 389.10895 -63.413894) (xy 389.10895 -63.794894) (xy 389.36295 -64.048894)
				(xy 392.66495 -64.048894) (xy 393.93495 -62.778894) (xy 393.93495 -60.238894) (xy 393.68095 -59.984894)
			)
		)
	)
	(zone
		(net "P3V3_STBY_B")
		(layer "F.Cu")
		(hatch none 0.5)
		(connect_pads
			(clearance 0.5)
		)
		(min_thickness 0.25)
		(fill yes
			(thermal_gap 0.5)
			(thermal_bridge_width 0.5)
			(island_removal_mode 0)
		)
		(polygon
			(pts
				(xy 332.640686 -29.130752) (xy 332.47203 -29.299408) (xy 332.47203 -30.693106) (xy 332.84287 -31.063946)
				(xy 336.001106 -31.063946) (xy 336.237326 -30.827726) (xy 336.25409 -30.827726) (xy 336.25409 -29.327602)
				(xy 336.05724 -29.130752)
			)
		)
		(polygon
			(pts
				(xy 334.035146 -30.02915) (xy 333.831946 -30.02915) (xy 333.831946 -30.23235) (xy 334.035146 -30.23235)
			)
		)
		(polygon
			(pts
				(xy 333.171546 -30.02915) (xy 332.968346 -30.02915) (xy 332.968346 -30.23235) (xy 333.171546 -30.23235)
			)
		)
		(polygon
			(pts
				(xy 335.09077 -29.756354) (xy 334.88757 -29.756354) (xy 334.88757 -29.959554) (xy 335.09077 -29.959554)
			)
		)
		(polygon
			(pts
				(xy 334.48117 -29.756354) (xy 334.27797 -29.756354) (xy 334.27797 -29.959554) (xy 334.48117 -29.959554)
			)
		)
	)
	(zone
		(net "GND")
		(layer "F.Cu")
		(hatch none 0.5)
		(connect_pads
			(clearance 0.5)
		)
		(min_thickness 0.25)
		(fill yes
			(thermal_gap 0.5)
			(thermal_bridge_width 0.5)
			(island_removal_mode 0)
		)
		(polygon
			(pts
				(xy 62.7634 -199.9234) (xy 62.7634 -200.49617) (xy 74.80935 -208.1784) (xy 74.9554 -208.1784) (xy 75.1332 -208.0006)
				(xy 75.1332 -207.618076) (xy 67.438524 -199.9234)
			)
		)
	)
	(zone
		(layer "F.Cu")
		(hatch none 0.5)
		(connect_pads
			(clearance 0)
		)
		(min_thickness 0.25)
		(keepout
			(tracks allowed)
			(vias allowed)
			(pads allowed)
			(copperpour allowed)
			(footprints allowed)
		)
		(placement
			(enabled no)
			(sheetname "")
		)
		(fill
			(thermal_gap 0.5)
			(thermal_bridge_width 0.5)
			(island_removal_mode 0)
		)
		(polygon
			(pts
				(xy 87.1474 -17.8562) (xy 87.1474 -16.8148) (xy 89.5858 -16.8148) (xy 89.5858 -17.8562)
			)
		)
	)
	(zone
		(net "P5V_HDD12")
		(layer "F.Cu")
		(hatch none 0.5)
		(connect_pads
			(clearance 0.5)
		)
		(min_thickness 0.25)
		(fill yes
			(thermal_gap 0.5)
			(thermal_bridge_width 0.5)
			(island_removal_mode 0)
		)
		(polygon
			(pts
				(xy 19.668998 -171.682918) (xy 19.414998 -171.936918) (xy 19.414998 -174.222918) (xy 19.668998 -174.476918)
				(xy 19.668998 -176.508918) (xy 20.430998 -177.270918) (xy 20.430998 -178.032918) (xy 20.811998 -178.413918)
				(xy 21.192998 -178.413918) (xy 24.367998 -181.588918) (xy 31.225998 -181.588918) (xy 31.352998 -181.461918)
				(xy 31.352998 -179.683918) (xy 31.225998 -179.556918) (xy 26.145998 -179.556918) (xy 24.240998 -177.651918)
				(xy 23.351998 -177.651918) (xy 22.462998 -176.762918) (xy 22.462998 -174.222918) (xy 23.097998 -173.587918)
				(xy 23.097998 -171.936918) (xy 22.843998 -171.682918)
			)
		)
		(polygon
			(pts
				(xy 21.675598 -178.109118) (xy 21.472398 -178.109118) (xy 21.472398 -178.312318) (xy 21.675598 -178.312318)
			)
		)
		(polygon
			(pts
				(xy 21.675598 -177.245518) (xy 21.472398 -177.245518) (xy 21.472398 -177.448718) (xy 21.675598 -177.448718)
			)
		)
		(polygon
			(pts
				(xy 20.811998 -177.245518) (xy 20.608798 -177.245518) (xy 20.608798 -177.448718) (xy 20.811998 -177.448718)
			)
		)
	)
	(zone
		(layer "F.Cu")
		(hatch none 0.5)
		(connect_pads
			(clearance 0)
		)
		(min_thickness 0.25)
		(keepout
			(tracks allowed)
			(vias allowed)
			(pads allowed)
			(copperpour allowed)
			(footprints not_allowed)
		)
		(placement
			(enabled no)
			(sheetname "")
		)
		(fill
			(thermal_gap 0.5)
			(thermal_bridge_width 0.5)
			(island_removal_mode 0)
		)
		(polygon
			(pts
				(arc
					(start 40.32504 -98.799904)
					(mid 33.325054 -105.79989)
					(end 26.325068 -98.799904)
				)
				(arc
					(start 26.325068 -92.799916)
					(mid 33.325054 -85.79993)
					(end 40.32504 -92.799916)
				)
			)
		)
	)
	(zone
		(net "P12V_A")
		(layer "F.Cu")
		(hatch none 0.5)
		(connect_pads
			(clearance 0.5)
		)
		(min_thickness 0.25)
		(fill yes
			(thermal_gap 0.5)
			(thermal_bridge_width 0.5)
			(island_removal_mode 0)
		)
		(polygon
			(pts
				(xy 14.207998 -54.142894) (xy 13.191998 -55.158894) (xy 12.556998 -55.158894) (xy 12.175998 -55.539894)
				(xy 12.175998 -58.079894) (xy 12.429998 -58.333894) (xy 15.731998 -58.333894) (xy 15.985998 -58.079894)
				(xy 15.985998 -55.793894) (xy 15.350998 -55.158894) (xy 14.969998 -55.158894) (xy 14.715998 -54.904894)
				(xy 14.715998 -54.269894) (xy 14.588998 -54.142894)
			)
		)
		(polygon
			(pts
				(xy 14.182598 -54.727094) (xy 13.979398 -54.727094) (xy 13.979398 -54.930294) (xy 14.182598 -54.930294)
			)
		)
	)
	(zone
		(net "GND")
		(layer "F.Cu")
		(hatch none 0.5)
		(connect_pads
			(clearance 0.5)
		)
		(min_thickness 0.25)
		(fill yes
			(thermal_gap 0.5)
			(thermal_bridge_width 0.5)
			(island_removal_mode 0)
		)
		(polygon
			(pts
				(arc
					(start 435.297326 -220.472)
					(mid 429.260328 -224.191029)
					(end 422.175432 -224.475294)
				)
				(arc
					(start 422.175432 -224.475294)
					(mid 421.85915 -226.182725)
					(end 420.863014 -227.605082)
				)
				(arc
					(start 420.863014 -227.605082)
					(mid 420.084534 -228.507599)
					(end 419.078918 -229.14737)
				)
				(arc
					(start 419.078918 -229.14737)
					(mid 418.781542 -229.371669)
					(end 418.465 -229.567994)
				)
				(arc
					(start 418.465 -232.190036)
					(mid 419.714187 -234.733725)
					(end 419.010338 -237.478824)
				)
				(arc
					(start 419.010338 -237.478824)
					(mid 417.849664 -240.689179)
					(end 414.658302 -241.900964)
				)
				(arc
					(start 414.658302 -243.698522)
					(mid 417.556243 -249.290061)
					(end 411.52445 -251.101098)
				)
				(arc
					(start 411.52445 -251.101098)
					(mid 409.561549 -251.203834)
					(end 407.777442 -250.378976)
				)
				(arc
					(start 407.777442 -250.378976)
					(mid 406.888111 -250.461862)
					(end 406.001982 -250.349766)
				)
				(arc
					(start 406.001982 -250.349766)
					(mid 405.161156 -250.326546)
					(end 404.342854 -250.131834)
				)
				(arc
					(start 404.342854 -250.131834)
					(mid 403.876285 -250.225142)
					(end 403.402038 -250.26366)
				)
				(arc
					(start 403.402038 -250.26366)
					(mid 402.701832 -251.100893)
					(end 401.80514 -251.723144)
				)
				(arc
					(start 401.80514 -251.723144)
					(mid 404.21106 -252.80798)
					(end 405.453596 -255.136396)
				)
				(arc
					(start 405.453596 -255.136396)
					(mid 409.021093 -255.357663)
					(end 411.052518 -258.298696)
				)
				(arc
					(start 411.052518 -258.298696)
					(mid 413.63925 -258.881838)
					(end 415.324798 -260.928866)
				)
				(arc
					(start 422.73855 -260.928866)
					(mid 422.668411 -260.45789)
					(end 422.65346 -259.981954)
				)
				(arc
					(start 422.65346 -259.981954)
					(mid 420.769944 -254.770386)
					(end 425.809156 -252.464824)
				)
				(arc
					(start 425.809156 -252.464824)
					(mid 427.142361 -249.749149)
					(end 429.961294 -248.651014)
				)
				(arc
					(start 431.104294 -248.651014)
					(mid 432.973793 -249.093907)
					(end 434.445918 -250.32843)
				)
				(arc
					(start 434.445918 -250.32843)
					(mid 434.669608 -250.309963)
					(end 434.893974 -250.303792)
				)
				(xy 437.053482 -250.303792) (xy 437.053482 -247.57126) (xy 437.416448 -247.208294) (xy 436.451502 -247.208294)
				(xy 436.451502 -237.299246) (xy 436.953152 -237.299246) (xy 436.953152 -230.378)
				(arc
					(start 436.212488 -230.378)
					(mid 434.861109 -231.637785)
					(end 433.093368 -232.174796)
				)
				(arc
					(start 433.093368 -232.174796)
					(mid 433.295045 -236.711651)
					(end 429.1838 -238.64062)
				)
				(arc
					(start 429.1838 -238.64062)
					(mid 430.811547 -241.739737)
					(end 429.447198 -244.963442)
				)
				(arc
					(start 429.447198 -244.963442)
					(mid 424.020063 -248.193348)
					(end 421.886634 -242.248944)
				)
				(arc
					(start 421.886634 -242.248944)
					(mid 422.478114 -240.347873)
					(end 423.89679 -238.951008)
				)
				(arc
					(start 423.89679 -238.951008)
					(mid 425.488561 -238.008655)
					(end 427.332648 -237.863634)
				)
				(arc
					(start 427.332648 -237.863634)
					(mid 425.871289 -233.428108)
					(end 429.518826 -230.511858)
				)
				(arc
					(start 429.518826 -230.511858)
					(mid 429.998097 -225.127388)
					(end 435.399688 -224.917)
				)
				(arc
					(start 436.731156 -224.917)
					(mid 436.738596 -223.987525)
					(end 436.953152 -223.08312)
				)
				(xy 436.953152 -220.472)
			)
		)
	)
	(zone
		(net "AGND_P5V_B")
		(layer "F.Cu")
		(hatch none 0.5)
		(connect_pads
			(clearance 0.5)
		)
		(min_thickness 0.25)
		(fill yes
			(thermal_gap 0.5)
			(thermal_bridge_width 0.5)
			(island_removal_mode 0)
		)
		(polygon
			(pts
				(xy 44.034202 -148.77415) (xy 43.526202 -149.28215) (xy 43.526202 -150.50135) (xy 43.678602 -150.65375)
				(xy 46.040802 -150.65375) (xy 46.472602 -150.22195) (xy 46.472602 -149.76475) (xy 46.904402 -149.33295)
				(xy 46.904402 -148.87575) (xy 46.802802 -148.77415)
			)
		)
		(polygon
			(pts
				(xy 44.135802 -150.29815) (xy 43.932602 -150.29815) (xy 43.932602 -150.50135) (xy 44.135802 -150.50135)
			)
		)
		(polygon
			(pts
				(xy 44.135802 -149.73935) (xy 43.932602 -149.73935) (xy 43.932602 -149.94255) (xy 44.135802 -149.94255)
			)
		)
		(polygon
			(pts
				(xy 46.48073 -149.292818) (xy 46.27753 -149.292818) (xy 46.27753 -149.496018) (xy 46.48073 -149.496018)
			)
		)
		(polygon
			(pts
				(xy 45.8978 -149.27072) (xy 45.6946 -149.27072) (xy 45.6946 -149.47392) (xy 45.8978 -149.47392)
			)
		)
		(polygon
			(pts
				(xy 45.339 -149.27072) (xy 45.1358 -149.27072) (xy 45.1358 -149.47392) (xy 45.339 -149.47392)
			)
		)
		(polygon
			(pts
				(xy 44.847002 -149.25675) (xy 44.643802 -149.25675) (xy 44.643802 -149.45995) (xy 44.847002 -149.45995)
			)
		)
		(polygon
			(pts
				(xy 44.288202 -149.25675) (xy 44.085002 -149.25675) (xy 44.085002 -149.45995) (xy 44.288202 -149.45995)
			)
		)
	)
	(zone
		(net "5V_PRE_20")
		(layer "F.Cu")
		(hatch none 0.5)
		(connect_pads
			(clearance 0.5)
		)
		(min_thickness 0.25)
		(fill yes
			(thermal_gap 0.5)
			(thermal_bridge_width 0.5)
			(island_removal_mode 0)
		)
		(polygon
			(pts
				(xy 392.53795 -174.984918) (xy 392.28395 -175.238918) (xy 392.28395 -177.778918) (xy 391.90295 -178.159918)
				(xy 389.36295 -178.159918) (xy 389.10895 -178.413918) (xy 389.10895 -178.794918) (xy 389.36295 -179.048918)
				(xy 392.66495 -179.048918) (xy 393.93495 -177.778918) (xy 393.93495 -175.238918) (xy 393.68095 -174.984918)
			)
		)
	)
	(zone
		(layer "F.Cu")
		(hatch none 0.5)
		(connect_pads
			(clearance 0)
		)
		(min_thickness 0.25)
		(keepout
			(tracks not_allowed)
			(vias allowed)
			(pads allowed)
			(copperpour not_allowed)
			(footprints allowed)
		)
		(placement
			(enabled no)
			(sheetname "")
		)
		(fill
			(thermal_gap 0.5)
			(thermal_bridge_width 0.5)
			(island_removal_mode 0)
		)
		(polygon
			(pts
				(arc
					(start 322.6816 -46.056042)
					(mid 322.3006 -46.437042)
					(end 322.6816 -46.818042)
				)
				(xy 323.03085 -46.818042)
				(arc
					(start 323.03085 -46.683168)
					(mid 323.004043 -46.591486)
					(end 322.932044 -46.528736)
				)
				(arc
					(start 322.932044 -46.528736)
					(mid 322.41523 -46.423745)
					(end 322.939918 -46.370748)
				)
				(arc
					(start 322.939918 -46.370748)
					(mid 323.104616 -46.472311)
					(end 323.181472 -46.649894)
				)
				(xy 323.18325 -46.651672) (xy 323.18325 -46.818042) (xy 323.32295 -46.818042) (xy 323.32295 -46.651672)
				(arc
					(start 323.324728 -46.649894)
					(mid 323.40157 -46.472299)
					(end 323.566282 -46.370748)
				)
				(arc
					(start 323.566282 -46.370748)
					(mid 324.090957 -46.423746)
					(end 323.574156 -46.528736)
				)
				(arc
					(start 323.574156 -46.528736)
					(mid 323.502201 -46.591514)
					(end 323.47535 -46.683168)
				)
				(xy 323.47535 -46.818042)
				(arc
					(start 323.824346 -46.818042)
					(mid 324.2056 -46.437169)
					(end 323.8246 -46.056042)
				)
			)
		)
	)
	(zone
		(net "GND")
		(layer "F.Cu")
		(hatch none 0.5)
		(connect_pads
			(clearance 0.5)
		)
		(min_thickness 0.25)
		(fill yes
			(thermal_gap 0.5)
			(thermal_bridge_width 0.5)
			(island_removal_mode 0)
		)
		(polygon
			(pts
				(xy 303.78527 -9.986772) (xy 303.293272 -10.47877) (xy 303.293272 -15.428976) (xy 303.796192 -15.931896)
				(xy 303.796192 -22.29485) (xy 304.200814 -22.699472) (xy 308.119272 -22.699472) (xy 308.424072 -22.394672)
				(xy 308.424072 -12.120372) (xy 306.290472 -9.986772)
			)
		)
	)
	(zone
		(layer "F.Cu")
		(hatch none 0.5)
		(connect_pads
			(clearance 0)
		)
		(min_thickness 0.25)
		(keepout
			(tracks allowed)
			(vias allowed)
			(pads allowed)
			(copperpour allowed)
			(footprints not_allowed)
		)
		(placement
			(enabled no)
			(sheetname "")
		)
		(fill
			(thermal_gap 0.5)
			(thermal_bridge_width 0.5)
			(island_removal_mode 0)
		)
		(polygon
			(pts
				(xy 189.799976 -199.799956) (xy 214.799926 -199.799956) (xy 214.799926 -173.800008) (xy 189.799976 -173.800008)
			)
		)
	)
	(zone
		(net "P12V_HDD8")
		(layer "F.Cu")
		(hatch none 0.5)
		(connect_pads
			(clearance 0.5)
		)
		(min_thickness 0.25)
		(fill yes
			(thermal_gap 0.5)
			(thermal_bridge_width 0.5)
			(island_removal_mode 0)
		)
		(polygon
			(pts
				(xy 398.2974 -278.6634) (xy 398.018 -278.9428) (xy 398.018 -289.306) (xy 397.637 -289.687) (xy 397.637 -297.902884)
				(xy 396.918942 -298.620942) (xy 396.918942 -300.90237) (xy 395.77137 -302.049942) (xy 389.36295 -302.049942)
				(xy 389.10895 -302.303942) (xy 389.10895 -303.954942) (xy 389.36295 -304.208942) (xy 393.29995 -304.208942)
				(xy 393.699492 -303.8094) (xy 397.3576 -303.8094) (xy 400.2024 -300.9646) (xy 400.2024 -287.2486)
				(xy 400.812 -286.639) (xy 400.812 -278.8666) (xy 400.6088 -278.6634)
			)
		)
		(polygon
			(pts
				(xy 393.45235 -303.091342) (xy 393.24915 -303.091342) (xy 393.24915 -303.294542) (xy 393.45235 -303.294542)
			)
		)
		(polygon
			(pts
				(xy 392.58875 -303.091342) (xy 392.38555 -303.091342) (xy 392.38555 -303.294542) (xy 392.58875 -303.294542)
			)
		)
	)
	(zone
		(net "GND")
		(layer "F.Cu")
		(hatch none 0.5)
		(connect_pads
			(clearance 0.5)
		)
		(min_thickness 0.25)
		(fill yes
			(thermal_gap 0.5)
			(thermal_bridge_width 0.5)
			(island_removal_mode 0)
		)
		(polygon
			(pts
				(xy 270.817848 -66.771012)
				(arc
					(start 270.817848 -25.192482)
					(mid 271.760175 -24.867291)
					(end 272.595848 -24.323802)
				)
				(arc
					(start 272.595848 -24.323802)
					(mid 272.966894 -24.316022)
					(end 273.33575 -24.275034)
				)
				(arc
					(start 273.33702 -24.275034)
					(mid 273.847613 -24.614231)
					(end 274.40509 -24.86914)
				)
				(arc
					(start 274.40509 -86.200234)
					(mid 275.301385 -88.84321)
					(end 277.620476 -90.395806)
				)
				(arc
					(start 277.620476 -90.395806)
					(mid 278.220104 -91.260762)
					(end 278.987758 -91.980766)
				)
				(arc
					(start 275.129498 -95.839026)
					(mid 274.180408 -95.643895)
					(end 273.212052 -95.677482)
				)
				(arc
					(start 273.212052 -95.677482)
					(mid 271.254978 -95.779687)
					(end 269.569946 -96.78035)
				)
				(arc
					(start 269.569946 -96.78035)
					(mid 269.516551 -96.729573)
					(end 269.46225 -96.679766)
				)
				(arc
					(start 269.46225 -96.679766)
					(mid 268.486998 -94.912168)
					(end 266.78509 -93.82633)
				)
				(arc
					(start 266.78509 -93.82633)
					(mid 265.578441 -93.289503)
					(end 264.263632 -93.165168)
				)
				(xy 264.263632 -73.324974)
			)
		)
	)
	(zone
		(layer "F.Cu")
		(hatch none 0.5)
		(connect_pads
			(clearance 0)
		)
		(min_thickness 0.25)
		(keepout
			(tracks allowed)
			(vias allowed)
			(pads allowed)
			(copperpour allowed)
			(footprints allowed)
		)
		(placement
			(enabled no)
			(sheetname "")
		)
		(fill
			(thermal_gap 0.5)
			(thermal_bridge_width 0.5)
			(island_removal_mode 0)
		)
		(polygon
			(pts
				(xy 365.9886 -45.2882) (xy 364.0836 -45.2882) (xy 364.0836 -44.577) (xy 365.9886 -44.577)
			)
		)
	)
	(zone
		(net "P12V_A")
		(layer "F.Cu")
		(hatch none 0.5)
		(connect_pads
			(clearance 0.5)
		)
		(min_thickness 0.25)
		(fill yes
			(thermal_gap 0.5)
			(thermal_bridge_width 0.5)
			(island_removal_mode 0)
		)
		(polygon
			(pts
				(xy 334.645 -56.428894) (xy 334.137 -56.936894) (xy 334.137 -60.365894) (xy 334.391 -60.619894)
				(xy 337.693 -60.619894) (xy 337.947 -60.365894) (xy 337.947 -58.333894) (xy 338.074 -58.206894)
				(xy 338.455 -58.206894) (xy 338.582 -58.079894) (xy 338.582 -56.555894) (xy 338.455 -56.428894)
			)
		)
		(polygon
			(pts
				(xy 338.0486 -57.444894) (xy 337.8454 -57.444894) (xy 337.8454 -57.648094) (xy 338.0486 -57.648094)
			)
		)
		(polygon
			(pts
				(xy 338.0994 -56.987694) (xy 337.8962 -56.987694) (xy 337.8962 -57.190894) (xy 338.0994 -57.190894)
			)
		)
	)
	(zone
		(layer "F.Cu")
		(hatch none 0.5)
		(connect_pads
			(clearance 0)
		)
		(min_thickness 0.25)
		(keepout
			(tracks not_allowed)
			(vias allowed)
			(pads allowed)
			(copperpour not_allowed)
			(footprints allowed)
		)
		(placement
			(enabled no)
			(sheetname "")
		)
		(fill
			(thermal_gap 0.5)
			(thermal_bridge_width 0.5)
			(island_removal_mode 0)
		)
		(polygon
			(pts
				(arc
					(start 170.200066 -265.122914)
					(mid 170.200066 -274.877022)
					(end 170.200066 -265.122914)
				)
			)
		)
	)
	(zone
		(layer "F.Cu")
		(hatch none 0.5)
		(connect_pads
			(clearance 0)
		)
		(min_thickness 0.25)
		(keepout
			(tracks allowed)
			(vias allowed)
			(pads allowed)
			(copperpour allowed)
			(footprints allowed)
		)
		(placement
			(enabled no)
			(sheetname "")
		)
		(fill
			(thermal_gap 0.5)
			(thermal_bridge_width 0.5)
			(island_removal_mode 0)
		)
		(polygon
			(pts
				(xy 172.268134 -28.128976) (xy 172.268134 -27.214576) (xy 170.286934 -27.214576) (xy 170.286934 -28.128976)
			)
		)
	)
	(zone
		(layer "F.Cu")
		(hatch none 0.5)
		(connect_pads
			(clearance 0)
		)
		(min_thickness 0.25)
		(keepout
			(tracks allowed)
			(vias allowed)
			(pads allowed)
			(copperpour allowed)
			(footprints not_allowed)
		)
		(placement
			(enabled no)
			(sheetname "")
		)
		(fill
			(thermal_gap 0.5)
			(thermal_bridge_width 0.5)
			(island_removal_mode 0)
		)
		(polygon
			(pts
				(xy 298.200064 -383.199894) (xy 291.599874 -383.199894) (xy 291.599874 -259.199888) (xy 298.200064 -259.199888)
				(xy 298.200064 -349.199962)
				(arc
					(start 296.69994 -349.199962)
					(mid 295.992835 -349.492855)
					(end 295.699942 -350.19996)
				)
				(arc
					(start 295.699942 -373.000016)
					(mid 295.992835 -373.707121)
					(end 296.69994 -374.000014)
				)
				(xy 298.200064 -374.000014)
			)
		)
	)
	(zone
		(layer "F.Cu")
		(hatch none 0.5)
		(connect_pads
			(clearance 0)
		)
		(min_thickness 0.25)
		(keepout
			(tracks allowed)
			(vias allowed)
			(pads allowed)
			(copperpour allowed)
			(footprints not_allowed)
		)
		(placement
			(enabled no)
			(sheetname "")
		)
		(fill
			(thermal_gap 0.5)
			(thermal_bridge_width 0.5)
			(island_removal_mode 0)
		)
		(polygon
			(pts
				(xy 198.399908 -199.799956) (xy 214.799926 -199.799956) (xy 214.799926 -173.800008) (xy 198.399908 -173.800008)
				(xy 198.399908 -167.699944) (xy 200.35012 -167.699944) (xy 208.049876 -167.699944) (xy 208.049876 -158.299912)
				(xy 200.35012 -158.299912) (xy 200.35012 -167.600122) (xy 198.399908 -167.600122) (xy 198.399908 -130.350006)
				(xy 287.699958 -130.350006) (xy 287.699958 -154.200098) (xy 291.599874 -154.200098) (xy 291.599874 -229.00005)
				(xy 289.649916 -229.00005) (xy 289.649916 -219.700094) (xy 281.949906 -219.700094) (xy 281.949906 -229.100126)
				(xy 289.649916 -229.100126) (xy 291.599874 -229.100126) (xy 291.599874 -233.19994) (xy 287.699958 -233.19994)
				(xy 287.699958 -239.529874) (xy 284.699964 -239.529874) (xy 284.699964 -230.229918) (xy 276.999954 -230.229918)
				(xy 276.999954 -239.62995) (xy 284.699964 -239.62995) (xy 287.699958 -239.62995) (xy 287.699958 -259.199888)
				(xy 291.599874 -259.199888) (xy 291.599874 -383.199894) (xy 290.20008 -383.199894) (xy 290.20008 -397.100044)
				(xy 264.500106 -397.100044) (xy 264.500106 -384.199892) (xy 254.500126 -384.199892) (xy 254.500126 -397.20012)
				(xy 264.500106 -397.20012) (xy 290.20008 -397.20012) (xy 290.20008 -409.200096) (xy 291.599874 -409.200096)
				(xy 291.599874 -421.200072)
				(arc
					(start 201.000106 -421.200072)
					(mid 200.293001 -420.907179)
					(end 200.000108 -420.200074)
				)
				(arc
					(start 200.000108 -374.000014)
					(mid 199.707215 -373.292909)
					(end 199.00011 -373.000016)
				)
				(xy 198.399908 -373.000016) (xy 198.399908 -312.999882) (xy 201.399902 -312.999882) (xy 209.099912 -312.999882)
				(xy 209.099912 -303.600104) (xy 201.399902 -303.600104) (xy 201.399902 -312.90006) (xy 198.399908 -312.90006)
			)
		)
	)
	(zone
		(layer "F.Cu")
		(hatch none 0.5)
		(connect_pads
			(clearance 0)
		)
		(min_thickness 0.25)
		(keepout
			(tracks allowed)
			(vias allowed)
			(pads allowed)
			(copperpour allowed)
			(footprints allowed)
		)
		(placement
			(enabled no)
			(sheetname "")
		)
		(fill
			(thermal_gap 0.5)
			(thermal_bridge_width 0.5)
			(island_removal_mode 0)
		)
		(polygon
			(pts
				(xy 286.28721 -138.249914) (xy 286.28721 -136.71931) (xy 284.21457 -136.71931) (xy 284.21457 -138.249914)
			)
		)
	)
	(zone
		(net "MB0_CM_GATE_R")
		(layer "F.Cu")
		(hatch none 0.5)
		(connect_pads
			(clearance 0.5)
		)
		(min_thickness 0.25)
		(fill yes
			(thermal_gap 0.5)
			(thermal_bridge_width 0.5)
			(island_removal_mode 0)
		)
		(polygon
			(pts
				(xy 165.943788 -144.94764) (xy 165.774624 -145.11655) (xy 165.774624 -147.110196) (xy 166.046912 -147.382484)
				(xy 167.34155 -147.382484) (xy 167.650414 -147.07362) (xy 167.650414 -145.073624) (xy 167.52443 -144.94764)
			)
		)
	)
	(zone
		(net "P5V_A_2")
		(layer "F.Cu")
		(hatch none 0.5)
		(connect_pads
			(clearance 0.5)
		)
		(min_thickness 0.25)
		(fill yes
			(thermal_gap 0.5)
			(thermal_bridge_width 0.5)
			(island_removal_mode 0)
		)
		(polygon
			(pts
				(xy 144.598898 -50.840894) (xy 144.344898 -51.094894) (xy 144.344898 -53.380894) (xy 144.598898 -53.634894)
				(xy 149.297898 -53.634894) (xy 149.551898 -53.380894) (xy 149.551898 -51.094894) (xy 149.297898 -50.840894)
			)
		)
	)
	(zone
		(net "GND")
		(layer "F.Cu")
		(hatch none 0.5)
		(connect_pads
			(clearance 0.5)
		)
		(min_thickness 0.25)
		(fill yes
			(thermal_gap 0.5)
			(thermal_bridge_width 0.5)
			(island_removal_mode 0)
		)
		(polygon
			(pts
				(xy 274.40509 -119.463566) (xy 274.40509 -124.551948)
				(arc
					(start 268.812518 -124.551948)
					(mid 268.53452 -124.448071)
					(end 268.249908 -124.363988)
				)
				(arc
					(start 268.249908 -120.196102)
					(mid 271.420801 -121.003361)
					(end 274.16887 -119.227346)
				)
			)
		)
	)
	(zone
		(layer "F.Cu")
		(hatch none 0.5)
		(connect_pads
			(clearance 0)
		)
		(min_thickness 0.25)
		(keepout
			(tracks allowed)
			(vias allowed)
			(pads allowed)
			(copperpour allowed)
			(footprints allowed)
		)
		(placement
			(enabled no)
			(sheetname "")
		)
		(fill
			(thermal_gap 0.5)
			(thermal_bridge_width 0.5)
			(island_removal_mode 0)
		)
		(polygon
			(pts
				(xy 228.3333 -348.5007) (xy 228.3333 -346.0369) (xy 221.4499 -346.0369) (xy 221.4499 -348.5007)
			)
		)
	)
	(zone
		(net "MB0_P12V_R")
		(layer "F.Cu")
		(hatch none 0.5)
		(connect_pads
			(clearance 0.5)
		)
		(min_thickness 0.25)
		(fill yes
			(thermal_gap 0.5)
			(thermal_bridge_width 0.5)
			(island_removal_mode 0)
		)
		(polygon
			(pts
				(xy 166.424102 -147.66417) (xy 165.916102 -148.17217) (xy 165.916102 -155.79217) (xy 166.424102 -156.30017)
				(xy 173.917102 -156.30017) (xy 174.171102 -156.04617) (xy 174.171102 -149.693122) (xy 174.140114 -149.662134)
				(xy 172.685964 -149.662134) (xy 172.562012 -149.538182) (xy 172.562012 -147.977606) (xy 172.248576 -147.66417)
			)
		)
	)
	(zone
		(net "P3V3_STBY_A")
		(layer "F.Cu")
		(hatch none 0.5)
		(connect_pads
			(clearance 0.5)
		)
		(min_thickness 0.25)
		(fill yes
			(thermal_gap 0.5)
			(thermal_bridge_width 0.5)
			(island_removal_mode 0)
		)
		(polygon
			(pts
				(xy 219.8624 -203.708) (xy 218.0082 -205.5622) (xy 218.0082 -218.0336) (xy 221.2086 -221.234) (xy 224.536 -221.234)
				(xy 229.8319 -226.5299) (xy 229.8319 -229.9589) (xy 231.0511 -231.1781) (xy 232.4735 -231.1781)
				(xy 232.5878 -231.0638) (xy 232.5878 -229.997) (xy 231.5464 -228.9556) (xy 231.5464 -228.38918)
				(xy 231.734106 -228.201474) (xy 239.10798 -228.201474) (xy 239.673892 -228.76764) (xy 239.673892 -232.449116)
				(xy 238.359188 -233.76382) (xy 238.359188 -236.613446) (xy 237.189264 -237.78337) (xy 237.189264 -239.87379)
				(xy 237.056676 -240.006378) (xy 237.056676 -241.639344) (xy 238.7346 -243.317268) (xy 238.7346 -243.984272)
				(xy 238.423704 -244.295168) (xy 236.614716 -244.295168) (xy 236.606588 -244.303296) (xy 236.516672 -244.392958)
				(xy 236.51337 -244.392958) (xy 236.51337 -245.12651) (xy 235.997496 -245.642384) (xy 234.405424 -245.642384)
				(xy 234.055412 -245.292372) (xy 234.055412 -244.938042) (xy 234.073446 -244.920008) (xy 234.07116 -244.917722)
				(xy 234.07116 -244.292628) (xy 234.002834 -244.224302) (xy 233.608118 -244.224302) (xy 233.556556 -244.275864)
				(xy 233.556556 -245.740936) (xy 234.37342 -246.5578) (xy 234.37342 -246.959882) (xy 233.800904 -247.532398)
				(xy 233.800904 -248.804684) (xy 233.882692 -248.886472) (xy 234.458256 -248.886472) (xy 234.658154 -248.686574)
				(xy 234.658154 -247.832372) (xy 235.120942 -247.369584) (xy 235.120942 -247.12549) (xy 235.44784 -246.798592)
				(xy 236.433868 -246.798592) (xy 237.231428 -246.001032) (xy 237.406942 -246.001032) (xy 237.411514 -246.005604)
				(xy 237.729776 -246.005604) (xy 237.729776 -245.999) (xy 240.7666 -245.999) (xy 242.2144 -247.4468)
				(xy 242.2144 -248.92) (xy 242.2906 -248.9962) (xy 242.824 -248.9962) (xy 242.951 -248.8692) (xy 242.951 -247.7262)
				(xy 243.2304 -247.4468) (xy 244.348 -247.4468) (xy 244.5004 -247.5992) (xy 244.5004 -248.92) (xy 244.6528 -249.0724)
				(xy 245.2878 -249.0724) (xy 245.300246 -249.059954) (xy 245.302786 -249.062494) (xy 248.001282 -249.062494)
				(xy 248.946416 -250.007628) (xy 248.946416 -259.766562) (xy 249.318272 -260.138418) (xy 249.318272 -260.993128)
				(xy 248.3866 -261.9248) (xy 244.5766 -261.9248) (xy 244.2464 -261.5946) (xy 244.2464 -260.8326)
				(xy 244.1448 -260.731) (xy 243.6368 -260.731) (xy 243.5352 -260.8326) (xy 243.5352 -262.374634)
				(xy 243.28247 -262.627364) (xy 240.283238 -262.627364) (xy 239.774476 -262.118602) (xy 239.774476 -258.765294)
				(xy 240.07445 -258.46532) (xy 241.0714 -258.46532) (xy 241.072924 -258.463796) (xy 241.072924 -258.22021)
				(xy 241.07902 -258.214114) (xy 241.07902 -256.95402) (xy 241.0714 -256.9464) (xy 240.021618 -256.9464)
				(xy 239.939576 -256.864358) (xy 238.114586 -256.864358) (xy 236.96549 -255.715262) (xy 236.96549 -253.412244)
				(xy 237.048294 -253.32944) (xy 237.048294 -252.464062) (xy 237.21568 -252.296676) (xy 237.21568 -251.524262)
				(xy 236.606842 -250.915424) (xy 235.40085 -250.915424) (xy 235.29925 -251.017024) (xy 235.29925 -252.5776)
				(xy 236.16666 -253.44501) (xy 236.16666 -258.419854) (xy 237.27283 -259.526024) (xy 237.313724 -259.526024)
				(xy 238.452914 -260.665214) (xy 238.452914 -262.835136) (xy 237.434882 -262.835136) (xy 237.32363 -262.723884)
				(xy 237.32363 -261.969504) (xy 237.253526 -261.8994) (xy 236.708188 -261.8994) (xy 236.641894 -261.833106)
				(xy 235.74502 -261.833106) (xy 235.704126 -261.874) (xy 235.704126 -262.282686) (xy 235.83138 -262.40994)
				(xy 236.499146 -262.40994) (xy 236.817154 -262.727948) (xy 236.817154 -263.532112) (xy 236.426248 -263.923018)
				(xy 235.02239 -263.923018) (xy 234.204764 -263.105392) (xy 234.204764 -261.95528) (xy 234.059476 -261.809992)
				(xy 233.72318 -261.809992) (xy 233.627676 -261.905496) (xy 233.627676 -262.323834) (xy 233.632248 -262.328406)
				(xy 233.632248 -262.596376) (xy 233.561128 -262.667496) (xy 233.561128 -263.558528) (xy 234.7595 -264.7569)
				(xy 242.9383 -264.7569) (xy 244.221 -263.4742) (xy 250.4694 -263.4742) (xy 251.9172 -264.922) (xy 256.0828 -264.922)
				(xy 259.153914 -267.993114) (xy 259.153914 -271.699736) (xy 259.592318 -272.13814) (xy 261.381494 -272.13814)
				(xy 261.487666 -272.031968) (xy 261.487666 -270.461994) (xy 261.747508 -270.202152) (xy 263.713976 -270.202152)
				(xy 264.104628 -270.592804) (xy 264.104628 -272.109946) (xy 264.246106 -272.251424) (xy 271.814036 -272.251424)
				(xy 272.00479 -272.06067) (xy 272.00479 -270.5354) (xy 272.474182 -270.066008) (xy 273.064986 -270.066008)
				(xy 273.364452 -270.365474) (xy 273.364452 -272.064988) (xy 273.542506 -272.243042) (xy 274.160234 -272.243042)
				(xy 274.296886 -272.10639) (xy 274.296886 -270.269208) (xy 274.500086 -270.066008) (xy 275.390356 -270.066008)
				(xy 275.677376 -270.353028) (xy 275.677376 -272.135346) (xy 275.776944 -272.234914) (xy 276.415246 -272.234914)
				(xy 276.63902 -272.01114) (xy 276.63902 -270.513556) (xy 277.086568 -270.066008) (xy 281.230324 -270.066008)
				(xy 281.64409 -270.479774) (xy 281.64409 -272.100294) (xy 281.733244 -272.189448) (xy 283.503116 -272.189448)
				(xy 283.577538 -272.115026) (xy 283.577538 -270.23187) (xy 283.7434 -270.066008) (xy 286.009588 -270.066008)
				(xy 286.330136 -270.386556) (xy 286.330136 -272.131536) (xy 286.417004 -272.218404) (xy 287.59023 -272.218404)
				(xy 288.049716 -271.758918) (xy 288.049716 -269.308326) (xy 287.72739 -268.986) (xy 262.636 -268.986)
				(xy 258.7752 -265.1252) (xy 258.7752 -261.7216) (xy 258.5974 -261.5438) (xy 258.0894 -261.5438)
				(xy 257.937 -261.6962) (xy 257.937 -263.0678) (xy 257.6068 -263.398) (xy 252.2982 -263.398) (xy 251.7648 -262.8646)
				(xy 251.7648 -261.4422) (xy 252.0442 -261.1628) (xy 252.73 -261.1628) (xy 252.8062 -261.0866) (xy 252.8062 -259.42036)
				(xy 253.566676 -258.659884) (xy 253.566676 -257.08356) (xy 253.515876 -257.03276) (xy 250.45924 -257.03276)
				(xy 250.161298 -256.734818) (xy 250.161298 -254.509016) (xy 250.673108 -253.997206) (xy 250.673108 -249.456448)
				(xy 250.179332 -248.962672) (xy 250.179332 -246.971058) (xy 250.36399 -246.7864) (xy 253.8984 -246.7864)
				(xy 254.1778 -247.0658) (xy 254.1778 -248.5898) (xy 254.3048 -248.7168) (xy 256.032 -248.7168) (xy 256.0828 -248.666)
				(xy 256.0828 -246.5324) (xy 254.8382 -245.2878) (xy 246.6086 -245.2878) (xy 245.3386 -244.0178)
				(xy 245.3386 -242.9256) (xy 245.237 -242.824) (xy 244.5766 -242.824) (xy 244.475 -242.9256) (xy 244.475 -244.5004)
				(xy 244.1194 -244.856) (xy 241.3 -244.856) (xy 238.23676 -241.79276) (xy 238.23676 -240.262664)
				(xy 238.05388 -240.07953) (xy 237.770416 -239.796066) (xy 237.770416 -238.652558) (xy 239.014508 -237.408466)
				(xy 239.014508 -237.39729) (xy 241.336322 -235.075476) (xy 241.336322 -231.216454) (xy 241.565176 -230.9876)
				(xy 243.2812 -230.9876) (xy 243.3828 -230.886) (xy 243.3828 -229.4636) (xy 243.7892 -229.0572) (xy 245.126002 -229.0572)
				(xy 246.126 -230.057198) (xy 246.126 -230.9368) (xy 246.1768 -230.9876) (xy 246.761 -230.9876) (xy 246.790464 -230.958136)
				(xy 246.790464 -230.740966) (xy 246.794528 -230.736902) (xy 246.794528 -229.884986) (xy 246.785384 -229.875842)
				(xy 246.785384 -229.76586) (xy 243.231924 -226.2124) (xy 232.1814 -226.2124) (xy 227.2792 -221.3102)
				(xy 227.2792 -217.1446) (xy 227.203 -217.0684) (xy 225.7044 -217.0684) (xy 225.6028 -217.17) (xy 225.6028 -219.2528)
				(xy 225.3742 -219.4814) (xy 221.5134 -219.4814) (xy 220.6752 -218.6432) (xy 220.6752 -216.6112)
				(xy 221.107 -216.1794) (xy 222.5802 -216.1794) (xy 222.7326 -216.027) (xy 222.7326 -214.0712) (xy 222.631 -213.9696)
				(xy 219.3798 -213.9696) (xy 219.1004 -213.6902) (xy 219.1004 -207.973676) (xy 219.861638 -207.212438)
				(xy 221.466918 -207.212438) (xy 221.54515 -207.134206) (xy 221.54515 -205.68285) (xy 221.742 -205.486)
				(xy 224.6376 -205.486) (xy 224.7519 -205.3717) (xy 224.7519 -203.8223) (xy 224.6376 -203.708)
			)
		)
		(polygon
			(pts
				(xy 287.1216 -271.5006) (xy 286.9184 -271.5006) (xy 286.9184 -271.7038) (xy 287.1216 -271.7038)
			)
		)
		(polygon
			(pts
				(xy 283.083 -271.5006) (xy 282.8798 -271.5006) (xy 282.8798 -271.7038) (xy 283.083 -271.7038)
			)
		)
		(polygon
			(pts
				(xy 282.448 -271.5006) (xy 282.2448 -271.5006) (xy 282.2448 -271.7038) (xy 282.448 -271.7038)
			)
		)
		(polygon
			(pts
				(xy 276.479 -271.4752) (xy 276.2758 -271.4752) (xy 276.2758 -271.6784) (xy 276.479 -271.6784)
			)
		)
		(polygon
			(pts
				(xy 271.3482 -271.4752) (xy 271.145 -271.4752) (xy 271.145 -271.6784) (xy 271.3482 -271.6784)
			)
		)
		(polygon
			(pts
				(xy 264.922 -271.4752) (xy 264.7188 -271.4752) (xy 264.7188 -271.6784) (xy 264.922 -271.6784)
			)
		)
		(polygon
			(pts
				(xy 260.9342 -271.4752) (xy 260.731 -271.4752) (xy 260.731 -271.6784) (xy 260.9342 -271.6784)
			)
		)
		(polygon
			(pts
				(xy 260.35 -271.4752) (xy 260.1468 -271.4752) (xy 260.1468 -271.6784) (xy 260.35 -271.6784)
			)
		)
		(polygon
			(pts
				(xy 259.7912 -271.4752) (xy 259.588 -271.4752) (xy 259.588 -271.6784) (xy 259.7912 -271.6784)
			)
		)
		(polygon
			(pts
				(xy 252.209046 -260.513322) (xy 252.005846 -260.513322) (xy 252.005846 -260.716522) (xy 252.209046 -260.716522)
			)
		)
		(polygon
			(pts
				(xy 251.47778 -257.837178) (xy 251.27458 -257.837178) (xy 251.27458 -258.040378) (xy 251.47778 -258.040378)
			)
		)
		(polygon
			(pts
				(xy 250.61418 -257.837178) (xy 250.41098 -257.837178) (xy 250.41098 -258.040378) (xy 250.61418 -258.040378)
			)
		)
		(polygon
			(pts
				(xy 239.0394 -257.6322) (xy 238.8362 -257.6322) (xy 238.8362 -257.8354) (xy 239.0394 -257.8354)
			)
		)
		(polygon
			(pts
				(xy 238.1758 -257.6322) (xy 237.9726 -257.6322) (xy 237.9726 -257.8354) (xy 238.1758 -257.8354)
			)
		)
		(polygon
			(pts
				(xy 252.626876 -257.54076) (xy 252.423676 -257.54076) (xy 252.423676 -257.74396) (xy 252.626876 -257.74396)
			)
		)
		(polygon
			(pts
				(xy 252.017276 -257.54076) (xy 251.814076 -257.54076) (xy 251.814076 -257.74396) (xy 252.017276 -257.74396)
			)
		)
		(polygon
			(pts
				(xy 240.0554 -257.3782) (xy 239.8522 -257.3782) (xy 239.8522 -257.5814) (xy 240.0554 -257.5814)
			)
		)
		(polygon
			(pts
				(xy 239.4458 -257.3782) (xy 239.2426 -257.3782) (xy 239.2426 -257.5814) (xy 239.4458 -257.5814)
			)
		)
		(polygon
			(pts
				(xy 236.468412 -253.14148) (xy 236.265212 -253.14148) (xy 236.265212 -253.34468) (xy 236.468412 -253.34468)
			)
		)
		(polygon
			(pts
				(xy 236.450886 -252.238002) (xy 236.247686 -252.238002) (xy 236.247686 -252.441202) (xy 236.265212 -252.53188)
				(xy 236.265212 -252.73508) (xy 236.468412 -252.73508) (xy 236.468412 -252.53188) (xy 236.450886 -252.441202)
			)
		)
		(polygon
			(pts
				(xy 236.450886 -251.374402) (xy 236.247686 -251.374402) (xy 236.247686 -251.577602) (xy 236.450886 -251.577602)
			)
		)
		(polygon
			(pts
				(xy 245.237 -248.3612) (xy 245.0338 -248.3612) (xy 245.0338 -248.5644) (xy 245.237 -248.5644)
			)
		)
		(polygon
			(pts
				(xy 234.4674 -248.158) (xy 234.2642 -248.158) (xy 234.2642 -248.3612) (xy 234.4674 -248.3612)
			)
		)
		(polygon
			(pts
				(xy 255.522476 -248.06656) (xy 255.319276 -248.06656) (xy 255.319276 -248.26976) (xy 255.522476 -248.26976)
			)
		)
		(polygon
			(pts
				(xy 254.938276 -248.06656) (xy 254.735076 -248.06656) (xy 254.735076 -248.26976) (xy 254.938276 -248.26976)
			)
		)
		(polygon
			(pts
				(xy 238.343694 -244.756178) (xy 238.140494 -244.756178) (xy 238.140494 -244.959378) (xy 238.343694 -244.959378)
			)
		)
		(polygon
			(pts
				(xy 237.784894 -244.756178) (xy 237.581694 -244.756178) (xy 237.581694 -244.959378) (xy 237.784894 -244.959378)
			)
		)
		(polygon
			(pts
				(xy 237.200694 -244.756178) (xy 236.997494 -244.756178) (xy 236.997494 -244.959378) (xy 237.200694 -244.959378)
			)
		)
		(polygon
			(pts
				(xy 245.2116 -243.2812) (xy 245.0084 -243.2812) (xy 245.0084 -243.4844) (xy 245.2116 -243.4844)
			)
		)
		(polygon
			(pts
				(xy 232.1306 -230.505) (xy 231.9274 -230.505) (xy 231.9274 -230.7082) (xy 232.1306 -230.7082)
			)
		)
		(polygon
			(pts
				(xy 242.9002 -230.3272) (xy 242.697 -230.3272) (xy 242.697 -230.5304) (xy 242.9002 -230.5304)
			)
		)
		(polygon
			(pts
				(xy 242.316 -230.3272) (xy 242.1128 -230.3272) (xy 242.1128 -230.5304) (xy 242.316 -230.5304)
			)
		)
		(polygon
			(pts
				(xy 241.7572 -230.3272) (xy 241.554 -230.3272) (xy 241.554 -230.5304) (xy 241.7572 -230.5304)
			)
		)
		(polygon
			(pts
				(xy 223.309942 -219.913962) (xy 223.106742 -219.913962) (xy 223.106742 -220.117162) (xy 223.309942 -220.117162)
			)
		)
		(polygon
			(pts
				(xy 222.751142 -219.913962) (xy 222.547942 -219.913962) (xy 222.547942 -220.117162) (xy 222.751142 -220.117162)
			)
		)
		(polygon
			(pts
				(xy 224.5106 -219.905072) (xy 224.3074 -219.905072) (xy 224.3074 -220.108272) (xy 224.5106 -220.108272)
			)
		)
		(polygon
			(pts
				(xy 223.9518 -219.905072) (xy 223.7486 -219.905072) (xy 223.7486 -220.108272) (xy 223.9518 -220.108272)
			)
		)
		(polygon
			(pts
				(xy 226.263962 -217.786458) (xy 226.060762 -217.786458) (xy 226.060762 -217.989658) (xy 226.263962 -217.989658)
			)
		)
		(polygon
			(pts
				(xy 226.263962 -217.227658) (xy 226.060762 -217.227658) (xy 226.060762 -217.430858) (xy 226.263962 -217.430858)
			)
		)
		(polygon
			(pts
				(xy 220.411802 -214.795862) (xy 220.208602 -214.795862) (xy 220.208602 -214.999062) (xy 220.411802 -214.999062)
			)
		)
		(polygon
			(pts
				(xy 219.548202 -214.795862) (xy 219.345002 -214.795862) (xy 219.345002 -214.999062) (xy 219.548202 -214.999062)
			)
		)
		(polygon
			(pts
				(xy 221.427802 -214.541862) (xy 221.224602 -214.541862) (xy 221.224602 -214.745062) (xy 221.427802 -214.745062)
			)
		)
		(polygon
			(pts
				(xy 220.818202 -214.541862) (xy 220.615002 -214.541862) (xy 220.615002 -214.745062) (xy 220.818202 -214.745062)
			)
		)
		(polygon
			(pts
				(xy 221.087442 -206.52232) (xy 220.884242 -206.52232) (xy 220.884242 -206.72552) (xy 221.087442 -206.72552)
			)
		)
		(polygon
			(pts
				(xy 224.2058 -204.833728) (xy 224.0026 -204.833728) (xy 224.0026 -205.036928) (xy 224.2058 -205.036928)
			)
		)
		(polygon
			(pts
				(xy 223.563942 -204.826362) (xy 223.360742 -204.826362) (xy 223.360742 -205.029562) (xy 223.563942 -205.029562)
			)
		)
		(polygon
			(pts
				(xy 223.005142 -204.826362) (xy 222.801942 -204.826362) (xy 222.801942 -205.029562) (xy 223.005142 -205.029562)
			)
		)
	)
	(zone
		(layer "F.Cu")
		(hatch none 0.5)
		(connect_pads
			(clearance 0)
		)
		(min_thickness 0.25)
		(keepout
			(tracks not_allowed)
			(vias allowed)
			(pads allowed)
			(copperpour not_allowed)
			(footprints allowed)
		)
		(placement
			(enabled no)
			(sheetname "")
		)
		(fill
			(thermal_gap 0.5)
			(thermal_bridge_width 0.5)
			(island_removal_mode 0)
		)
		(polygon
			(pts
				(arc
					(start 271.970754 -350.124014)
					(mid 271.5895 -350.504887)
					(end 271.9705 -350.886014)
				)
				(arc
					(start 273.1135 -350.886014)
					(mid 273.4945 -350.505014)
					(end 273.1135 -350.124014)
				)
				(xy 272.76425 -350.124014)
				(arc
					(start 272.76425 -350.378014)
					(mid 272.779129 -350.413935)
					(end 272.81505 -350.428814)
				)
				(arc
					(start 272.857976 -350.428814)
					(mid 273.380144 -350.505014)
					(end 272.857976 -350.581214)
				)
				(xy 272.783554 -350.581214)
				(arc
					(start 272.780506 -350.578166)
					(mid 272.671429 -350.521635)
					(end 272.614898 -350.412558)
				)
				(xy 272.61185 -350.40951) (xy 272.61185 -350.124014) (xy 272.47215 -350.124014) (xy 272.47215 -350.40951)
				(arc
					(start 272.469102 -350.412558)
					(mid 272.412571 -350.521635)
					(end 272.303494 -350.578166)
				)
				(xy 272.300446 -350.581214)
				(arc
					(start 272.226024 -350.581214)
					(mid 271.703856 -350.505014)
					(end 272.226024 -350.428814)
				)
				(arc
					(start 272.26895 -350.428814)
					(mid 272.304871 -350.413935)
					(end 272.31975 -350.378014)
				)
				(xy 272.31975 -350.124014)
			)
		)
	)
	(zone
		(layer "F.Cu")
		(hatch none 0.5)
		(connect_pads
			(clearance 0)
		)
		(min_thickness 0.25)
		(keepout
			(tracks allowed)
			(vias allowed)
			(pads allowed)
			(copperpour allowed)
			(footprints allowed)
		)
		(placement
			(enabled no)
			(sheetname "")
		)
		(fill
			(thermal_gap 0.5)
			(thermal_bridge_width 0.5)
			(island_removal_mode 0)
		)
		(polygon
			(pts
				(xy 225.7806 -373.634) (xy 225.7806 -376.8344) (xy 222.123 -376.8344) (xy 222.123 -373.634)
			)
		)
	)
	(zone
		(layer "F.Cu")
		(hatch none 0.5)
		(connect_pads
			(clearance 0)
		)
		(min_thickness 0.25)
		(keepout
			(tracks allowed)
			(vias allowed)
			(pads allowed)
			(copperpour allowed)
			(footprints not_allowed)
		)
		(placement
			(enabled no)
			(sheetname "")
		)
		(fill
			(thermal_gap 0.5)
			(thermal_bridge_width 0.5)
			(island_removal_mode 0)
		)
		(polygon
			(pts
				(arc
					(start 293.200074 -393.199874)
					(mid 300.20006 -386.199888)
					(end 307.200046 -393.199874)
				)
				(arc
					(start 307.200046 -399.200116)
					(mid 300.20006 -406.200102)
					(end 293.200074 -399.200116)
				)
			)
		)
	)
	(zone
		(layer "F.Cu")
		(hatch none 0.5)
		(connect_pads
			(clearance 0)
		)
		(min_thickness 0.25)
		(keepout
			(tracks allowed)
			(vias allowed)
			(pads allowed)
			(copperpour allowed)
			(footprints allowed)
		)
		(placement
			(enabled no)
			(sheetname "")
		)
		(fill
			(thermal_gap 0.5)
			(thermal_bridge_width 0.5)
			(island_removal_mode 0)
		)
		(polygon
			(pts
				(xy 94.0054 -278.511) (xy 95.9358 -278.511) (xy 96.1136 -278.3332) (xy 96.1136 -277.2664) (xy 95.7326 -276.8854)
				(xy 94.0054 -276.8854) (xy 93.9038 -276.987) (xy 93.9038 -278.4094)
			)
		)
	)
	(zone
		(layer "F.Cu")
		(hatch none 0.5)
		(connect_pads
			(clearance 0)
		)
		(min_thickness 0.25)
		(keepout
			(tracks allowed)
			(vias allowed)
			(pads allowed)
			(copperpour allowed)
			(footprints not_allowed)
		)
		(placement
			(enabled no)
			(sheetname "")
		)
		(fill
			(thermal_gap 0.5)
			(thermal_bridge_width 0.5)
			(island_removal_mode 0)
		)
		(polygon
			(pts
				(arc
					(start 439.17489 -210.799934)
					(mid 425.174918 -224.799906)
					(end 411.174946 -210.799934)
				)
				(arc
					(start 411.174946 -210.799934)
					(mid 425.174918 -196.799962)
					(end 439.17489 -210.799934)
				)
			)
		)
	)
	(zone
		(net "P5V_HDD35")
		(layer "F.Cu")
		(hatch none 0.5)
		(connect_pads
			(clearance 0.5)
		)
		(min_thickness 0.25)
		(fill yes
			(thermal_gap 0.5)
			(thermal_bridge_width 0.5)
			(island_removal_mode 0)
		)
		(polygon
			(pts
				(xy 474.768926 -56.682894) (xy 474.514926 -56.936894) (xy 474.514926 -59.222894) (xy 474.768926 -59.476894)
				(xy 474.768926 -61.508894) (xy 475.530926 -62.270894) (xy 475.530926 -63.032894) (xy 475.911926 -63.413894)
				(xy 476.292926 -63.413894) (xy 479.467926 -66.588894) (xy 486.325926 -66.588894) (xy 486.452926 -66.461894)
				(xy 486.452926 -64.683894) (xy 486.325926 -64.556894) (xy 481.245926 -64.556894) (xy 479.340926 -62.651894)
				(xy 478.451926 -62.651894) (xy 477.562926 -61.762894) (xy 477.562926 -59.222894) (xy 478.197926 -58.587894)
				(xy 478.197926 -56.936894) (xy 477.943926 -56.682894)
			)
		)
		(polygon
			(pts
				(xy 476.775526 -63.109094) (xy 476.572326 -63.109094) (xy 476.572326 -63.312294) (xy 476.775526 -63.312294)
			)
		)
		(polygon
			(pts
				(xy 476.775526 -62.245494) (xy 476.572326 -62.245494) (xy 476.572326 -62.448694) (xy 476.775526 -62.448694)
			)
		)
		(polygon
			(pts
				(xy 475.911926 -62.245494) (xy 475.708726 -62.245494) (xy 475.708726 -62.448694) (xy 475.911926 -62.448694)
			)
		)
	)
	(zone
		(net "P5V_HDD30")
		(layer "F.Cu")
		(hatch none 0.5)
		(connect_pads
			(clearance 0.5)
		)
		(min_thickness 0.25)
		(fill yes
			(thermal_gap 0.5)
			(thermal_bridge_width 0.5)
			(island_removal_mode 0)
		)
		(polygon
			(pts
				(xy 331.597 -51.729894) (xy 331.343 -51.983894) (xy 331.343 -62.778894) (xy 329.692 -64.429894)
				(xy 326.263 -64.429894) (xy 326.009 -64.683894) (xy 326.009 -66.334894) (xy 326.263 -66.588894)
				(xy 330.835 -66.588894) (xy 331.47 -65.953894) (xy 333.248 -65.953894) (xy 333.756 -65.445894) (xy 333.756 -51.983894)
				(xy 333.502 -51.729894)
			)
		)
		(polygon
			(pts
				(xy 330.3524 -65.598294) (xy 330.1492 -65.598294) (xy 330.1492 -65.801494) (xy 330.3524 -65.801494)
			)
		)
		(polygon
			(pts
				(xy 329.4888 -65.598294) (xy 329.2856 -65.598294) (xy 329.2856 -65.801494) (xy 329.4888 -65.801494)
			)
		)
	)
	(zone
		(net "GND")
		(layer "F.Cu")
		(hatch none 0.5)
		(connect_pads
			(clearance 0.5)
		)
		(min_thickness 0.25)
		(fill yes
			(thermal_gap 0.5)
			(thermal_bridge_width 0.5)
			(island_removal_mode 0)
		)
		(polygon
			(pts
				(xy 167.64 -48.3362) (xy 168.019476 -47.956724)
				(arc
					(start 168.019476 -47.71136)
					(mid 167.982134 -47.159926)
					(end 168.019476 -46.608492)
				)
				(xy 168.019476 -41.51757) (xy 170.305476 -41.51757) (xy 170.305476 -41.18737) (xy 172.159676 -41.18737)
				(xy 172.159676 -41.11117) (xy 176.223676 -41.11117) (xy 176.223676 -40.73017) (xy 180.843936 -40.73017)
				(arc
					(start 180.843936 -37.818314)
					(mid 180.348583 -37.010397)
					(end 180.052472 -36.110164)
				)
				(xy 169.234866 -38.316408) (xy 161.2392 -36.743132) (xy 161.2392 -39.671244) (xy 162.93211 -39.671244)
				(xy 162.93211 -41.065196) (xy 164.936424 -42.33418) (xy 167.041068 -48.042068) (xy 167.3352 -48.3362)
			)
		)
	)
	(zone
		(net "5V_PRE_13")
		(layer "F.Cu")
		(hatch none 0.5)
		(connect_pads
			(clearance 0.5)
		)
		(min_thickness 0.25)
		(fill yes
			(thermal_gap 0.5)
			(thermal_bridge_width 0.5)
			(island_removal_mode 0)
		)
		(polygon
			(pts
				(xy 54.470046 -175.0568) (xy 54.393846 -175.133) (xy 54.393846 -176.508918) (xy 54.520846 -176.635918)
				(xy 55.790846 -176.635918) (xy 58.330846 -179.175918) (xy 62.775846 -179.175918) (xy 62.902846 -179.048918)
				(xy 62.902846 -178.286918) (xy 62.775846 -178.159918) (xy 59.6392 -178.159918) (xy 56.536082 -175.0568)
			)
		)
	)
	(zone
		(layer "F.Cu")
		(hatch none 0.5)
		(connect_pads
			(clearance 0)
		)
		(min_thickness 0.25)
		(keepout
			(tracks not_allowed)
			(vias allowed)
			(pads allowed)
			(copperpour not_allowed)
			(footprints allowed)
		)
		(placement
			(enabled no)
			(sheetname "")
		)
		(fill
			(thermal_gap 0.5)
			(thermal_bridge_width 0.5)
			(island_removal_mode 0)
		)
		(polygon
			(pts
				(arc
					(start 190.639954 -277.17877)
					(mid 190.259081 -276.797516)
					(end 189.877954 -277.178516)
				)
				(xy 189.877954 -277.527766)
				(arc
					(start 190.131954 -277.527766)
					(mid 190.167875 -277.512887)
					(end 190.182754 -277.476966)
				)
				(arc
					(start 190.182754 -277.43404)
					(mid 190.258954 -276.911872)
					(end 190.335154 -277.43404)
				)
				(xy 190.335154 -277.508462)
				(arc
					(start 190.332106 -277.51151)
					(mid 190.275575 -277.620587)
					(end 190.166498 -277.677118)
				)
				(xy 190.16345 -277.680166) (xy 189.877954 -277.680166) (xy 189.877954 -277.819866) (xy 190.16345 -277.819866)
				(arc
					(start 190.166498 -277.822914)
					(mid 190.275575 -277.879445)
					(end 190.332106 -277.988522)
				)
				(xy 190.335154 -277.99157)
				(arc
					(start 190.335154 -278.065992)
					(mid 190.258954 -278.58816)
					(end 190.182754 -278.065992)
				)
				(arc
					(start 190.182754 -278.023066)
					(mid 190.167875 -277.987145)
					(end 190.131954 -277.972266)
				)
				(xy 189.877954 -277.972266)
				(arc
					(start 189.877954 -278.321516)
					(mid 190.258954 -278.702516)
					(end 190.639954 -278.321516)
				)
			)
		)
	)
	(zone
		(net "P3V3_STBY_A")
		(layer "F.Cu")
		(hatch none 0.5)
		(connect_pads
			(clearance 0.5)
		)
		(min_thickness 0.25)
		(fill yes
			(thermal_gap 0.5)
			(thermal_bridge_width 0.5)
			(island_removal_mode 0)
		)
		(polygon
			(pts
				(xy 246.14378 -297.053) (xy 245.580154 -297.616626) (xy 245.580154 -299.555662) (xy 246.150892 -300.1264)
				(xy 247.4468 -300.1264) (xy 247.7516 -299.8216) (xy 247.7516 -297.2054) (xy 247.5992 -297.053)
			)
		)
		(polygon
			(pts
				(xy 247.56237 -299.174662) (xy 247.35917 -299.174662) (xy 247.35917 -299.377862) (xy 247.56237 -299.377862)
			)
		)
		(polygon
			(pts
				(xy 246.95277 -299.174662) (xy 246.74957 -299.174662) (xy 246.74957 -299.377862) (xy 246.95277 -299.377862)
			)
		)
	)
	(zone
		(layer "F.Cu")
		(hatch none 0.5)
		(connect_pads
			(clearance 0)
		)
		(min_thickness 0.25)
		(keepout
			(tracks not_allowed)
			(vias allowed)
			(pads allowed)
			(copperpour not_allowed)
			(footprints allowed)
		)
		(placement
			(enabled no)
			(sheetname "")
		)
		(fill
			(thermal_gap 0.5)
			(thermal_bridge_width 0.5)
			(island_removal_mode 0)
		)
		(polygon
			(pts
				(arc
					(start 64.4398 -162.178746)
					(mid 64.058927 -161.797492)
					(end 63.6778 -162.178492)
				)
				(xy 63.6778 -162.527742)
				(arc
					(start 63.9318 -162.527742)
					(mid 63.967721 -162.512863)
					(end 63.9826 -162.476942)
				)
				(arc
					(start 63.9826 -162.434016)
					(mid 64.0588 -161.911848)
					(end 64.135 -162.434016)
				)
				(xy 64.135 -162.508438)
				(arc
					(start 64.131952 -162.511486)
					(mid 64.075421 -162.620563)
					(end 63.966344 -162.677094)
				)
				(xy 63.963296 -162.680142) (xy 63.6778 -162.680142) (xy 63.6778 -162.819842) (xy 63.963296 -162.819842)
				(arc
					(start 63.966344 -162.82289)
					(mid 64.075421 -162.879421)
					(end 64.131952 -162.988498)
				)
				(xy 64.135 -162.991546)
				(arc
					(start 64.135 -163.065968)
					(mid 64.0588 -163.588136)
					(end 63.9826 -163.065968)
				)
				(arc
					(start 63.9826 -163.023042)
					(mid 63.967721 -162.987121)
					(end 63.9318 -162.972242)
				)
				(xy 63.6778 -162.972242)
				(arc
					(start 63.6778 -163.321492)
					(mid 64.0588 -163.702492)
					(end 64.4398 -163.321492)
				)
			)
		)
	)
	(zone
		(layer "F.Cu")
		(hatch none 0.5)
		(connect_pads
			(clearance 0)
		)
		(min_thickness 0.25)
		(keepout
			(tracks allowed)
			(vias allowed)
			(pads allowed)
			(copperpour allowed)
			(footprints not_allowed)
		)
		(placement
			(enabled no)
			(sheetname "")
		)
		(fill
			(thermal_gap 0.5)
			(thermal_bridge_width 0.5)
			(island_removal_mode 0)
		)
		(polygon
			(pts
				(arc
					(start 178.649884 -208.499964)
					(mid 182.39994 -204.749908)
					(end 186.149996 -208.499964)
				)
				(arc
					(start 186.149996 -208.499964)
					(mid 182.39994 -212.25002)
					(end 178.649884 -208.499964)
				)
			)
		)
	)
	(zone
		(net "12V_PRE_24")
		(layer "F.Cu")
		(hatch none 0.5)
		(connect_pads
			(clearance 0.5)
		)
		(min_thickness 0.25)
		(fill yes
			(thermal_gap 0.5)
			(thermal_bridge_width 0.5)
			(island_removal_mode 0)
		)
		(polygon
			(pts
				(xy 19.668998 -63.794894) (xy 19.541998 -63.921894) (xy 19.541998 -65.445894) (xy 20.938998 -66.842894)
				(xy 22.335998 -66.842894) (xy 27.288998 -71.795894) (xy 31.225998 -71.795894) (xy 31.352998 -71.668894)
				(xy 31.352998 -70.906894) (xy 31.225998 -70.779894) (xy 27.923998 -70.779894) (xy 20.938998 -63.794894)
			)
		)
	)
	(zone
		(net "P12V_HDD29")
		(layer "F.Cu")
		(hatch none 0.5)
		(connect_pads
			(clearance 0.5)
		)
		(min_thickness 0.25)
		(fill yes
			(thermal_gap 0.5)
			(thermal_bridge_width 0.5)
			(island_removal_mode 0)
		)
		(polygon
			(pts
				(xy 170.053 -61.254894) (xy 169.799 -61.508894) (xy 169.799 -63.159894) (xy 170.053 -63.413894)
				(xy 172.212 -63.413894) (xy 172.72 -63.921894) (xy 172.72 -66.461894) (xy 180.467 -74.208894) (xy 188.976 -74.208894)
				(xy 189.103 -74.081894) (xy 189.103 -72.303894) (xy 188.976 -72.176894) (xy 183.007 -72.176894)
				(xy 182.372 -71.541894) (xy 180.721 -71.541894) (xy 176.403 -67.223894) (xy 176.403 -63.667894)
				(xy 175.26 -62.524894) (xy 175.26 -61.508894) (xy 175.006 -61.254894)
			)
		)
		(polygon
			(pts
				(xy 182.5244 -73.218294) (xy 182.3212 -73.218294) (xy 182.3212 -73.421494) (xy 182.5244 -73.421494)
			)
		)
		(polygon
			(pts
				(xy 181.6608 -73.218294) (xy 181.4576 -73.218294) (xy 181.4576 -73.421494) (xy 181.6608 -73.421494)
			)
		)
	)
	(zone
		(layer "F.Cu")
		(hatch none 0.5)
		(connect_pads
			(clearance 0)
		)
		(min_thickness 0.25)
		(keepout
			(tracks allowed)
			(vias allowed)
			(pads allowed)
			(copperpour allowed)
			(footprints allowed)
		)
		(placement
			(enabled no)
			(sheetname "")
		)
		(fill
			(thermal_gap 0.5)
			(thermal_bridge_width 0.5)
			(island_removal_mode 0)
		)
		(polygon
			(pts
				(xy 229.616 -370.4336) (xy 229.616 -368.0206) (xy 230.6066 -368.0206) (xy 230.6066 -370.4336)
			)
		)
	)
	(zone
		(net "P5V_HDD16")
		(layer "F.Cu")
		(hatch none 0.5)
		(connect_pads
			(clearance 0.5)
		)
		(min_thickness 0.25)
		(fill yes
			(thermal_gap 0.5)
			(thermal_bridge_width 0.5)
			(island_removal_mode 0)
		)
		(polygon
			(pts
				(xy 145.868898 -171.682918) (xy 145.614898 -171.936918) (xy 145.614898 -174.222918) (xy 145.868898 -174.476918)
				(xy 145.868898 -176.508918) (xy 146.630898 -177.270918) (xy 146.630898 -178.032918) (xy 147.011898 -178.413918)
				(xy 147.392898 -178.413918) (xy 150.567898 -181.588918) (xy 157.425898 -181.588918) (xy 157.552898 -181.461918)
				(xy 157.552898 -179.683918) (xy 157.425898 -179.556918) (xy 152.345898 -179.556918) (xy 150.440898 -177.651918)
				(xy 149.551898 -177.651918) (xy 148.662898 -176.762918) (xy 148.662898 -174.222918) (xy 149.297898 -173.587918)
				(xy 149.297898 -171.936918) (xy 149.043898 -171.682918)
			)
		)
		(polygon
			(pts
				(xy 147.875498 -178.109118) (xy 147.672298 -178.109118) (xy 147.672298 -178.312318) (xy 147.875498 -178.312318)
			)
		)
		(polygon
			(pts
				(xy 147.875498 -177.245518) (xy 147.672298 -177.245518) (xy 147.672298 -177.448718) (xy 147.875498 -177.448718)
			)
		)
		(polygon
			(pts
				(xy 147.011898 -177.245518) (xy 146.808698 -177.245518) (xy 146.808698 -177.448718) (xy 147.011898 -177.448718)
			)
		)
	)
	(zone
		(net "P5V_A_2")
		(layer "F.Cu")
		(hatch none 0.5)
		(connect_pads
			(clearance 0.5)
		)
		(min_thickness 0.25)
		(fill yes
			(thermal_gap 0.5)
			(thermal_bridge_width 0.5)
			(island_removal_mode 0)
		)
		(polygon
			(pts
				(xy 261.493 14.097) (xy 261.325106 13.929106) (xy 261.325106 10.51941) (xy 261.46125 10.383266)
				(xy 262.384794 10.383266) (xy 262.509 10.507472) (xy 262.509 13.97) (xy 262.382 14.097)
			)
		)
		(polygon
			(pts
				(xy 261.938262 11.09345) (xy 261.735062 11.09345) (xy 261.735062 10.89025) (xy 261.938262 10.89025)
			)
		)
	)
	(zone
		(layer "F.Cu")
		(hatch none 0.5)
		(connect_pads
			(clearance 0)
		)
		(min_thickness 0.25)
		(keepout
			(tracks not_allowed)
			(vias allowed)
			(pads allowed)
			(copperpour not_allowed)
			(footprints allowed)
		)
		(placement
			(enabled no)
			(sheetname "")
		)
		(fill
			(thermal_gap 0.5)
			(thermal_bridge_width 0.5)
			(island_removal_mode 0)
		)
		(polygon
			(pts
				(arc
					(start 383.47015 -158.368492)
					(mid 383.08915 -157.987492)
					(end 382.70815 -158.368492)
				)
				(arc
					(start 382.70815 -159.511238)
					(mid 383.089023 -159.892492)
					(end 383.47015 -159.511492)
				)
				(xy 383.47015 -159.162242)
				(arc
					(start 383.232406 -159.162242)
					(mid 383.213049 -159.166075)
					(end 383.196592 -159.176974)
				)
				(arc
					(start 383.180082 -159.193484)
					(mid 383.169156 -159.20993)
					(end 383.16535 -159.229298)
				)
				(arc
					(start 383.16535 -159.255968)
					(mid 383.08915 -159.778136)
					(end 383.01295 -159.255968)
				)
				(xy 383.01295 -159.197802)
				(arc
					(start 383.015998 -159.194754)
					(mid 383.028433 -159.151591)
					(end 383.050034 -159.112204)
				)
				(xy 383.050034 -159.10814) (xy 383.111248 -159.046926)
				(arc
					(start 383.115312 -159.046926)
					(mid 383.15469 -159.025304)
					(end 383.197862 -159.01289)
				)
				(xy 383.20091 -159.009842) (xy 383.47015 -159.009842) (xy 383.47015 -158.870142) (xy 383.201164 -158.870142)
				(arc
					(start 383.198116 -158.867094)
					(mid 383.154953 -158.854659)
					(end 383.115566 -158.833058)
				)
				(xy 383.111502 -158.833058) (xy 383.050034 -158.77159)
				(arc
					(start 383.050034 -158.767526)
					(mid 383.028412 -158.728148)
					(end 383.015998 -158.684976)
				)
				(xy 383.01295 -158.681928)
				(arc
					(start 383.01295 -158.624016)
					(mid 383.08915 -158.101848)
					(end 383.16535 -158.624016)
				)
				(arc
					(start 383.16535 -158.650432)
					(mid 383.169183 -158.669789)
					(end 383.180082 -158.686246)
				)
				(arc
					(start 383.196846 -158.70301)
					(mid 383.213292 -158.713936)
					(end 383.23266 -158.717742)
				)
				(xy 383.47015 -158.717742)
			)
		)
	)
	(zone
		(net "P12V_HDD33")
		(layer "F.Cu")
		(hatch none 0.5)
		(connect_pads
			(clearance 0.5)
		)
		(min_thickness 0.25)
		(fill yes
			(thermal_gap 0.5)
			(thermal_bridge_width 0.5)
			(island_removal_mode 0)
		)
		(polygon
			(pts
				(xy 429.295052 -63.540894) (xy 429.041052 -63.794894) (xy 429.041052 -67.858894) (xy 428.582328 -68.317618)
				(xy 428.582328 -71.139812) (xy 427.748446 -71.973694) (xy 420.82847 -71.973694) (xy 420.659052 -72.143112)
				(xy 420.659052 -73.954894) (xy 420.913052 -74.208894) (xy 424.850052 -74.208894) (xy 425.358052 -73.700894)
				(xy 433.105052 -73.700894) (xy 433.994052 -72.811894) (xy 433.994052 -63.794894) (xy 433.740052 -63.540894)
			)
		)
		(polygon
			(pts
				(xy 425.002452 -73.091294) (xy 424.799252 -73.091294) (xy 424.799252 -73.294494) (xy 425.002452 -73.294494)
			)
		)
		(polygon
			(pts
				(xy 424.138852 -73.091294) (xy 423.935652 -73.091294) (xy 423.935652 -73.294494) (xy 424.138852 -73.294494)
			)
		)
	)
	(zone
		(net "P5V_HDD31")
		(layer "F.Cu")
		(hatch none 0.5)
		(connect_pads
			(clearance 0.5)
		)
		(min_thickness 0.25)
		(fill yes
			(thermal_gap 0.5)
			(thermal_bridge_width 0.5)
			(island_removal_mode 0)
		)
		(polygon
			(pts
				(xy 363.147102 -51.729894) (xy 362.893102 -51.983894) (xy 362.893102 -62.778894) (xy 361.242102 -64.429894)
				(xy 357.813102 -64.429894) (xy 357.559102 -64.683894) (xy 357.559102 -66.334894) (xy 357.813102 -66.588894)
				(xy 362.385102 -66.588894) (xy 363.020102 -65.953894) (xy 364.798102 -65.953894) (xy 365.306102 -65.445894)
				(xy 365.306102 -51.983894) (xy 365.052102 -51.729894)
			)
		)
		(polygon
			(pts
				(xy 361.902502 -65.598294) (xy 361.699302 -65.598294) (xy 361.699302 -65.801494) (xy 361.902502 -65.801494)
			)
		)
		(polygon
			(pts
				(xy 361.038902 -65.598294) (xy 360.835702 -65.598294) (xy 360.835702 -65.801494) (xy 361.038902 -65.801494)
			)
		)
	)
	(zone
		(net "P5V_A_2")
		(layer "F.Cu")
		(hatch none 0.5)
		(connect_pads
			(clearance 0.5)
		)
		(min_thickness 0.25)
		(fill yes
			(thermal_gap 0.5)
			(thermal_bridge_width 0.5)
			(island_removal_mode 0)
		)
		(polygon
			(pts
				(xy 206.827882 -6.82244) (xy 206.553054 -7.097268) (xy 206.553054 -8.273542) (xy 206.561436 -8.281924)
				(xy 206.561436 -11.39952) (xy 207.036416 -11.8745) (xy 210.303364 -11.8745) (xy 210.6041 -11.573764)
				(xy 210.6041 -9.158986) (xy 210.46821 -9.023096) (xy 209.545682 -9.023096) (xy 209.164936 -8.64235)
				(xy 209.164936 -7.03834) (xy 208.949036 -6.82244)
			)
		)
		(polygon
			(pts
				(xy 209.856832 -9.822688) (xy 209.653632 -9.822688) (xy 209.653632 -10.025888) (xy 209.856832 -10.025888)
			)
		)
	)
	(zone
		(layer "F.Cu")
		(hatch none 0.5)
		(connect_pads
			(clearance 0)
		)
		(min_thickness 0.25)
		(keepout
			(tracks allowed)
			(vias allowed)
			(pads allowed)
			(copperpour allowed)
			(footprints not_allowed)
		)
		(placement
			(enabled no)
			(sheetname "")
		)
		(fill
			(thermal_gap 0.5)
			(thermal_bridge_width 0.5)
			(island_removal_mode 0)
		)
		(polygon
			(pts
				(xy 312.699908 -240.799874) (xy 491.450122 -240.799874) (xy 491.450122 -190.799974) (xy 478.00006 -190.799974)
				(xy 478.00006 -180.799994) (xy 463.449924 -180.799994) (xy 463.449924 -190.799974) (xy 446.449958 -190.799974)
				(xy 446.449958 -180.799994) (xy 431.900076 -180.799994) (xy 431.900076 -190.799974) (xy 414.90011 -190.799974)
				(xy 414.90011 -180.799994) (xy 400.349974 -180.799994) (xy 400.349974 -190.799974) (xy 383.350008 -190.799974)
				(xy 383.350008 -180.799994) (xy 368.800126 -180.799994) (xy 368.800126 -190.799974) (xy 351.799906 -190.799974)
				(xy 351.799906 -180.799994) (xy 337.250024 -180.799994) (xy 337.250024 -190.799974) (xy 320.250058 -190.799974)
				(xy 320.250058 -180.799994) (xy 305.699922 -180.799994) (xy 305.699922 -190.799974) (xy 298.200064 -190.799974)
				(xy 298.200064 -233.19994) (xy 312.699908 -233.19994)
			)
		)
	)
	(zone
		(net "GND")
		(layer "F.Cu")
		(hatch none 0.5)
		(connect_pads
			(clearance 0.5)
		)
		(min_thickness 0.25)
		(fill yes
			(thermal_gap 0.5)
			(thermal_bridge_width 0.5)
			(island_removal_mode 0)
		)
		(polygon
			(pts
				(xy 293.96436 -121.103898) (xy 298.588176 -100.696776) (xy 298.1706 -100.2792) (xy 297.866562 -100.2792)
				(xy 296.376598 -102.337616) (xy 294.231568 -105.300272) (xy 294.071548 -105.325926) (xy 292.143434 -107.988608)
				(arc
					(start 289.355784 -109.920786)
					(mid 289.24197 -110.214863)
					(end 289.107118 -110.499906)
				)
				(arc
					(start 289.107118 -110.499906)
					(mid 289.471113 -111.470605)
					(end 289.594798 -112.499902)
				)
				(xy 289.594798 -125.485398) (xy 289.8648 -125.7554) (xy 290.59632 -125.7554)
			)
		)
	)
	(zone
		(net "P5V_A_3")
		(layer "F.Cu")
		(hatch none 0.5)
		(connect_pads
			(clearance 0.5)
		)
		(min_thickness 0.25)
		(fill yes
			(thermal_gap 0.5)
			(thermal_bridge_width 0.5)
			(island_removal_mode 0)
		)
		(polygon
			(pts
				(xy 336.804 -280.332942) (xy 336.55 -280.586942) (xy 336.55 -285.285942) (xy 336.804 -285.539942)
				(xy 339.09 -285.539942) (xy 339.344 -285.285942) (xy 339.344 -280.586942) (xy 339.09 -280.332942)
			)
		)
	)
	(zone
		(layer "F.Cu")
		(hatch none 0.5)
		(connect_pads
			(clearance 0)
		)
		(min_thickness 0.25)
		(keepout
			(tracks not_allowed)
			(vias allowed)
			(pads allowed)
			(copperpour not_allowed)
			(footprints allowed)
		)
		(placement
			(enabled no)
			(sheetname "")
		)
		(fill
			(thermal_gap 0.5)
			(thermal_bridge_width 0.5)
			(island_removal_mode 0)
		)
		(polygon
			(pts
				(arc
					(start 281.074876 -138.149584)
					(mid 281.399742 -137.174986)
					(end 280.425144 -136.85012)
				)
				(xy 280.423874 -136.847834) (xy 278.424132 -137.847832) (xy 278.424132 -137.848086)
				(arc
					(start 278.425148 -137.850118)
					(mid 278.100282 -138.824716)
					(end 279.07488 -139.149582)
				)
				(xy 279.07615 -139.151868)
				(arc
					(start 279.996138 -138.691874)
					(mid 279.903921 -138.635727)
					(end 279.82545 -138.561572)
				)
				(xy 279.823164 -138.561318) (xy 279.589738 -138.239754)
				(arc
					(start 279.571958 -138.222228)
					(mid 279.542817 -138.216851)
					(end 279.514046 -138.224006)
				)
				(arc
					(start 279.273508 -138.344402)
					(mid 278.261684 -138.744276)
					(end 279.188164 -138.173968)
				)
				(xy 279.428702 -138.053826) (xy 279.464008 -138.036046)
				(arc
					(start 279.468834 -138.03757)
					(mid 279.587296 -138.029621)
					(end 279.696926 -138.075162)
				)
				(xy 279.701752 -138.075162) (xy 279.728422 -138.101832) (xy 279.729946 -138.103102) (xy 279.757632 -138.131042)
				(xy 279.757632 -138.14679)
				(arc
					(start 279.953974 -138.4173)
					(mid 280.068803 -138.515324)
					(end 280.215594 -138.55065)
				)
				(xy 280.278586 -138.55065) (xy 280.481786 -138.44905) (xy 280.176986 -138.44905)
				(arc
					(start 280.172668 -138.444732)
					(mid 280.115455 -138.424919)
					(end 280.065734 -138.390376)
				)
				(xy 280.059638 -138.38936) (xy 280.036524 -138.35761) (xy 280.036524 -138.357356) (xy 279.881838 -138.144758)
				(xy 279.859232 -138.122152) (xy 279.859232 -138.11377) (xy 279.854152 -138.106912)
				(arc
					(start 279.856184 -138.094212)
					(mid 279.853552 -137.930987)
					(end 279.94864 -137.798302)
				)
				(xy 279.950164 -137.793476) (xy 279.98547 -137.77595)
				(arc
					(start 280.226516 -137.6553)
					(mid 281.23834 -137.255426)
					(end 280.31186 -137.825734)
				)
				(arc
					(start 280.070814 -137.94613)
					(mid 280.03797 -137.980805)
					(end 280.035254 -138.028426)
				)
				(xy 280.049732 -138.043158) (xy 280.049732 -138.051794)
				(arc
					(start 280.190448 -138.245596)
					(mid 280.201721 -138.255165)
					(end 280.216102 -138.25855)
				)
				(xy 280.862786 -138.25855) (xy 281.076146 -138.15187)
			)
		)
	)
	(zone
		(net "P12V_A")
		(layer "F.Cu")
		(hatch none 0.5)
		(connect_pads
			(clearance 0.5)
		)
		(min_thickness 0.25)
		(fill yes
			(thermal_gap 0.5)
			(thermal_bridge_width 0.5)
			(island_removal_mode 0)
		)
		(polygon
			(pts
				(xy 77.307948 -284.142942) (xy 76.291948 -285.158942) (xy 75.656948 -285.158942) (xy 75.275948 -285.539942)
				(xy 75.275948 -288.079942) (xy 75.529948 -288.333942) (xy 78.831948 -288.333942) (xy 79.085948 -288.079942)
				(xy 79.085948 -285.793942) (xy 78.450948 -285.158942) (xy 78.069948 -285.158942) (xy 77.815948 -284.904942)
				(xy 77.815948 -284.269942) (xy 77.688948 -284.142942)
			)
		)
		(polygon
			(pts
				(xy 77.282548 -284.727142) (xy 77.079348 -284.727142) (xy 77.079348 -284.930342) (xy 77.282548 -284.930342)
			)
		)
	)
	(zone
		(net "MB3_P12V_IN_R")
		(layer "F.Cu")
		(hatch none 0.5)
		(connect_pads
			(clearance 0.5)
		)
		(min_thickness 0.25)
		(fill yes
			(thermal_gap 0.5)
			(thermal_bridge_width 0.5)
			(island_removal_mode 0)
		)
		(polygon
			(pts
				(xy 252.69698 -377.83008) (xy 252.496828 -378.030232) (xy 252.496828 -384.2385) (xy 252.667008 -384.40868)
				(xy 256.87782 -384.40868) (xy 257.1242 -384.65506) (xy 257.1242 -389.89) (xy 257.4036 -390.1694)
				(xy 273.9136 -390.1694) (xy 274.465542 -389.617458) (xy 274.465542 -381.720598) (xy 274.464272 -381.719328)
				(xy 274.464272 -378.073412) (xy 274.22094 -377.83008)
			)
		)
	)
	(zone
		(net "GND")
		(layer "F.Cu")
		(hatch none 0.5)
		(connect_pads
			(clearance 0.5)
		)
		(min_thickness 0.25)
		(fill yes
			(thermal_gap 0.5)
			(thermal_bridge_width 0.5)
			(island_removal_mode 0)
		)
		(polygon
			(pts
				(xy 214.82431 -12.981686) (xy 213.684358 -14.121638) (xy 213.684358 -22.370034) (xy 214.529924 -23.2156)
				(xy 219.193872 -23.2156) (xy 219.269818 -23.139654) (xy 219.269818 -13.190982) (xy 219.060522 -12.981686)
			)
		)
	)
	(zone
		(net "P5V_A_1")
		(layer "F.Cu")
		(hatch none 0.5)
		(connect_pads
			(clearance 0.5)
		)
		(min_thickness 0.25)
		(fill yes
			(thermal_gap 0.5)
			(thermal_bridge_width 0.5)
			(island_removal_mode 0)
		)
		(polygon
			(pts
				(xy 130.295396 -280.815542) (xy 130.041396 -281.069542) (xy 130.041396 -283.355542) (xy 130.295396 -283.609542)
				(xy 134.994396 -283.609542) (xy 135.248396 -283.355542) (xy 135.248396 -281.069542) (xy 134.994396 -280.815542)
			)
		)
	)
	(zone
		(net "P12V_IN")
		(layer "F.Cu")
		(hatch none 0.5)
		(connect_pads
			(clearance 0.5)
		)
		(min_thickness 0.25)
		(fill yes
			(thermal_gap 0.5)
			(thermal_bridge_width 0.5)
			(island_removal_mode 0)
		)
		(polygon
			(pts
				(xy 257.469132 -390.637268) (xy 257.1242 -390.9822) (xy 257.1242 -396.5194) (xy 256.921 -396.7226)
				(xy 250.557538 -396.7226) (xy 249.973338 -397.3068) (xy 249.973338 -401.038568) (xy 250.63577 -401.701)
				(xy 274.377912 -401.701) (xy 275.347684 -400.731228) (xy 275.347684 -391.617708) (xy 274.367244 -390.637268)
			)
		)
		(polygon
			(pts
				(xy 274.855178 -396.885922) (xy 274.651978 -396.885922) (xy 274.651978 -397.089122) (xy 274.855178 -397.089122)
			)
		)
		(polygon
			(pts
				(xy 274.855178 -396.276322) (xy 274.651978 -396.276322) (xy 274.651978 -396.479522) (xy 274.855178 -396.479522)
			)
		)
	)
	(zone
		(net "5V_PRE_1")
		(layer "F.Cu")
		(hatch none 0.5)
		(connect_pads
			(clearance 0.5)
		)
		(min_thickness 0.25)
		(fill yes
			(thermal_gap 0.5)
			(thermal_bridge_width 0.5)
			(island_removal_mode 0)
		)
		(polygon
			(pts
				(xy 54.571646 -289.941) (xy 54.393846 -290.1188) (xy 54.393846 -291.508942) (xy 54.520846 -291.635942)
				(xy 55.790846 -291.635942) (xy 58.330846 -294.175942) (xy 62.775846 -294.175942) (xy 62.902846 -294.048942)
				(xy 62.902846 -293.286942) (xy 62.775846 -293.159942) (xy 59.69 -293.159942) (xy 56.471058 -289.941)
			)
		)
	)
	(zone
		(net "GND")
		(layer "F.Cu")
		(hatch none 0.5)
		(connect_pads
			(clearance 0.5)
		)
		(min_thickness 0.25)
		(fill yes
			(thermal_gap 0.5)
			(thermal_bridge_width 0.5)
			(island_removal_mode 0)
		)
		(polygon
			(pts
				(xy 276.747732 -388.52348) (xy 276.647402 -388.62381) (xy 276.647402 -396.65275) (xy 276.962362 -396.96771)
				(xy 278.785828 -396.96771) (xy 279.208738 -396.545054) (xy 279.208738 -388.726934) (xy 279.005284 -388.52348)
			)
		)
	)
	(zone
		(layer "F.Cu")
		(hatch none 0.5)
		(connect_pads
			(clearance 0)
		)
		(min_thickness 0.25)
		(keepout
			(tracks allowed)
			(vias allowed)
			(pads allowed)
			(copperpour allowed)
			(footprints allowed)
		)
		(placement
			(enabled no)
			(sheetname "")
		)
		(fill
			(thermal_gap 0.5)
			(thermal_bridge_width 0.5)
			(island_removal_mode 0)
		)
		(polygon
			(pts
				(xy 272.0721 15.7099) (xy 272.0721 17.3101) (xy 273.0119 17.3101) (xy 273.0119 15.7099)
			)
		)
	)
	(zone
		(layer "F.Cu")
		(hatch none 0.5)
		(connect_pads
			(clearance 0)
		)
		(min_thickness 0.25)
		(keepout
			(tracks allowed)
			(vias allowed)
			(pads allowed)
			(copperpour allowed)
			(footprints not_allowed)
		)
		(placement
			(enabled no)
			(sheetname "")
		)
		(fill
			(thermal_gap 0.5)
			(thermal_bridge_width 0.5)
			(island_removal_mode 0)
		)
		(polygon
			(pts
				(arc
					(start 0.100076 -120.499886)
					(mid 3.850132 -116.74983)
					(end 7.599934 -120.499886)
				)
				(arc
					(start 7.599934 -120.499886)
					(mid 3.850132 -124.249688)
					(end 0.100076 -120.499886)
				)
			)
		)
	)
	(zone
		(net "12V_PRE_15")
		(layer "F.Cu")
		(hatch none 0.5)
		(connect_pads
			(clearance 0.5)
		)
		(min_thickness 0.25)
		(fill yes
			(thermal_gap 0.5)
			(thermal_bridge_width 0.5)
			(island_removal_mode 0)
		)
		(polygon
			(pts
				(xy 114.318796 -178.794918) (xy 114.191796 -178.921918) (xy 114.191796 -180.445918) (xy 115.588796 -181.842918)
				(xy 116.985796 -181.842918) (xy 121.938796 -186.795918) (xy 125.875796 -186.795918) (xy 126.002796 -186.668918)
				(xy 126.002796 -185.906918) (xy 125.875796 -185.779918) (xy 122.573796 -185.779918) (xy 115.588796 -178.794918)
			)
		)
	)
	(zone
		(layer "F.Cu")
		(hatch none 0.5)
		(connect_pads
			(clearance 0)
		)
		(min_thickness 0.25)
		(keepout
			(tracks not_allowed)
			(vias allowed)
			(pads allowed)
			(copperpour not_allowed)
			(footprints allowed)
		)
		(placement
			(enabled no)
			(sheetname "")
		)
		(fill
			(thermal_gap 0.5)
			(thermal_bridge_width 0.5)
			(island_removal_mode 0)
		)
		(polygon
			(pts
				(arc
					(start 64.4398 -47.178722)
					(mid 64.058927 -46.797468)
					(end 63.6778 -47.178468)
				)
				(xy 63.6778 -47.527718)
				(arc
					(start 63.9318 -47.527718)
					(mid 63.967721 -47.512839)
					(end 63.9826 -47.476918)
				)
				(arc
					(start 63.9826 -47.433992)
					(mid 64.0588 -46.911824)
					(end 64.135 -47.433992)
				)
				(xy 64.135 -47.508414)
				(arc
					(start 64.131952 -47.511462)
					(mid 64.075421 -47.620539)
					(end 63.966344 -47.67707)
				)
				(xy 63.963296 -47.680118) (xy 63.6778 -47.680118) (xy 63.6778 -47.819818) (xy 63.963296 -47.819818)
				(arc
					(start 63.966344 -47.822866)
					(mid 64.075421 -47.879397)
					(end 64.131952 -47.988474)
				)
				(xy 64.135 -47.991522)
				(arc
					(start 64.135 -48.065944)
					(mid 64.0588 -48.588112)
					(end 63.9826 -48.065944)
				)
				(arc
					(start 63.9826 -48.023018)
					(mid 63.967721 -47.987097)
					(end 63.9318 -47.972218)
				)
				(xy 63.6778 -47.972218)
				(arc
					(start 63.6778 -48.321468)
					(mid 64.0588 -48.702468)
					(end 64.4398 -48.321468)
				)
			)
		)
	)
	(zone
		(net "GND")
		(layer "F.Cu")
		(hatch none 0.5)
		(connect_pads
			(clearance 0.5)
		)
		(min_thickness 0.25)
		(fill yes
			(thermal_gap 0.5)
			(thermal_bridge_width 0.5)
			(island_removal_mode 0)
		)
		(polygon
			(pts
				(xy 33.8074 -148.9202)
				(arc
					(start 33.8074 -149.177756)
					(mid 34.228103 -150.580934)
					(end 34.12744 -152.042368)
				)
				(xy 35.01771 -152.042368) (xy 35.01771 -154.671268) (xy 36.73221 -154.671268) (xy 36.73221 -155.86583)
				(arc
					(start 37.128958 -156.11856)
					(mid 37.786866 -156.646578)
					(end 38.314884 -157.304486)
				)
				(arc
					(start 38.925754 -158.263336)
					(mid 40.849 -157.398839)
					(end 42.941748 -157.140656)
				)
				(arc
					(start 42.941748 -157.140656)
					(mid 42.938222 -156.893649)
					(end 42.949622 -156.64688)
				)
				(xy 42.949622 -155.251912)
				(arc
					(start 42.713402 -155.251912)
					(mid 41.282127 -154.982487)
					(end 40.046656 -154.211274)
				)
				(xy 38.800278 -154.211274)
				(arc
					(start 38.800278 -152.913334)
					(mid 38.215512 -151.796523)
					(end 38.01364 -150.55215)
				)
				(arc
					(start 38.01364 -150.444962)
					(mid 36.381452 -150.202556)
					(end 34.977832 -149.334982)
				)
				(arc
					(start 34.977832 -149.334982)
					(mid 34.606065 -149.146017)
					(end 34.255456 -148.9202)
				)
			)
		)
	)
	(zone
		(net "P5V_A_3")
		(layer "F.Cu")
		(hatch none 0.5)
		(connect_pads
			(clearance 0.5)
		)
		(min_thickness 0.25)
		(fill yes
			(thermal_gap 0.5)
			(thermal_bridge_width 0.5)
			(island_removal_mode 0)
		)
		(polygon
			(pts
				(xy 431.454052 -280.332942) (xy 431.200052 -280.586942) (xy 431.200052 -285.285942) (xy 431.454052 -285.539942)
				(xy 433.740052 -285.539942) (xy 433.994052 -285.285942) (xy 433.994052 -280.586942) (xy 433.740052 -280.332942)
			)
		)
	)
	(zone
		(net "12V_PRE_11")
		(layer "F.Cu")
		(hatch none 0.5)
		(connect_pads
			(clearance 0.5)
		)
		(min_thickness 0.25)
		(fill yes
			(thermal_gap 0.5)
			(thermal_bridge_width 0.5)
			(island_removal_mode 0)
		)
		(polygon
			(pts
				(xy 478.097342 -293.751) (xy 477.789748 -294.058594) (xy 477.789748 -298.975272) (xy 478.2185 -299.404024)
				(xy 479.997008 -299.404024) (xy 482.388926 -301.795942) (xy 486.325926 -301.795942) (xy 486.452926 -301.668942)
				(xy 486.452926 -300.906942) (xy 486.325926 -300.779942) (xy 483.023926 -300.779942) (xy 480.378008 -298.134024)
				(xy 478.961704 -298.134024) (xy 478.58807 -297.76039) (xy 478.58807 -296.411142) (xy 478.971864 -296.027348)
				(xy 479.453194 -296.027348) (xy 479.859594 -295.620948) (xy 479.859594 -294.058594) (xy 479.552 -293.751)
			)
		)
	)
	(zone
		(layer "F.Cu")
		(hatch none 0.5)
		(connect_pads
			(clearance 0)
		)
		(min_thickness 0.25)
		(keepout
			(tracks not_allowed)
			(vias allowed)
			(pads allowed)
			(copperpour not_allowed)
			(footprints allowed)
		)
		(placement
			(enabled no)
			(sheetname "")
		)
		(fill
			(thermal_gap 0.5)
			(thermal_bridge_width 0.5)
			(island_removal_mode 0)
		)
		(polygon
			(pts
				(arc
					(start 478.120202 -158.368492)
					(mid 477.739202 -157.987492)
					(end 477.358202 -158.368492)
				)
				(arc
					(start 477.358202 -159.511238)
					(mid 477.739075 -159.892492)
					(end 478.120202 -159.511492)
				)
				(xy 478.120202 -159.162242)
				(arc
					(start 477.876108 -159.162242)
					(mid 477.856751 -159.166075)
					(end 477.840294 -159.176974)
				)
				(arc
					(start 477.830134 -159.187134)
					(mid 477.819208 -159.20358)
					(end 477.815402 -159.222948)
				)
				(arc
					(start 477.815402 -159.255968)
					(mid 477.739202 -159.778136)
					(end 477.663002 -159.255968)
				)
				(xy 477.663002 -159.191452)
				(arc
					(start 477.66605 -159.188404)
					(mid 477.678485 -159.145241)
					(end 477.700086 -159.105854)
				)
				(xy 477.700086 -159.10179) (xy 477.75495 -159.046926)
				(arc
					(start 477.759014 -159.046926)
					(mid 477.798392 -159.025304)
					(end 477.841564 -159.01289)
				)
				(xy 477.844612 -159.009842) (xy 478.120202 -159.009842) (xy 478.120202 -158.870142) (xy 477.8629 -158.870142)
				(arc
					(start 477.859852 -158.867094)
					(mid 477.816689 -158.854659)
					(end 477.777302 -158.833058)
				)
				(xy 477.773238 -158.833058) (xy 477.700086 -158.759906)
				(arc
					(start 477.700086 -158.755842)
					(mid 477.678464 -158.716464)
					(end 477.66605 -158.673292)
				)
				(xy 477.663002 -158.670244)
				(arc
					(start 477.663002 -158.624016)
					(mid 477.739202 -158.101848)
					(end 477.815402 -158.624016)
				)
				(arc
					(start 477.815402 -158.638748)
					(mid 477.819235 -158.658105)
					(end 477.830134 -158.674562)
				)
				(arc
					(start 477.858582 -158.70301)
					(mid 477.875028 -158.713936)
					(end 477.894396 -158.717742)
				)
				(xy 478.120202 -158.717742)
			)
		)
	)
	(zone
		(layer "F.Cu")
		(hatch none 0.5)
		(connect_pads
			(clearance 0)
		)
		(min_thickness 0.25)
		(keepout
			(tracks allowed)
			(vias allowed)
			(pads allowed)
			(copperpour allowed)
			(footprints not_allowed)
		)
		(placement
			(enabled no)
			(sheetname "")
		)
		(fill
			(thermal_gap 0.5)
			(thermal_bridge_width 0.5)
			(island_removal_mode 0)
		)
		(polygon
			(pts
				(arc
					(start 485.000046 -5.500116)
					(mid 481.24999 -9.250172)
					(end 477.499934 -5.500116)
				)
				(arc
					(start 477.499934 -5.500116)
					(mid 481.24999 -1.75006)
					(end 485.000046 -5.500116)
				)
			)
		)
	)
	(zone
		(layer "F.Cu")
		(hatch none 0.5)
		(connect_pads
			(clearance 0)
		)
		(min_thickness 0.25)
		(keepout
			(tracks allowed)
			(vias allowed)
			(pads allowed)
			(copperpour allowed)
			(footprints not_allowed)
		)
		(placement
			(enabled no)
			(sheetname "")
		)
		(fill
			(thermal_gap 0.5)
			(thermal_bridge_width 0.5)
			(island_removal_mode 0)
		)
		(polygon
			(pts
				(xy 177.32502 -9.99998) (xy 177.32502 0) (xy 191.799972 0) (xy 191.799972 -9.99998)
			)
		)
	)
	(zone
		(net "P12V_HDD27")
		(layer "F.Cu")
		(hatch none 0.5)
		(connect_pads
			(clearance 0.5)
		)
		(min_thickness 0.25)
		(fill yes
			(thermal_gap 0.5)
			(thermal_bridge_width 0.5)
			(island_removal_mode 0)
		)
		(polygon
			(pts
				(xy 106.952796 -61.254894) (xy 106.698796 -61.508894) (xy 106.698796 -63.159894) (xy 106.952796 -63.413894)
				(xy 109.111796 -63.413894) (xy 109.619796 -63.921894) (xy 109.619796 -66.461894) (xy 117.366796 -74.208894)
				(xy 125.875796 -74.208894) (xy 126.002796 -74.081894) (xy 126.002796 -72.303894) (xy 125.875796 -72.176894)
				(xy 119.906796 -72.176894) (xy 119.271796 -71.541894) (xy 117.620796 -71.541894) (xy 113.302796 -67.223894)
				(xy 113.302796 -63.667894) (xy 112.159796 -62.524894) (xy 112.159796 -61.508894) (xy 111.905796 -61.254894)
			)
		)
		(polygon
			(pts
				(xy 119.424196 -73.218294) (xy 119.220996 -73.218294) (xy 119.220996 -73.421494) (xy 119.424196 -73.421494)
			)
		)
		(polygon
			(pts
				(xy 118.560596 -73.218294) (xy 118.357396 -73.218294) (xy 118.357396 -73.421494) (xy 118.560596 -73.421494)
			)
		)
	)
	(zone
		(net "P12V_HDD32")
		(layer "F.Cu")
		(hatch none 0.5)
		(connect_pads
			(clearance 0.5)
		)
		(min_thickness 0.25)
		(fill yes
			(thermal_gap 0.5)
			(thermal_bridge_width 0.5)
			(island_removal_mode 0)
		)
		(polygon
			(pts
				(xy 397.74495 -63.540894) (xy 397.49095 -63.794894) (xy 397.49095 -67.858894) (xy 397.032226 -68.317618)
				(xy 397.032226 -71.139812) (xy 396.198344 -71.973694) (xy 389.278368 -71.973694) (xy 389.10895 -72.143112)
				(xy 389.10895 -73.954894) (xy 389.36295 -74.208894) (xy 393.29995 -74.208894) (xy 393.80795 -73.700894)
				(xy 401.55495 -73.700894) (xy 402.44395 -72.811894) (xy 402.44395 -63.794894) (xy 402.18995 -63.540894)
			)
		)
		(polygon
			(pts
				(xy 393.45235 -73.091294) (xy 393.24915 -73.091294) (xy 393.24915 -73.294494) (xy 393.45235 -73.294494)
			)
		)
		(polygon
			(pts
				(xy 392.58875 -73.091294) (xy 392.38555 -73.091294) (xy 392.38555 -73.294494) (xy 392.58875 -73.294494)
			)
		)
	)
	(zone
		(net "P12V_A")
		(layer "F.Cu")
		(hatch none 0.5)
		(connect_pads
			(clearance 0.5)
		)
		(min_thickness 0.25)
		(fill yes
			(thermal_gap 0.5)
			(thermal_bridge_width 0.5)
			(island_removal_mode 0)
		)
		(polygon
			(pts
				(xy 334.645 -286.428942) (xy 334.137 -286.936942) (xy 334.137 -290.365942) (xy 334.391 -290.619942)
				(xy 337.693 -290.619942) (xy 337.947 -290.365942) (xy 337.947 -288.333942) (xy 338.074 -288.206942)
				(xy 338.455 -288.206942) (xy 338.582 -288.079942) (xy 338.582 -286.555942) (xy 338.455 -286.428942)
			)
		)
		(polygon
			(pts
				(xy 338.0486 -287.444942) (xy 337.8454 -287.444942) (xy 337.8454 -287.648142) (xy 338.0486 -287.648142)
			)
		)
		(polygon
			(pts
				(xy 338.0994 -286.987742) (xy 337.8962 -286.987742) (xy 337.8962 -287.190942) (xy 338.0994 -287.190942)
			)
		)
	)
	(zone
		(layer "F.Cu")
		(hatch none 0.5)
		(connect_pads
			(clearance 0)
		)
		(min_thickness 0.25)
		(keepout
			(tracks not_allowed)
			(vias allowed)
			(pads allowed)
			(copperpour not_allowed)
			(footprints allowed)
		)
		(placement
			(enabled no)
			(sheetname "")
		)
		(fill
			(thermal_gap 0.5)
			(thermal_bridge_width 0.5)
			(island_removal_mode 0)
		)
		(polygon
			(pts
				(arc
					(start 271.970754 -328.521568)
					(mid 271.58696 -328.904981)
					(end 271.9705 -329.288648)
				)
				(arc
					(start 273.1135 -329.288648)
					(mid 273.49704 -328.905108)
					(end 273.1135 -328.521568)
				)
				(xy 272.76425 -328.521568)
				(arc
					(start 272.76425 -328.778108)
					(mid 272.779129 -328.814029)
					(end 272.81505 -328.828908)
				)
				(arc
					(start 272.857976 -328.828908)
					(mid 273.380144 -328.905108)
					(end 272.857976 -328.981308)
				)
				(xy 272.783554 -328.981308)
				(arc
					(start 272.780506 -328.97826)
					(mid 272.671429 -328.921729)
					(end 272.614898 -328.812652)
				)
				(xy 272.61185 -328.809604) (xy 272.61185 -328.521568) (xy 272.47215 -328.521568) (xy 272.47215 -328.809604)
				(arc
					(start 272.469102 -328.812652)
					(mid 272.412571 -328.921729)
					(end 272.303494 -328.97826)
				)
				(xy 272.300446 -328.981308)
				(arc
					(start 272.226024 -328.981308)
					(mid 271.703856 -328.905108)
					(end 272.226024 -328.828908)
				)
				(arc
					(start 272.26895 -328.828908)
					(mid 272.304871 -328.814029)
					(end 272.31975 -328.778108)
				)
				(xy 272.31975 -328.521568)
			)
		)
	)
	(zone
		(layer "F.Cu")
		(hatch none 0.5)
		(connect_pads
			(clearance 0)
		)
		(min_thickness 0.25)
		(keepout
			(tracks not_allowed)
			(vias allowed)
			(pads allowed)
			(copperpour not_allowed)
			(footprints allowed)
		)
		(placement
			(enabled no)
			(sheetname "")
		)
		(fill
			(thermal_gap 0.5)
			(thermal_bridge_width 0.5)
			(island_removal_mode 0)
		)
		(polygon
			(pts
				(arc
					(start 419.770052 -277.17877)
					(mid 419.389179 -276.797516)
					(end 419.008052 -277.178516)
				)
				(arc
					(start 419.008052 -278.321516)
					(mid 419.389052 -278.702516)
					(end 419.770052 -278.321516)
				)
				(xy 419.770052 -277.972266)
				(arc
					(start 419.516306 -277.972266)
					(mid 419.480205 -277.987219)
					(end 419.465252 -278.02332)
				)
				(arc
					(start 419.465252 -278.065992)
					(mid 419.389052 -278.58816)
					(end 419.312852 -278.065992)
				)
				(xy 419.312852 -277.991824)
				(arc
					(start 419.3159 -277.988776)
					(mid 419.372508 -277.879522)
					(end 419.481762 -277.822914)
				)
				(xy 419.48481 -277.819866) (xy 419.770052 -277.819866) (xy 419.770052 -277.680166) (xy 419.48481 -277.680166)
				(arc
					(start 419.481762 -277.677118)
					(mid 419.372508 -277.62051)
					(end 419.3159 -277.511256)
				)
				(xy 419.312852 -277.508208)
				(arc
					(start 419.312852 -277.43404)
					(mid 419.389052 -276.911872)
					(end 419.465252 -277.43404)
				)
				(arc
					(start 419.465252 -277.476712)
					(mid 419.480205 -277.512813)
					(end 419.516306 -277.527766)
				)
				(xy 419.770052 -277.527766)
			)
		)
	)
	(zone
		(net "GND")
		(layer "F.Cu")
		(hatch none 0.5)
		(connect_pads
			(clearance 0.5)
		)
		(min_thickness 0.25)
		(fill yes
			(thermal_gap 0.5)
			(thermal_bridge_width 0.5)
			(island_removal_mode 0)
		)
		(polygon
			(pts
				(xy 246.894858 -151.535638)
				(arc
					(start 246.894858 -172.737272)
					(mid 250.963025 -173.401454)
					(end 252.3871 -177.269648)
				)
				(arc
					(start 252.3871 -177.269648)
					(mid 250.811563 -180.904451)
					(end 246.894858 -181.499256)
				)
				(arc
					(start 246.894858 -182.500016)
					(mid 246.728539 -183.690621)
					(end 246.242332 -184.79008)
				)
				(arc
					(start 246.242332 -184.79008)
					(mid 246.989844 -186.242366)
					(end 247.109488 -187.871354)
				)
				(arc
					(start 247.109488 -187.871354)
					(mid 247.184597 -188.967896)
					(end 246.964962 -190.044832)
				)
				(arc
					(start 246.964962 -190.044832)
					(mid 246.828601 -191.089871)
					(end 246.429784 -192.065402)
				)
				(arc
					(start 246.429784 -192.065402)
					(mid 247.211922 -193.655454)
					(end 247.248172 -195.427092)
				)
				(arc
					(start 247.248172 -195.427092)
					(mid 245.778309 -198.675604)
					(end 242.318286 -199.536558)
				)
				(arc
					(start 242.318286 -199.536558)
					(mid 239.969405 -198.998707)
					(end 238.330994 -197.231762)
				)
				(arc
					(start 238.330994 -197.231762)
					(mid 238.024763 -196.982286)
					(end 237.744 -196.704458)
				)
				(arc
					(start 237.744 -196.704458)
					(mid 236.375001 -195.300013)
					(end 235.817156 -193.41973)
				)
				(arc
					(start 235.817156 -193.41973)
					(mid 235.201585 -190.783144)
					(end 236.367828 -188.33973)
				)
				(arc
					(start 236.367828 -188.33973)
					(mid 236.251734 -188.252879)
					(end 236.138212 -188.162692)
				)
				(xy 230.886 -188.162692) (xy 230.886 -193.166492) (xy 249.455686 -224.028) (xy 253.56439 -224.028)
				(xy 254.812546 -222.779844) (xy 254.812546 -209.473292) (xy 253.708916 -208.369662) (xy 253.708916 -151.535638)
			)
		)
	)
	(zone
		(net "P5V_A_4")
		(layer "F.Cu")
		(hatch none 0.5)
		(connect_pads
			(clearance 0.5)
		)
		(min_thickness 0.25)
		(fill yes
			(thermal_gap 0.5)
			(thermal_bridge_width 0.5)
			(island_removal_mode 0)
		)
		(polygon
			(pts
				(xy 463.0039 -165.332918) (xy 462.7499 -165.586918) (xy 462.7499 -170.285918) (xy 463.0039 -170.539918)
				(xy 465.2899 -170.539918) (xy 465.5439 -170.285918) (xy 465.5439 -165.586918) (xy 465.2899 -165.332918)
			)
		)
	)
	(zone
		(layer "F.Cu")
		(hatch none 0.5)
		(connect_pads
			(clearance 0)
		)
		(min_thickness 0.25)
		(keepout
			(tracks not_allowed)
			(vias allowed)
			(pads allowed)
			(copperpour not_allowed)
			(footprints allowed)
		)
		(placement
			(enabled no)
			(sheetname "")
		)
		(fill
			(thermal_gap 0.5)
			(thermal_bridge_width 0.5)
			(island_removal_mode 0)
		)
		(polygon
			(pts
				(arc
					(start 238.377222 -114.154204)
					(mid 238.704374 -113.172748)
					(end 237.722918 -112.845596)
				)
				(arc
					(start 235.733844 -113.84026)
					(mid 235.393447 -114.82129)
					(end 236.377226 -115.154202)
				)
				(xy 236.902244 -114.891566)
				(arc
					(start 237.109762 -114.684302)
					(mid 237.138504 -114.625805)
					(end 237.125764 -114.561874)
				)
				(xy 237.123224 -114.561366) (xy 236.889798 -114.239802)
				(arc
					(start 236.872018 -114.222276)
					(mid 236.842877 -114.216899)
					(end 236.814106 -114.224054)
				)
				(arc
					(start 236.573568 -114.34445)
					(mid 235.561744 -114.744324)
					(end 236.488224 -114.174016)
				)
				(xy 236.764068 -114.036094)
				(arc
					(start 236.768894 -114.037618)
					(mid 236.887356 -114.029669)
					(end 236.996986 -114.07521)
				)
				(xy 237.001812 -114.07521) (xy 237.028482 -114.10188) (xy 237.030006 -114.10315) (xy 237.057692 -114.13109)
				(xy 237.057692 -114.146838)
				(arc
					(start 237.250224 -114.412014)
					(mid 237.32026 -114.537924)
					(end 237.321598 -114.682016)
				)
				(arc
					(start 237.43158 -114.627152)
					(mid 237.413732 -114.494625)
					(end 237.352586 -114.375692)
				)
				(xy 237.349284 -114.375184) (xy 237.258352 -114.249708) (xy 237.181898 -114.144806) (xy 237.159292 -114.1222)
				(xy 237.159292 -114.113818) (xy 237.154212 -114.10696)
				(arc
					(start 237.156244 -114.09426)
					(mid 237.153612 -113.931035)
					(end 237.2487 -113.79835)
				)
				(xy 237.250224 -113.793524) (xy 237.28553 -113.775998)
				(arc
					(start 237.526576 -113.655348)
					(mid 238.5384 -113.255474)
					(end 237.61192 -113.825782)
				)
				(arc
					(start 237.370874 -113.946178)
					(mid 237.33803 -113.980853)
					(end 237.335314 -114.028474)
				)
				(xy 237.349792 -114.043206) (xy 237.349792 -114.051842) (xy 237.389162 -114.105944) (xy 237.412276 -114.137948)
				(xy 237.435644 -114.169698)
				(arc
					(start 237.477554 -114.22761)
					(mid 237.569837 -114.370635)
					(end 237.617 -114.534188)
				)
			)
		)
	)
	(zone
		(layer "F.Cu")
		(hatch none 0.5)
		(connect_pads
			(clearance 0)
		)
		(min_thickness 0.25)
		(keepout
			(tracks allowed)
			(vias allowed)
			(pads allowed)
			(copperpour allowed)
			(footprints not_allowed)
		)
		(placement
			(enabled no)
			(sheetname "")
		)
		(fill
			(thermal_gap 0.5)
			(thermal_bridge_width 0.5)
			(island_removal_mode 0)
		)
		(polygon
			(pts
				(arc
					(start 11.75004 -224.199958)
					(mid 7.999984 -227.950014)
					(end 4.249928 -224.199958)
				)
				(arc
					(start 4.249928 -224.199958)
					(mid 7.999984 -220.449902)
					(end 11.75004 -224.199958)
				)
			)
		)
	)
	(zone
		(net "12V_PRE_23")
		(layer "F.Cu")
		(hatch none 0.5)
		(connect_pads
			(clearance 0.5)
		)
		(min_thickness 0.25)
		(fill yes
			(thermal_gap 0.5)
			(thermal_bridge_width 0.5)
			(island_removal_mode 0)
		)
		(polygon
			(pts
				(xy 473.44457 -178.542696) (xy 473.272104 -178.715162) (xy 473.272104 -181.033674) (xy 476.64243 -184.404)
				(xy 479.997008 -184.404) (xy 482.388926 -186.795918) (xy 486.325926 -186.795918) (xy 486.452926 -186.668918)
				(xy 486.452926 -185.906918) (xy 486.325926 -185.779918) (xy 483.023926 -185.779918) (xy 480.378008 -183.134)
				(xy 478.663 -183.134) (xy 475.460314 -179.931314) (xy 475.460314 -178.789584) (xy 475.213426 -178.542696)
			)
		)
	)
	(zone
		(net "P5V_HDD27")
		(layer "F.Cu")
		(hatch none 0.5)
		(connect_pads
			(clearance 0.5)
		)
		(min_thickness 0.25)
		(fill yes
			(thermal_gap 0.5)
			(thermal_bridge_width 0.5)
			(island_removal_mode 0)
		)
		(polygon
			(pts
				(xy 114.318796 -56.682894) (xy 114.064796 -56.936894) (xy 114.064796 -59.222894) (xy 114.318796 -59.476894)
				(xy 114.318796 -61.508894) (xy 115.080796 -62.270894) (xy 115.080796 -63.032894) (xy 115.461796 -63.413894)
				(xy 115.842796 -63.413894) (xy 119.017796 -66.588894) (xy 125.875796 -66.588894) (xy 126.002796 -66.461894)
				(xy 126.002796 -64.683894) (xy 125.875796 -64.556894) (xy 120.795796 -64.556894) (xy 118.890796 -62.651894)
				(xy 118.001796 -62.651894) (xy 117.112796 -61.762894) (xy 117.112796 -59.222894) (xy 117.747796 -58.587894)
				(xy 117.747796 -56.936894) (xy 117.493796 -56.682894)
			)
		)
		(polygon
			(pts
				(xy 116.325396 -63.109094) (xy 116.122196 -63.109094) (xy 116.122196 -63.312294) (xy 116.325396 -63.312294)
			)
		)
		(polygon
			(pts
				(xy 116.325396 -62.245494) (xy 116.122196 -62.245494) (xy 116.122196 -62.448694) (xy 116.325396 -62.448694)
			)
		)
		(polygon
			(pts
				(xy 115.461796 -62.245494) (xy 115.258596 -62.245494) (xy 115.258596 -62.448694) (xy 115.461796 -62.448694)
			)
		)
	)
	(zone
		(net "GND")
		(layer "F.Cu")
		(hatch none 0.5)
		(connect_pads
			(clearance 0.5)
		)
		(min_thickness 0.25)
		(fill yes
			(thermal_gap 0.5)
			(thermal_bridge_width 0.5)
			(island_removal_mode 0)
		)
		(polygon
			(pts
				(arc
					(start 285.328614 -213.01329)
					(mid 286.154996 -214.271696)
					(end 287.38068 -215.145874)
				)
				(xy 287.38068 -215.866472) (xy 282.031186 -215.866472) (xy 281.67584 -216.221818) (xy 281.493976 -216.221818)
				(xy 281.493976 -216.403682) (xy 279.328626 -218.569032) (xy 279.328626 -218.810586) (xy 279.307544 -218.692476)
				(arc
					(start 279.307544 -215.505792)
					(mid 280.772357 -212.371026)
					(end 279.310084 -209.23504)
				)
				(arc
					(start 279.310084 -209.23504)
					(mid 277.23468 -207.734542)
					(end 274.673822 -207.762348)
				)
				(xy 264.263632 -197.352412) (xy 264.263632 -191.948562)
			)
		)
	)
	(zone
		(layer "F.Cu")
		(hatch none 0.5)
		(connect_pads
			(clearance 0)
		)
		(min_thickness 0.25)
		(keepout
			(tracks not_allowed)
			(vias allowed)
			(pads allowed)
			(copperpour not_allowed)
			(footprints allowed)
		)
		(placement
			(enabled no)
			(sheetname "")
		)
		(fill
			(thermal_gap 0.5)
			(thermal_bridge_width 0.5)
			(island_removal_mode 0)
		)
		(polygon
			(pts
				(arc
					(start 271.970754 -312.321448)
					(mid 271.58696 -312.704861)
					(end 271.9705 -313.088528)
				)
				(arc
					(start 273.1135 -313.088528)
					(mid 273.49704 -312.704988)
					(end 273.1135 -312.321448)
				)
				(xy 272.76425 -312.321448)
				(arc
					(start 272.76425 -312.577988)
					(mid 272.779129 -312.613909)
					(end 272.81505 -312.628788)
				)
				(arc
					(start 272.857976 -312.628788)
					(mid 273.380144 -312.704988)
					(end 272.857976 -312.781188)
				)
				(xy 272.783554 -312.781188)
				(arc
					(start 272.780506 -312.77814)
					(mid 272.671429 -312.721609)
					(end 272.614898 -312.612532)
				)
				(xy 272.61185 -312.609484) (xy 272.61185 -312.321448) (xy 272.47215 -312.321448) (xy 272.47215 -312.609484)
				(arc
					(start 272.469102 -312.612532)
					(mid 272.412571 -312.721609)
					(end 272.303494 -312.77814)
				)
				(xy 272.300446 -312.781188)
				(arc
					(start 272.226024 -312.781188)
					(mid 271.703856 -312.704988)
					(end 272.226024 -312.628788)
				)
				(arc
					(start 272.26895 -312.628788)
					(mid 272.304871 -312.613909)
					(end 272.31975 -312.577988)
				)
				(xy 272.31975 -312.321448)
			)
		)
	)
	(zone
		(layer "F.Cu")
		(hatch none 0.5)
		(connect_pads
			(clearance 0)
		)
		(min_thickness 0.25)
		(keepout
			(tracks allowed)
			(vias allowed)
			(pads allowed)
			(copperpour allowed)
			(footprints not_allowed)
		)
		(placement
			(enabled no)
			(sheetname "")
		)
		(fill
			(thermal_gap 0.5)
			(thermal_bridge_width 0.5)
			(island_removal_mode 0)
		)
		(polygon
			(pts
				(arc
					(start 468.900002 -282.999942)
					(mid 467.499954 -284.39999)
					(end 466.099906 -282.999942)
				)
				(arc
					(start 466.099906 -282.999942)
					(mid 467.499954 -281.599894)
					(end 468.900002 -282.999942)
				)
			)
		)
	)
	(zone
		(net "MB1_CM_GATE_R")
		(layer "F.Cu")
		(hatch none 0.5)
		(connect_pads
			(clearance 0.5)
		)
		(min_thickness 0.25)
		(fill yes
			(thermal_gap 0.5)
			(thermal_bridge_width 0.5)
			(island_removal_mode 0)
		)
		(polygon
			(pts
				(xy 355.6 -138.960352) (xy 355.431344 -139.129008) (xy 355.431344 -140.420344) (xy 355.6 -140.589)
				(xy 357.759 -140.589) (xy 358.013 -140.335) (xy 358.013 -139.214352) (xy 357.759 -138.960352)
			)
		)
	)
	(zone
		(net "12V_PRE_19")
		(layer "F.Cu")
		(hatch none 0.5)
		(connect_pads
			(clearance 0.5)
		)
		(min_thickness 0.25)
		(fill yes
			(thermal_gap 0.5)
			(thermal_bridge_width 0.5)
			(island_removal_mode 0)
		)
		(polygon
			(pts
				(xy 362.81868 -183.31434) (xy 360.353102 -185.779918) (xy 357.813102 -185.779918) (xy 357.559102 -186.033918)
				(xy 357.559102 -186.414918) (xy 357.813102 -186.668918) (xy 364.511336 -186.668918) (xy 365.171736 -186.008518)
				(xy 365.171736 -183.43499) (xy 365.051086 -183.31434)
			)
		)
	)
	(zone
		(layer "F.Cu")
		(hatch none 0.5)
		(connect_pads
			(clearance 0)
		)
		(min_thickness 0.25)
		(keepout
			(tracks allowed)
			(vias allowed)
			(pads allowed)
			(copperpour allowed)
			(footprints not_allowed)
		)
		(placement
			(enabled no)
			(sheetname "")
		)
		(fill
			(thermal_gap 0.5)
			(thermal_bridge_width 0.5)
			(island_removal_mode 0)
		)
		(polygon
			(pts
				(arc
					(start 45.39996 -282.999942)
					(mid 44.000166 -284.399736)
					(end 42.600118 -282.999942)
				)
				(arc
					(start 42.600118 -282.999942)
					(mid 44.000166 -281.599894)
					(end 45.39996 -282.999942)
				)
			)
		)
	)
	(zone
		(net "P12V_A")
		(layer "F.Cu")
		(hatch none 0.5)
		(connect_pads
			(clearance 0.5)
		)
		(min_thickness 0.25)
		(fill yes
			(thermal_gap 0.5)
			(thermal_bridge_width 0.5)
			(island_removal_mode 0)
		)
		(polygon
			(pts
				(xy 176.457102 -149.06117) (xy 176.330102 -149.18817) (xy 176.330102 -149.56917) (xy 176.252124 -149.647148)
				(xy 174.638208 -149.647148) (xy 174.558198 -149.727158) (xy 174.558198 -155.891738) (xy 174.96663 -156.30017)
				(xy 179.124102 -156.30017) (xy 179.505102 -155.91917) (xy 179.505102 -149.31517) (xy 179.251102 -149.06117)
			)
		)
		(polygon
			(pts
				(xy 177.390298 -149.60473) (xy 177.187098 -149.60473) (xy 177.187098 -149.80793) (xy 177.390298 -149.80793)
			)
		)
		(polygon
			(pts
				(xy 176.780698 -149.60473) (xy 176.577498 -149.60473) (xy 176.577498 -149.80793) (xy 176.780698 -149.80793)
			)
		)
	)
	(zone
		(layer "F.Cu")
		(hatch none 0.5)
		(connect_pads
			(clearance 0)
		)
		(min_thickness 0.25)
		(keepout
			(tracks allowed)
			(vias allowed)
			(pads allowed)
			(copperpour allowed)
			(footprints allowed)
		)
		(placement
			(enabled no)
			(sheetname "")
		)
		(fill
			(thermal_gap 0.5)
			(thermal_bridge_width 0.5)
			(island_removal_mode 0)
		)
		(polygon
			(pts
				(xy 89.408 -22.4028) (xy 89.408 -20.5232) (xy 89.9414 -20.5232) (xy 89.9414 -22.4028)
			)
		)
	)
	(zone
		(net "GND")
		(layer "F.Cu")
		(hatch none 0.5)
		(connect_pads
			(clearance 0.5)
		)
		(min_thickness 0.25)
		(fill yes
			(thermal_gap 0.5)
			(thermal_bridge_width 0.5)
			(island_removal_mode 0)
		)
		(polygon
			(pts
				(xy 179.913534 -142.281148) (xy 170.019726 -133.984238) (xy 170.019726 -134.240524)
				(arc
					(start 169.592244 -134.240524)
					(mid 168.577844 -134.739834)
					(end 167.465502 -134.942326)
				)
				(arc
					(start 167.465502 -134.942326)
					(mid 166.70873 -135.199707)
					(end 165.916356 -135.305038)
				)
				(arc
					(start 165.916356 -135.305038)
					(mid 164.710377 -136.049431)
					(end 163.322762 -136.337548)
				)
				(arc
					(start 163.322762 -136.337548)
					(mid 163.34238 -136.568064)
					(end 163.348924 -136.79932)
				)
				(arc
					(start 163.348924 -137.898886)
					(mid 162.976646 -139.603975)
					(end 161.92754 -140.998702)
				)
				(arc
					(start 161.92754 -140.998702)
					(mid 162.13453 -141.462767)
					(end 162.282378 -141.948916)
				)
				(xy 163.55441 -141.948916) (xy 164.36721 -141.137386) (xy 169.102786 -141.137386) (xy 170.131994 -142.166594)
				(xy 171.150534 -142.166594) (xy 171.150534 -143.185134) (xy 171.460668 -143.495268) (xy 171.460668 -143.853916)
				(arc
					(start 171.602908 -143.853916)
					(mid 172.554071 -143.478528)
					(end 173.568614 -143.350742)
				)
				(arc
					(start 175.195992 -143.350742)
					(mid 175.691121 -143.380846)
					(end 176.178972 -143.47063)
				)
				(arc
					(start 176.178972 -143.47063)
					(mid 177.996405 -143.517948)
					(end 179.613814 -144.3482)
				)
				(xy 181.408832 -144.3482)
			)
		)
	)
	(zone
		(layer "F.Cu")
		(hatch none 0.5)
		(connect_pads
			(clearance 0)
		)
		(min_thickness 0.25)
		(keepout
			(tracks allowed)
			(vias allowed)
			(pads allowed)
			(copperpour allowed)
			(footprints allowed)
		)
		(placement
			(enabled no)
			(sheetname "")
		)
		(fill
			(thermal_gap 0.5)
			(thermal_bridge_width 0.5)
			(island_removal_mode 0)
		)
		(polygon
			(pts
				(xy 137.07872 -139.229592) (xy 137.07872 -137.273792) (xy 134.36092 -137.273792) (xy 134.36092 -139.229592)
			)
		)
	)
	(zone
		(layer "F.Cu")
		(hatch none 0.5)
		(connect_pads
			(clearance 0)
		)
		(min_thickness 0.25)
		(keepout
			(tracks not_allowed)
			(vias allowed)
			(pads allowed)
			(copperpour not_allowed)
			(footprints allowed)
		)
		(placement
			(enabled no)
			(sheetname "")
		)
		(fill
			(thermal_gap 0.5)
			(thermal_bridge_width 0.5)
			(island_removal_mode 0)
		)
		(polygon
			(pts
				(arc
					(start 446.5701 -273.368516)
					(mid 446.1891 -272.987516)
					(end 445.8081 -273.368516)
				)
				(arc
					(start 445.8081 -274.511262)
					(mid 446.188973 -274.892516)
					(end 446.5701 -274.511516)
				)
				(xy 446.5701 -274.162266)
				(arc
					(start 446.340992 -274.162266)
					(mid 446.321635 -274.166099)
					(end 446.305178 -274.176998)
				)
				(arc
					(start 446.280032 -274.202144)
					(mid 446.269106 -274.21859)
					(end 446.2653 -274.237958)
				)
				(arc
					(start 446.2653 -274.255992)
					(mid 446.1891 -274.77816)
					(end 446.1129 -274.255992)
				)
				(xy 446.1129 -274.206462)
				(arc
					(start 446.115948 -274.203414)
					(mid 446.128383 -274.160251)
					(end 446.149984 -274.120864)
				)
				(xy 446.149984 -274.1168) (xy 446.219834 -274.04695)
				(arc
					(start 446.223898 -274.04695)
					(mid 446.263276 -274.025328)
					(end 446.306448 -274.012914)
				)
				(xy 446.309496 -274.009866) (xy 446.5701 -274.009866) (xy 446.5701 -273.870166) (xy 446.323466 -273.870166)
				(arc
					(start 446.320418 -273.867118)
					(mid 446.277255 -273.854683)
					(end 446.237868 -273.833082)
				)
				(xy 446.233804 -273.833082) (xy 446.149984 -273.749262)
				(arc
					(start 446.149984 -273.745198)
					(mid 446.128362 -273.70582)
					(end 446.115948 -273.662648)
				)
				(xy 446.1129 -273.6596)
				(arc
					(start 446.1129 -273.62404)
					(mid 446.1891 -273.101872)
					(end 446.2653 -273.62404)
				)
				(arc
					(start 446.2653 -273.628104)
					(mid 446.269133 -273.647461)
					(end 446.280032 -273.663918)
				)
				(arc
					(start 446.319148 -273.703034)
					(mid 446.335594 -273.71396)
					(end 446.354962 -273.717766)
				)
				(xy 446.5701 -273.717766)
			)
		)
	)
	(zone
		(layer "F.Cu")
		(hatch none 0.5)
		(connect_pads
			(clearance 0)
		)
		(min_thickness 0.25)
		(keepout
			(tracks allowed)
			(vias allowed)
			(pads allowed)
			(copperpour allowed)
			(footprints not_allowed)
		)
		(placement
			(enabled no)
			(sheetname "")
		)
		(fill
			(thermal_gap 0.5)
			(thermal_bridge_width 0.5)
			(island_removal_mode 0)
		)
		(polygon
			(pts
				(arc
					(start 479.700082 -204.199998)
					(mid 483.450138 -200.449942)
					(end 487.19994 -204.199998)
				)
				(arc
					(start 487.19994 -204.199998)
					(mid 483.450138 -207.9498)
					(end 479.700082 -204.199998)
				)
			)
		)
	)
	(zone
		(layer "F.Cu")
		(hatch none 0.5)
		(connect_pads
			(clearance 0)
		)
		(min_thickness 0.25)
		(keepout
			(tracks allowed)
			(vias allowed)
			(pads allowed)
			(copperpour allowed)
			(footprints not_allowed)
		)
		(placement
			(enabled no)
			(sheetname "")
		)
		(fill
			(thermal_gap 0.5)
			(thermal_bridge_width 0.5)
			(island_removal_mode 0)
		)
		(polygon
			(pts
				(arc
					(start 386.675122 -207.79994)
					(mid 393.675108 -200.799954)
					(end 400.675094 -207.79994)
				)
				(arc
					(start 400.675094 -213.799928)
					(mid 393.675108 -220.799914)
					(end 386.675122 -213.799928)
				)
			)
		)
	)
	(zone
		(net "12V_PRE_26")
		(layer "F.Cu")
		(hatch none 0.5)
		(connect_pads
			(clearance 0.5)
		)
		(min_thickness 0.25)
		(fill yes
			(thermal_gap 0.5)
			(thermal_bridge_width 0.5)
			(island_removal_mode 0)
		)
		(polygon
			(pts
				(xy 82.768948 -63.794894) (xy 82.641948 -63.921894) (xy 82.641948 -65.445894) (xy 84.038948 -66.842894)
				(xy 85.435948 -66.842894) (xy 90.388948 -71.795894) (xy 94.325948 -71.795894) (xy 94.452948 -71.668894)
				(xy 94.452948 -70.906894) (xy 94.325948 -70.779894) (xy 91.023948 -70.779894) (xy 84.038948 -63.794894)
			)
		)
	)
	(zone
		(net "GND")
		(layer "F.Cu")
		(hatch none 0.5)
		(connect_pads
			(clearance 0.5)
		)
		(min_thickness 0.25)
		(fill yes
			(thermal_gap 0.5)
			(thermal_bridge_width 0.5)
			(island_removal_mode 0)
		)
		(polygon
			(pts
				(xy 219.6973 -173.1899) (xy 219.2528 -173.6344) (xy 219.2528 -175.93437) (xy 219.722192 -176.404016)
				(xy 222.541592 -176.404016) (xy 222.819976 -176.6824) (xy 224.879408 -176.6824) (xy 225.2472 -176.314608)
				(xy 225.2472 -173.6217) (xy 224.8154 -173.1899)
			)
		)
	)
	(zone
		(net "P12V_HDD34")
		(layer "F.Cu")
		(hatch none 0.5)
		(connect_pads
			(clearance 0.5)
		)
		(min_thickness 0.25)
		(fill yes
			(thermal_gap 0.5)
			(thermal_bridge_width 0.5)
			(island_removal_mode 0)
		)
		(polygon
			(pts
				(xy 460.8449 -63.540894) (xy 460.5909 -63.794894) (xy 460.5909 -67.858894) (xy 460.132176 -68.317618)
				(xy 460.132176 -71.139812) (xy 459.298294 -71.973694) (xy 452.378318 -71.973694) (xy 452.2089 -72.143112)
				(xy 452.2089 -73.954894) (xy 452.4629 -74.208894) (xy 456.3999 -74.208894) (xy 456.9079 -73.700894)
				(xy 464.6549 -73.700894) (xy 465.5439 -72.811894) (xy 465.5439 -63.794894) (xy 465.2899 -63.540894)
			)
		)
		(polygon
			(pts
				(xy 456.5523 -73.091294) (xy 456.3491 -73.091294) (xy 456.3491 -73.294494) (xy 456.5523 -73.294494)
			)
		)
		(polygon
			(pts
				(xy 455.6887 -73.091294) (xy 455.4855 -73.091294) (xy 455.4855 -73.294494) (xy 455.6887 -73.294494)
			)
		)
	)
	(zone
		(layer "F.Cu")
		(hatch none 0.5)
		(connect_pads
			(clearance 0)
		)
		(min_thickness 0.25)
		(keepout
			(tracks allowed)
			(vias allowed)
			(pads allowed)
			(copperpour allowed)
			(footprints not_allowed)
		)
		(placement
			(enabled no)
			(sheetname "")
		)
		(fill
			(thermal_gap 0.5)
			(thermal_bridge_width 0.5)
			(island_removal_mode 0)
		)
		(polygon
			(pts
				(arc
					(start 472.250008 -269.999968)
					(mid 467.499954 -274.750022)
					(end 462.7499 -269.999968)
				)
				(arc
					(start 462.7499 -269.999968)
					(mid 467.499954 -265.249914)
					(end 472.250008 -269.999968)
				)
			)
		)
	)
	(zone
		(net "P5V_HDD13")
		(layer "F.Cu")
		(hatch none 0.5)
		(connect_pads
			(clearance 0.5)
		)
		(min_thickness 0.25)
		(fill yes
			(thermal_gap 0.5)
			(thermal_bridge_width 0.5)
			(island_removal_mode 0)
		)
		(polygon
			(pts
				(xy 51.218846 -171.682918) (xy 50.964846 -171.936918) (xy 50.964846 -174.222918) (xy 51.218846 -174.476918)
				(xy 51.218846 -176.508918) (xy 51.980846 -177.270918) (xy 51.980846 -178.032918) (xy 52.361846 -178.413918)
				(xy 52.742846 -178.413918) (xy 55.917846 -181.588918) (xy 62.775846 -181.588918) (xy 62.902846 -181.461918)
				(xy 62.902846 -179.683918) (xy 62.775846 -179.556918) (xy 57.695846 -179.556918) (xy 55.790846 -177.651918)
				(xy 54.901846 -177.651918) (xy 54.012846 -176.762918) (xy 54.012846 -174.222918) (xy 54.647846 -173.587918)
				(xy 54.647846 -171.936918) (xy 54.393846 -171.682918)
			)
		)
		(polygon
			(pts
				(xy 53.225446 -178.109118) (xy 53.022246 -178.109118) (xy 53.022246 -178.312318) (xy 53.225446 -178.312318)
			)
		)
		(polygon
			(pts
				(xy 53.225446 -177.245518) (xy 53.022246 -177.245518) (xy 53.022246 -177.448718) (xy 53.225446 -177.448718)
			)
		)
		(polygon
			(pts
				(xy 52.361846 -177.245518) (xy 52.158646 -177.245518) (xy 52.158646 -177.448718) (xy 52.361846 -177.448718)
			)
		)
	)
	(zone
		(net "GND")
		(layer "F.Cu")
		(hatch none 0.5)
		(connect_pads
			(clearance 0.5)
		)
		(min_thickness 0.25)
		(fill yes
			(thermal_gap 0.5)
			(thermal_bridge_width 0.5)
			(island_removal_mode 0)
		)
		(polygon
			(pts
				(xy 202.257914 -156.972) (xy 201.83475 -157.395164) (xy 201.83475 -161.76625) (xy 202.2475 -162.179)
				(xy 204.958696 -162.179) (xy 205.260702 -161.876994) (xy 205.260702 -158.434024) (xy 203.798678 -156.972)
			)
		)
	)
	(zone
		(net "P12V_HDD35")
		(layer "F.Cu")
		(hatch none 0.5)
		(connect_pads
			(clearance 0.5)
		)
		(min_thickness 0.25)
		(fill yes
			(thermal_gap 0.5)
			(thermal_bridge_width 0.5)
			(island_removal_mode 0)
		)
		(polygon
			(pts
				(xy 467.402926 -61.254894) (xy 467.148926 -61.508894) (xy 467.148926 -63.159894) (xy 467.402926 -63.413894)
				(xy 469.561926 -63.413894) (xy 470.069926 -63.921894) (xy 470.069926 -68.470526) (xy 475.808294 -74.208894)
				(xy 486.325926 -74.208894) (xy 486.452926 -74.081894) (xy 486.452926 -72.303894) (xy 486.325926 -72.176894)
				(xy 480.356926 -72.176894) (xy 479.721926 -71.541894) (xy 477.027494 -71.541894) (xy 473.752926 -68.267326)
				(xy 473.752926 -63.667894) (xy 472.609926 -62.524894) (xy 472.609926 -61.508894) (xy 472.355926 -61.254894)
			)
		)
		(polygon
			(pts
				(xy 479.874326 -73.218294) (xy 479.671126 -73.218294) (xy 479.671126 -73.421494) (xy 479.874326 -73.421494)
			)
		)
		(polygon
			(pts
				(xy 479.010726 -73.218294) (xy 478.807526 -73.218294) (xy 478.807526 -73.421494) (xy 479.010726 -73.421494)
			)
		)
	)
	(zone
		(layer "F.Cu")
		(hatch none 0.5)
		(connect_pads
			(clearance 0)
		)
		(min_thickness 0.25)
		(keepout
			(tracks not_allowed)
			(vias allowed)
			(pads allowed)
			(copperpour not_allowed)
			(footprints allowed)
		)
		(placement
			(enabled no)
			(sheetname "")
		)
		(fill
			(thermal_gap 0.5)
			(thermal_bridge_width 0.5)
			(island_removal_mode 0)
		)
		(polygon
			(pts
				(arc
					(start 95.989902 -162.178746)
					(mid 95.609029 -161.797492)
					(end 95.227902 -162.178492)
				)
				(xy 95.227902 -162.527742)
				(arc
					(start 95.481902 -162.527742)
					(mid 95.517823 -162.512863)
					(end 95.532702 -162.476942)
				)
				(arc
					(start 95.532702 -162.434016)
					(mid 95.608902 -161.911848)
					(end 95.685102 -162.434016)
				)
				(xy 95.685102 -162.508438)
				(arc
					(start 95.682054 -162.511486)
					(mid 95.625523 -162.620563)
					(end 95.516446 -162.677094)
				)
				(xy 95.513398 -162.680142) (xy 95.227902 -162.680142) (xy 95.227902 -162.819842) (xy 95.513398 -162.819842)
				(arc
					(start 95.516446 -162.82289)
					(mid 95.625523 -162.879421)
					(end 95.682054 -162.988498)
				)
				(xy 95.685102 -162.991546)
				(arc
					(start 95.685102 -163.065968)
					(mid 95.608902 -163.588136)
					(end 95.532702 -163.065968)
				)
				(arc
					(start 95.532702 -163.023042)
					(mid 95.517823 -162.987121)
					(end 95.481902 -162.972242)
				)
				(xy 95.227902 -162.972242)
				(arc
					(start 95.227902 -163.321492)
					(mid 95.608902 -163.702492)
					(end 95.989902 -163.321492)
				)
			)
		)
	)
	(zone
		(layer "F.Cu")
		(hatch none 0.5)
		(connect_pads
			(clearance 0)
		)
		(min_thickness 0.25)
		(keepout
			(tracks not_allowed)
			(vias allowed)
			(pads allowed)
			(copperpour not_allowed)
			(footprints allowed)
		)
		(placement
			(enabled no)
			(sheetname "")
		)
		(fill
			(thermal_gap 0.5)
			(thermal_bridge_width 0.5)
			(island_removal_mode 0)
		)
		(polygon
			(pts
				(arc
					(start 341.300054 -274.877022)
					(mid 341.300054 -265.122914)
					(end 341.300054 -274.877022)
				)
			)
		)
	)
	(zone
		(net "P12V_A")
		(layer "F.Cu")
		(hatch none 0.5)
		(connect_pads
			(clearance 0.5)
		)
		(min_thickness 0.25)
		(fill yes
			(thermal_gap 0.5)
			(thermal_bridge_width 0.5)
			(island_removal_mode 0)
		)
		(polygon
			(pts
				(xy 403.5806 -278.8666) (xy 403.333458 -279.113742) (xy 403.333458 -282.194) (xy 403.587458 -282.448)
				(xy 407.2382 -282.448) (xy 407.524458 -282.161742) (xy 407.524458 -279.102058) (xy 407.289 -278.8666)
			)
		)
		(polygon
			(pts
				(xy 407.3398 -281.8638) (xy 407.1366 -281.8638) (xy 407.1366 -282.067) (xy 407.3398 -282.067)
			)
		)
		(polygon
			(pts
				(xy 406.781 -281.8638) (xy 406.5778 -281.8638) (xy 406.5778 -282.067) (xy 406.781 -282.067)
			)
		)
		(polygon
			(pts
				(xy 406.4 -281.8384) (xy 406.1968 -281.8384) (xy 406.1968 -282.0416) (xy 406.4 -282.0416)
			)
		)
		(polygon
			(pts
				(xy 405.7904 -281.8384) (xy 405.5872 -281.8384) (xy 405.5872 -282.0416) (xy 405.7904 -282.0416)
			)
		)
	)
	(zone
		(net "P12V_HDD10")
		(layer "F.Cu")
		(hatch none 0.5)
		(connect_pads
			(clearance 0.5)
		)
		(min_thickness 0.25)
		(fill yes
			(thermal_gap 0.5)
			(thermal_bridge_width 0.5)
			(island_removal_mode 0)
		)
		(polygon
			(pts
				(xy 460.8449 -293.540942) (xy 460.5909 -293.794942) (xy 460.5909 -297.858942) (xy 460.132176 -298.317666)
				(xy 460.132176 -301.13986) (xy 459.298294 -301.973742) (xy 452.378318 -301.973742) (xy 452.2089 -302.14316)
				(xy 452.2089 -303.954942) (xy 452.4629 -304.208942) (xy 456.3999 -304.208942) (xy 456.9079 -303.700942)
				(xy 464.6549 -303.700942) (xy 465.5439 -302.811942) (xy 465.5439 -293.794942) (xy 465.2899 -293.540942)
			)
		)
		(polygon
			(pts
				(xy 456.5523 -303.091342) (xy 456.3491 -303.091342) (xy 456.3491 -303.294542) (xy 456.5523 -303.294542)
			)
		)
		(polygon
			(pts
				(xy 455.6887 -303.091342) (xy 455.4855 -303.091342) (xy 455.4855 -303.294542) (xy 455.6887 -303.294542)
			)
		)
	)
	(zone
		(layer "F.Cu")
		(hatch none 0.5)
		(connect_pads
			(clearance 0)
		)
		(min_thickness 0.25)
		(keepout
			(tracks allowed)
			(vias allowed)
			(pads allowed)
			(copperpour allowed)
			(footprints not_allowed)
		)
		(placement
			(enabled no)
			(sheetname "")
		)
		(fill
			(thermal_gap 0.5)
			(thermal_bridge_width 0.5)
			(island_removal_mode 0)
		)
		(polygon
			(pts
				(arc
					(start 323.674994 -92.799916)
					(mid 330.67498 -85.79993)
					(end 337.674966 -92.799916)
				)
				(arc
					(start 337.674966 -98.799904)
					(mid 330.67498 -105.79989)
					(end 323.674994 -98.799904)
				)
			)
		)
	)
	(zone
		(net "P12V_HDD13")
		(layer "F.Cu")
		(hatch none 0.5)
		(connect_pads
			(clearance 0.5)
		)
		(min_thickness 0.25)
		(fill yes
			(thermal_gap 0.5)
			(thermal_bridge_width 0.5)
			(island_removal_mode 0)
		)
		(polygon
			(pts
				(xy 43.852846 -176.254918) (xy 43.598846 -176.508918) (xy 43.598846 -178.159918) (xy 43.852846 -178.413918)
				(xy 46.011846 -178.413918) (xy 46.519846 -178.921918) (xy 46.519846 -181.461918) (xy 54.266846 -189.208918)
				(xy 62.775846 -189.208918) (xy 62.902846 -189.081918) (xy 62.902846 -187.303918) (xy 62.775846 -187.176918)
				(xy 56.806846 -187.176918) (xy 56.171846 -186.541918) (xy 54.520846 -186.541918) (xy 50.202846 -182.223918)
				(xy 50.202846 -178.667918) (xy 49.059846 -177.524918) (xy 49.059846 -176.508918) (xy 48.805846 -176.254918)
			)
		)
		(polygon
			(pts
				(xy 56.324246 -188.218318) (xy 56.121046 -188.218318) (xy 56.121046 -188.421518) (xy 56.324246 -188.421518)
			)
		)
		(polygon
			(pts
				(xy 55.460646 -188.218318) (xy 55.257446 -188.218318) (xy 55.257446 -188.421518) (xy 55.460646 -188.421518)
			)
		)
	)
	(zone
		(net "P12V_A")
		(layer "F.Cu")
		(hatch none 0.5)
		(connect_pads
			(clearance 0.5)
		)
		(min_thickness 0.25)
		(fill yes
			(thermal_gap 0.5)
			(thermal_bridge_width 0.5)
			(island_removal_mode 0)
		)
		(polygon
			(pts
				(xy 469.307926 -54.142894) (xy 468.291926 -55.158894) (xy 467.656926 -55.158894) (xy 467.275926 -55.539894)
				(xy 467.275926 -58.079894) (xy 467.529926 -58.333894) (xy 470.831926 -58.333894) (xy 471.085926 -58.079894)
				(xy 471.085926 -55.793894) (xy 470.450926 -55.158894) (xy 470.069926 -55.158894) (xy 469.815926 -54.904894)
				(xy 469.815926 -54.269894) (xy 469.688926 -54.142894)
			)
		)
		(polygon
			(pts
				(xy 469.282526 -54.727094) (xy 469.079326 -54.727094) (xy 469.079326 -54.930294) (xy 469.282526 -54.930294)
			)
		)
	)
	(zone
		(layer "F.Cu")
		(hatch none 0.5)
		(connect_pads
			(clearance 0)
		)
		(min_thickness 0.25)
		(keepout
			(tracks allowed)
			(vias allowed)
			(pads allowed)
			(copperpour allowed)
			(footprints not_allowed)
		)
		(placement
			(enabled no)
			(sheetname "")
		)
		(fill
			(thermal_gap 0.5)
			(thermal_bridge_width 0.5)
			(island_removal_mode 0)
		)
		(polygon
			(pts
				(xy 312.699908 -233.19994) (xy 287.699958 -233.19994) (xy 287.699958 -259.199888) (xy 312.699908 -259.199888)
			)
		)
	)
	(zone
		(layer "F.Cu")
		(hatch none 0.5)
		(connect_pads
			(clearance 0)
		)
		(min_thickness 0.25)
		(keepout
			(tracks allowed)
			(vias allowed)
			(pads allowed)
			(copperpour allowed)
			(footprints allowed)
		)
		(placement
			(enabled no)
			(sheetname "")
		)
		(fill
			(thermal_gap 0.5)
			(thermal_bridge_width 0.5)
			(island_removal_mode 0)
		)
		(polygon
			(pts
				(xy 478.6884 -44.5516) (xy 480.0346 -44.5516) (xy 480.314 -44.2722) (xy 480.314 -43.688) (xy 480.0854 -43.4594)
				(xy 478.8916 -43.4594) (xy 478.6376 -43.7134) (xy 478.6376 -44.5008)
			)
		)
	)
	(zone
		(net "GND")
		(layer "F.Cu")
		(hatch none 0.5)
		(connect_pads
			(clearance 0.5)
		)
		(min_thickness 0.25)
		(fill yes
			(thermal_gap 0.5)
			(thermal_bridge_width 0.5)
			(island_removal_mode 0)
		)
		(polygon
			(pts
				(arc
					(start 348.777814 -88.075262)
					(mid 347.513746 -87.230639)
					(end 346.022676 -86.93404)
				)
				(arc
					(start 344.61958 -86.93404)
					(mid 343.128508 -87.230633)
					(end 341.864442 -88.075262)
				)
				(arc
					(start 340.842854 -89.09685)
					(mid 340.254474 -87.766926)
					(end 339.493098 -86.527894)
				)
				(arc
					(start 362.312712 -86.527894)
					(mid 361.991899 -87.075838)
					(end 361.759754 -87.66683)
				)
				(arc
					(start 361.759754 -87.66683)
					(mid 359.657358 -91.854771)
					(end 362.867448 -95.268542)
				)
				(arc
					(start 362.867448 -95.268542)
					(mid 365.550942 -96.947447)
					(end 368.62893 -96.208596)
				)
				(arc
					(start 368.62893 -96.208596)
					(mid 369.300844 -96.627653)
					(end 370.040916 -96.909382)
				)
				(arc
					(start 370.040916 -98.735642)
					(mid 369.367866 -98.995169)
					(end 368.75085 -99.368864)
				)
				(arc
					(start 368.75085 -99.368864)
					(mid 365.95287 -98.534823)
					(end 363.311694 -99.779074)
				)
				(arc
					(start 363.311694 -99.779074)
					(mid 356.925384 -97.635051)
					(end 357.19766 -104.36606)
				)
				(arc
					(start 357.19766 -104.36606)
					(mid 356.317641 -105.916344)
					(end 356.180644 -107.693714)
				)
				(arc
					(start 356.180644 -107.693714)
					(mid 354.27413 -107.290902)
					(end 352.397568 -107.815888)
				)
				(arc
					(start 352.397568 -107.815888)
					(mid 353.451902 -104.270875)
					(end 351.21596 -101.324918)
				)
				(arc
					(start 351.21596 -101.324918)
					(mid 351.161209 -101.128251)
					(end 351.096834 -100.93452)
				)
				(xy 351.096834 -99.37369) (xy 351.443798 -99.37369) (xy 351.443798 -89.426542)
				(arc
					(start 350.08058 -89.426542)
					(mid 349.916741 -89.226316)
					(end 349.739966 -89.037414)
				)
			)
		)
	)
	(zone
		(net "P5V_HDD9")
		(layer "F.Cu")
		(hatch none 0.5)
		(connect_pads
			(clearance 0.5)
		)
		(min_thickness 0.25)
		(fill yes
			(thermal_gap 0.5)
			(thermal_bridge_width 0.5)
			(island_removal_mode 0)
		)
		(polygon
			(pts
				(xy 426.247052 -281.729942) (xy 425.993052 -281.983942) (xy 425.993052 -292.778942) (xy 424.342052 -294.429942)
				(xy 420.913052 -294.429942) (xy 420.659052 -294.683942) (xy 420.659052 -296.334942) (xy 420.913052 -296.588942)
				(xy 425.485052 -296.588942) (xy 426.120052 -295.953942) (xy 427.898052 -295.953942) (xy 428.406052 -295.445942)
				(xy 428.406052 -281.983942) (xy 428.152052 -281.729942)
			)
		)
		(polygon
			(pts
				(xy 425.002452 -295.598342) (xy 424.799252 -295.598342) (xy 424.799252 -295.801542) (xy 425.002452 -295.801542)
			)
		)
		(polygon
			(pts
				(xy 424.138852 -295.598342) (xy 423.935652 -295.598342) (xy 423.935652 -295.801542) (xy 424.138852 -295.801542)
			)
		)
	)
	(zone
		(layer "F.Cu")
		(hatch none 0.5)
		(connect_pads
			(clearance 0)
		)
		(min_thickness 0.25)
		(keepout
			(tracks allowed)
			(vias allowed)
			(pads allowed)
			(copperpour allowed)
			(footprints not_allowed)
		)
		(placement
			(enabled no)
			(sheetname "")
		)
		(fill
			(thermal_gap 0.5)
			(thermal_bridge_width 0.5)
			(island_removal_mode 0)
		)
		(polygon
			(pts
				(arc
					(start 411.174946 -210.799934)
					(mid 425.174918 -196.799962)
					(end 439.17489 -210.799934)
				)
				(arc
					(start 439.17489 -210.799934)
					(mid 425.174918 -224.799906)
					(end 411.174946 -210.799934)
				)
			)
		)
	)
	(zone
		(net "GND")
		(layer "F.Cu")
		(hatch none 0.5)
		(connect_pads
			(clearance 0.5)
		)
		(min_thickness 0.25)
		(fill yes
			(thermal_gap 0.5)
			(thermal_bridge_width 0.5)
			(island_removal_mode 0)
		)
		(polygon
			(pts
				(xy 274.40509 -155.94457) (xy 274.40509 -175.716946) (xy 273.325844 -175.716946) (xy 270.484346 -178.558444)
				(xy 270.484346 -185.5978) (xy 268.249908 -183.363362)
				(arc
					(start 268.249908 -156.07411)
					(mid 268.429801 -156.013357)
					(end 268.606778 -155.94457)
				)
			)
		)
	)
	(zone
		(net "P12V_A")
		(layer "F.Cu")
		(hatch none 0.5)
		(connect_pads
			(clearance 0.5)
		)
		(min_thickness 0.25)
		(fill yes
			(thermal_gap 0.5)
			(thermal_bridge_width 0.5)
			(island_removal_mode 0)
		)
		(polygon
			(pts
				(xy 140.407898 -169.142918) (xy 139.391898 -170.158918) (xy 138.756898 -170.158918) (xy 138.375898 -170.539918)
				(xy 138.375898 -173.079918) (xy 138.629898 -173.333918) (xy 141.931898 -173.333918) (xy 142.185898 -173.079918)
				(xy 142.185898 -171.175426) (xy 140.892276 -169.881804) (xy 140.892276 -169.246296) (xy 140.788898 -169.142918)
			)
		)
		(polygon
			(pts
				(xy 140.382498 -169.727118) (xy 140.179298 -169.727118) (xy 140.179298 -169.930318) (xy 140.382498 -169.930318)
			)
		)
	)
	(zone
		(net "GND")
		(layer "F.Cu")
		(hatch none 0.5)
		(connect_pads
			(clearance 0.5)
		)
		(min_thickness 0.25)
		(fill yes
			(thermal_gap 0.5)
			(thermal_bridge_width 0.5)
			(island_removal_mode 0)
		)
		(polygon
			(pts
				(arc
					(start 398.641316 -30.846522)
					(mid 398.654446 -31.160653)
					(end 398.691354 -31.472886)
				)
				(arc
					(start 398.691354 -34.073338)
					(mid 398.907307 -35.384884)
					(end 399.532348 -36.557966)
				)
				(arc
					(start 399.532348 -36.557966)
					(mid 399.493523 -37.302319)
					(end 399.588736 -38.04158)
				)
				(arc
					(start 399.588736 -38.04158)
					(mid 399.521083 -38.051818)
					(end 399.453608 -38.06317)
				)
				(arc
					(start 398.829022 -38.06317)
					(mid 397.657365 -37.440194)
					(end 396.34795 -37.22497)
				)
				(xy 395.467586 -37.22497) (xy 395.467586 -37.042344) (xy 393.756134 -37.042344) (xy 393.756134 -30.928818)
				(xy 393.525502 -30.928818) (xy 393.532106 -30.846522)
			)
		)
	)
	(zone
		(layer "F.Cu")
		(hatch none 0.5)
		(connect_pads
			(clearance 0)
		)
		(min_thickness 0.25)
		(keepout
			(tracks not_allowed)
			(vias allowed)
			(pads allowed)
			(copperpour not_allowed)
			(footprints allowed)
		)
		(placement
			(enabled no)
			(sheetname "")
		)
		(fill
			(thermal_gap 0.5)
			(thermal_bridge_width 0.5)
			(island_removal_mode 0)
		)
		(polygon
			(pts
				(arc
					(start 127.53975 -162.178746)
					(mid 127.158877 -161.797492)
					(end 126.77775 -162.178492)
				)
				(xy 126.77775 -162.527742)
				(arc
					(start 127.03175 -162.527742)
					(mid 127.067671 -162.512863)
					(end 127.08255 -162.476942)
				)
				(arc
					(start 127.08255 -162.434016)
					(mid 127.15875 -161.911848)
					(end 127.23495 -162.434016)
				)
				(xy 127.23495 -162.508438)
				(arc
					(start 127.231902 -162.511486)
					(mid 127.175371 -162.620563)
					(end 127.066294 -162.677094)
				)
				(xy 127.063246 -162.680142) (xy 126.77775 -162.680142) (xy 126.77775 -162.819842) (xy 127.063246 -162.819842)
				(arc
					(start 127.066294 -162.82289)
					(mid 127.175371 -162.879421)
					(end 127.231902 -162.988498)
				)
				(xy 127.23495 -162.991546)
				(arc
					(start 127.23495 -163.065968)
					(mid 127.15875 -163.588136)
					(end 127.08255 -163.065968)
				)
				(arc
					(start 127.08255 -163.023042)
					(mid 127.067671 -162.987121)
					(end 127.03175 -162.972242)
				)
				(xy 126.77775 -162.972242)
				(arc
					(start 126.77775 -163.321492)
					(mid 127.15875 -163.702492)
					(end 127.53975 -163.321492)
				)
			)
		)
	)
	(zone
		(layer "F.Cu")
		(hatch none 0.5)
		(connect_pads
			(clearance 0)
		)
		(min_thickness 0.25)
		(keepout
			(tracks allowed)
			(vias allowed)
			(pads allowed)
			(copperpour allowed)
			(footprints not_allowed)
		)
		(placement
			(enabled no)
			(sheetname "")
		)
		(fill
			(thermal_gap 0.5)
			(thermal_bridge_width 0.5)
			(island_removal_mode 0)
		)
		(polygon
			(pts
				(arc
					(start 336.55 -269.999968)
					(mid 341.300054 -265.249914)
					(end 346.050108 -269.999968)
				)
				(arc
					(start 346.050108 -269.999968)
					(mid 341.300054 -274.750022)
					(end 336.55 -269.999968)
				)
			)
		)
	)
	(zone
		(layer "F.Cu")
		(hatch none 0.5)
		(connect_pads
			(clearance 0)
		)
		(min_thickness 0.25)
		(keepout
			(tracks not_allowed)
			(vias allowed)
			(pads allowed)
			(copperpour not_allowed)
			(footprints allowed)
		)
		(placement
			(enabled no)
			(sheetname "")
		)
		(fill
			(thermal_gap 0.5)
			(thermal_bridge_width 0.5)
			(island_removal_mode 0)
		)
		(polygon
			(pts
				(arc
					(start 26.325068 -92.799916)
					(mid 33.325054 -85.79993)
					(end 40.32504 -92.799916)
				)
				(arc
					(start 40.32504 -98.799904)
					(mid 33.325054 -105.79989)
					(end 26.325068 -98.799904)
				)
			)
		)
	)
	(zone
		(layer "F.Cu")
		(hatch none 0.5)
		(connect_pads
			(clearance 0)
		)
		(min_thickness 0.25)
		(keepout
			(tracks not_allowed)
			(vias allowed)
			(pads allowed)
			(copperpour not_allowed)
			(footprints allowed)
		)
		(placement
			(enabled no)
			(sheetname "")
		)
		(fill
			(thermal_gap 0.5)
			(thermal_bridge_width 0.5)
			(island_removal_mode 0)
		)
		(polygon
			(pts
				(arc
					(start 351.920302 -273.368516)
					(mid 351.539302 -272.987516)
					(end 351.158302 -273.368516)
				)
				(arc
					(start 351.158302 -274.511262)
					(mid 351.539175 -274.892516)
					(end 351.920302 -274.511516)
				)
				(xy 351.920302 -274.162266)
				(arc
					(start 351.683828 -274.162266)
					(mid 351.664471 -274.166099)
					(end 351.648014 -274.176998)
				)
				(arc
					(start 351.630234 -274.194778)
					(mid 351.619308 -274.211224)
					(end 351.615502 -274.230592)
				)
				(arc
					(start 351.615502 -274.255992)
					(mid 351.539302 -274.77816)
					(end 351.463102 -274.255992)
				)
				(xy 351.463102 -274.199096)
				(arc
					(start 351.46615 -274.196048)
					(mid 351.478585 -274.152885)
					(end 351.500186 -274.113498)
				)
				(xy 351.500186 -274.109434) (xy 351.56267 -274.04695)
				(arc
					(start 351.566734 -274.04695)
					(mid 351.606112 -274.025328)
					(end 351.649284 -274.012914)
				)
				(xy 351.652332 -274.009866) (xy 351.920302 -274.009866) (xy 351.920302 -273.870166) (xy 351.652586 -273.870166)
				(arc
					(start 351.649538 -273.867118)
					(mid 351.606375 -273.854683)
					(end 351.566988 -273.833082)
				)
				(xy 351.562924 -273.833082) (xy 351.500186 -273.770344)
				(arc
					(start 351.500186 -273.76628)
					(mid 351.478564 -273.726902)
					(end 351.46615 -273.68373)
				)
				(xy 351.463102 -273.680682)
				(arc
					(start 351.463102 -273.62404)
					(mid 351.539302 -273.101872)
					(end 351.615502 -273.62404)
				)
				(arc
					(start 351.615502 -273.649186)
					(mid 351.619335 -273.668543)
					(end 351.630234 -273.685)
				)
				(arc
					(start 351.648268 -273.703034)
					(mid 351.664714 -273.71396)
					(end 351.684082 -273.717766)
				)
				(xy 351.920302 -273.717766)
			)
		)
	)
	(zone
		(layer "F.Cu")
		(hatch none 0.5)
		(connect_pads
			(clearance 0)
		)
		(min_thickness 0.25)
		(keepout
			(tracks allowed)
			(vias allowed)
			(pads allowed)
			(copperpour allowed)
			(footprints not_allowed)
		)
		(placement
			(enabled no)
			(sheetname "")
		)
		(fill
			(thermal_gap 0.5)
			(thermal_bridge_width 0.5)
			(island_removal_mode 0)
		)
		(polygon
			(pts
				(arc
					(start 38.999922 -164.200078)
					(mid 42.749978 -160.450022)
					(end 46.500034 -164.200078)
				)
				(arc
					(start 46.500034 -164.200078)
					(mid 42.749978 -167.950134)
					(end 38.999922 -164.200078)
				)
			)
		)
	)
	(zone
		(layer "F.Cu")
		(hatch none 0.5)
		(connect_pads
			(clearance 0)
		)
		(min_thickness 0.25)
		(keepout
			(tracks allowed)
			(vias allowed)
			(pads allowed)
			(copperpour allowed)
			(footprints not_allowed)
		)
		(placement
			(enabled no)
			(sheetname "")
		)
		(fill
			(thermal_gap 0.5)
			(thermal_bridge_width 0.5)
			(island_removal_mode 0)
		)
		(polygon
			(pts
				(xy 298.200064 -128.199896) (xy 291.599874 -128.199896) (xy 291.599874 38.800024) (xy 298.200064 38.800024)
			)
		)
	)
	(zone
		(net "P5V_A_2")
		(layer "F.Cu")
		(hatch none 0.5)
		(connect_pads
			(clearance 0.5)
		)
		(min_thickness 0.25)
		(fill yes
			(thermal_gap 0.5)
			(thermal_bridge_width 0.5)
			(island_removal_mode 0)
		)
		(polygon
			(pts
				(xy 216.676732 -6.773672) (xy 216.509854 -6.94055) (xy 216.509854 -11.702542) (xy 216.565988 -11.758676)
				(xy 219.530676 -11.758676) (xy 219.583508 -11.705844) (xy 219.583508 -9.054846) (xy 219.121736 -8.593074)
				(xy 219.121736 -6.881622) (xy 219.013786 -6.773672)
			)
		)
		(polygon
			(pts
				(xy 218.815158 -9.787636) (xy 218.611958 -9.787636) (xy 218.611958 -9.990836) (xy 218.815158 -9.990836)
			)
		)
		(polygon
			(pts
				(xy 218.815158 -8.924036) (xy 218.611958 -8.924036) (xy 218.611958 -9.127236) (xy 218.815158 -9.127236)
			)
		)
	)
	(zone
		(net "P12V_A_COMP")
		(layer "F.Cu")
		(hatch none 0.5)
		(connect_pads
			(clearance 0.5)
		)
		(min_thickness 0.25)
		(fill yes
			(thermal_gap 0.5)
			(thermal_bridge_width 0.5)
			(island_removal_mode 0)
		)
		(polygon
			(pts
				(xy 159.634428 -149.41677) (xy 159.174688 -149.87651) (xy 159.174688 -154.182826) (xy 159.412432 -154.42057)
				(xy 165.128702 -154.42057) (xy 165.408102 -154.14117) (xy 165.408102 -150.415244) (xy 165.255702 -150.262844)
				(xy 163.536376 -150.262844) (xy 162.690302 -149.41677)
			)
		)
		(polygon
			(pts
				(xy 162.233102 -149.87397) (xy 162.029902 -149.87397) (xy 162.029902 -150.07717) (xy 162.233102 -150.07717)
			)
		)
		(polygon
			(pts
				(xy 161.674302 -149.87397) (xy 161.471102 -149.87397) (xy 161.471102 -150.07717) (xy 161.674302 -150.07717)
			)
		)
	)
	(zone
		(net "GND")
		(layer "F.Cu")
		(hatch none 0.5)
		(connect_pads
			(clearance 0.5)
		)
		(min_thickness 0.25)
		(fill yes
			(thermal_gap 0.5)
			(thermal_bridge_width 0.5)
			(island_removal_mode 0)
		)
		(polygon
			(pts
				(xy 210.628738 -6.832092) (xy 210.520788 -6.940042) (xy 210.520788 -8.36422) (xy 210.991958 -8.83539)
				(xy 210.991958 -11.67765) (xy 211.253324 -11.939016) (xy 212.954616 -11.939016) (xy 213.216744 -11.676888)
				(xy 213.216744 -7.083044) (xy 212.965792 -6.832092)
			)
		)
		(polygon
			(pts
				(xy 212.142832 -9.822688) (xy 211.939632 -9.822688) (xy 211.939632 -10.025888) (xy 212.142832 -10.025888)
			)
		)
		(polygon
			(pts
				(xy 212.142832 -8.959088) (xy 211.939632 -8.959088) (xy 211.939632 -9.162288) (xy 212.142832 -9.162288)
			)
		)
	)
	(zone
		(net "P12V_HDD3")
		(layer "F.Cu")
		(hatch none 0.5)
		(connect_pads
			(clearance 0.5)
		)
		(min_thickness 0.25)
		(fill yes
			(thermal_gap 0.5)
			(thermal_bridge_width 0.5)
			(island_removal_mode 0)
		)
		(polygon
			(pts
				(xy 113.214658 -291.229542) (xy 113.1062 -291.338) (xy 113.1062 -296.782744) (xy 112.6744 -297.214544)
				(xy 112.6744 -300.5582) (xy 116.299742 -304.183542) (xy 125.7554 -304.183542) (xy 126.0602 -303.878742)
				(xy 126.0602 -302.354742) (xy 125.857 -302.151542) (xy 121.3612 -302.151542) (xy 120.7262 -301.516542)
				(xy 117.163342 -301.516542) (xy 116.6241 -300.9773) (xy 116.6241 -299.1866) (xy 117.1448 -298.6659)
				(xy 117.1448 -293.7256) (xy 117.8687 -293.0017) (xy 117.8687 -291.369242) (xy 117.729 -291.229542)
			)
		)
		(polygon
			(pts
				(xy 119.424196 -303.218342) (xy 119.220996 -303.218342) (xy 119.220996 -303.421542) (xy 119.424196 -303.421542)
			)
		)
		(polygon
			(pts
				(xy 118.560596 -303.218342) (xy 118.357396 -303.218342) (xy 118.357396 -303.421542) (xy 118.560596 -303.421542)
			)
		)
	)
	(zone
		(net "MB1_CM_GATE_R")
		(layer "F.Cu")
		(hatch none 0.5)
		(connect_pads
			(clearance 0.5)
		)
		(min_thickness 0.25)
		(fill yes
			(thermal_gap 0.5)
			(thermal_bridge_width 0.5)
			(island_removal_mode 0)
		)
		(polygon
			(pts
				(xy 364.233206 -146.992594) (xy 363.982 -147.2438) (xy 363.982 -147.574) (xy 363.990128 -147.582128)
				(xy 363.990128 -149.413976) (xy 363.993684 -149.417532) (xy 363.993684 -150.091394) (xy 363.999272 -150.097236)
				(xy 363.999272 -150.679404) (xy 364.242096 -150.922228) (xy 366.696498 -150.922228) (xy 366.903 -150.715726)
				(xy 366.903 -147.113752) (xy 366.781842 -146.992594)
			)
		)
	)
	(zone
		(net "12V_PRE_8")
		(layer "F.Cu")
		(hatch none 0.5)
		(connect_pads
			(clearance 0.5)
		)
		(min_thickness 0.25)
		(fill yes
			(thermal_gap 0.5)
			(thermal_bridge_width 0.5)
			(island_removal_mode 0)
		)
		(polygon
			(pts
				(xy 394.368528 -298.314364) (xy 391.90295 -300.779942) (xy 389.36295 -300.779942) (xy 389.10895 -301.033942)
				(xy 389.10895 -301.414942) (xy 389.36295 -301.668942) (xy 395.70406 -301.668942) (xy 396.594076 -300.778926)
				(xy 396.594076 -298.538646) (xy 396.369794 -298.314364)
			)
		)
	)
	(zone
		(net "MB1_12V_CTRL_GATE1")
		(layer "F.Cu")
		(hatch none 0.5)
		(connect_pads
			(clearance 0.5)
		)
		(min_thickness 0.25)
		(fill yes
			(thermal_gap 0.5)
			(thermal_bridge_width 0.5)
			(island_removal_mode 0)
		)
		(polygon
			(pts
				(xy 353.2632 -135.6868) (xy 352.933 -136.017) (xy 352.933 -138.176) (xy 353.105974 -138.348974)
				(xy 357.052626 -138.348974) (xy 357.162608 -138.238992) (xy 357.162608 -135.9408) (xy 356.908608 -135.6868)
			)
		)
	)
	(zone
		(net "P12V_A")
		(layer "F.Cu")
		(hatch none 0.5)
		(connect_pads
			(clearance 0.5)
		)
		(min_thickness 0.25)
		(fill yes
			(thermal_gap 0.5)
			(thermal_bridge_width 0.5)
			(island_removal_mode 0)
		)
		(polygon
			(pts
				(xy 171.622974 -168.843198) (xy 171.32427 -169.141648) (xy 169.926 -170.539918) (xy 169.926 -173.079918)
				(xy 170.18 -173.333918) (xy 173.482 -173.333918) (xy 173.736 -173.079918) (xy 173.736 -171.048172)
				(xy 173.475396 -170.787568) (xy 172.781214 -170.787568) (xy 172.567346 -170.5737) (xy 172.567346 -168.885108)
				(xy 172.525436 -168.843198)
			)
		)
		(polygon
			(pts
				(xy 172.0596 -170.362118) (xy 171.8564 -170.362118) (xy 171.8564 -170.565318) (xy 172.0596 -170.565318)
			)
		)
		(polygon
			(pts
				(xy 172.0596 -169.752518) (xy 171.8564 -169.752518) (xy 171.8564 -169.955718) (xy 172.0596 -169.955718)
			)
		)
		(polygon
			(pts
				(xy 172.1104 -169.295318) (xy 171.9072 -169.295318) (xy 171.9072 -169.498518) (xy 172.1104 -169.498518)
			)
		)
	)
	(zone
		(net "MB3_12V_CTRL_GATE3")
		(layer "F.Cu")
		(hatch none 0.5)
		(connect_pads
			(clearance 0.5)
		)
		(min_thickness 0.25)
		(fill yes
			(thermal_gap 0.5)
			(thermal_bridge_width 0.5)
			(island_removal_mode 0)
		)
		(polygon
			(pts
				(xy 257.96748 -372.25732) (xy 257.824732 -372.400068) (xy 257.824732 -377.141232) (xy 258.01066 -377.32716)
				(xy 259.39242 -377.32716) (xy 259.615432 -377.104148) (xy 259.615432 -374.404382) (xy 259.60705 -374.396254)
				(xy 259.60705 -372.43639) (xy 259.42798 -372.25732)
			)
		)
	)
	(zone
		(net "12V_PRE_28")
		(layer "F.Cu")
		(hatch none 0.5)
		(connect_pads
			(clearance 0.5)
		)
		(min_thickness 0.25)
		(fill yes
			(thermal_gap 0.5)
			(thermal_bridge_width 0.5)
			(island_removal_mode 0)
		)
		(polygon
			(pts
				(xy 145.868898 -63.794894) (xy 145.741898 -63.921894) (xy 145.741898 -65.445894) (xy 147.138898 -66.842894)
				(xy 148.535898 -66.842894) (xy 153.488898 -71.795894) (xy 157.425898 -71.795894) (xy 157.552898 -71.668894)
				(xy 157.552898 -70.906894) (xy 157.425898 -70.779894) (xy 154.123898 -70.779894) (xy 147.138898 -63.794894)
			)
		)
	)
	(zone
		(layer "F.Cu")
		(hatch none 0.5)
		(connect_pads
			(clearance 0)
		)
		(min_thickness 0.25)
		(keepout
			(tracks allowed)
			(vias allowed)
			(pads allowed)
			(copperpour allowed)
			(footprints not_allowed)
		)
		(placement
			(enabled no)
			(sheetname "")
		)
		(fill
			(thermal_gap 0.5)
			(thermal_bridge_width 0.5)
			(island_removal_mode 0)
		)
		(polygon
			(pts
				(arc
					(start 244.100096 -143.500094)
					(mid 247.850152 -139.750038)
					(end 251.599954 -143.500094)
				)
				(arc
					(start 251.599954 -143.500094)
					(mid 247.850152 -147.249896)
					(end 244.100096 -143.500094)
				)
			)
		)
	)
	(zone
		(net "P5V_HDD6")
		(layer "F.Cu")
		(hatch none 0.5)
		(connect_pads
			(clearance 0.5)
		)
		(min_thickness 0.25)
		(fill yes
			(thermal_gap 0.5)
			(thermal_bridge_width 0.5)
			(island_removal_mode 0)
		)
		(polygon
			(pts
				(xy 331.597 -281.729942) (xy 331.343 -281.983942) (xy 331.343 -292.778942) (xy 329.692 -294.429942)
				(xy 326.263 -294.429942) (xy 326.009 -294.683942) (xy 326.009 -296.334942) (xy 326.263 -296.588942)
				(xy 330.835 -296.588942) (xy 331.47 -295.953942) (xy 333.248 -295.953942) (xy 333.756 -295.445942)
				(xy 333.756 -281.983942) (xy 333.502 -281.729942)
			)
		)
		(polygon
			(pts
				(xy 330.3524 -295.598342) (xy 330.1492 -295.598342) (xy 330.1492 -295.801542) (xy 330.3524 -295.801542)
			)
		)
		(polygon
			(pts
				(xy 329.4888 -295.598342) (xy 329.2856 -295.598342) (xy 329.2856 -295.801542) (xy 329.4888 -295.801542)
			)
		)
	)
	(zone
		(net "GND")
		(layer "F.Cu")
		(hatch none 0.5)
		(connect_pads
			(clearance 0.5)
		)
		(min_thickness 0.25)
		(fill yes
			(thermal_gap 0.5)
			(thermal_bridge_width 0.5)
			(island_removal_mode 0)
		)
		(polygon
			(pts
				(arc
					(start 177.743358 -203.190602)
					(mid 178.565054 -202.569907)
					(end 179.468272 -202.075288)
				)
				(xy 171.204128 -190.7032) (xy 170.7896 -190.7032)
				(arc
					(start 170.7896 -191.290956)
					(mid 170.803926 -192.282106)
					(end 170.582336 -193.24828)
				)
				(xy 170.582336 -196.02958)
			)
		)
	)
	(zone
		(layer "F.Cu")
		(hatch none 0.5)
		(connect_pads
			(clearance 0)
		)
		(min_thickness 0.25)
		(keepout
			(tracks allowed)
			(vias allowed)
			(pads allowed)
			(copperpour allowed)
			(footprints allowed)
		)
		(placement
			(enabled no)
			(sheetname "")
		)
		(fill
			(thermal_gap 0.5)
			(thermal_bridge_width 0.5)
			(island_removal_mode 0)
		)
		(polygon
			(pts
				(xy 342.9 -24.5872) (xy 342.9 -22.6822) (xy 343.6112 -22.6822) (xy 343.6112 -24.5872)
			)
		)
	)
	(zone
		(layer "F.Cu")
		(hatch none 0.5)
		(connect_pads
			(clearance 0)
		)
		(min_thickness 0.25)
		(keepout
			(tracks allowed)
			(vias allowed)
			(pads allowed)
			(copperpour allowed)
			(footprints not_allowed)
		)
		(placement
			(enabled no)
			(sheetname "")
		)
		(fill
			(thermal_gap 0.5)
			(thermal_bridge_width 0.5)
			(island_removal_mode 0)
		)
		(polygon
			(pts
				(arc
					(start 367.849912 -220.199966)
					(mid 371.599968 -216.44991)
					(end 375.350024 -220.199966)
				)
				(arc
					(start 375.350024 -220.199966)
					(mid 371.599968 -223.950022)
					(end 367.849912 -220.199966)
				)
			)
		)
	)
	(zone
		(layer "F.Cu")
		(hatch none 0.5)
		(connect_pads
			(clearance 0)
		)
		(min_thickness 0.25)
		(keepout
			(tracks allowed)
			(vias allowed)
			(pads allowed)
			(copperpour allowed)
			(footprints not_allowed)
		)
		(placement
			(enabled no)
			(sheetname "")
		)
		(fill
			(thermal_gap 0.5)
			(thermal_bridge_width 0.5)
			(island_removal_mode 0)
		)
		(polygon
			(pts
				(xy 15.32509 -20.200112) (xy 15.32509 0) (xy 37.325046 0) (xy 37.325046 -20.200112)
			)
		)
	)
	(zone
		(layer "F.Cu")
		(hatch none 0.5)
		(connect_pads
			(clearance 0)
		)
		(min_thickness 0.25)
		(keepout
			(tracks not_allowed)
			(vias allowed)
			(pads allowed)
			(copperpour not_allowed)
			(footprints allowed)
		)
		(placement
			(enabled no)
			(sheetname "")
		)
		(fill
			(thermal_gap 0.5)
			(thermal_bridge_width 0.5)
			(island_removal_mode 0)
		)
		(polygon
			(pts
				(arc
					(start 482.870002 -162.178746)
					(mid 482.489129 -161.797492)
					(end 482.108002 -162.178492)
				)
				(arc
					(start 482.108002 -163.321492)
					(mid 482.489002 -163.702492)
					(end 482.870002 -163.321492)
				)
				(xy 482.870002 -162.972242)
				(arc
					(start 482.658674 -162.972242)
					(mid 482.592579 -162.999619)
					(end 482.565202 -163.065714)
				)
				(arc
					(start 482.565202 -163.065968)
					(mid 482.489002 -163.588136)
					(end 482.412802 -163.065968)
				)
				(xy 482.412802 -163.034218)
				(arc
					(start 482.415088 -163.031678)
					(mid 482.484759 -162.891799)
					(end 482.624638 -162.822128)
				)
				(xy 482.627178 -162.819842) (xy 482.870002 -162.819842) (xy 482.870002 -162.680142) (xy 482.627178 -162.680142)
				(arc
					(start 482.624638 -162.677856)
					(mid 482.484759 -162.608185)
					(end 482.415088 -162.468306)
				)
				(xy 482.412802 -162.465766)
				(arc
					(start 482.412802 -162.434016)
					(mid 482.489002 -161.911848)
					(end 482.565202 -162.434016)
				)
				(arc
					(start 482.565202 -162.43427)
					(mid 482.592579 -162.500365)
					(end 482.658674 -162.527742)
				)
				(xy 482.870002 -162.527742)
			)
		)
	)
	(zone
		(net "5V_PRE_29")
		(layer "F.Cu")
		(hatch none 0.5)
		(connect_pads
			(clearance 0.5)
		)
		(min_thickness 0.25)
		(fill yes
			(thermal_gap 0.5)
			(thermal_bridge_width 0.5)
			(island_removal_mode 0)
		)
		(polygon
			(pts
				(xy 180.6956 -60.0964) (xy 180.594 -60.198) (xy 180.594 -61.508894) (xy 180.721 -61.635894) (xy 181.991 -61.635894)
				(xy 184.531 -64.175894) (xy 188.976 -64.175894) (xy 189.103 -64.048894) (xy 189.103 -63.286894)
				(xy 188.976 -63.159894) (xy 185.333894 -63.159894) (xy 182.2704 -60.0964)
			)
		)
	)
	(zone
		(net "P5V_HDD34")
		(layer "F.Cu")
		(hatch none 0.5)
		(connect_pads
			(clearance 0.5)
		)
		(min_thickness 0.25)
		(fill yes
			(thermal_gap 0.5)
			(thermal_bridge_width 0.5)
			(island_removal_mode 0)
		)
		(polygon
			(pts
				(xy 457.7969 -51.729894) (xy 457.5429 -51.983894) (xy 457.5429 -62.778894) (xy 455.8919 -64.429894)
				(xy 452.4629 -64.429894) (xy 452.2089 -64.683894) (xy 452.2089 -66.334894) (xy 452.4629 -66.588894)
				(xy 457.0349 -66.588894) (xy 457.6699 -65.953894) (xy 459.4479 -65.953894) (xy 459.9559 -65.445894)
				(xy 459.9559 -51.983894) (xy 459.7019 -51.729894)
			)
		)
		(polygon
			(pts
				(xy 456.5523 -65.598294) (xy 456.3491 -65.598294) (xy 456.3491 -65.801494) (xy 456.5523 -65.801494)
			)
		)
		(polygon
			(pts
				(xy 455.6887 -65.598294) (xy 455.4855 -65.598294) (xy 455.4855 -65.801494) (xy 455.6887 -65.801494)
			)
		)
	)
	(zone
		(net "P12V_B_COMP")
		(layer "F.Cu")
		(hatch none 0.5)
		(connect_pads
			(clearance 0.5)
		)
		(min_thickness 0.25)
		(fill yes
			(thermal_gap 0.5)
			(thermal_bridge_width 0.5)
			(island_removal_mode 0)
		)
		(polygon
			(pts
				(xy 274.9042 -179.5272) (xy 274.2946 -180.1368) (xy 274.2946 -190.5) (xy 275.2852 -191.4906) (xy 299.7454 -191.4906)
				(xy 300.324012 -190.911988) (xy 300.324012 -180.055012) (xy 299.8216 -179.5526) (xy 283.7688 -179.5526)
				(xy 283.7434 -179.5272)
			)
		)
	)
	(zone
		(layer "F.Cu")
		(hatch none 0.5)
		(connect_pads
			(clearance 0)
		)
		(min_thickness 0.25)
		(keepout
			(tracks allowed)
			(vias allowed)
			(pads allowed)
			(copperpour allowed)
			(footprints allowed)
		)
		(placement
			(enabled no)
			(sheetname "")
		)
		(fill
			(thermal_gap 0.5)
			(thermal_bridge_width 0.5)
			(island_removal_mode 0)
		)
		(polygon
			(pts
				(xy 300.181518 -183.33466) (xy 300.181518 -180.973476) (xy 301.432468 -180.973476) (xy 301.432468 -183.33466)
			)
		)
	)
	(zone
		(layer "F.Cu")
		(hatch none 0.5)
		(connect_pads
			(clearance 0)
		)
		(min_thickness 0.25)
		(keepout
			(tracks allowed)
			(vias allowed)
			(pads allowed)
			(copperpour allowed)
			(footprints allowed)
		)
		(placement
			(enabled no)
			(sheetname "")
		)
		(fill
			(thermal_gap 0.5)
			(thermal_bridge_width 0.5)
			(island_removal_mode 0)
		)
		(polygon
			(pts
				(xy 232.8672 -252.0696) (xy 232.8672 -249.3264) (xy 232.80751 -249.26671) (xy 232.80751 -249.100086)
				(xy 232.833164 -249.074432) (xy 235.492036 -249.074432) (xy 236.622336 -249.074432) (xy 236.744256 -249.196352)
				(xy 236.744256 -249.748548) (xy 235.607352 -250.885452) (xy 235.556298 -250.885452) (xy 235.556298 -252.542548)
				(xy 235.260896 -252.83795) (xy 233.141774 -252.83795) (xy 232.923334 -252.61951) (xy 232.923334 -252.108208)
				(xy 232.884726 -252.0696)
			)
		)
	)
	(zone
		(net "5V_PRE_28")
		(layer "F.Cu")
		(hatch none 0.5)
		(connect_pads
			(clearance 0.5)
		)
		(min_thickness 0.25)
		(fill yes
			(thermal_gap 0.5)
			(thermal_bridge_width 0.5)
			(island_removal_mode 0)
		)
		(polygon
			(pts
				(xy 149.145498 -60.071) (xy 149.043898 -60.1726) (xy 149.043898 -61.508894) (xy 149.170898 -61.635894)
				(xy 150.440898 -61.635894) (xy 152.980898 -64.175894) (xy 157.425898 -64.175894) (xy 157.552898 -64.048894)
				(xy 157.552898 -63.286894) (xy 157.425898 -63.159894) (xy 153.837894 -63.159894) (xy 150.749 -60.071)
			)
		)
	)
	(zone
		(layer "F.Cu")
		(hatch none 0.5)
		(connect_pads
			(clearance 0)
		)
		(min_thickness 0.25)
		(keepout
			(tracks allowed)
			(vias allowed)
			(pads allowed)
			(copperpour allowed)
			(footprints not_allowed)
		)
		(placement
			(enabled no)
			(sheetname "")
		)
		(fill
			(thermal_gap 0.5)
			(thermal_bridge_width 0.5)
			(island_removal_mode 0)
		)
		(polygon
			(pts
				(arc
					(start 487.19994 -204.199998)
					(mid 483.450138 -207.9498)
					(end 479.700082 -204.199998)
				)
				(arc
					(start 479.700082 -204.199998)
					(mid 483.450138 -200.449942)
					(end 487.19994 -204.199998)
				)
			)
		)
	)
	(zone
		(layer "F.Cu")
		(hatch none 0.5)
		(connect_pads
			(clearance 0)
		)
		(min_thickness 0.25)
		(keepout
			(tracks allowed)
			(vias allowed)
			(pads allowed)
			(copperpour allowed)
			(footprints allowed)
		)
		(placement
			(enabled no)
			(sheetname "")
		)
		(fill
			(thermal_gap 0.5)
			(thermal_bridge_width 0.5)
			(island_removal_mode 0)
		)
		(polygon
			(pts
				(xy 214.458296 -389.905748) (xy 212.003132 -389.905748) (xy 212.003132 -388.158228) (xy 214.458296 -388.158228)
			)
		)
	)
	(zone
		(net "GND")
		(layer "F.Cu")
		(hatch none 0.5)
		(connect_pads
			(clearance 0.5)
		)
		(min_thickness 0.25)
		(fill yes
			(thermal_gap 0.5)
			(thermal_bridge_width 0.5)
			(island_removal_mode 0)
		)
		(polygon
			(pts
				(arc
					(start 215.710516 -132.412994)
					(mid 209.638317 -127.208406)
					(end 217.311478 -129.46253)
				)
				(arc
					(start 219.744036 -124.979938)
					(mid 219.254974 -124.766397)
					(end 218.797886 -124.490988)
				)
				(arc
					(start 218.797886 -124.490988)
					(mid 216.139662 -125.293207)
					(end 213.581742 -124.213112)
				)
				(arc
					(start 213.581742 -124.213112)
					(mid 211.633078 -122.715022)
					(end 210.894676 -120.3706)
				)
				(arc
					(start 210.894676 -119.2022)
					(mid 211.283478 -117.461779)
					(end 212.37575 -116.052092)
				)
				(arc
					(start 212.37575 -116.052092)
					(mid 212.508149 -114.133986)
					(end 213.50224 -112.488218)
				)
				(xy 213.50224 -112.082072) (xy 211.340954 -109.920786) (xy 211.340954 -97.910142) (xy 214.05215 -95.198946)
				(arc
					(start 218.112086 -95.198946)
					(mid 218.115452 -95.104915)
					(end 218.120976 -95.010986)
				)
				(arc
					(start 218.120976 -90.684858)
					(mid 218.109046 -90.372692)
					(end 218.120976 -90.060526)
				)
				(xy 218.120976 -87.120476)
				(arc
					(start 219.71889 -87.120476)
					(mid 220.651143 -86.586818)
					(end 221.690184 -86.31428)
				)
				(arc
					(start 221.690184 -86.31428)
					(mid 219.866883 -83.476321)
					(end 220.79585 -80.23352)
				)
				(xy 214.712042 -70.6882) (xy 213.5124 -70.6882)
				(arc
					(start 213.034626 -71.165974)
					(mid 206.679293 -79.695364)
					(end 196.092572 -78.6638)
				)
				(xy 195.7324 -78.6638) (xy 195.529708 -78.866492)
				(arc
					(start 198.207122 -89.51341)
					(mid 204.560465 -91.837706)
					(end 200.062338 -96.890586)
				)
				(xy 210.877912 -139.9032) (xy 212.2678 -139.9032) (xy 213.131908 -139.039092) (xy 213.742524 -136.039098)
			)
		)
	)
	(zone
		(layer "F.Cu")
		(hatch none 0.5)
		(connect_pads
			(clearance 0)
		)
		(min_thickness 0.25)
		(keepout
			(tracks allowed)
			(vias allowed)
			(pads allowed)
			(copperpour allowed)
			(footprints not_allowed)
		)
		(placement
			(enabled no)
			(sheetname "")
		)
		(fill
			(thermal_gap 0.5)
			(thermal_bridge_width 0.5)
			(island_removal_mode 0)
		)
		(polygon
			(pts
				(arc
					(start 124.944886 -20.550124)
					(mid 126.150116 -19.344894)
					(end 127.355092 -20.550124)
				)
				(arc
					(start 127.355092 -20.550124)
					(mid 126.150116 -21.7551)
					(end 124.944886 -20.550124)
				)
			)
		)
	)
	(zone
		(layer "F.Cu")
		(hatch none 0.5)
		(connect_pads
			(clearance 0)
		)
		(min_thickness 0.25)
		(keepout
			(tracks not_allowed)
			(vias allowed)
			(pads allowed)
			(copperpour not_allowed)
			(footprints allowed)
		)
		(placement
			(enabled no)
			(sheetname "")
		)
		(fill
			(thermal_gap 0.5)
			(thermal_bridge_width 0.5)
			(island_removal_mode 0)
		)
		(polygon
			(pts
				(arc
					(start 271.970754 -353.723956)
					(mid 271.5895 -354.104829)
					(end 271.9705 -354.485956)
				)
				(arc
					(start 273.1135 -354.485956)
					(mid 273.4945 -354.104956)
					(end 273.1135 -353.723956)
				)
				(xy 272.76425 -353.723956)
				(arc
					(start 272.76425 -353.977956)
					(mid 272.779129 -354.013877)
					(end 272.81505 -354.028756)
				)
				(arc
					(start 272.857976 -354.028756)
					(mid 273.380144 -354.104956)
					(end 272.857976 -354.181156)
				)
				(xy 272.783554 -354.181156)
				(arc
					(start 272.780506 -354.178108)
					(mid 272.671429 -354.121577)
					(end 272.614898 -354.0125)
				)
				(xy 272.61185 -354.009452) (xy 272.61185 -353.723956) (xy 272.47215 -353.723956) (xy 272.47215 -354.009452)
				(arc
					(start 272.469102 -354.0125)
					(mid 272.412571 -354.121577)
					(end 272.303494 -354.178108)
				)
				(xy 272.300446 -354.181156)
				(arc
					(start 272.226024 -354.181156)
					(mid 271.703856 -354.104956)
					(end 272.226024 -354.028756)
				)
				(arc
					(start 272.26895 -354.028756)
					(mid 272.304871 -354.013877)
					(end 272.31975 -353.977956)
				)
				(xy 272.31975 -353.723956)
			)
		)
	)
	(zone
		(layer "F.Cu")
		(hatch none 0.5)
		(connect_pads
			(clearance 0)
		)
		(min_thickness 0.25)
		(keepout
			(tracks allowed)
			(vias allowed)
			(pads allowed)
			(copperpour allowed)
			(footprints not_allowed)
		)
		(placement
			(enabled no)
			(sheetname "")
		)
		(fill
			(thermal_gap 0.5)
			(thermal_bridge_width 0.5)
			(island_removal_mode 0)
		)
		(polygon
			(pts
				(xy 395.99997 -9.99998)
				(arc
					(start 395.99997 -0.999998)
					(mid 396.292863 -0.292893)
					(end 396.999968 0)
				)
				(xy 452.67499 0) (xy 452.67499 -9.99998)
			)
		)
	)
	(zone
		(layer "F.Cu")
		(hatch none 0.5)
		(connect_pads
			(clearance 0)
		)
		(min_thickness 0.25)
		(keepout
			(tracks allowed)
			(vias allowed)
			(pads allowed)
			(copperpour allowed)
			(footprints not_allowed)
		)
		(placement
			(enabled no)
			(sheetname "")
		)
		(fill
			(thermal_gap 0.5)
			(thermal_bridge_width 0.5)
			(island_removal_mode 0)
		)
		(polygon
			(pts
				(arc
					(start 209.300064 -189.799976)
					(mid 202.300078 -196.799962)
					(end 195.300092 -189.799976)
				)
				(arc
					(start 195.300092 -183.799988)
					(mid 202.300078 -176.800002)
					(end 209.300064 -183.799988)
				)
			)
		)
	)
	(zone
		(layer "F.Cu")
		(hatch none 0.5)
		(connect_pads
			(clearance 0)
		)
		(min_thickness 0.25)
		(keepout
			(tracks allowed)
			(vias allowed)
			(pads allowed)
			(copperpour allowed)
			(footprints allowed)
		)
		(placement
			(enabled no)
			(sheetname "")
		)
		(fill
			(thermal_gap 0.5)
			(thermal_bridge_width 0.5)
			(island_removal_mode 0)
		)
		(polygon
			(pts
				(xy 227.8126 -259.5372) (xy 227.8126 -257.048) (xy 228.5746 -257.048) (xy 228.5746 -259.5372)
			)
		)
	)
	(zone
		(layer "F.Cu")
		(hatch none 0.5)
		(connect_pads
			(clearance 0)
		)
		(min_thickness 0.25)
		(keepout
			(tracks allowed)
			(vias allowed)
			(pads allowed)
			(copperpour allowed)
			(footprints not_allowed)
		)
		(placement
			(enabled no)
			(sheetname "")
		)
		(fill
			(thermal_gap 0.5)
			(thermal_bridge_width 0.5)
			(island_removal_mode 0)
		)
		(polygon
			(pts
				(arc
					(start 171.600114 -282.999942)
					(mid 170.200066 -284.39999)
					(end 168.800018 -282.999942)
				)
				(arc
					(start 168.800018 -282.999942)
					(mid 170.200066 -281.599894)
					(end 171.600114 -282.999942)
				)
			)
		)
	)
	(zone
		(layer "F.Cu")
		(hatch none 0.5)
		(connect_pads
			(clearance 0)
		)
		(min_thickness 0.25)
		(keepout
			(tracks not_allowed)
			(vias allowed)
			(pads allowed)
			(copperpour not_allowed)
			(footprints allowed)
		)
		(placement
			(enabled no)
			(sheetname "")
		)
		(fill
			(thermal_gap 0.5)
			(thermal_bridge_width 0.5)
			(island_removal_mode 0)
		)
		(polygon
			(pts
				(arc
					(start 32.889952 -162.178746)
					(mid 32.509079 -161.797492)
					(end 32.127952 -162.178492)
				)
				(xy 32.127952 -162.527742)
				(arc
					(start 32.381952 -162.527742)
					(mid 32.417873 -162.512863)
					(end 32.432752 -162.476942)
				)
				(arc
					(start 32.432752 -162.434016)
					(mid 32.508952 -161.911848)
					(end 32.585152 -162.434016)
				)
				(xy 32.585152 -162.508438)
				(arc
					(start 32.582104 -162.511486)
					(mid 32.525573 -162.620563)
					(end 32.416496 -162.677094)
				)
				(xy 32.413448 -162.680142) (xy 32.127952 -162.680142) (xy 32.127952 -162.819842) (xy 32.413448 -162.819842)
				(arc
					(start 32.416496 -162.82289)
					(mid 32.525573 -162.879421)
					(end 32.582104 -162.988498)
				)
				(xy 32.585152 -162.991546)
				(arc
					(start 32.585152 -163.065968)
					(mid 32.508952 -163.588136)
					(end 32.432752 -163.065968)
				)
				(arc
					(start 32.432752 -163.023042)
					(mid 32.417873 -162.987121)
					(end 32.381952 -162.972242)
				)
				(xy 32.127952 -162.972242)
				(arc
					(start 32.127952 -163.321492)
					(mid 32.508952 -163.702492)
					(end 32.889952 -163.321492)
				)
			)
		)
	)
	(zone
		(layers "F.Cu" "B.Cu")
		(hatch none 0.5)
		(connect_pads
			(clearance 0)
		)
		(min_thickness 0.25)
		(keepout
			(tracks allowed)
			(vias allowed)
			(pads allowed)
			(copperpour allowed)
			(footprints not_allowed)
		)
		(placement
			(enabled no)
			(sheetname "")
		)
		(fill yes
			(thermal_gap 0.5)
			(thermal_bridge_width 0.5)
			(island_removal_mode 0)
		)
		(polygon
			(pts
				(arc
					(start 103.324914 -207.79994)
					(mid 96.324928 -200.799954)
					(end 89.324942 -207.79994)
				)
				(arc
					(start 89.324942 -213.799928)
					(mid 96.324928 -220.799914)
					(end 103.324914 -213.799928)
				)
			)
		)
	)
	(zone
		(layers "F.Cu" "B.Cu")
		(hatch none 0.5)
		(connect_pads
			(clearance 0)
		)
		(min_thickness 0.25)
		(keepout
			(tracks allowed)
			(vias allowed)
			(pads allowed)
			(copperpour allowed)
			(footprints not_allowed)
		)
		(placement
			(enabled no)
			(sheetname "")
		)
		(fill yes
			(thermal_gap 0.5)
			(thermal_bridge_width 0.5)
			(island_removal_mode 0)
		)
		(polygon
			(pts
				(arc
					(start 166.325042 -207.79994)
					(mid 159.325056 -200.799954)
					(end 152.32507 -207.79994)
				)
				(arc
					(start 152.32507 -213.799928)
					(mid 159.325056 -220.799914)
					(end 166.325042 -213.799928)
				)
			)
		)
	)
	(zone
		(net "GND")
		(layers "F.Cu" "B.Cu")
		(hatch none 0.5)
		(connect_pads
			(clearance 0.5)
		)
		(min_thickness 0.25)
		(fill yes
			(thermal_gap 0.5)
			(thermal_bridge_width 0.5)
			(island_removal_mode 0)
		)
		(polygon
			(pts
				(xy 174.848774 -156.706824) (xy 174.7901 -156.765498) (xy 174.7901 -158.995618) (xy 175.387254 -159.592772)
				(xy 179.206652 -159.592772) (xy 179.501546 -159.297878) (xy 179.501546 -157.022546) (xy 179.185824 -156.706824)
			)
		)
	)
	(zone
		(layers "F.Cu" "B.Cu")
		(hatch none 0.5)
		(connect_pads
			(clearance 0)
		)
		(min_thickness 0.25)
		(keepout
			(tracks allowed)
			(vias allowed)
			(pads allowed)
			(copperpour allowed)
			(footprints allowed)
		)
		(placement
			(enabled no)
			(sheetname "")
		)
		(fill yes
			(thermal_gap 0.5)
			(thermal_bridge_width 0.5)
			(island_removal_mode 0)
		)
		(polygon
			(pts
				(xy 174.67326 -157.801056) (xy 174.67326 -155.650184) (xy 179.642008 -155.650184) (xy 179.642008 -157.801056)
			)
		)
	)
	(zone
		(layers "F.Cu" "B.Cu")
		(hatch none 0.5)
		(connect_pads
			(clearance 0)
		)
		(min_thickness 0.25)
		(keepout
			(tracks allowed)
			(vias allowed)
			(pads allowed)
			(copperpour allowed)
			(footprints not_allowed)
		)
		(placement
			(enabled no)
			(sheetname "")
		)
		(fill yes
			(thermal_gap 0.5)
			(thermal_bridge_width 0.5)
			(island_removal_mode 0)
		)
		(polygon
			(pts
				(arc
					(start 386.675122 -322.799964)
					(mid 393.675108 -315.799978)
					(end 400.675094 -322.799964)
				)
				(arc
					(start 400.675094 -328.799952)
					(mid 393.675108 -335.799938)
					(end 386.675122 -328.799952)
				)
			)
		)
	)
	(zone
		(layers "F.Cu" "B.Cu")
		(hatch none 0.5)
		(connect_pads
			(clearance 0)
		)
		(min_thickness 0.25)
		(keepout
			(tracks allowed)
			(vias allowed)
			(pads allowed)
			(copperpour allowed)
			(footprints not_allowed)
		)
		(placement
			(enabled no)
			(sheetname "")
		)
		(fill yes
			(thermal_gap 0.5)
			(thermal_bridge_width 0.5)
			(island_removal_mode 0)
		)
		(polygon
			(pts
				(arc
					(start 209.300064 -183.799988)
					(mid 202.300078 -176.800002)
					(end 195.300092 -183.799988)
				)
				(arc
					(start 195.300092 -189.799976)
					(mid 202.300078 -196.799962)
					(end 209.300064 -189.799976)
				)
			)
		)
	)
	(zone
		(layers "F.Cu" "B.Cu")
		(hatch none 0.5)
		(connect_pads
			(clearance 0)
		)
		(min_thickness 0.25)
		(keepout
			(tracks allowed)
			(vias allowed)
			(pads allowed)
			(copperpour allowed)
			(footprints not_allowed)
		)
		(placement
			(enabled no)
			(sheetname "")
		)
		(fill yes
			(thermal_gap 0.5)
			(thermal_bridge_width 0.5)
			(island_removal_mode 0)
		)
		(polygon
			(pts
				(arc
					(start 166.325042 -92.799916)
					(mid 159.325056 -85.79993)
					(end 152.32507 -92.799916)
				)
				(arc
					(start 152.32507 -98.799904)
					(mid 159.325056 -105.79989)
					(end 166.325042 -98.799904)
				)
			)
		)
	)
	(zone
		(layers "F.Cu" "B.Cu")
		(hatch none 0.5)
		(connect_pads
			(clearance 0)
		)
		(min_thickness 0.25)
		(keepout
			(tracks allowed)
			(vias allowed)
			(pads allowed)
			(copperpour allowed)
			(footprints not_allowed)
		)
		(placement
			(enabled no)
			(sheetname "")
		)
		(fill yes
			(thermal_gap 0.5)
			(thermal_bridge_width 0.5)
			(island_removal_mode 0)
		)
		(polygon
			(pts
				(arc
					(start 209.300064 -63.799974)
					(mid 202.300078 -56.799988)
					(end 195.300092 -63.799974)
				)
				(arc
					(start 195.300092 -69.799962)
					(mid 202.300078 -76.799948)
					(end 209.300064 -69.799962)
				)
			)
		)
	)
	(zone
		(layers "F.Cu" "B.Cu")
		(hatch none 0.5)
		(connect_pads
			(clearance 0)
		)
		(min_thickness 0.25)
		(keepout
			(tracks allowed)
			(vias allowed)
			(pads allowed)
			(copperpour allowed)
			(footprints not_allowed)
		)
		(placement
			(enabled no)
			(sheetname "")
		)
		(fill yes
			(thermal_gap 0.5)
			(thermal_bridge_width 0.5)
			(island_removal_mode 0)
		)
		(polygon
			(pts
				(arc
					(start 307.200046 -243.19992)
					(mid 300.20006 -236.199934)
					(end 293.200074 -243.19992)
				)
				(arc
					(start 293.200074 -249.199908)
					(mid 300.20006 -256.199894)
					(end 307.200046 -249.199908)
				)
			)
		)
	)
	(zone
		(layers "F.Cu" "B.Cu")
		(hatch none 0.5)
		(connect_pads
			(clearance 0)
		)
		(min_thickness 0.25)
		(keepout
			(tracks allowed)
			(vias allowed)
			(pads allowed)
			(copperpour allowed)
			(footprints not_allowed)
		)
		(placement
			(enabled no)
			(sheetname "")
		)
		(fill yes
			(thermal_gap 0.5)
			(thermal_bridge_width 0.5)
			(island_removal_mode 0)
		)
		(polygon
			(pts
				(arc
					(start 40.32504 -207.79994)
					(mid 33.325054 -200.799954)
					(end 26.325068 -207.79994)
				)
				(arc
					(start 26.325068 -213.799928)
					(mid 33.325054 -220.799914)
					(end 40.32504 -213.799928)
				)
			)
		)
	)
	(zone
		(layers "F.Cu" "B.Cu")
		(hatch none 0.5)
		(connect_pads
			(clearance 0)
		)
		(min_thickness 0.25)
		(keepout
			(tracks allowed)
			(vias allowed)
			(pads allowed)
			(copperpour allowed)
			(footprints not_allowed)
		)
		(placement
			(enabled no)
			(sheetname "")
		)
		(fill yes
			(thermal_gap 0.5)
			(thermal_bridge_width 0.5)
			(island_removal_mode 0)
		)
		(polygon
			(pts
				(arc
					(start 103.324914 -92.799916)
					(mid 96.324928 -85.79993)
					(end 89.324942 -92.799916)
				)
				(arc
					(start 89.324942 -98.799904)
					(mid 96.324928 -105.79989)
					(end 103.324914 -98.799904)
				)
			)
		)
	)
	(zone
		(layers "F.Cu" "B.Cu")
		(hatch none 0.5)
		(connect_pads
			(clearance 0)
		)
		(min_thickness 0.25)
		(keepout
			(tracks allowed)
			(vias allowed)
			(pads allowed)
			(copperpour allowed)
			(footprints not_allowed)
		)
		(placement
			(enabled no)
			(sheetname "")
		)
		(fill yes
			(thermal_gap 0.5)
			(thermal_bridge_width 0.5)
			(island_removal_mode 0)
		)
		(polygon
			(pts
				(arc
					(start 251.199904 -273.200114)
					(mid 244.199918 -266.200128)
					(end 237.199932 -273.200114)
				)
				(arc
					(start 237.199932 -279.200102)
					(mid 244.199918 -286.200088)
					(end 251.199904 -279.200102)
				)
			)
		)
	)
	(zone
		(layers "F.Cu" "B.Cu")
		(hatch none 0.5)
		(connect_pads
			(clearance 0)
		)
		(min_thickness 0.25)
		(keepout
			(tracks allowed)
			(vias allowed)
			(pads allowed)
			(copperpour allowed)
			(footprints not_allowed)
		)
		(placement
			(enabled no)
			(sheetname "")
		)
		(fill yes
			(thermal_gap 0.5)
			(thermal_bridge_width 0.5)
			(island_removal_mode 0)
		)
		(polygon
			(pts
				(arc
					(start 40.32504 -92.799916)
					(mid 33.325054 -85.79993)
					(end 26.325068 -92.799916)
				)
				(arc
					(start 26.325068 -98.799904)
					(mid 33.325054 -105.79989)
					(end 40.32504 -98.799904)
				)
			)
		)
	)
	(zone
		(layers "F.Cu" "B.Cu")
		(hatch none 0.5)
		(connect_pads
			(clearance 0)
		)
		(min_thickness 0.25)
		(keepout
			(tracks allowed)
			(vias allowed)
			(pads allowed)
			(copperpour allowed)
			(footprints not_allowed)
		)
		(placement
			(enabled no)
			(sheetname "")
		)
		(fill yes
			(thermal_gap 0.5)
			(thermal_bridge_width 0.5)
			(island_removal_mode 0)
		)
		(polygon
			(pts
				(arc
					(start 449.674996 -322.799964)
					(mid 456.674982 -315.799978)
					(end 463.674968 -322.799964)
				)
				(arc
					(start 463.674968 -328.799952)
					(mid 456.674982 -335.799938)
					(end 449.674996 -328.799952)
				)
			)
		)
	)
	(zone
		(net "GND")
		(layers "F.Cu" "B.Cu")
		(hatch none 0.5)
		(connect_pads
			(clearance 0.5)
		)
		(min_thickness 0.25)
		(fill yes
			(thermal_gap 0.5)
			(thermal_bridge_width 0.5)
			(island_removal_mode 0)
		)
		(polygon
			(pts
				(xy 344.17 -148.844) (xy 344.0176 -148.9964) (xy 344.0176 -153.0604) (xy 344.2716 -153.3144) (xy 346.4052 -153.3144)
				(xy 346.6338 -153.0858) (xy 346.6338 -149.0218) (xy 346.456 -148.844)
			)
		)
	)
	(zone
		(layers "F.Cu" "B.Cu" "In1.Cu" "In2.Cu" "In3.Cu" "In4.Cu" "In5.Cu" "In6.Cu"
			"In7.Cu" "In8.Cu" "In9.Cu" "In10.Cu"
		)
		(hatch none 0.5)
		(connect_pads
			(clearance 0)
		)
		(min_thickness 0.25)
		(keepout
			(tracks not_allowed)
			(vias allowed)
			(pads allowed)
			(copperpour not_allowed)
			(footprints allowed)
		)
		(placement
			(enabled no)
			(sheetname "")
		)
		(fill yes
			(thermal_gap 0.5)
			(thermal_bridge_width 0.5)
			(island_removal_mode 0)
		)
		(polygon
			(pts
				(arc
					(start 251.599954 6.500114)
					(mid 247.850152 2.750312)
					(end 244.100096 6.500114)
				)
				(arc
					(start 244.100096 6.500114)
					(mid 247.850152 10.25017)
					(end 251.599954 6.500114)
				)
			)
		)
	)
	(zone
		(layers "F.Cu" "B.Cu" "In1.Cu" "In2.Cu" "In3.Cu" "In4.Cu" "In5.Cu" "In6.Cu"
			"In7.Cu" "In8.Cu" "In9.Cu" "In10.Cu"
		)
		(hatch none 0.5)
		(connect_pads
			(clearance 0)
		)
		(min_thickness 0.25)
		(keepout
			(tracks not_allowed)
			(vias allowed)
			(pads allowed)
			(copperpour not_allowed)
			(footprints allowed)
		)
		(placement
			(enabled no)
			(sheetname "")
		)
		(fill yes
			(thermal_gap 0.5)
			(thermal_bridge_width 0.5)
			(island_removal_mode 0)
		)
		(polygon
			(pts
				(arc
					(start 323.674994 -207.79994)
					(mid 330.67498 -200.799954)
					(end 337.674966 -207.79994)
				)
				(arc
					(start 337.674966 -213.799928)
					(mid 330.67498 -220.799914)
					(end 323.674994 -213.799928)
				)
			)
		)
	)
	(zone
		(layers "F.Cu" "B.Cu" "In1.Cu" "In2.Cu" "In3.Cu" "In4.Cu" "In5.Cu" "In6.Cu"
			"In7.Cu" "In8.Cu" "In9.Cu" "In10.Cu"
		)
		(hatch none 0.5)
		(connect_pads
			(clearance 0)
		)
		(min_thickness 0.25)
		(keepout
			(tracks not_allowed)
			(vias allowed)
			(pads allowed)
			(copperpour not_allowed)
			(footprints allowed)
		)
		(placement
			(enabled no)
			(sheetname "")
		)
		(fill yes
			(thermal_gap 0.5)
			(thermal_bridge_width 0.5)
			(island_removal_mode 0)
		)
		(polygon
			(pts
				(arc
					(start 26.325068 -322.799964)
					(mid 33.325054 -315.799978)
					(end 40.32504 -322.799964)
				)
				(arc
					(start 40.32504 -328.799952)
					(mid 33.325054 -335.799938)
					(end 26.325068 -328.799952)
				)
			)
		)
	)
	(zone
		(layers "F.Cu" "B.Cu" "In1.Cu" "In2.Cu" "In3.Cu" "In4.Cu" "In5.Cu" "In6.Cu"
			"In7.Cu" "In8.Cu" "In9.Cu" "In10.Cu"
		)
		(hatch none 0.5)
		(connect_pads
			(clearance 0)
		)
		(min_thickness 0.25)
		(keepout
			(tracks not_allowed)
			(vias allowed)
			(pads allowed)
			(copperpour not_allowed)
			(footprints allowed)
		)
		(placement
			(enabled no)
			(sheetname "")
		)
		(fill yes
			(thermal_gap 0.5)
			(thermal_bridge_width 0.5)
			(island_removal_mode 0)
		)
		(polygon
			(pts
				(arc
					(start 293.200074 -393.199874)
					(mid 300.20006 -386.199888)
					(end 307.200046 -393.199874)
				)
				(arc
					(start 307.200046 -399.200116)
					(mid 300.20006 -406.200102)
					(end 293.200074 -399.200116)
				)
			)
		)
	)
	(zone
		(layers "F.Cu" "B.Cu" "In1.Cu" "In2.Cu" "In3.Cu" "In4.Cu" "In5.Cu" "In6.Cu"
			"In7.Cu" "In8.Cu" "In9.Cu" "In10.Cu"
		)
		(hatch none 0.5)
		(connect_pads
			(clearance 0)
		)
		(min_thickness 0.25)
		(keepout
			(tracks not_allowed)
			(vias allowed)
			(pads allowed)
			(copperpour not_allowed)
			(footprints allowed)
		)
		(placement
			(enabled no)
			(sheetname "")
		)
		(fill yes
			(thermal_gap 0.5)
			(thermal_bridge_width 0.5)
			(island_removal_mode 0)
		)
		(polygon
			(pts
				(arc
					(start 195.300092 -63.799974)
					(mid 202.300078 -56.799988)
					(end 209.300064 -63.799974)
				)
				(arc
					(start 209.300064 -69.799962)
					(mid 202.300078 -76.799948)
					(end 195.300092 -69.799962)
				)
			)
		)
	)
	(zone
		(layers "F.Cu" "B.Cu" "In1.Cu" "In2.Cu" "In3.Cu" "In4.Cu" "In5.Cu" "In6.Cu"
			"In7.Cu" "In8.Cu" "In9.Cu" "In10.Cu"
		)
		(name "Route Keepin")
		(hatch none 0.5)
		(connect_pads
			(clearance 0)
		)
		(min_thickness 0.25)
		(keepout
			(tracks allowed)
			(vias allowed)
			(pads allowed)
			(copperpour allowed)
			(footprints allowed)
		)
		(placement
			(enabled no)
			(sheetname "")
		)
		(fill
			(thermal_gap 0.5)
			(thermal_bridge_width 0.5)
			(island_removal_mode 0)
		)
		(polygon
			(pts
				(arc
					(start 308.99989 -420.438072)
					(mid 309.16818 -420.368364)
					(end 309.237888 -420.200074)
				)
				(arc
					(start 309.237888 -375.000012)
					(mid 309.16818 -374.831722)
					(end 308.99989 -374.762014)
				)
				(arc
					(start 296.69994 -374.762014)
					(mid 295.454019 -374.245937)
					(end 294.937942 -373.000016)
				)
				(arc
					(start 294.937942 -350.19996)
					(mid 295.454019 -348.954039)
					(end 296.69994 -348.437962)
				)
				(arc
					(start 490.450124 -348.437962)
					(mid 490.618414 -348.368254)
					(end 490.688122 -348.199964)
				)
				(arc
					(start 490.688122 -0.999998)
					(mid 490.618414 -0.831708)
					(end 490.450124 -0.762)
				)
				(arc
					(start 396.999968 -0.762)
					(mid 396.831678 -0.831708)
					(end 396.76197 -0.999998)
				)
				(arc
					(start 396.76197 -13.999972)
					(mid 396.245893 -15.245893)
					(end 394.999972 -15.76197)
				)
				(arc
					(start 349.000064 -15.76197)
					(mid 347.754143 -15.245893)
					(end 347.238066 -13.999972)
				)
				(arc
					(start 347.238066 -0.999998)
					(mid 347.168358 -0.831708)
					(end 347.000068 -0.762)
				)
				(arc
					(start 300.999906 -0.762)
					(mid 299.753985 -0.245923)
					(end 299.237908 0.999998)
				)
				(arc
					(start 299.237908 37.800026)
					(mid 299.1682 37.968316)
					(end 298.99991 38.038024)
				)
				(arc
					(start 221.000066 38.038024)
					(mid 220.831776 37.968316)
					(end 220.762068 37.800026)
				)
				(arc
					(start 220.762068 2.999994)
					(mid 220.245991 1.754073)
					(end 219.00007 1.237996)
				)
				(arc
					(start 201.000106 1.237996)
					(mid 200.831816 1.168288)
					(end 200.762108 0.999998)
				)
				(arc
					(start 200.762108 0.999998)
					(mid 200.246031 -0.245923)
					(end 199.00011 -0.762)
				)
				(arc
					(start 150.999952 -0.762)
					(mid 150.831662 -0.831708)
					(end 150.761954 -0.999998)
				)
				(arc
					(start 150.761954 -13.999972)
					(mid 150.245877 -15.245893)
					(end 148.999956 -15.76197)
				)
				(arc
					(start 103.000048 -15.76197)
					(mid 101.754127 -15.245893)
					(end 101.23805 -13.999972)
				)
				(arc
					(start 101.23805 -0.999998)
					(mid 101.168342 -0.831708)
					(end 101.000052 -0.762)
				)
				(arc
					(start 0.999998 -0.762)
					(mid 0.831708 -0.831708)
					(end 0.762 -0.999998)
				)
				(arc
					(start 0.762 -348.199964)
					(mid 0.831708 -348.368254)
					(end 0.999998 -348.437962)
				)
				(arc
					(start 189.6999 -348.437962)
					(mid 190.945821 -348.954039)
					(end 191.461898 -350.19996)
				)
				(arc
					(start 191.461898 -372.000018)
					(mid 191.531606 -372.168308)
					(end 191.699896 -372.238016)
				)
				(arc
					(start 199.00011 -372.238016)
					(mid 200.246031 -372.754093)
					(end 200.762108 -374.000014)
				)
				(arc
					(start 200.762108 -420.200074)
					(mid 200.831816 -420.368364)
					(end 201.000106 -420.438072)
				)
			)
		)
	)
	(zone
		(layers "F.Cu" "B.Cu" "In1.Cu" "In2.Cu" "In3.Cu" "In4.Cu" "In5.Cu" "In6.Cu"
			"In7.Cu" "In8.Cu" "In9.Cu" "In10.Cu"
		)
		(hatch none 0.5)
		(connect_pads
			(clearance 0)
		)
		(min_thickness 0.25)
		(keepout
			(tracks not_allowed)
			(vias allowed)
			(pads allowed)
			(copperpour not_allowed)
			(footprints allowed)
		)
		(placement
			(enabled no)
			(sheetname "")
		)
		(fill yes
			(thermal_gap 0.5)
			(thermal_bridge_width 0.5)
			(island_removal_mode 0)
		)
		(polygon
			(pts
				(arc
					(start 386.675122 -92.799916)
					(mid 393.675108 -85.79993)
					(end 400.675094 -92.799916)
				)
				(arc
					(start 400.675094 -98.799904)
					(mid 393.675108 -105.79989)
					(end 386.675122 -98.799904)
				)
			)
		)
	)
	(zone
		(layers "F.Cu" "B.Cu" "In1.Cu" "In2.Cu" "In3.Cu" "In4.Cu" "In5.Cu" "In6.Cu"
			"In7.Cu" "In8.Cu" "In9.Cu" "In10.Cu"
		)
		(hatch none 0.5)
		(connect_pads
			(clearance 0)
		)
		(min_thickness 0.25)
		(keepout
			(tracks not_allowed)
			(vias allowed)
			(pads allowed)
			(copperpour not_allowed)
			(footprints allowed)
		)
		(placement
			(enabled no)
			(sheetname "")
		)
		(fill yes
			(thermal_gap 0.5)
			(thermal_bridge_width 0.5)
			(island_removal_mode 0)
		)
		(polygon
			(pts
				(arc
					(start 251.599954 -143.500094)
					(mid 247.850152 -147.249896)
					(end 244.100096 -143.500094)
				)
				(arc
					(start 244.100096 -143.500094)
					(mid 247.850152 -139.750038)
					(end 251.599954 -143.500094)
				)
			)
		)
	)
	(zone
		(layers "F.Cu" "B.Cu" "In1.Cu" "In2.Cu" "In3.Cu" "In4.Cu" "In5.Cu" "In6.Cu"
			"In7.Cu" "In8.Cu" "In9.Cu" "In10.Cu"
		)
		(hatch none 0.5)
		(connect_pads
			(clearance 0)
		)
		(min_thickness 0.25)
		(keepout
			(tracks not_allowed)
			(vias allowed)
			(pads allowed)
			(copperpour not_allowed)
			(footprints allowed)
		)
		(placement
			(enabled no)
			(sheetname "")
		)
		(fill
			(thermal_gap 0.5)
			(thermal_bridge_width 0.5)
			(island_removal_mode 0)
		)
		(polygon
			(pts
				(arc
					(start 48.749966 -269.999968)
					(mid 39.249858 -269.999968)
					(end 48.749966 -269.999968)
				)
			)
		)
	)
	(zone
		(layers "F.Cu" "B.Cu" "In1.Cu" "In2.Cu" "In3.Cu" "In4.Cu" "In5.Cu" "In6.Cu"
			"In7.Cu" "In8.Cu" "In9.Cu" "In10.Cu"
		)
		(hatch none 0.5)
		(connect_pads
			(clearance 0)
		)
		(min_thickness 0.25)
		(keepout
			(tracks not_allowed)
			(vias allowed)
			(pads allowed)
			(copperpour not_allowed)
			(footprints allowed)
		)
		(placement
			(enabled no)
			(sheetname "")
		)
		(fill
			(thermal_gap 0.5)
			(thermal_bridge_width 0.5)
			(island_removal_mode 0)
		)
		(polygon
			(pts
				(arc
					(start 7.599934 -120.499886)
					(mid 0.099822 -120.499886)
					(end 7.599934 -120.499886)
				)
			)
		)
	)
	(zone
		(layers "F.Cu" "B.Cu" "In1.Cu" "In2.Cu" "In3.Cu" "In4.Cu" "In5.Cu" "In6.Cu"
			"In7.Cu" "In8.Cu" "In9.Cu" "In10.Cu"
		)
		(hatch none 0.5)
		(connect_pads
			(clearance 0)
		)
		(min_thickness 0.25)
		(keepout
			(tracks not_allowed)
			(vias allowed)
			(pads allowed)
			(copperpour not_allowed)
			(footprints allowed)
		)
		(placement
			(enabled no)
			(sheetname "")
		)
		(fill yes
			(thermal_gap 0.5)
			(thermal_bridge_width 0.5)
			(island_removal_mode 0)
		)
		(polygon
			(pts
				(arc
					(start 323.674994 -92.799916)
					(mid 330.67498 -85.79993)
					(end 337.674966 -92.799916)
				)
				(arc
					(start 337.674966 -98.799904)
					(mid 330.67498 -105.79989)
					(end 323.674994 -98.799904)
				)
			)
		)
	)
	(zone
		(layers "F.Cu" "B.Cu" "In1.Cu" "In2.Cu" "In3.Cu" "In4.Cu" "In5.Cu" "In6.Cu"
			"In7.Cu" "In8.Cu" "In9.Cu" "In10.Cu"
		)
		(hatch none 0.5)
		(connect_pads
			(clearance 0)
		)
		(min_thickness 0.25)
		(keepout
			(tracks not_allowed)
			(vias allowed)
			(pads allowed)
			(copperpour not_allowed)
			(footprints allowed)
		)
		(placement
			(enabled no)
			(sheetname "")
		)
		(fill yes
			(thermal_gap 0.5)
			(thermal_bridge_width 0.5)
			(island_removal_mode 0)
		)
		(polygon
			(pts
				(arc
					(start 386.675122 -207.79994)
					(mid 393.675108 -200.799954)
					(end 400.675094 -207.79994)
				)
				(arc
					(start 400.675094 -213.799928)
					(mid 393.675108 -220.799914)
					(end 386.675122 -213.799928)
				)
			)
		)
	)
	(zone
		(layers "F.Cu" "B.Cu" "In1.Cu" "In2.Cu" "In3.Cu" "In4.Cu" "In5.Cu" "In6.Cu"
			"In7.Cu" "In8.Cu" "In9.Cu" "In10.Cu"
		)
		(hatch none 0.5)
		(connect_pads
			(clearance 0)
		)
		(min_thickness 0.25)
		(keepout
			(tracks not_allowed)
			(vias allowed)
			(pads allowed)
			(copperpour not_allowed)
			(footprints allowed)
		)
		(placement
			(enabled no)
			(sheetname "")
		)
		(fill yes
			(thermal_gap 0.5)
			(thermal_bridge_width 0.5)
			(island_removal_mode 0)
		)
		(polygon
			(pts
				(arc
					(start 479.700082 -204.199998)
					(mid 483.450138 -200.449942)
					(end 487.19994 -204.199998)
				)
				(arc
					(start 487.19994 -204.199998)
					(mid 483.450138 -207.9498)
					(end 479.700082 -204.199998)
				)
			)
		)
	)
	(zone
		(layers "F.Cu" "B.Cu" "In1.Cu" "In2.Cu" "In3.Cu" "In4.Cu" "In5.Cu" "In6.Cu"
			"In7.Cu" "In8.Cu" "In9.Cu" "In10.Cu"
		)
		(hatch none 0.5)
		(connect_pads
			(clearance 0)
		)
		(min_thickness 0.25)
		(keepout
			(tracks not_allowed)
			(vias allowed)
			(pads allowed)
			(copperpour not_allowed)
			(footprints allowed)
		)
		(placement
			(enabled no)
			(sheetname "")
		)
		(fill yes
			(thermal_gap 0.5)
			(thermal_bridge_width 0.5)
			(island_removal_mode 0)
		)
		(polygon
			(pts
				(arc
					(start 152.32507 -92.799916)
					(mid 159.325056 -85.79993)
					(end 166.325042 -92.799916)
				)
				(arc
					(start 166.325042 -98.799904)
					(mid 159.325056 -105.79989)
					(end 152.32507 -98.799904)
				)
			)
		)
	)
	(zone
		(layers "F.Cu" "B.Cu" "In1.Cu" "In2.Cu" "In3.Cu" "In4.Cu" "In5.Cu" "In6.Cu"
			"In7.Cu" "In8.Cu" "In9.Cu" "In10.Cu"
		)
		(hatch none 0.5)
		(connect_pads
			(clearance 0)
		)
		(min_thickness 0.25)
		(keepout
			(tracks not_allowed)
			(vias allowed)
			(pads allowed)
			(copperpour not_allowed)
			(footprints allowed)
		)
		(placement
			(enabled no)
			(sheetname "")
		)
		(fill yes
			(thermal_gap 0.5)
			(thermal_bridge_width 0.5)
			(island_removal_mode 0)
		)
		(polygon
			(pts
				(arc
					(start 485.000046 -5.500116)
					(mid 481.24999 -9.250172)
					(end 477.499934 -5.500116)
				)
				(arc
					(start 477.499934 -5.500116)
					(mid 481.24999 -1.75006)
					(end 485.000046 -5.500116)
				)
			)
		)
	)
	(zone
		(layers "F.Cu" "B.Cu" "In1.Cu" "In2.Cu" "In3.Cu" "In4.Cu" "In5.Cu" "In6.Cu"
			"In7.Cu" "In8.Cu" "In9.Cu" "In10.Cu"
		)
		(hatch none 0.5)
		(connect_pads
			(clearance 0)
		)
		(min_thickness 0.25)
		(keepout
			(tracks not_allowed)
			(vias allowed)
			(pads allowed)
			(copperpour not_allowed)
			(footprints allowed)
		)
		(placement
			(enabled no)
			(sheetname "")
		)
		(fill yes
			(thermal_gap 0.5)
			(thermal_bridge_width 0.5)
			(island_removal_mode 0)
		)
		(polygon
			(pts
				(arc
					(start 152.32507 -322.799964)
					(mid 159.325056 -315.799978)
					(end 166.325042 -322.799964)
				)
				(arc
					(start 166.325042 -328.799952)
					(mid 159.325056 -335.799938)
					(end 152.32507 -328.799952)
				)
			)
		)
	)
	(zone
		(layers "F.Cu" "B.Cu" "In1.Cu" "In2.Cu" "In3.Cu" "In4.Cu" "In5.Cu" "In6.Cu"
			"In7.Cu" "In8.Cu" "In9.Cu" "In10.Cu"
		)
		(hatch none 0.5)
		(connect_pads
			(clearance 0)
		)
		(min_thickness 0.25)
		(keepout
			(tracks not_allowed)
			(vias allowed)
			(pads allowed)
			(copperpour not_allowed)
			(footprints allowed)
		)
		(placement
			(enabled no)
			(sheetname "")
		)
		(fill
			(thermal_gap 0.5)
			(thermal_bridge_width 0.5)
			(island_removal_mode 0)
		)
		(polygon
			(pts
				(arc
					(start 409.150058 -289.999928)
					(mid 399.64995 -289.999928)
					(end 409.150058 -289.999928)
				)
			)
		)
	)
	(zone
		(layers "F.Cu" "B.Cu" "In1.Cu" "In2.Cu" "In3.Cu" "In4.Cu" "In5.Cu" "In6.Cu"
			"In7.Cu" "In8.Cu" "In9.Cu" "In10.Cu"
		)
		(hatch none 0.5)
		(connect_pads
			(clearance 0)
		)
		(min_thickness 0.25)
		(keepout
			(tracks not_allowed)
			(vias allowed)
			(pads allowed)
			(copperpour not_allowed)
			(footprints allowed)
		)
		(placement
			(enabled no)
			(sheetname "")
		)
		(fill yes
			(thermal_gap 0.5)
			(thermal_bridge_width 0.5)
			(island_removal_mode 0)
		)
		(polygon
			(pts
				(arc
					(start 152.32507 -207.79994)
					(mid 159.325056 -200.799954)
					(end 166.325042 -207.79994)
				)
				(arc
					(start 166.325042 -213.799928)
					(mid 159.325056 -220.799914)
					(end 152.32507 -213.799928)
				)
			)
		)
	)
	(zone
		(layers "F.Cu" "B.Cu" "In1.Cu" "In2.Cu" "In3.Cu" "In4.Cu" "In5.Cu" "In6.Cu"
			"In7.Cu" "In8.Cu" "In9.Cu" "In10.Cu"
		)
		(hatch none 0.5)
		(connect_pads
			(clearance 0)
		)
		(min_thickness 0.25)
		(keepout
			(tracks not_allowed)
			(vias allowed)
			(pads allowed)
			(copperpour not_allowed)
			(footprints allowed)
		)
		(placement
			(enabled no)
			(sheetname "")
		)
		(fill yes
			(thermal_gap 0.5)
			(thermal_bridge_width 0.5)
			(island_removal_mode 0)
		)
		(polygon
			(pts
				(arc
					(start 38.999922 -164.200078)
					(mid 42.749978 -160.450022)
					(end 46.500034 -164.200078)
				)
				(arc
					(start 46.500034 -164.200078)
					(mid 42.749978 -167.950134)
					(end 38.999922 -164.200078)
				)
			)
		)
	)
	(zone
		(layers "F.Cu" "B.Cu" "In1.Cu" "In2.Cu" "In3.Cu" "In4.Cu" "In5.Cu" "In6.Cu"
			"In7.Cu" "In8.Cu" "In9.Cu" "In10.Cu"
		)
		(hatch none 0.5)
		(connect_pads
			(clearance 0)
		)
		(min_thickness 0.25)
		(keepout
			(tracks not_allowed)
			(vias allowed)
			(pads allowed)
			(copperpour not_allowed)
			(footprints allowed)
		)
		(placement
			(enabled no)
			(sheetname "")
		)
		(fill yes
			(thermal_gap 0.5)
			(thermal_bridge_width 0.5)
			(island_removal_mode 0)
		)
		(polygon
			(pts
				(arc
					(start 293.200074 -138.199876)
					(mid 300.20006 -131.19989)
					(end 307.200046 -138.199876)
				)
				(arc
					(start 307.200046 -144.200118)
					(mid 300.20006 -151.200104)
					(end 293.200074 -144.200118)
				)
			)
		)
	)
	(zone
		(layers "F.Cu" "B.Cu" "In1.Cu" "In2.Cu" "In3.Cu" "In4.Cu" "In5.Cu" "In6.Cu"
			"In7.Cu" "In8.Cu" "In9.Cu" "In10.Cu"
		)
		(hatch none 0.5)
		(connect_pads
			(clearance 0)
		)
		(min_thickness 0.25)
		(keepout
			(tracks not_allowed)
			(vias allowed)
			(pads allowed)
			(copperpour not_allowed)
			(footprints allowed)
		)
		(placement
			(enabled no)
			(sheetname "")
		)
		(fill
			(thermal_gap 0.5)
			(thermal_bridge_width 0.5)
			(island_removal_mode 0)
		)
		(polygon
			(pts
				(arc
					(start 328.424794 -9.19988)
					(mid 318.924686 -9.19988)
					(end 328.424794 -9.19988)
				)
			)
		)
	)
	(zone
		(layers "F.Cu" "B.Cu" "In1.Cu" "In2.Cu" "In3.Cu" "In4.Cu" "In5.Cu" "In6.Cu"
			"In7.Cu" "In8.Cu" "In9.Cu" "In10.Cu"
		)
		(hatch none 0.5)
		(connect_pads
			(clearance 0)
		)
		(min_thickness 0.25)
		(keepout
			(tracks not_allowed)
			(vias allowed)
			(pads allowed)
			(copperpour not_allowed)
			(footprints allowed)
		)
		(placement
			(enabled no)
			(sheetname "")
		)
		(fill yes
			(thermal_gap 0.5)
			(thermal_bridge_width 0.5)
			(island_removal_mode 0)
		)
		(polygon
			(pts
				(arc
					(start 226.099878 -143.500094)
					(mid 229.849934 -139.750038)
					(end 233.59999 -143.500094)
				)
				(arc
					(start 233.59999 -143.500094)
					(mid 229.849934 -147.25015)
					(end 226.099878 -143.500094)
				)
			)
		)
	)
	(zone
		(layers "F.Cu" "B.Cu" "In1.Cu" "In2.Cu" "In3.Cu" "In4.Cu" "In5.Cu" "In6.Cu"
			"In7.Cu" "In8.Cu" "In9.Cu" "In10.Cu"
		)
		(hatch none 0.5)
		(connect_pads
			(clearance 0)
		)
		(min_thickness 0.25)
		(keepout
			(tracks not_allowed)
			(vias allowed)
			(pads allowed)
			(copperpour not_allowed)
			(footprints allowed)
		)
		(placement
			(enabled no)
			(sheetname "")
		)
		(fill
			(thermal_gap 0.5)
			(thermal_bridge_width 0.5)
			(island_removal_mode 0)
		)
		(polygon
			(pts
				(arc
					(start 111.849916 -289.999928)
					(mid 102.350316 -289.999928)
					(end 111.849916 -289.999928)
				)
			)
		)
	)
	(zone
		(layers "F.Cu" "B.Cu" "In1.Cu" "In2.Cu" "In3.Cu" "In4.Cu" "In5.Cu" "In6.Cu"
			"In7.Cu" "In8.Cu" "In9.Cu" "In10.Cu"
		)
		(hatch none 0.5)
		(connect_pads
			(clearance 0)
		)
		(min_thickness 0.25)
		(keepout
			(tracks not_allowed)
			(vias allowed)
			(pads allowed)
			(copperpour not_allowed)
			(footprints allowed)
		)
		(placement
			(enabled no)
			(sheetname "")
		)
		(fill yes
			(thermal_gap 0.5)
			(thermal_bridge_width 0.5)
			(island_removal_mode 0)
		)
		(polygon
			(pts
				(arc
					(start 7.599934 -5.500116)
					(mid 3.850132 -9.249918)
					(end 0.100076 -5.500116)
				)
				(arc
					(start 0.100076 -5.500116)
					(mid 3.850132 -1.75006)
					(end 7.599934 -5.500116)
				)
			)
		)
	)
	(zone
		(layers "F.Cu" "B.Cu" "In1.Cu" "In2.Cu" "In3.Cu" "In4.Cu" "In5.Cu" "In6.Cu"
			"In7.Cu" "In8.Cu" "In9.Cu" "In10.Cu"
		)
		(hatch none 0.5)
		(connect_pads
			(clearance 0)
		)
		(min_thickness 0.25)
		(keepout
			(tracks not_allowed)
			(vias allowed)
			(pads allowed)
			(copperpour not_allowed)
			(footprints allowed)
		)
		(placement
			(enabled no)
			(sheetname "")
		)
		(fill yes
			(thermal_gap 0.5)
			(thermal_bridge_width 0.5)
			(island_removal_mode 0)
		)
		(polygon
			(pts
				(arc
					(start 343.250012 -164.200078)
					(mid 347.000068 -160.450022)
					(end 350.750124 -164.200078)
				)
				(arc
					(start 350.750124 -164.200078)
					(mid 347.000068 -167.950134)
					(end 343.250012 -164.200078)
				)
			)
		)
	)
	(zone
		(layers "F.Cu" "B.Cu" "In1.Cu" "In2.Cu" "In3.Cu" "In4.Cu" "In5.Cu" "In6.Cu"
			"In7.Cu" "In8.Cu" "In9.Cu" "In10.Cu"
		)
		(hatch none 0.5)
		(connect_pads
			(clearance 0)
		)
		(min_thickness 0.25)
		(keepout
			(tracks not_allowed)
			(vias allowed)
			(pads allowed)
			(copperpour not_allowed)
			(footprints allowed)
		)
		(placement
			(enabled no)
			(sheetname "")
		)
		(fill yes
			(thermal_gap 0.5)
			(thermal_bridge_width 0.5)
			(island_removal_mode 0)
		)
		(polygon
			(pts
				(arc
					(start 367.849912 -220.199966)
					(mid 371.599968 -216.44991)
					(end 375.350024 -220.199966)
				)
				(arc
					(start 375.350024 -220.199966)
					(mid 371.599968 -223.950022)
					(end 367.849912 -220.199966)
				)
			)
		)
	)
	(zone
		(layers "F.Cu" "B.Cu" "In1.Cu" "In2.Cu" "In3.Cu" "In4.Cu" "In5.Cu" "In6.Cu"
			"In7.Cu" "In8.Cu" "In9.Cu" "In10.Cu"
		)
		(hatch none 0.5)
		(connect_pads
			(clearance 0)
		)
		(min_thickness 0.25)
		(keepout
			(tracks not_allowed)
			(vias allowed)
			(pads allowed)
			(copperpour not_allowed)
			(footprints allowed)
		)
		(placement
			(enabled no)
			(sheetname "")
		)
		(fill
			(thermal_gap 0.5)
			(thermal_bridge_width 0.5)
			(island_removal_mode 0)
		)
		(polygon
			(pts
				(arc
					(start 485.000046 -120.499886)
					(mid 477.499934 -120.499886)
					(end 485.000046 -120.499886)
				)
			)
		)
	)
	(zone
		(layers "F.Cu" "B.Cu" "In1.Cu" "In2.Cu" "In3.Cu" "In4.Cu" "In5.Cu" "In6.Cu"
			"In7.Cu" "In8.Cu" "In9.Cu" "In10.Cu"
		)
		(hatch none 0.5)
		(connect_pads
			(clearance 0)
		)
		(min_thickness 0.25)
		(keepout
			(tracks not_allowed)
			(vias allowed)
			(pads allowed)
			(copperpour not_allowed)
			(footprints allowed)
		)
		(placement
			(enabled no)
			(sheetname "")
		)
		(fill yes
			(thermal_gap 0.5)
			(thermal_bridge_width 0.5)
			(island_removal_mode 0)
		)
		(polygon
			(pts
				(arc
					(start 386.675122 -322.799964)
					(mid 393.675108 -315.799978)
					(end 400.675094 -322.799964)
				)
				(arc
					(start 400.675094 -328.799952)
					(mid 393.675108 -335.799938)
					(end 386.675122 -328.799952)
				)
			)
		)
	)
	(zone
		(layers "F.Cu" "B.Cu" "In1.Cu" "In2.Cu" "In3.Cu" "In4.Cu" "In5.Cu" "In6.Cu"
			"In7.Cu" "In8.Cu" "In9.Cu" "In10.Cu"
		)
		(hatch none 0.5)
		(connect_pads
			(clearance 0)
		)
		(min_thickness 0.25)
		(keepout
			(tracks not_allowed)
			(vias allowed)
			(pads allowed)
			(copperpour not_allowed)
			(footprints allowed)
		)
		(placement
			(enabled no)
			(sheetname "")
		)
		(fill
			(thermal_gap 0.5)
			(thermal_bridge_width 0.5)
			(island_removal_mode 0)
		)
		(polygon
			(pts
				(arc
					(start 129.15011 -28.079954)
					(mid 123.150122 -28.079954)
					(end 129.15011 -28.079954)
				)
			)
		)
	)
	(zone
		(layers "F.Cu" "B.Cu" "In1.Cu" "In2.Cu" "In3.Cu" "In4.Cu" "In5.Cu" "In6.Cu"
			"In7.Cu" "In8.Cu" "In9.Cu" "In10.Cu"
		)
		(hatch none 0.5)
		(connect_pads
			(clearance 0)
		)
		(min_thickness 0.25)
		(keepout
			(tracks not_allowed)
			(vias allowed)
			(pads allowed)
			(copperpour not_allowed)
			(footprints allowed)
		)
		(placement
			(enabled no)
			(sheetname "")
		)
		(fill
			(thermal_gap 0.5)
			(thermal_bridge_width 0.5)
			(island_removal_mode 0)
		)
		(polygon
			(pts
				(arc
					(start 103.324914 -98.799904)
					(mid 96.324928 -105.79989)
					(end 89.324942 -98.799904)
				)
				(arc
					(start 89.324942 -92.799916)
					(mid 96.324928 -85.79993)
					(end 103.324914 -92.799916)
				)
			)
		)
	)
	(zone
		(layers "F.Cu" "B.Cu" "In1.Cu" "In2.Cu" "In3.Cu" "In4.Cu" "In5.Cu" "In6.Cu"
			"In7.Cu" "In8.Cu" "In9.Cu" "In10.Cu"
		)
		(hatch none 0.5)
		(connect_pads
			(clearance 0)
		)
		(min_thickness 0.25)
		(keepout
			(tracks not_allowed)
			(vias allowed)
			(pads allowed)
			(copperpour not_allowed)
			(footprints allowed)
		)
		(placement
			(enabled no)
			(sheetname "")
		)
		(fill
			(thermal_gap 0.5)
			(thermal_bridge_width 0.5)
			(island_removal_mode 0)
		)
		(polygon
			(pts
				(arc
					(start 174.949866 -269.999968)
					(mid 165.449758 -269.999968)
					(end 174.949866 -269.999968)
				)
			)
		)
	)
	(zone
		(layers "F.Cu" "B.Cu" "In1.Cu" "In2.Cu" "In3.Cu" "In4.Cu" "In5.Cu" "In6.Cu"
			"In7.Cu" "In8.Cu" "In9.Cu" "In10.Cu"
		)
		(hatch none 0.5)
		(connect_pads
			(clearance 0)
		)
		(min_thickness 0.25)
		(keepout
			(tracks not_allowed)
			(vias allowed)
			(pads allowed)
			(copperpour not_allowed)
			(footprints allowed)
		)
		(placement
			(enabled no)
			(sheetname "")
		)
		(fill
			(thermal_gap 0.5)
			(thermal_bridge_width 0.5)
			(island_removal_mode 0)
		)
		(polygon
			(pts
				(arc
					(start 251.199904 -360.19994)
					(mid 244.199918 -353.199954)
					(end 237.199932 -360.19994)
				)
				(arc
					(start 237.199932 -366.199928)
					(mid 244.199918 -373.199914)
					(end 251.199904 -366.199928)
				)
			)
		)
	)
	(zone
		(layers "F.Cu" "B.Cu" "In1.Cu" "In2.Cu" "In3.Cu" "In4.Cu" "In5.Cu" "In6.Cu"
			"In7.Cu" "In8.Cu" "In9.Cu" "In10.Cu"
		)
		(hatch none 0.5)
		(connect_pads
			(clearance 0)
		)
		(min_thickness 0.25)
		(keepout
			(tracks not_allowed)
			(vias allowed)
			(pads allowed)
			(copperpour not_allowed)
			(footprints allowed)
		)
		(placement
			(enabled no)
			(sheetname "")
		)
		(fill yes
			(thermal_gap 0.5)
			(thermal_bridge_width 0.5)
			(island_removal_mode 0)
		)
		(polygon
			(pts
				(arc
					(start 449.674996 -92.799916)
					(mid 456.674982 -85.79993)
					(end 463.674968 -92.799916)
				)
				(arc
					(start 463.674968 -98.799904)
					(mid 456.674982 -105.79989)
					(end 449.674996 -98.799904)
				)
			)
		)
	)
	(zone
		(layers "F.Cu" "B.Cu" "In1.Cu" "In2.Cu" "In3.Cu" "In4.Cu" "In5.Cu" "In6.Cu"
			"In7.Cu" "In8.Cu" "In9.Cu" "In10.Cu"
		)
		(hatch none 0.5)
		(connect_pads
			(clearance 0)
		)
		(min_thickness 0.25)
		(keepout
			(tracks not_allowed)
			(vias allowed)
			(pads allowed)
			(copperpour not_allowed)
			(footprints allowed)
		)
		(placement
			(enabled no)
			(sheetname "")
		)
		(fill yes
			(thermal_gap 0.5)
			(thermal_bridge_width 0.5)
			(island_removal_mode 0)
		)
		(polygon
			(pts
				(arc
					(start 163.949888 -164.200078)
					(mid 167.699944 -160.450022)
					(end 171.45 -164.200078)
				)
				(arc
					(start 171.45 -164.200078)
					(mid 167.699944 -167.950134)
					(end 163.949888 -164.200078)
				)
			)
		)
	)
	(zone
		(layers "F.Cu" "B.Cu" "In1.Cu" "In2.Cu" "In3.Cu" "In4.Cu" "In5.Cu" "In6.Cu"
			"In7.Cu" "In8.Cu" "In9.Cu" "In10.Cu"
		)
		(hatch none 0.5)
		(connect_pads
			(clearance 0)
		)
		(min_thickness 0.25)
		(keepout
			(tracks not_allowed)
			(vias allowed)
			(pads allowed)
			(copperpour not_allowed)
			(footprints allowed)
		)
		(placement
			(enabled no)
			(sheetname "")
		)
		(fill
			(thermal_gap 0.5)
			(thermal_bridge_width 0.5)
			(island_removal_mode 0)
		)
		(polygon
			(pts
				(arc
					(start 233.59999 6.500114)
					(mid 226.099878 6.500114)
					(end 233.59999 6.500114)
				)
			)
		)
	)
	(zone
		(layers "F.Cu" "B.Cu" "In1.Cu" "In2.Cu" "In3.Cu" "In4.Cu" "In5.Cu" "In6.Cu"
			"In7.Cu" "In8.Cu" "In9.Cu" "In10.Cu"
		)
		(hatch none 0.5)
		(connect_pads
			(clearance 0)
		)
		(min_thickness 0.25)
		(keepout
			(tracks not_allowed)
			(vias allowed)
			(pads allowed)
			(copperpour not_allowed)
			(footprints allowed)
		)
		(placement
			(enabled no)
			(sheetname "")
		)
		(fill
			(thermal_gap 0.5)
			(thermal_bridge_width 0.5)
			(island_removal_mode 0)
		)
		(polygon
			(pts
				(arc
					(start 40.32504 -98.799904)
					(mid 33.325054 -105.79989)
					(end 26.325068 -98.799904)
				)
				(arc
					(start 26.325068 -92.799916)
					(mid 33.325054 -85.79993)
					(end 40.32504 -92.799916)
				)
			)
		)
	)
	(zone
		(layers "F.Cu" "B.Cu" "In1.Cu" "In2.Cu" "In3.Cu" "In4.Cu" "In5.Cu" "In6.Cu"
			"In7.Cu" "In8.Cu" "In9.Cu" "In10.Cu"
		)
		(hatch none 0.5)
		(connect_pads
			(clearance 0)
		)
		(min_thickness 0.25)
		(keepout
			(tracks not_allowed)
			(vias allowed)
			(pads allowed)
			(copperpour not_allowed)
			(footprints allowed)
		)
		(placement
			(enabled no)
			(sheetname "")
		)
		(fill
			(thermal_gap 0.5)
			(thermal_bridge_width 0.5)
			(island_removal_mode 0)
		)
		(polygon
			(pts
				(arc
					(start 346.049854 -269.999968)
					(mid 336.549746 -269.999968)
					(end 346.049854 -269.999968)
				)
			)
		)
	)
	(zone
		(layers "F.Cu" "B.Cu" "In1.Cu" "In2.Cu" "In3.Cu" "In4.Cu" "In5.Cu" "In6.Cu"
			"In7.Cu" "In8.Cu" "In9.Cu" "In10.Cu"
		)
		(hatch none 0.5)
		(connect_pads
			(clearance 0)
		)
		(min_thickness 0.25)
		(keepout
			(tracks not_allowed)
			(vias allowed)
			(pads allowed)
			(copperpour not_allowed)
			(footprints allowed)
		)
		(placement
			(enabled no)
			(sheetname "")
		)
		(fill yes
			(thermal_gap 0.5)
			(thermal_bridge_width 0.5)
			(island_removal_mode 0)
		)
		(polygon
			(pts
				(arc
					(start 237.199932 -273.200114)
					(mid 244.199918 -266.200128)
					(end 251.199904 -273.200114)
				)
				(arc
					(start 251.199904 -279.200102)
					(mid 244.199918 -286.200088)
					(end 237.199932 -279.200102)
				)
			)
		)
	)
	(zone
		(layers "F.Cu" "B.Cu" "In1.Cu" "In2.Cu" "In3.Cu" "In4.Cu" "In5.Cu" "In6.Cu"
			"In7.Cu" "In8.Cu" "In9.Cu" "In10.Cu"
		)
		(hatch none 0.5)
		(connect_pads
			(clearance 0)
		)
		(min_thickness 0.25)
		(keepout
			(tracks not_allowed)
			(vias allowed)
			(pads allowed)
			(copperpour not_allowed)
			(footprints allowed)
		)
		(placement
			(enabled no)
			(sheetname "")
		)
		(fill yes
			(thermal_gap 0.5)
			(thermal_bridge_width 0.5)
			(island_removal_mode 0)
		)
		(polygon
			(pts
				(arc
					(start 293.200074 -243.19992)
					(mid 300.20006 -236.199934)
					(end 307.200046 -243.19992)
				)
				(arc
					(start 307.200046 -249.199908)
					(mid 300.20006 -256.199894)
					(end 293.200074 -249.199908)
				)
			)
		)
	)
	(zone
		(layers "F.Cu" "B.Cu" "In1.Cu" "In2.Cu" "In3.Cu" "In4.Cu" "In5.Cu" "In6.Cu"
			"In7.Cu" "In8.Cu" "In9.Cu" "In10.Cu"
		)
		(hatch none 0.5)
		(connect_pads
			(clearance 0)
		)
		(min_thickness 0.25)
		(keepout
			(tracks not_allowed)
			(vias allowed)
			(pads allowed)
			(copperpour not_allowed)
			(footprints allowed)
		)
		(placement
			(enabled no)
			(sheetname "")
		)
		(fill yes
			(thermal_gap 0.5)
			(thermal_bridge_width 0.5)
			(island_removal_mode 0)
		)
		(polygon
			(pts
				(arc
					(start 449.674996 -207.79994)
					(mid 456.674982 -200.799954)
					(end 463.674968 -207.79994)
				)
				(arc
					(start 463.674968 -213.799928)
					(mid 456.674982 -220.799914)
					(end 449.674996 -213.799928)
				)
			)
		)
	)
	(zone
		(layers "F.Cu" "B.Cu" "In1.Cu" "In2.Cu" "In3.Cu" "In4.Cu" "In5.Cu" "In6.Cu"
			"In7.Cu" "In8.Cu" "In9.Cu" "In10.Cu"
		)
		(hatch none 0.5)
		(connect_pads
			(clearance 0)
		)
		(min_thickness 0.25)
		(keepout
			(tracks not_allowed)
			(vias allowed)
			(pads allowed)
			(copperpour not_allowed)
			(footprints allowed)
		)
		(placement
			(enabled no)
			(sheetname "")
		)
		(fill
			(thermal_gap 0.5)
			(thermal_bridge_width 0.5)
			(island_removal_mode 0)
		)
		(polygon
			(pts
				(arc
					(start 439.175144 -210.799934)
					(mid 411.174692 -210.799934)
					(end 439.175144 -210.799934)
				)
			)
		)
	)
	(zone
		(layers "F.Cu" "B.Cu" "In1.Cu" "In2.Cu" "In3.Cu" "In4.Cu" "In5.Cu" "In6.Cu"
			"In7.Cu" "In8.Cu" "In9.Cu" "In10.Cu"
		)
		(hatch none 0.5)
		(connect_pads
			(clearance 0)
		)
		(min_thickness 0.25)
		(keepout
			(tracks not_allowed)
			(vias allowed)
			(pads allowed)
			(copperpour not_allowed)
			(footprints allowed)
		)
		(placement
			(enabled no)
			(sheetname "")
		)
		(fill
			(thermal_gap 0.5)
			(thermal_bridge_width 0.5)
			(island_removal_mode 0)
		)
		(polygon
			(pts
				(arc
					(start 31.074868 -9.19988)
					(mid 21.57476 -9.19988)
					(end 31.074868 -9.19988)
				)
			)
		)
	)
	(zone
		(layers "F.Cu" "B.Cu" "In1.Cu" "In2.Cu" "In3.Cu" "In4.Cu" "In5.Cu" "In6.Cu"
			"In7.Cu" "In8.Cu" "In9.Cu" "In10.Cu"
		)
		(hatch none 0.5)
		(connect_pads
			(clearance 0)
		)
		(min_thickness 0.25)
		(keepout
			(tracks not_allowed)
			(vias allowed)
			(pads allowed)
			(copperpour not_allowed)
			(footprints allowed)
		)
		(placement
			(enabled no)
			(sheetname "")
		)
		(fill yes
			(thermal_gap 0.5)
			(thermal_bridge_width 0.5)
			(island_removal_mode 0)
		)
		(polygon
			(pts
				(arc
					(start 323.674994 -322.799964)
					(mid 330.67498 -315.799978)
					(end 337.674966 -322.799964)
				)
				(arc
					(start 337.674966 -328.799952)
					(mid 330.67498 -335.799938)
					(end 323.674994 -328.799952)
				)
			)
		)
	)
	(zone
		(layers "F.Cu" "B.Cu" "In1.Cu" "In2.Cu" "In3.Cu" "In4.Cu" "In5.Cu" "In6.Cu"
			"In7.Cu" "In8.Cu" "In9.Cu" "In10.Cu"
		)
		(name "Package Keepin")
		(hatch none 0.5)
		(connect_pads
			(clearance 0)
		)
		(min_thickness 0.25)
		(keepout
			(tracks allowed)
			(vias allowed)
			(pads allowed)
			(copperpour allowed)
			(footprints allowed)
		)
		(placement
			(enabled no)
			(sheetname "")
		)
		(fill
			(thermal_gap 0.5)
			(thermal_bridge_width 0.5)
			(island_removal_mode 0)
		)
		(polygon
			(pts
				(xy 304.996088 -416.196272) (xy 304.996088 -379.003814)
				(arc
					(start 296.69994 -379.003814)
					(mid 292.454614 -377.245342)
					(end 290.696142 -373.000016)
				)
				(arc
					(start 290.696142 -350.19996)
					(mid 292.454614 -345.954634)
					(end 296.69994 -344.196162)
				)
				(xy 486.446322 -344.196162) (xy 486.446322 -5.0038) (xy 401.00377 -5.0038)
				(arc
					(start 401.00377 -13.999972)
					(mid 399.245298 -18.245298)
					(end 394.999972 -20.00377)
				)
				(arc
					(start 349.000064 -20.00377)
					(mid 344.754738 -18.245298)
					(end 342.996266 -13.999972)
				)
				(xy 342.996266 -5.0038)
				(arc
					(start 300.999906 -5.0038)
					(mid 296.75458 -3.245328)
					(end 294.996108 0.999998)
				)
				(xy 294.996108 33.796224) (xy 225.003868 33.796224)
				(arc
					(start 225.003868 2.999994)
					(mid 223.245396 -1.245332)
					(end 219.00007 -3.003804)
				)
				(arc
					(start 203.473812 -3.003804)
					(mid 201.450311 -4.481059)
					(end 199.00011 -5.0038)
				)
				(xy 155.003754 -5.0038)
				(arc
					(start 155.003754 -13.999972)
					(mid 153.245282 -18.245298)
					(end 148.999956 -20.00377)
				)
				(arc
					(start 103.000048 -20.00377)
					(mid 98.754722 -18.245298)
					(end 96.99625 -13.999972)
				)
				(xy 96.99625 -5.0038) (xy 5.0038 -5.0038) (xy 5.0038 -344.196162)
				(arc
					(start 189.6999 -344.196162)
					(mid 193.945226 -345.954634)
					(end 195.703698 -350.19996)
				)
				(xy 195.703698 -367.996216)
				(arc
					(start 199.00011 -367.996216)
					(mid 203.245436 -369.754688)
					(end 205.003908 -374.000014)
				)
				(xy 205.003908 -416.196272)
			)
		)
	)
	(zone
		(layers "F.Cu" "B.Cu" "In1.Cu" "In2.Cu" "In3.Cu" "In4.Cu" "In5.Cu" "In6.Cu"
			"In7.Cu" "In8.Cu" "In9.Cu" "In10.Cu"
		)
		(hatch none 0.5)
		(connect_pads
			(clearance 0)
		)
		(min_thickness 0.25)
		(keepout
			(tracks not_allowed)
			(vias allowed)
			(pads allowed)
			(copperpour not_allowed)
			(footprints allowed)
		)
		(placement
			(enabled no)
			(sheetname "")
		)
		(fill yes
			(thermal_gap 0.5)
			(thermal_bridge_width 0.5)
			(island_removal_mode 0)
		)
		(polygon
			(pts
				(arc
					(start 403.349968 -164.200078)
					(mid 407.100024 -160.450022)
					(end 410.85008 -164.200078)
				)
				(arc
					(start 410.85008 -164.200078)
					(mid 407.100024 -167.950134)
					(end 403.349968 -164.200078)
				)
			)
		)
	)
	(zone
		(layers "F.Cu" "B.Cu" "In1.Cu" "In2.Cu" "In3.Cu" "In4.Cu" "In5.Cu" "In6.Cu"
			"In7.Cu" "In8.Cu" "In9.Cu" "In10.Cu"
		)
		(hatch none 0.5)
		(connect_pads
			(clearance 0)
		)
		(min_thickness 0.25)
		(keepout
			(tracks not_allowed)
			(vias allowed)
			(pads allowed)
			(copperpour not_allowed)
			(footprints allowed)
		)
		(placement
			(enabled no)
			(sheetname "")
		)
		(fill yes
			(thermal_gap 0.5)
			(thermal_bridge_width 0.5)
			(island_removal_mode 0)
		)
		(polygon
			(pts
				(arc
					(start 26.325068 -207.79994)
					(mid 33.325054 -200.799954)
					(end 40.32504 -207.79994)
				)
				(arc
					(start 40.32504 -213.799928)
					(mid 33.325054 -220.799914)
					(end 26.325068 -213.799928)
				)
			)
		)
	)
	(zone
		(layers "F.Cu" "B.Cu" "In1.Cu" "In2.Cu" "In3.Cu" "In4.Cu" "In5.Cu" "In6.Cu"
			"In7.Cu" "In8.Cu" "In9.Cu" "In10.Cu"
		)
		(hatch none 0.5)
		(connect_pads
			(clearance 0)
		)
		(min_thickness 0.25)
		(keepout
			(tracks not_allowed)
			(vias allowed)
			(pads allowed)
			(copperpour not_allowed)
			(footprints allowed)
		)
		(placement
			(enabled no)
			(sheetname "")
		)
		(fill yes
			(thermal_gap 0.5)
			(thermal_bridge_width 0.5)
			(island_removal_mode 0)
		)
		(polygon
			(pts
				(arc
					(start 226.099878 6.500114)
					(mid 229.849934 10.25017)
					(end 233.59999 6.500114)
				)
				(arc
					(start 233.59999 6.500114)
					(mid 229.849934 2.750058)
					(end 226.099878 6.500114)
				)
			)
		)
	)
	(zone
		(layers "F.Cu" "B.Cu" "In1.Cu" "In2.Cu" "In3.Cu" "In4.Cu" "In5.Cu" "In6.Cu"
			"In7.Cu" "In8.Cu" "In9.Cu" "In10.Cu"
		)
		(hatch none 0.5)
		(connect_pads
			(clearance 0)
		)
		(min_thickness 0.25)
		(keepout
			(tracks not_allowed)
			(vias allowed)
			(pads allowed)
			(copperpour not_allowed)
			(footprints allowed)
		)
		(placement
			(enabled no)
			(sheetname "")
		)
		(fill
			(thermal_gap 0.5)
			(thermal_bridge_width 0.5)
			(island_removal_mode 0)
		)
		(polygon
			(pts
				(arc
					(start 171.074842 -9.19988)
					(mid 161.574734 -9.19988)
					(end 171.074842 -9.19988)
				)
			)
		)
	)
	(zone
		(layers "F.Cu" "B.Cu" "In1.Cu" "In2.Cu" "In3.Cu" "In4.Cu" "In5.Cu" "In6.Cu"
			"In7.Cu" "In8.Cu" "In9.Cu" "In10.Cu"
		)
		(hatch none 0.5)
		(connect_pads
			(clearance 0)
		)
		(min_thickness 0.25)
		(keepout
			(tracks not_allowed)
			(vias allowed)
			(pads allowed)
			(copperpour not_allowed)
			(footprints allowed)
		)
		(placement
			(enabled no)
			(sheetname "")
		)
		(fill
			(thermal_gap 0.5)
			(thermal_bridge_width 0.5)
			(island_removal_mode 0)
		)
		(polygon
			(pts
				(arc
					(start 375.150126 -28.079954)
					(mid 369.150138 -28.079954)
					(end 375.150126 -28.079954)
				)
			)
		)
	)
	(zone
		(layers "F.Cu" "B.Cu" "In1.Cu" "In2.Cu" "In3.Cu" "In4.Cu" "In5.Cu" "In6.Cu"
			"In7.Cu" "In8.Cu" "In9.Cu" "In10.Cu"
		)
		(hatch none 0.5)
		(connect_pads
			(clearance 0)
		)
		(min_thickness 0.25)
		(keepout
			(tracks not_allowed)
			(vias allowed)
			(pads allowed)
			(copperpour not_allowed)
			(footprints allowed)
		)
		(placement
			(enabled no)
			(sheetname "")
		)
		(fill
			(thermal_gap 0.5)
			(thermal_bridge_width 0.5)
			(island_removal_mode 0)
		)
		(polygon
			(pts
				(arc
					(start 141.824964 -210.799934)
					(mid 113.82502 -210.799934)
					(end 141.824964 -210.799934)
				)
			)
		)
	)
	(zone
		(layers "F.Cu" "B.Cu" "In1.Cu" "In2.Cu" "In3.Cu" "In4.Cu" "In5.Cu" "In6.Cu"
			"In7.Cu" "In8.Cu" "In9.Cu" "In10.Cu"
		)
		(hatch none 0.5)
		(connect_pads
			(clearance 0)
		)
		(min_thickness 0.25)
		(keepout
			(tracks not_allowed)
			(vias allowed)
			(pads allowed)
			(copperpour not_allowed)
			(footprints allowed)
		)
		(placement
			(enabled no)
			(sheetname "")
		)
		(fill
			(thermal_gap 0.5)
			(thermal_bridge_width 0.5)
			(island_removal_mode 0)
		)
		(polygon
			(pts
				(arc
					(start 195.300092 -183.79948)
					(mid 202.300078 -176.799494)
					(end 209.300064 -183.79948)
				)
				(arc
					(start 209.300064 -189.799468)
					(mid 202.300078 -196.799454)
					(end 195.300092 -189.799468)
				)
			)
		)
	)
	(zone
		(layers "F.Cu" "B.Cu" "In1.Cu" "In2.Cu" "In3.Cu" "In4.Cu" "In5.Cu" "In6.Cu"
			"In7.Cu" "In8.Cu" "In9.Cu" "In10.Cu"
		)
		(hatch none 0.5)
		(connect_pads
			(clearance 0)
		)
		(min_thickness 0.25)
		(keepout
			(tracks not_allowed)
			(vias allowed)
			(pads allowed)
			(copperpour not_allowed)
			(footprints allowed)
		)
		(placement
			(enabled no)
			(sheetname "")
		)
		(fill yes
			(thermal_gap 0.5)
			(thermal_bridge_width 0.5)
			(island_removal_mode 0)
		)
		(polygon
			(pts
				(arc
					(start 89.324942 -207.79994)
					(mid 96.324928 -200.799954)
					(end 103.324914 -207.79994)
				)
				(arc
					(start 103.324914 -213.799928)
					(mid 96.324928 -220.799914)
					(end 89.324942 -213.799928)
				)
			)
		)
	)
	(zone
		(layers "F.Cu" "B.Cu" "In1.Cu" "In2.Cu" "In3.Cu" "In4.Cu" "In5.Cu" "In6.Cu"
			"In7.Cu" "In8.Cu" "In9.Cu" "In10.Cu"
		)
		(hatch none 0.5)
		(connect_pads
			(clearance 0)
		)
		(min_thickness 0.25)
		(keepout
			(tracks not_allowed)
			(vias allowed)
			(pads allowed)
			(copperpour not_allowed)
			(footprints allowed)
		)
		(placement
			(enabled no)
			(sheetname "")
		)
		(fill yes
			(thermal_gap 0.5)
			(thermal_bridge_width 0.5)
			(island_removal_mode 0)
		)
		(polygon
			(pts
				(arc
					(start 449.674996 -322.799964)
					(mid 456.674982 -315.799978)
					(end 463.674968 -322.799964)
				)
				(arc
					(start 463.674968 -328.799952)
					(mid 456.674982 -335.799938)
					(end 449.674996 -328.799952)
				)
			)
		)
	)
	(zone
		(layers "F.Cu" "B.Cu" "In1.Cu" "In2.Cu" "In3.Cu" "In4.Cu" "In5.Cu" "In6.Cu"
			"In7.Cu" "In8.Cu" "In9.Cu" "In10.Cu"
		)
		(hatch none 0.5)
		(connect_pads
			(clearance 0)
		)
		(min_thickness 0.25)
		(keepout
			(tracks not_allowed)
			(vias allowed)
			(pads allowed)
			(copperpour not_allowed)
			(footprints allowed)
		)
		(placement
			(enabled no)
			(sheetname "")
		)
		(fill
			(thermal_gap 0.5)
			(thermal_bridge_width 0.5)
			(island_removal_mode 0)
		)
		(polygon
			(pts
				(arc
					(start 251.599954 6.500114)
					(mid 244.099842 6.500114)
					(end 251.599954 6.500114)
				)
			)
		)
	)
	(zone
		(layers "F.Cu" "B.Cu" "In1.Cu" "In2.Cu" "In3.Cu" "In4.Cu" "In5.Cu" "In6.Cu"
			"In7.Cu" "In8.Cu" "In9.Cu" "In10.Cu"
		)
		(hatch none 0.5)
		(connect_pads
			(clearance 0)
		)
		(min_thickness 0.25)
		(keepout
			(tracks not_allowed)
			(vias allowed)
			(pads allowed)
			(copperpour not_allowed)
			(footprints allowed)
		)
		(placement
			(enabled no)
			(sheetname "")
		)
		(fill yes
			(thermal_gap 0.5)
			(thermal_bridge_width 0.5)
			(island_removal_mode 0)
		)
		(polygon
			(pts
				(arc
					(start 244.10924 6.763766)
					(mid 244.102353 6.63202)
					(end 244.100096 6.500114)
				)
				(arc
					(start 244.100096 6.500114)
					(mid 244.670305 8.487697)
					(end 246.20728 9.870948)
				)
				(arc
					(start 246.20728 9.870948)
					(mid 246.426391 10.82447)
					(end 246.499888 11.800078)
				)
				(arc
					(start 246.499888 17.800066)
					(mid 240.000028 24.299926)
					(end 233.499914 17.800066)
				)
				(arc
					(start 233.499914 11.800078)
					(mid 237.212494 5.928014)
					(end 244.10924 6.763766)
				)
			)
		)
	)
	(zone
		(layers "F.Cu" "B.Cu" "In1.Cu" "In2.Cu" "In3.Cu" "In4.Cu" "In5.Cu" "In6.Cu"
			"In7.Cu" "In8.Cu" "In9.Cu" "In10.Cu"
		)
		(hatch none 0.5)
		(connect_pads
			(clearance 0)
		)
		(min_thickness 0.25)
		(keepout
			(tracks not_allowed)
			(vias allowed)
			(pads allowed)
			(copperpour not_allowed)
			(footprints allowed)
		)
		(placement
			(enabled no)
			(sheetname "")
		)
		(fill
			(thermal_gap 0.5)
			(thermal_bridge_width 0.5)
			(island_removal_mode 0)
		)
		(polygon
			(pts
				(arc
					(start 468.424768 -9.19988)
					(mid 458.925168 -9.19988)
					(end 468.424768 -9.19988)
				)
			)
		)
	)
	(zone
		(layers "F.Cu" "B.Cu" "In1.Cu" "In2.Cu" "In3.Cu" "In4.Cu" "In5.Cu" "In6.Cu"
			"In7.Cu" "In8.Cu" "In9.Cu" "In10.Cu"
		)
		(hatch none 0.5)
		(connect_pads
			(clearance 0)
		)
		(min_thickness 0.25)
		(keepout
			(tracks not_allowed)
			(vias allowed)
			(pads allowed)
			(copperpour not_allowed)
			(footprints allowed)
		)
		(placement
			(enabled no)
			(sheetname "")
		)
		(fill yes
			(thermal_gap 0.5)
			(thermal_bridge_width 0.5)
			(island_removal_mode 0)
		)
		(polygon
			(pts
				(arc
					(start 4.249928 -224.199958)
					(mid 7.999984 -220.449902)
					(end 11.75004 -224.199958)
				)
				(arc
					(start 11.75004 -224.199958)
					(mid 7.999984 -227.950014)
					(end 4.249928 -224.199958)
				)
			)
		)
	)
	(zone
		(layers "F.Cu" "B.Cu" "In1.Cu" "In2.Cu" "In3.Cu" "In4.Cu" "In5.Cu" "In6.Cu"
			"In7.Cu" "In8.Cu" "In9.Cu" "In10.Cu"
		)
		(hatch none 0.5)
		(connect_pads
			(clearance 0)
		)
		(min_thickness 0.25)
		(keepout
			(tracks not_allowed)
			(vias allowed)
			(pads allowed)
			(copperpour not_allowed)
			(footprints allowed)
		)
		(placement
			(enabled no)
			(sheetname "")
		)
		(fill yes
			(thermal_gap 0.5)
			(thermal_bridge_width 0.5)
			(island_removal_mode 0)
		)
		(polygon
			(pts
				(arc
					(start 89.324942 -322.799964)
					(mid 96.324928 -315.799978)
					(end 103.324914 -322.799964)
				)
				(arc
					(start 103.324914 -328.799952)
					(mid 96.324928 -335.799938)
					(end 89.324942 -328.799952)
				)
			)
		)
	)
	(zone
		(layers "F.Cu" "B.Cu" "In1.Cu" "In2.Cu" "In3.Cu" "In4.Cu" "In5.Cu" "In6.Cu"
			"In7.Cu" "In8.Cu" "In9.Cu" "In10.Cu"
		)
		(hatch none 0.5)
		(connect_pads
			(clearance 0)
		)
		(min_thickness 0.25)
		(keepout
			(tracks not_allowed)
			(vias allowed)
			(pads allowed)
			(copperpour not_allowed)
			(footprints allowed)
		)
		(placement
			(enabled no)
			(sheetname "")
		)
		(fill
			(thermal_gap 0.5)
			(thermal_bridge_width 0.5)
			(island_removal_mode 0)
		)
		(polygon
			(pts
				(arc
					(start 472.249754 -269.999968)
					(mid 462.749646 -269.999968)
					(end 472.249754 -269.999968)
				)
			)
		)
	)
	(zone
		(layers "F.Cu" "B.Cu" "In1.Cu" "In2.Cu" "In3.Cu" "In4.Cu" "In5.Cu" "In6.Cu"
			"In7.Cu" "In8.Cu" "In9.Cu" "In10.Cu"
		)
		(hatch none 0.5)
		(connect_pads
			(clearance 0)
		)
		(min_thickness 0.25)
		(keepout
			(tracks not_allowed)
			(vias allowed)
			(pads allowed)
			(copperpour not_allowed)
			(footprints allowed)
		)
		(placement
			(enabled no)
			(sheetname "")
		)
		(fill yes
			(thermal_gap 0.5)
			(thermal_bridge_width 0.5)
			(island_removal_mode 0)
		)
		(polygon
			(pts
				(arc
					(start 178.649884 -208.499964)
					(mid 182.39994 -204.749908)
					(end 186.149996 -208.499964)
				)
				(arc
					(start 186.149996 -208.499964)
					(mid 182.39994 -212.25002)
					(end 178.649884 -208.499964)
				)
			)
		)
	)
	(zone
		(layers "F.Cu" "B.Cu" "In2.Cu" "In4.Cu" "In7.Cu")
		(hatch none 0.5)
		(connect_pads
			(clearance 0)
		)
		(min_thickness 0.25)
		(keepout
			(tracks not_allowed)
			(vias allowed)
			(pads allowed)
			(copperpour not_allowed)
			(footprints allowed)
		)
		(placement
			(enabled no)
			(sheetname "")
		)
		(fill yes
			(thermal_gap 0.5)
			(thermal_bridge_width 0.5)
			(island_removal_mode 0)
		)
		(polygon
			(pts
				(arc
					(start 283.563314 -78.572868)
					(mid 282.622752 -78.886558)
					(end 282.936442 -79.82712)
				)
				(arc
					(start 284.928056 -80.8228)
					(mid 285.613377 -80.799427)
					(end 285.950914 -80.202532)
				)
				(arc
					(start 285.795974 -80.202532)
					(mid 285.249874 -80.746098)
					(end 284.703774 -80.202532)
				)
				(arc
					(start 284.703774 -80.199992)
					(mid 285.249874 -79.653892)
					(end 285.795974 -80.199992)
				)
				(arc
					(start 285.950914 -80.199992)
					(mid 285.846184 -79.831385)
					(end 285.56331 -79.572866)
				)
				(xy 284.822646 -79.202534)
				(arc
					(start 283.795978 -79.202534)
					(mid 283.249878 -79.7461)
					(end 282.703778 -79.202534)
				)
				(arc
					(start 282.703778 -79.199994)
					(mid 283.249878 -78.653894)
					(end 283.795978 -79.199994)
				)
				(xy 284.817566 -79.199994)
			)
		)
	)
	(zone
		(layers "F.Cu" "B.Cu" "In2.Cu" "In4.Cu" "In7.Cu")
		(hatch none 0.5)
		(connect_pads
			(clearance 0)
		)
		(min_thickness 0.25)
		(keepout
			(tracks not_allowed)
			(vias allowed)
			(pads allowed)
			(copperpour not_allowed)
			(footprints allowed)
		)
		(placement
			(enabled no)
			(sheetname "")
		)
		(fill yes
			(thermal_gap 0.5)
			(thermal_bridge_width 0.5)
			(island_removal_mode 0)
		)
		(polygon
			(pts
				(arc
					(start 240.871756 -174.876968)
					(mid 239.92498 -175.182153)
					(end 240.236502 -176.126902)
				)
				(arc
					(start 242.236498 -177.1269)
					(mid 242.917487 -177.096795)
					(end 243.250974 -176.502314)
				)
				(arc
					(start 243.096034 -176.502314)
					(mid 242.549934 -177.04588)
					(end 242.003834 -176.502314)
				)
				(arc
					(start 242.003834 -176.499774)
					(mid 242.549934 -175.953674)
					(end 243.096034 -176.499774)
				)
				(arc
					(start 243.250974 -176.499774)
					(mid 243.146244 -176.131167)
					(end 242.86337 -175.872648)
				)
				(xy 242.122706 -175.502316)
				(arc
					(start 241.096038 -175.502316)
					(mid 240.549938 -176.045882)
					(end 240.003838 -175.502316)
				)
				(arc
					(start 240.003838 -175.499776)
					(mid 240.549938 -174.953676)
					(end 241.096038 -175.499776)
				)
				(xy 242.117626 -175.499776)
			)
		)
	)
	(zone
		(layers "F.Cu" "B.Cu" "In2.Cu" "In4.Cu" "In7.Cu")
		(hatch none 0.5)
		(connect_pads
			(clearance 0)
		)
		(min_thickness 0.25)
		(keepout
			(tracks not_allowed)
			(vias allowed)
			(pads allowed)
			(copperpour not_allowed)
			(footprints allowed)
		)
		(placement
			(enabled no)
			(sheetname "")
		)
		(fill yes
			(thermal_gap 0.5)
			(thermal_bridge_width 0.5)
			(island_removal_mode 0)
		)
		(polygon
			(pts
				(arc
					(start 283.563314 -62.5729)
					(mid 282.622752 -62.88659)
					(end 282.936442 -63.827152)
				)
				(arc
					(start 284.928056 -64.822832)
					(mid 285.613377 -64.799459)
					(end 285.950914 -64.202564)
				)
				(arc
					(start 285.795974 -64.202564)
					(mid 285.249874 -64.74613)
					(end 284.703774 -64.202564)
				)
				(arc
					(start 284.703774 -64.200024)
					(mid 285.249874 -63.653924)
					(end 285.795974 -64.200024)
				)
				(arc
					(start 285.950914 -64.200024)
					(mid 285.846184 -63.831417)
					(end 285.56331 -63.572898)
				)
				(xy 284.822646 -63.202566)
				(arc
					(start 283.795978 -63.202566)
					(mid 283.249878 -63.746132)
					(end 282.703778 -63.202566)
				)
				(arc
					(start 282.703778 -63.200026)
					(mid 283.249878 -62.653926)
					(end 283.795978 -63.200026)
				)
				(xy 284.817566 -63.200026)
			)
		)
	)
	(zone
		(layers "F.Cu" "B.Cu" "In2.Cu" "In4.Cu" "In7.Cu")
		(hatch none 0.5)
		(connect_pads
			(clearance 0)
		)
		(min_thickness 0.25)
		(keepout
			(tracks not_allowed)
			(vias allowed)
			(pads allowed)
			(copperpour not_allowed)
			(footprints allowed)
		)
		(placement
			(enabled no)
			(sheetname "")
		)
		(fill yes
			(thermal_gap 0.5)
			(thermal_bridge_width 0.5)
			(island_removal_mode 0)
		)
		(polygon
			(pts
				(arc
					(start 283.563314 -66.572892)
					(mid 282.622752 -66.886582)
					(end 282.936442 -67.827144)
				)
				(arc
					(start 284.928056 -68.822824)
					(mid 285.613377 -68.799451)
					(end 285.950914 -68.202556)
				)
				(arc
					(start 285.795974 -68.202556)
					(mid 285.249874 -68.746122)
					(end 284.703774 -68.202556)
				)
				(arc
					(start 284.703774 -68.200016)
					(mid 285.249874 -67.653916)
					(end 285.795974 -68.200016)
				)
				(arc
					(start 285.950914 -68.200016)
					(mid 285.846184 -67.831409)
					(end 285.56331 -67.57289)
				)
				(xy 284.822646 -67.202558)
				(arc
					(start 283.795978 -67.202558)
					(mid 283.249878 -67.746124)
					(end 282.703778 -67.202558)
				)
				(arc
					(start 282.703778 -67.200018)
					(mid 283.249878 -66.653918)
					(end 283.795978 -67.200018)
				)
				(xy 284.817566 -67.200018)
			)
		)
	)
	(zone
		(layers "F.Cu" "B.Cu" "In2.Cu" "In4.Cu" "In7.Cu")
		(hatch none 0.5)
		(connect_pads
			(clearance 0)
		)
		(min_thickness 0.25)
		(keepout
			(tracks not_allowed)
			(vias allowed)
			(pads allowed)
			(copperpour not_allowed)
			(footprints allowed)
		)
		(placement
			(enabled no)
			(sheetname "")
		)
		(fill yes
			(thermal_gap 0.5)
			(thermal_bridge_width 0.5)
			(island_removal_mode 0)
		)
		(polygon
			(pts
				(arc
					(start 215.948768 -416.80003)
					(mid 215.400128 -416.25139)
					(end 214.851488 -416.80003)
				)
				(arc
					(start 214.851488 -418.200078)
					(mid 215.398858 -418.748717)
					(end 215.948768 -418.202618)
				)
				(arc
					(start 215.793828 -418.202618)
					(mid 215.400128 -418.593786)
					(end 215.006428 -418.202618)
				)
				(arc
					(start 215.006428 -418.200078)
					(mid 215.400128 -417.806378)
					(end 215.793828 -418.200078)
				)
				(xy 215.948768 -418.200078) (xy 215.948768 -416.80257)
				(arc
					(start 215.793828 -416.80257)
					(mid 215.400128 -417.193738)
					(end 215.006428 -416.80257)
				)
				(arc
					(start 215.006428 -416.80003)
					(mid 215.400128 -416.40633)
					(end 215.793828 -416.80003)
				)
			)
		)
	)
	(zone
		(layers "F.Cu" "B.Cu" "In2.Cu" "In4.Cu" "In7.Cu")
		(hatch none 0.5)
		(connect_pads
			(clearance 0)
		)
		(min_thickness 0.25)
		(keepout
			(tracks not_allowed)
			(vias allowed)
			(pads allowed)
			(copperpour not_allowed)
			(footprints allowed)
		)
		(placement
			(enabled no)
			(sheetname "")
		)
		(fill yes
			(thermal_gap 0.5)
			(thermal_bridge_width 0.5)
			(island_removal_mode 0)
		)
		(polygon
			(pts
				(arc
					(start 283.563314 -162.872674)
					(mid 282.622752 -163.186364)
					(end 282.936442 -164.126926)
				)
				(arc
					(start 284.928056 -165.122606)
					(mid 285.613377 -165.099233)
					(end 285.950914 -164.502338)
				)
				(arc
					(start 285.795974 -164.502338)
					(mid 285.249874 -165.045904)
					(end 284.703774 -164.502338)
				)
				(arc
					(start 284.703774 -164.499798)
					(mid 285.249874 -163.953698)
					(end 285.795974 -164.499798)
				)
				(arc
					(start 285.950914 -164.499798)
					(mid 285.846184 -164.131191)
					(end 285.56331 -163.872672)
				)
				(xy 284.822646 -163.50234)
				(arc
					(start 283.795978 -163.50234)
					(mid 283.249878 -164.045906)
					(end 282.703778 -163.50234)
				)
				(arc
					(start 282.703778 -163.4998)
					(mid 283.249878 -162.9537)
					(end 283.795978 -163.4998)
				)
				(xy 284.817566 -163.4998)
			)
		)
	)
	(zone
		(layers "F.Cu" "B.Cu" "In2.Cu" "In4.Cu" "In7.Cu")
		(hatch none 0.5)
		(connect_pads
			(clearance 0)
		)
		(min_thickness 0.25)
		(keepout
			(tracks not_allowed)
			(vias allowed)
			(pads allowed)
			(copperpour not_allowed)
			(footprints allowed)
		)
		(placement
			(enabled no)
			(sheetname "")
		)
		(fill yes
			(thermal_gap 0.5)
			(thermal_bridge_width 0.5)
			(island_removal_mode 0)
		)
		(polygon
			(pts
				(arc
					(start 279.236678 -324.756526)
					(mid 278.688038 -325.305166)
					(end 279.236678 -325.853806)
				)
				(arc
					(start 280.636726 -325.853806)
					(mid 281.023774 -325.69401)
					(end 281.185366 -325.307706)
				)
				(arc
					(start 281.030426 -325.307706)
					(mid 280.636726 -325.698874)
					(end 280.243026 -325.307706)
				)
				(arc
					(start 279.630378 -325.307706)
					(mid 279.236678 -325.698874)
					(end 278.842978 -325.307706)
				)
				(arc
					(start 278.842978 -325.305166)
					(mid 279.236678 -324.911466)
					(end 279.630378 -325.305166)
				)
				(arc
					(start 280.243026 -325.305166)
					(mid 280.636726 -324.911466)
					(end 281.030426 -325.305166)
				)
				(arc
					(start 281.185366 -325.305166)
					(mid 281.024673 -324.917219)
					(end 280.636726 -324.756526)
				)
				(xy 279.236932 -324.756526)
			)
		)
	)
	(zone
		(layers "F.Cu" "B.Cu" "In2.Cu" "In4.Cu" "In7.Cu")
		(hatch none 0.5)
		(connect_pads
			(clearance 0)
		)
		(min_thickness 0.25)
		(keepout
			(tracks not_allowed)
			(vias allowed)
			(pads allowed)
			(copperpour not_allowed)
			(footprints allowed)
		)
		(placement
			(enabled no)
			(sheetname "")
		)
		(fill yes
			(thermal_gap 0.5)
			(thermal_bridge_width 0.5)
			(island_removal_mode 0)
		)
		(polygon
			(pts
				(arc
					(start 210.548728 -410.600144)
					(mid 210.000088 -410.051504)
					(end 209.451448 -410.600144)
				)
				(arc
					(start 209.451448 -412.000192)
					(mid 209.998818 -412.548831)
					(end 210.548728 -412.002732)
				)
				(arc
					(start 210.393788 -412.002732)
					(mid 210.000088 -412.3939)
					(end 209.606388 -412.002732)
				)
				(arc
					(start 209.606388 -412.000192)
					(mid 210.000088 -411.606492)
					(end 210.393788 -412.000192)
				)
				(xy 210.548728 -412.000192) (xy 210.548728 -410.602684)
				(arc
					(start 210.393788 -410.602684)
					(mid 210.000088 -410.993852)
					(end 209.606388 -410.602684)
				)
				(arc
					(start 209.606388 -410.600144)
					(mid 210.000088 -410.206444)
					(end 210.393788 -410.600144)
				)
			)
		)
	)
	(zone
		(layers "F.Cu" "B.Cu" "In2.Cu" "In4.Cu" "In7.Cu")
		(hatch none 0.5)
		(connect_pads
			(clearance 0)
		)
		(min_thickness 0.25)
		(keepout
			(tracks not_allowed)
			(vias allowed)
			(pads allowed)
			(copperpour not_allowed)
			(footprints allowed)
		)
		(placement
			(enabled no)
			(sheetname "")
		)
		(fill yes
			(thermal_gap 0.5)
			(thermal_bridge_width 0.5)
			(island_removal_mode 0)
		)
		(polygon
			(pts
				(arc
					(start 283.571696 -158.877)
					(mid 282.62492 -159.182185)
					(end 282.936442 -160.126934)
				)
				(arc
					(start 284.936438 -161.126932)
					(mid 285.617427 -161.096827)
					(end 285.950914 -160.502346)
				)
				(arc
					(start 285.795974 -160.502346)
					(mid 285.249874 -161.045912)
					(end 284.703774 -160.502346)
				)
				(arc
					(start 284.703774 -160.499806)
					(mid 285.249874 -159.953706)
					(end 285.795974 -160.499806)
				)
				(arc
					(start 285.950914 -160.499806)
					(mid 285.846184 -160.131199)
					(end 285.56331 -159.87268)
				)
				(xy 284.822646 -159.502348)
				(arc
					(start 283.795978 -159.502348)
					(mid 283.249878 -160.045914)
					(end 282.703778 -159.502348)
				)
				(arc
					(start 282.703778 -159.499808)
					(mid 283.249878 -158.953708)
					(end 283.795978 -159.499808)
				)
				(xy 284.817566 -159.499808)
			)
		)
	)
	(zone
		(layers "F.Cu" "B.Cu" "In2.Cu" "In4.Cu" "In7.Cu")
		(hatch none 0.5)
		(connect_pads
			(clearance 0)
		)
		(min_thickness 0.25)
		(keepout
			(tracks not_allowed)
			(vias allowed)
			(pads allowed)
			(copperpour not_allowed)
			(footprints allowed)
		)
		(placement
			(enabled no)
			(sheetname "")
		)
		(fill yes
			(thermal_gap 0.5)
			(thermal_bridge_width 0.5)
			(island_removal_mode 0)
		)
		(polygon
			(pts
				(arc
					(start 279.236678 -299.556424)
					(mid 278.688038 -300.105064)
					(end 279.236678 -300.653704)
				)
				(arc
					(start 280.636726 -300.653704)
					(mid 281.023774 -300.493908)
					(end 281.185366 -300.107604)
				)
				(arc
					(start 281.030426 -300.107604)
					(mid 280.636726 -300.498772)
					(end 280.243026 -300.107604)
				)
				(arc
					(start 279.630378 -300.107604)
					(mid 279.236678 -300.498772)
					(end 278.842978 -300.107604)
				)
				(arc
					(start 278.842978 -300.105064)
					(mid 279.236678 -299.711364)
					(end 279.630378 -300.105064)
				)
				(arc
					(start 280.243026 -300.105064)
					(mid 280.636726 -299.711364)
					(end 281.030426 -300.105064)
				)
				(arc
					(start 281.185366 -300.105064)
					(mid 281.024673 -299.717117)
					(end 280.636726 -299.556424)
				)
				(xy 279.236932 -299.556424)
			)
		)
	)
	(zone
		(layers "F.Cu" "B.Cu" "In2.Cu" "In4.Cu" "In7.Cu")
		(hatch none 0.5)
		(connect_pads
			(clearance 0)
		)
		(min_thickness 0.25)
		(keepout
			(tracks not_allowed)
			(vias allowed)
			(pads allowed)
			(copperpour not_allowed)
			(footprints allowed)
		)
		(placement
			(enabled no)
			(sheetname "")
		)
		(fill yes
			(thermal_gap 0.5)
			(thermal_bridge_width 0.5)
			(island_removal_mode 0)
		)
		(polygon
			(pts
				(arc
					(start 279.236678 -321.156584)
					(mid 278.688038 -321.705224)
					(end 279.236678 -322.253864)
				)
				(arc
					(start 280.636726 -322.253864)
					(mid 281.023774 -322.094068)
					(end 281.185366 -321.707764)
				)
				(arc
					(start 281.030426 -321.707764)
					(mid 280.636726 -322.098932)
					(end 280.243026 -321.707764)
				)
				(arc
					(start 279.630378 -321.707764)
					(mid 279.236678 -322.098932)
					(end 278.842978 -321.707764)
				)
				(arc
					(start 278.842978 -321.705224)
					(mid 279.236678 -321.311524)
					(end 279.630378 -321.705224)
				)
				(arc
					(start 280.243026 -321.705224)
					(mid 280.636726 -321.311524)
					(end 281.030426 -321.705224)
				)
				(arc
					(start 281.185366 -321.705224)
					(mid 281.024673 -321.317277)
					(end 280.636726 -321.156584)
				)
				(xy 279.236932 -321.156584)
			)
		)
	)
	(zone
		(layers "F.Cu" "B.Cu" "In2.Cu" "In4.Cu" "In7.Cu")
		(hatch none 0.5)
		(connect_pads
			(clearance 0)
		)
		(min_thickness 0.25)
		(keepout
			(tracks not_allowed)
			(vias allowed)
			(pads allowed)
			(copperpour not_allowed)
			(footprints allowed)
		)
		(placement
			(enabled no)
			(sheetname "")
		)
		(fill yes
			(thermal_gap 0.5)
			(thermal_bridge_width 0.5)
			(island_removal_mode 0)
		)
		(polygon
			(pts
				(arc
					(start 212.348826 -416.80003)
					(mid 211.800186 -416.25139)
					(end 211.251546 -416.80003)
				)
				(arc
					(start 211.251546 -418.200078)
					(mid 211.798916 -418.748717)
					(end 212.348826 -418.202618)
				)
				(arc
					(start 212.193886 -418.202618)
					(mid 211.800186 -418.593786)
					(end 211.406486 -418.202618)
				)
				(arc
					(start 211.406486 -418.200078)
					(mid 211.800186 -417.806378)
					(end 212.193886 -418.200078)
				)
				(xy 212.348826 -418.200078) (xy 212.348826 -416.80257)
				(arc
					(start 212.193886 -416.80257)
					(mid 211.800186 -417.193738)
					(end 211.406486 -416.80257)
				)
				(arc
					(start 211.406486 -416.80003)
					(mid 211.800186 -416.40633)
					(end 212.193886 -416.80003)
				)
			)
		)
	)
	(zone
		(layers "F.Cu" "B.Cu" "In2.Cu" "In4.Cu" "In7.Cu")
		(hatch none 0.5)
		(connect_pads
			(clearance 0)
		)
		(min_thickness 0.25)
		(keepout
			(tracks not_allowed)
			(vias allowed)
			(pads allowed)
			(copperpour not_allowed)
			(footprints allowed)
		)
		(placement
			(enabled no)
			(sheetname "")
		)
		(fill yes
			(thermal_gap 0.5)
			(thermal_bridge_width 0.5)
			(island_removal_mode 0)
		)
		(polygon
			(pts
				(arc
					(start 240.871756 -66.57721)
					(mid 239.92498 -66.882395)
					(end 240.236502 -67.827144)
				)
				(arc
					(start 242.236498 -68.827142)
					(mid 242.917487 -68.797037)
					(end 243.250974 -68.202556)
				)
				(arc
					(start 243.096034 -68.202556)
					(mid 242.549934 -68.746122)
					(end 242.003834 -68.202556)
				)
				(arc
					(start 242.003834 -68.200016)
					(mid 242.549934 -67.653916)
					(end 243.096034 -68.200016)
				)
				(arc
					(start 243.250974 -68.200016)
					(mid 243.146244 -67.831409)
					(end 242.86337 -67.57289)
				)
				(xy 242.122706 -67.202558)
				(arc
					(start 241.096038 -67.202558)
					(mid 240.549938 -67.746124)
					(end 240.003838 -67.202558)
				)
				(arc
					(start 240.003838 -67.200018)
					(mid 240.549938 -66.653918)
					(end 241.096038 -67.200018)
				)
				(xy 242.117626 -67.200018)
			)
		)
	)
	(zone
		(layers "F.Cu" "B.Cu" "In2.Cu" "In4.Cu" "In7.Cu")
		(hatch none 0.5)
		(connect_pads
			(clearance 0)
		)
		(min_thickness 0.25)
		(keepout
			(tracks not_allowed)
			(vias allowed)
			(pads allowed)
			(copperpour not_allowed)
			(footprints allowed)
		)
		(placement
			(enabled no)
			(sheetname "")
		)
		(fill yes
			(thermal_gap 0.5)
			(thermal_bridge_width 0.5)
			(island_removal_mode 0)
		)
		(polygon
			(pts
				(arc
					(start 240.871756 -82.577178)
					(mid 239.92498 -82.882363)
					(end 240.236502 -83.827112)
				)
				(arc
					(start 242.236498 -84.82711)
					(mid 242.917487 -84.797005)
					(end 243.250974 -84.202524)
				)
				(arc
					(start 243.096034 -84.202524)
					(mid 242.549934 -84.74609)
					(end 242.003834 -84.202524)
				)
				(arc
					(start 242.003834 -84.199984)
					(mid 242.549934 -83.653884)
					(end 243.096034 -84.199984)
				)
				(arc
					(start 243.250974 -84.199984)
					(mid 243.146244 -83.831377)
					(end 242.86337 -83.572858)
				)
				(xy 242.122706 -83.202526)
				(arc
					(start 241.096038 -83.202526)
					(mid 240.549938 -83.746092)
					(end 240.003838 -83.202526)
				)
				(arc
					(start 240.003838 -83.199986)
					(mid 240.549938 -82.653886)
					(end 241.096038 -83.199986)
				)
				(xy 242.117626 -83.199986)
			)
		)
	)
	(zone
		(layers "F.Cu" "B.Cu" "In2.Cu" "In4.Cu" "In7.Cu")
		(hatch none 0.5)
		(connect_pads
			(clearance 0)
		)
		(min_thickness 0.25)
		(keepout
			(tracks not_allowed)
			(vias allowed)
			(pads allowed)
			(copperpour not_allowed)
			(footprints allowed)
		)
		(placement
			(enabled no)
			(sheetname "")
		)
		(fill yes
			(thermal_gap 0.5)
			(thermal_bridge_width 0.5)
			(island_removal_mode 0)
		)
		(polygon
			(pts
				(arc
					(start 240.871756 -58.577226)
					(mid 239.92498 -58.882411)
					(end 240.236502 -59.82716)
				)
				(arc
					(start 242.236498 -60.827158)
					(mid 242.917487 -60.797053)
					(end 243.250974 -60.202572)
				)
				(arc
					(start 243.096034 -60.202572)
					(mid 242.549934 -60.746138)
					(end 242.003834 -60.202572)
				)
				(arc
					(start 242.003834 -60.200032)
					(mid 242.549934 -59.653932)
					(end 243.096034 -60.200032)
				)
				(arc
					(start 243.250974 -60.200032)
					(mid 243.146244 -59.831425)
					(end 242.86337 -59.572906)
				)
				(xy 242.122706 -59.202574)
				(arc
					(start 241.096038 -59.202574)
					(mid 240.549938 -59.74614)
					(end 240.003838 -59.202574)
				)
				(arc
					(start 240.003838 -59.200034)
					(mid 240.549938 -58.653934)
					(end 241.096038 -59.200034)
				)
				(xy 242.117626 -59.200034)
			)
		)
	)
	(zone
		(layers "F.Cu" "B.Cu" "In2.Cu" "In4.Cu" "In7.Cu")
		(hatch none 0.5)
		(connect_pads
			(clearance 0)
		)
		(min_thickness 0.25)
		(keepout
			(tracks not_allowed)
			(vias allowed)
			(pads allowed)
			(copperpour not_allowed)
			(footprints allowed)
		)
		(placement
			(enabled no)
			(sheetname "")
		)
		(fill yes
			(thermal_gap 0.5)
			(thermal_bridge_width 0.5)
			(island_removal_mode 0)
		)
		(polygon
			(pts
				(arc
					(start 283.563314 -178.872642)
					(mid 282.622752 -179.186332)
					(end 282.936442 -180.126894)
				)
				(arc
					(start 284.928056 -181.122574)
					(mid 285.613377 -181.099201)
					(end 285.950914 -180.502306)
				)
				(arc
					(start 285.795974 -180.502306)
					(mid 285.249874 -181.045872)
					(end 284.703774 -180.502306)
				)
				(arc
					(start 284.703774 -180.499766)
					(mid 285.249874 -179.953666)
					(end 285.795974 -180.499766)
				)
				(arc
					(start 285.950914 -180.499766)
					(mid 285.846184 -180.131159)
					(end 285.56331 -179.87264)
				)
				(xy 284.822646 -179.502308)
				(arc
					(start 283.795978 -179.502308)
					(mid 283.249878 -180.045874)
					(end 282.703778 -179.502308)
				)
				(arc
					(start 282.703778 -179.499768)
					(mid 283.249878 -178.953668)
					(end 283.795978 -179.499768)
				)
				(xy 284.817566 -179.499768)
			)
		)
	)
	(zone
		(layers "F.Cu" "B.Cu" "In2.Cu" "In4.Cu" "In7.Cu")
		(hatch none 0.5)
		(connect_pads
			(clearance 0)
		)
		(min_thickness 0.25)
		(keepout
			(tracks not_allowed)
			(vias allowed)
			(pads allowed)
			(copperpour not_allowed)
			(footprints allowed)
		)
		(placement
			(enabled no)
			(sheetname "")
		)
		(fill yes
			(thermal_gap 0.5)
			(thermal_bridge_width 0.5)
			(island_removal_mode 0)
		)
		(polygon
			(pts
				(arc
					(start 278.23668 -301.356522)
					(mid 277.68804 -301.905162)
					(end 278.23668 -302.453802)
				)
				(arc
					(start 279.636728 -302.453802)
					(mid 280.023776 -302.294006)
					(end 280.185368 -301.907702)
				)
				(arc
					(start 280.030428 -301.907702)
					(mid 279.636728 -302.29887)
					(end 279.243028 -301.907702)
				)
				(arc
					(start 278.63038 -301.907702)
					(mid 278.23668 -302.29887)
					(end 277.84298 -301.907702)
				)
				(arc
					(start 277.84298 -301.905162)
					(mid 278.23668 -301.511462)
					(end 278.63038 -301.905162)
				)
				(arc
					(start 279.243028 -301.905162)
					(mid 279.636728 -301.511462)
					(end 280.030428 -301.905162)
				)
				(arc
					(start 280.185368 -301.905162)
					(mid 280.024675 -301.517215)
					(end 279.636728 -301.356522)
				)
				(xy 278.236934 -301.356522)
			)
		)
	)
	(zone
		(layers "F.Cu" "B.Cu" "In2.Cu" "In4.Cu" "In7.Cu")
		(hatch none 0.5)
		(connect_pads
			(clearance 0)
		)
		(min_thickness 0.25)
		(keepout
			(tracks not_allowed)
			(vias allowed)
			(pads allowed)
			(copperpour not_allowed)
			(footprints allowed)
		)
		(placement
			(enabled no)
			(sheetname "")
		)
		(fill yes
			(thermal_gap 0.5)
			(thermal_bridge_width 0.5)
			(island_removal_mode 0)
		)
		(polygon
			(pts
				(arc
					(start 279.236678 -303.15662)
					(mid 278.688038 -303.70526)
					(end 279.236678 -304.2539)
				)
				(arc
					(start 280.636726 -304.2539)
					(mid 281.023774 -304.094104)
					(end 281.185366 -303.7078)
				)
				(arc
					(start 281.030426 -303.7078)
					(mid 280.636726 -304.098968)
					(end 280.243026 -303.7078)
				)
				(arc
					(start 279.630378 -303.7078)
					(mid 279.236678 -304.098968)
					(end 278.842978 -303.7078)
				)
				(arc
					(start 278.842978 -303.70526)
					(mid 279.236678 -303.31156)
					(end 279.630378 -303.70526)
				)
				(arc
					(start 280.243026 -303.70526)
					(mid 280.636726 -303.31156)
					(end 281.030426 -303.70526)
				)
				(arc
					(start 281.185366 -303.70526)
					(mid 281.024673 -303.317313)
					(end 280.636726 -303.15662)
				)
				(xy 279.236932 -303.15662)
			)
		)
	)
	(zone
		(layers "F.Cu" "B.Cu" "In2.Cu" "In4.Cu" "In7.Cu")
		(hatch none 0.5)
		(connect_pads
			(clearance 0)
		)
		(min_thickness 0.25)
		(keepout
			(tracks not_allowed)
			(vias allowed)
			(pads allowed)
			(copperpour not_allowed)
			(footprints allowed)
		)
		(placement
			(enabled no)
			(sheetname "")
		)
		(fill yes
			(thermal_gap 0.5)
			(thermal_bridge_width 0.5)
			(island_removal_mode 0)
		)
		(polygon
			(pts
				(arc
					(start 240.871756 -38.577266)
					(mid 239.92498 -38.882451)
					(end 240.236502 -39.8272)
				)
				(arc
					(start 242.236498 -40.827198)
					(mid 242.917487 -40.797093)
					(end 243.250974 -40.202612)
				)
				(arc
					(start 243.096034 -40.202612)
					(mid 242.549934 -40.746178)
					(end 242.003834 -40.202612)
				)
				(arc
					(start 242.003834 -40.200072)
					(mid 242.549934 -39.653972)
					(end 243.096034 -40.200072)
				)
				(arc
					(start 243.250974 -40.200072)
					(mid 243.146244 -39.831465)
					(end 242.86337 -39.572946)
				)
				(xy 242.122706 -39.202614)
				(arc
					(start 241.096038 -39.202614)
					(mid 240.549938 -39.74618)
					(end 240.003838 -39.202614)
				)
				(arc
					(start 240.003838 -39.200074)
					(mid 240.549938 -38.653974)
					(end 241.096038 -39.200074)
				)
				(xy 242.117626 -39.200074)
			)
		)
	)
	(zone
		(layers "F.Cu" "B.Cu" "In2.Cu" "In4.Cu" "In7.Cu")
		(hatch none 0.5)
		(connect_pads
			(clearance 0)
		)
		(min_thickness 0.25)
		(keepout
			(tracks not_allowed)
			(vias allowed)
			(pads allowed)
			(copperpour not_allowed)
			(footprints allowed)
		)
		(placement
			(enabled no)
			(sheetname "")
		)
		(fill yes
			(thermal_gap 0.5)
			(thermal_bridge_width 0.5)
			(island_removal_mode 0)
		)
		(polygon
			(pts
				(arc
					(start 240.863374 -78.572868)
					(mid 239.922812 -78.886558)
					(end 240.236502 -79.82712)
				)
				(arc
					(start 242.228116 -80.8228)
					(mid 242.913437 -80.799427)
					(end 243.250974 -80.202532)
				)
				(arc
					(start 243.096034 -80.202532)
					(mid 242.549934 -80.746098)
					(end 242.003834 -80.202532)
				)
				(arc
					(start 242.003834 -80.199992)
					(mid 242.549934 -79.653892)
					(end 243.096034 -80.199992)
				)
				(arc
					(start 243.250974 -80.199992)
					(mid 243.146244 -79.831385)
					(end 242.86337 -79.572866)
				)
				(xy 242.122706 -79.202534)
				(arc
					(start 241.096038 -79.202534)
					(mid 240.549938 -79.7461)
					(end 240.003838 -79.202534)
				)
				(arc
					(start 240.003838 -79.199994)
					(mid 240.549938 -78.653894)
					(end 241.096038 -79.199994)
				)
				(xy 242.117626 -79.199994)
			)
		)
	)
	(zone
		(layers "F.Cu" "B.Cu" "In2.Cu" "In4.Cu" "In7.Cu")
		(hatch none 0.5)
		(connect_pads
			(clearance 0)
		)
		(min_thickness 0.25)
		(keepout
			(tracks not_allowed)
			(vias allowed)
			(pads allowed)
			(copperpour not_allowed)
			(footprints allowed)
		)
		(placement
			(enabled no)
			(sheetname "")
		)
		(fill yes
			(thermal_gap 0.5)
			(thermal_bridge_width 0.5)
			(island_removal_mode 0)
		)
		(polygon
			(pts
				(arc
					(start 240.871756 -46.57725)
					(mid 239.92498 -46.882435)
					(end 240.236502 -47.827184)
				)
				(arc
					(start 242.236498 -48.827182)
					(mid 242.917487 -48.797077)
					(end 243.250974 -48.202596)
				)
				(arc
					(start 243.096034 -48.202596)
					(mid 242.549934 -48.746162)
					(end 242.003834 -48.202596)
				)
				(arc
					(start 242.003834 -48.200056)
					(mid 242.549934 -47.653956)
					(end 243.096034 -48.200056)
				)
				(arc
					(start 243.250974 -48.200056)
					(mid 243.146244 -47.831449)
					(end 242.86337 -47.57293)
				)
				(xy 242.122706 -47.202598)
				(arc
					(start 241.096038 -47.202598)
					(mid 240.549938 -47.746164)
					(end 240.003838 -47.202598)
				)
				(arc
					(start 240.003838 -47.200058)
					(mid 240.549938 -46.653958)
					(end 241.096038 -47.200058)
				)
				(xy 242.117626 -47.200058)
			)
		)
	)
	(zone
		(layers "F.Cu" "B.Cu" "In2.Cu" "In4.Cu" "In7.Cu")
		(hatch none 0.5)
		(connect_pads
			(clearance 0)
		)
		(min_thickness 0.25)
		(keepout
			(tracks not_allowed)
			(vias allowed)
			(pads allowed)
			(copperpour not_allowed)
			(footprints allowed)
		)
		(placement
			(enabled no)
			(sheetname "")
		)
		(fill yes
			(thermal_gap 0.5)
			(thermal_bridge_width 0.5)
			(island_removal_mode 0)
		)
		(polygon
			(pts
				(arc
					(start 279.236678 -317.556388)
					(mid 278.688038 -318.105028)
					(end 279.236678 -318.653668)
				)
				(arc
					(start 280.636726 -318.653668)
					(mid 281.023774 -318.493872)
					(end 281.185366 -318.107568)
				)
				(arc
					(start 281.030426 -318.107568)
					(mid 280.636726 -318.498736)
					(end 280.243026 -318.107568)
				)
				(arc
					(start 279.630378 -318.107568)
					(mid 279.236678 -318.498736)
					(end 278.842978 -318.107568)
				)
				(arc
					(start 278.842978 -318.105028)
					(mid 279.236678 -317.711328)
					(end 279.630378 -318.105028)
				)
				(arc
					(start 280.243026 -318.105028)
					(mid 280.636726 -317.711328)
					(end 281.030426 -318.105028)
				)
				(arc
					(start 281.185366 -318.105028)
					(mid 281.024673 -317.717081)
					(end 280.636726 -317.556388)
				)
				(xy 279.236932 -317.556388)
			)
		)
	)
	(zone
		(layers "F.Cu" "B.Cu" "In2.Cu" "In4.Cu" "In7.Cu")
		(hatch none 0.5)
		(connect_pads
			(clearance 0)
		)
		(min_thickness 0.25)
		(keepout
			(tracks not_allowed)
			(vias allowed)
			(pads allowed)
			(copperpour not_allowed)
			(footprints allowed)
		)
		(placement
			(enabled no)
			(sheetname "")
		)
		(fill yes
			(thermal_gap 0.5)
			(thermal_bridge_width 0.5)
			(island_removal_mode 0)
		)
		(polygon
			(pts
				(arc
					(start 283.563314 -126.872746)
					(mid 282.622752 -127.186436)
					(end 282.936442 -128.126998)
				)
				(arc
					(start 284.928056 -129.122678)
					(mid 285.613377 -129.099305)
					(end 285.950914 -128.50241)
				)
				(arc
					(start 285.795974 -128.50241)
					(mid 285.249874 -129.045976)
					(end 284.703774 -128.50241)
				)
				(arc
					(start 284.703774 -128.49987)
					(mid 285.249874 -127.95377)
					(end 285.795974 -128.49987)
				)
				(arc
					(start 285.950914 -128.49987)
					(mid 285.846184 -128.131263)
					(end 285.56331 -127.872744)
				)
				(xy 284.822646 -127.502412)
				(arc
					(start 283.795978 -127.502412)
					(mid 283.249878 -128.045978)
					(end 282.703778 -127.502412)
				)
				(arc
					(start 282.703778 -127.499872)
					(mid 283.249878 -126.953772)
					(end 283.795978 -127.499872)
				)
				(xy 284.817566 -127.499872)
			)
		)
	)
	(zone
		(layers "F.Cu" "B.Cu" "In2.Cu" "In4.Cu" "In7.Cu")
		(hatch none 0.5)
		(connect_pads
			(clearance 0)
		)
		(min_thickness 0.25)
		(keepout
			(tracks not_allowed)
			(vias allowed)
			(pads allowed)
			(copperpour not_allowed)
			(footprints allowed)
		)
		(placement
			(enabled no)
			(sheetname "")
		)
		(fill yes
			(thermal_gap 0.5)
			(thermal_bridge_width 0.5)
			(island_removal_mode 0)
		)
		(polygon
			(pts
				(arc
					(start 240.871756 -42.577258)
					(mid 239.92498 -42.882443)
					(end 240.236502 -43.827192)
				)
				(arc
					(start 242.236498 -44.82719)
					(mid 242.917487 -44.797085)
					(end 243.250974 -44.202604)
				)
				(arc
					(start 243.096034 -44.202604)
					(mid 242.549934 -44.74617)
					(end 242.003834 -44.202604)
				)
				(arc
					(start 242.003834 -44.200064)
					(mid 242.549934 -43.653964)
					(end 243.096034 -44.200064)
				)
				(arc
					(start 243.250974 -44.200064)
					(mid 243.146244 -43.831457)
					(end 242.86337 -43.572938)
				)
				(xy 242.122706 -43.202606)
				(arc
					(start 241.096038 -43.202606)
					(mid 240.549938 -43.746172)
					(end 240.003838 -43.202606)
				)
				(arc
					(start 240.003838 -43.200066)
					(mid 240.549938 -42.653966)
					(end 241.096038 -43.200066)
				)
				(xy 242.117626 -43.200066)
			)
		)
	)
	(zone
		(layers "F.Cu" "B.Cu" "In2.Cu" "In4.Cu" "In7.Cu")
		(hatch none 0.5)
		(connect_pads
			(clearance 0)
		)
		(min_thickness 0.25)
		(keepout
			(tracks not_allowed)
			(vias allowed)
			(pads allowed)
			(copperpour not_allowed)
			(footprints allowed)
		)
		(placement
			(enabled no)
			(sheetname "")
		)
		(fill yes
			(thermal_gap 0.5)
			(thermal_bridge_width 0.5)
			(island_removal_mode 0)
		)
		(polygon
			(pts
				(arc
					(start 279.236678 -346.356432)
					(mid 278.688038 -346.905072)
					(end 279.236678 -347.453712)
				)
				(arc
					(start 280.636726 -347.453712)
					(mid 281.023774 -347.293916)
					(end 281.185366 -346.907612)
				)
				(arc
					(start 281.030426 -346.907612)
					(mid 280.636726 -347.29878)
					(end 280.243026 -346.907612)
				)
				(arc
					(start 279.630378 -346.907612)
					(mid 279.236678 -347.29878)
					(end 278.842978 -346.907612)
				)
				(arc
					(start 278.842978 -346.905072)
					(mid 279.236678 -346.511372)
					(end 279.630378 -346.905072)
				)
				(arc
					(start 280.243026 -346.905072)
					(mid 280.636726 -346.511372)
					(end 281.030426 -346.905072)
				)
				(arc
					(start 281.185366 -346.905072)
					(mid 281.024673 -346.517125)
					(end 280.636726 -346.356432)
				)
				(xy 279.236932 -346.356432)
			)
		)
	)
	(zone
		(layers "F.Cu" "B.Cu" "In2.Cu" "In4.Cu" "In7.Cu")
		(hatch none 0.5)
		(connect_pads
			(clearance 0)
		)
		(min_thickness 0.25)
		(keepout
			(tracks not_allowed)
			(vias allowed)
			(pads allowed)
			(copperpour not_allowed)
			(footprints allowed)
		)
		(placement
			(enabled no)
			(sheetname "")
		)
		(fill yes
			(thermal_gap 0.5)
			(thermal_bridge_width 0.5)
			(island_removal_mode 0)
		)
		(polygon
			(pts
				(arc
					(start 283.563314 -122.872754)
					(mid 282.622752 -123.186444)
					(end 282.936442 -124.127006)
				)
				(arc
					(start 284.928056 -125.122686)
					(mid 285.613377 -125.099313)
					(end 285.950914 -124.502418)
				)
				(arc
					(start 285.795974 -124.502418)
					(mid 285.249874 -125.045984)
					(end 284.703774 -124.502418)
				)
				(arc
					(start 284.703774 -124.499878)
					(mid 285.249874 -123.953778)
					(end 285.795974 -124.499878)
				)
				(arc
					(start 285.950914 -124.499878)
					(mid 285.846184 -124.131271)
					(end 285.56331 -123.872752)
				)
				(xy 284.822646 -123.50242)
				(arc
					(start 283.795978 -123.50242)
					(mid 283.249878 -124.045986)
					(end 282.703778 -123.50242)
				)
				(arc
					(start 282.703778 -123.49988)
					(mid 283.249878 -122.95378)
					(end 283.795978 -123.49988)
				)
				(xy 284.817566 -123.49988)
			)
		)
	)
	(zone
		(layers "F.Cu" "B.Cu" "In2.Cu" "In4.Cu" "In7.Cu")
		(hatch none 0.5)
		(connect_pads
			(clearance 0)
		)
		(min_thickness 0.25)
		(keepout
			(tracks not_allowed)
			(vias allowed)
			(pads allowed)
			(copperpour not_allowed)
			(footprints allowed)
		)
		(placement
			(enabled no)
			(sheetname "")
		)
		(fill yes
			(thermal_gap 0.5)
			(thermal_bridge_width 0.5)
			(island_removal_mode 0)
		)
		(polygon
			(pts
				(arc
					(start 283.563314 -114.87277)
					(mid 282.622752 -115.18646)
					(end 282.936442 -116.127022)
				)
				(arc
					(start 284.928056 -117.122702)
					(mid 285.613377 -117.099329)
					(end 285.950914 -116.502434)
				)
				(arc
					(start 285.795974 -116.502434)
					(mid 285.249874 -117.046)
					(end 284.703774 -116.502434)
				)
				(arc
					(start 284.703774 -116.499894)
					(mid 285.249874 -115.953794)
					(end 285.795974 -116.499894)
				)
				(arc
					(start 285.950914 -116.499894)
					(mid 285.846184 -116.131287)
					(end 285.56331 -115.872768)
				)
				(xy 284.822646 -115.502436)
				(arc
					(start 283.795978 -115.502436)
					(mid 283.249878 -116.046002)
					(end 282.703778 -115.502436)
				)
				(arc
					(start 282.703778 -115.499896)
					(mid 283.249878 -114.953796)
					(end 283.795978 -115.499896)
				)
				(xy 284.817566 -115.499896)
			)
		)
	)
	(zone
		(layers "F.Cu" "B.Cu" "In2.Cu" "In4.Cu" "In7.Cu")
		(hatch none 0.5)
		(connect_pads
			(clearance 0)
		)
		(min_thickness 0.25)
		(keepout
			(tracks not_allowed)
			(vias allowed)
			(pads allowed)
			(copperpour not_allowed)
			(footprints allowed)
		)
		(placement
			(enabled no)
			(sheetname "")
		)
		(fill yes
			(thermal_gap 0.5)
			(thermal_bridge_width 0.5)
			(island_removal_mode 0)
		)
		(polygon
			(pts
				(arc
					(start 279.236678 -339.156548)
					(mid 278.688038 -339.705188)
					(end 279.236678 -340.253828)
				)
				(arc
					(start 280.636726 -340.253828)
					(mid 281.023774 -340.094032)
					(end 281.185366 -339.707728)
				)
				(arc
					(start 281.030426 -339.707728)
					(mid 280.636726 -340.098896)
					(end 280.243026 -339.707728)
				)
				(arc
					(start 279.630378 -339.707728)
					(mid 279.236678 -340.098896)
					(end 278.842978 -339.707728)
				)
				(arc
					(start 278.842978 -339.705188)
					(mid 279.236678 -339.311488)
					(end 279.630378 -339.705188)
				)
				(arc
					(start 280.243026 -339.705188)
					(mid 280.636726 -339.311488)
					(end 281.030426 -339.705188)
				)
				(arc
					(start 281.185366 -339.705188)
					(mid 281.024673 -339.317241)
					(end 280.636726 -339.156548)
				)
				(xy 279.236932 -339.156548)
			)
		)
	)
	(zone
		(layers "F.Cu" "B.Cu" "In2.Cu" "In4.Cu" "In7.Cu")
		(hatch none 0.5)
		(connect_pads
			(clearance 0)
		)
		(min_thickness 0.25)
		(keepout
			(tracks not_allowed)
			(vias allowed)
			(pads allowed)
			(copperpour not_allowed)
			(footprints allowed)
		)
		(placement
			(enabled no)
			(sheetname "")
		)
		(fill yes
			(thermal_gap 0.5)
			(thermal_bridge_width 0.5)
			(island_removal_mode 0)
		)
		(polygon
			(pts
				(arc
					(start 217.748612 -414.200086)
					(mid 217.199972 -413.651446)
					(end 216.651332 -414.200086)
				)
				(arc
					(start 216.651332 -415.600134)
					(mid 217.198702 -416.148773)
					(end 217.748612 -415.602674)
				)
				(arc
					(start 217.593672 -415.602674)
					(mid 217.199972 -415.993842)
					(end 216.806272 -415.602674)
				)
				(arc
					(start 216.806272 -415.600134)
					(mid 217.199972 -415.206434)
					(end 217.593672 -415.600134)
				)
				(xy 217.748612 -415.600134) (xy 217.748612 -414.202626)
				(arc
					(start 217.593672 -414.202626)
					(mid 217.199972 -414.593794)
					(end 216.806272 -414.202626)
				)
				(arc
					(start 216.806272 -414.200086)
					(mid 217.199972 -413.806386)
					(end 217.593672 -414.200086)
				)
			)
		)
	)
	(zone
		(layers "F.Cu" "B.Cu" "In2.Cu" "In4.Cu" "In7.Cu")
		(hatch none 0.5)
		(connect_pads
			(clearance 0)
		)
		(min_thickness 0.25)
		(keepout
			(tracks not_allowed)
			(vias allowed)
			(pads allowed)
			(copperpour not_allowed)
			(footprints allowed)
		)
		(placement
			(enabled no)
			(sheetname "")
		)
		(fill yes
			(thermal_gap 0.5)
			(thermal_bridge_width 0.5)
			(island_removal_mode 0)
		)
		(polygon
			(pts
				(arc
					(start 240.871756 -166.876984)
					(mid 239.92498 -167.182169)
					(end 240.236502 -168.126918)
				)
				(arc
					(start 242.236498 -169.126916)
					(mid 242.917487 -169.096811)
					(end 243.250974 -168.50233)
				)
				(arc
					(start 243.096034 -168.50233)
					(mid 242.549934 -169.045896)
					(end 242.003834 -168.50233)
				)
				(arc
					(start 242.003834 -168.49979)
					(mid 242.549934 -167.95369)
					(end 243.096034 -168.49979)
				)
				(arc
					(start 243.250974 -168.49979)
					(mid 243.146244 -168.131183)
					(end 242.86337 -167.872664)
				)
				(xy 242.122706 -167.502332)
				(arc
					(start 241.096038 -167.502332)
					(mid 240.549938 -168.045898)
					(end 240.003838 -167.502332)
				)
				(arc
					(start 240.003838 -167.499792)
					(mid 240.549938 -166.953692)
					(end 241.096038 -167.499792)
				)
				(xy 242.117626 -167.499792)
			)
		)
	)
	(zone
		(layers "F.Cu" "B.Cu" "In2.Cu" "In4.Cu" "In7.Cu")
		(hatch none 0.5)
		(connect_pads
			(clearance 0)
		)
		(min_thickness 0.25)
		(keepout
			(tracks not_allowed)
			(vias allowed)
			(pads allowed)
			(copperpour not_allowed)
			(footprints allowed)
		)
		(placement
			(enabled no)
			(sheetname "")
		)
		(fill yes
			(thermal_gap 0.5)
			(thermal_bridge_width 0.5)
			(island_removal_mode 0)
		)
		(polygon
			(pts
				(arc
					(start 240.863374 -70.572884)
					(mid 239.922812 -70.886574)
					(end 240.236502 -71.827136)
				)
				(arc
					(start 242.228116 -72.822816)
					(mid 242.913437 -72.799443)
					(end 243.250974 -72.202548)
				)
				(arc
					(start 243.096034 -72.202548)
					(mid 242.549934 -72.746114)
					(end 242.003834 -72.202548)
				)
				(arc
					(start 242.003834 -72.200008)
					(mid 242.549934 -71.653908)
					(end 243.096034 -72.200008)
				)
				(arc
					(start 243.250974 -72.200008)
					(mid 243.146244 -71.831401)
					(end 242.86337 -71.572882)
				)
				(xy 242.122706 -71.20255)
				(arc
					(start 241.096038 -71.20255)
					(mid 240.549938 -71.746116)
					(end 240.003838 -71.20255)
				)
				(arc
					(start 240.003838 -71.20001)
					(mid 240.549938 -70.65391)
					(end 241.096038 -71.20001)
				)
				(xy 242.117626 -71.20001)
			)
		)
	)
	(zone
		(layers "F.Cu" "B.Cu" "In2.Cu" "In4.Cu" "In7.Cu")
		(hatch none 0.5)
		(connect_pads
			(clearance 0)
		)
		(min_thickness 0.25)
		(keepout
			(tracks not_allowed)
			(vias allowed)
			(pads allowed)
			(copperpour not_allowed)
			(footprints allowed)
		)
		(placement
			(enabled no)
			(sheetname "")
		)
		(fill yes
			(thermal_gap 0.5)
			(thermal_bridge_width 0.5)
			(island_removal_mode 0)
		)
		(polygon
			(pts
				(arc
					(start 210.548728 -414.200086)
					(mid 210.000088 -413.651446)
					(end 209.451448 -414.200086)
				)
				(arc
					(start 209.451448 -415.600134)
					(mid 209.998818 -416.148773)
					(end 210.548728 -415.602674)
				)
				(arc
					(start 210.393788 -415.602674)
					(mid 210.000088 -415.993842)
					(end 209.606388 -415.602674)
				)
				(arc
					(start 209.606388 -415.600134)
					(mid 210.000088 -415.206434)
					(end 210.393788 -415.600134)
				)
				(xy 210.548728 -415.600134) (xy 210.548728 -414.202626)
				(arc
					(start 210.393788 -414.202626)
					(mid 210.000088 -414.593794)
					(end 209.606388 -414.202626)
				)
				(arc
					(start 209.606388 -414.200086)
					(mid 210.000088 -413.806386)
					(end 210.393788 -414.200086)
				)
			)
		)
	)
	(zone
		(layers "F.Cu" "B.Cu" "In2.Cu" "In4.Cu" "In7.Cu")
		(hatch none 0.5)
		(connect_pads
			(clearance 0)
		)
		(min_thickness 0.25)
		(keepout
			(tracks not_allowed)
			(vias allowed)
			(pads allowed)
			(copperpour not_allowed)
			(footprints allowed)
		)
		(placement
			(enabled no)
			(sheetname "")
		)
		(fill yes
			(thermal_gap 0.5)
			(thermal_bridge_width 0.5)
			(island_removal_mode 0)
		)
		(polygon
			(pts
				(arc
					(start 240.863374 -74.572876)
					(mid 239.922812 -74.886566)
					(end 240.236502 -75.827128)
				)
				(arc
					(start 242.228116 -76.822808)
					(mid 242.913437 -76.799435)
					(end 243.250974 -76.20254)
				)
				(arc
					(start 243.096034 -76.20254)
					(mid 242.549934 -76.746106)
					(end 242.003834 -76.20254)
				)
				(arc
					(start 242.003834 -76.2)
					(mid 242.549934 -75.6539)
					(end 243.096034 -76.2)
				)
				(arc
					(start 243.250974 -76.2)
					(mid 243.146244 -75.831393)
					(end 242.86337 -75.572874)
				)
				(xy 242.122706 -75.202542)
				(arc
					(start 241.096038 -75.202542)
					(mid 240.549938 -75.746108)
					(end 240.003838 -75.202542)
				)
				(arc
					(start 240.003838 -75.200002)
					(mid 240.549938 -74.653902)
					(end 241.096038 -75.200002)
				)
				(xy 242.117626 -75.200002)
			)
		)
	)
	(zone
		(layers "F.Cu" "B.Cu" "In2.Cu" "In4.Cu" "In7.Cu")
		(hatch none 0.5)
		(connect_pads
			(clearance 0)
		)
		(min_thickness 0.25)
		(keepout
			(tracks not_allowed)
			(vias allowed)
			(pads allowed)
			(copperpour not_allowed)
			(footprints allowed)
		)
		(placement
			(enabled no)
			(sheetname "")
		)
		(fill yes
			(thermal_gap 0.5)
			(thermal_bridge_width 0.5)
			(island_removal_mode 0)
		)
		(polygon
			(pts
				(arc
					(start 279.236678 -342.75649)
					(mid 278.688038 -343.30513)
					(end 279.236678 -343.85377)
				)
				(arc
					(start 280.636726 -343.85377)
					(mid 281.023774 -343.693974)
					(end 281.185366 -343.30767)
				)
				(arc
					(start 281.030426 -343.30767)
					(mid 280.636726 -343.698838)
					(end 280.243026 -343.30767)
				)
				(arc
					(start 279.630378 -343.30767)
					(mid 279.236678 -343.698838)
					(end 278.842978 -343.30767)
				)
				(arc
					(start 278.842978 -343.30513)
					(mid 279.236678 -342.91143)
					(end 279.630378 -343.30513)
				)
				(arc
					(start 280.243026 -343.30513)
					(mid 280.636726 -342.91143)
					(end 281.030426 -343.30513)
				)
				(arc
					(start 281.185366 -343.30513)
					(mid 281.024673 -342.917183)
					(end 280.636726 -342.75649)
				)
				(xy 279.236932 -342.75649)
			)
		)
	)
	(zone
		(layers "F.Cu" "B.Cu" "In2.Cu" "In4.Cu" "In7.Cu")
		(hatch none 0.5)
		(connect_pads
			(clearance 0)
		)
		(min_thickness 0.25)
		(keepout
			(tracks not_allowed)
			(vias allowed)
			(pads allowed)
			(copperpour not_allowed)
			(footprints allowed)
		)
		(placement
			(enabled no)
			(sheetname "")
		)
		(fill yes
			(thermal_gap 0.5)
			(thermal_bridge_width 0.5)
			(island_removal_mode 0)
		)
		(polygon
			(pts
				(arc
					(start 283.563314 -54.572916)
					(mid 282.622752 -54.886606)
					(end 282.936442 -55.827168)
				)
				(arc
					(start 284.928056 -56.822848)
					(mid 285.613377 -56.799475)
					(end 285.950914 -56.20258)
				)
				(arc
					(start 285.795974 -56.20258)
					(mid 285.249874 -56.746146)
					(end 284.703774 -56.20258)
				)
				(arc
					(start 284.703774 -56.20004)
					(mid 285.249874 -55.65394)
					(end 285.795974 -56.20004)
				)
				(arc
					(start 285.950914 -56.20004)
					(mid 285.846184 -55.831433)
					(end 285.56331 -55.572914)
				)
				(xy 284.822646 -55.202582)
				(arc
					(start 283.795978 -55.202582)
					(mid 283.249878 -55.746148)
					(end 282.703778 -55.202582)
				)
				(arc
					(start 282.703778 -55.200042)
					(mid 283.249878 -54.653942)
					(end 283.795978 -55.200042)
				)
				(xy 284.817566 -55.200042)
			)
		)
	)
	(zone
		(layers "F.Cu" "B.Cu" "In2.Cu" "In4.Cu" "In7.Cu")
		(hatch none 0.5)
		(connect_pads
			(clearance 0)
		)
		(min_thickness 0.25)
		(keepout
			(tracks not_allowed)
			(vias allowed)
			(pads allowed)
			(copperpour not_allowed)
			(footprints allowed)
		)
		(placement
			(enabled no)
			(sheetname "")
		)
		(fill yes
			(thermal_gap 0.5)
			(thermal_bridge_width 0.5)
			(island_removal_mode 0)
		)
		(polygon
			(pts
				(arc
					(start 278.23668 -322.956428)
					(mid 277.68804 -323.505068)
					(end 278.23668 -324.053708)
				)
				(arc
					(start 279.636728 -324.053708)
					(mid 280.023776 -323.893912)
					(end 280.185368 -323.507608)
				)
				(arc
					(start 280.030428 -323.507608)
					(mid 279.636728 -323.898776)
					(end 279.243028 -323.507608)
				)
				(arc
					(start 278.63038 -323.507608)
					(mid 278.23668 -323.898776)
					(end 277.84298 -323.507608)
				)
				(arc
					(start 277.84298 -323.505068)
					(mid 278.23668 -323.111368)
					(end 278.63038 -323.505068)
				)
				(arc
					(start 279.243028 -323.505068)
					(mid 279.636728 -323.111368)
					(end 280.030428 -323.505068)
				)
				(arc
					(start 280.185368 -323.505068)
					(mid 280.024675 -323.117121)
					(end 279.636728 -322.956428)
				)
				(xy 278.236934 -322.956428)
			)
		)
	)
	(zone
		(layers "F.Cu" "B.Cu" "In2.Cu" "In4.Cu" "In7.Cu")
		(hatch none 0.5)
		(connect_pads
			(clearance 0)
		)
		(min_thickness 0.25)
		(keepout
			(tracks not_allowed)
			(vias allowed)
			(pads allowed)
			(copperpour not_allowed)
			(footprints allowed)
		)
		(placement
			(enabled no)
			(sheetname "")
		)
		(fill yes
			(thermal_gap 0.5)
			(thermal_bridge_width 0.5)
			(island_removal_mode 0)
		)
		(polygon
			(pts
				(arc
					(start 283.563314 -118.872762)
					(mid 282.622752 -119.186452)
					(end 282.936442 -120.127014)
				)
				(arc
					(start 284.928056 -121.122694)
					(mid 285.613377 -121.099321)
					(end 285.950914 -120.502426)
				)
				(arc
					(start 285.795974 -120.502426)
					(mid 285.249874 -121.045992)
					(end 284.703774 -120.502426)
				)
				(arc
					(start 284.703774 -120.499886)
					(mid 285.249874 -119.953786)
					(end 285.795974 -120.499886)
				)
				(arc
					(start 285.950914 -120.499886)
					(mid 285.846184 -120.131279)
					(end 285.56331 -119.87276)
				)
				(xy 284.822646 -119.502428)
				(arc
					(start 283.795978 -119.502428)
					(mid 283.249878 -120.045994)
					(end 282.703778 -119.502428)
				)
				(arc
					(start 282.703778 -119.499888)
					(mid 283.249878 -118.953788)
					(end 283.795978 -119.499888)
				)
				(xy 284.817566 -119.499888)
			)
		)
	)
	(zone
		(layers "F.Cu" "B.Cu" "In2.Cu" "In4.Cu" "In7.Cu")
		(hatch none 0.5)
		(connect_pads
			(clearance 0)
		)
		(min_thickness 0.25)
		(keepout
			(tracks not_allowed)
			(vias allowed)
			(pads allowed)
			(copperpour not_allowed)
			(footprints allowed)
		)
		(placement
			(enabled no)
			(sheetname "")
		)
		(fill yes
			(thermal_gap 0.5)
			(thermal_bridge_width 0.5)
			(island_removal_mode 0)
		)
		(polygon
			(pts
				(arc
					(start 283.563314 -42.57294)
					(mid 282.622752 -42.88663)
					(end 282.936442 -43.827192)
				)
				(arc
					(start 284.928056 -44.822872)
					(mid 285.613377 -44.799499)
					(end 285.950914 -44.202604)
				)
				(arc
					(start 285.795974 -44.202604)
					(mid 285.249874 -44.74617)
					(end 284.703774 -44.202604)
				)
				(arc
					(start 284.703774 -44.200064)
					(mid 285.249874 -43.653964)
					(end 285.795974 -44.200064)
				)
				(arc
					(start 285.950914 -44.200064)
					(mid 285.846184 -43.831457)
					(end 285.56331 -43.572938)
				)
				(xy 284.822646 -43.202606)
				(arc
					(start 283.795978 -43.202606)
					(mid 283.249878 -43.746172)
					(end 282.703778 -43.202606)
				)
				(arc
					(start 282.703778 -43.200066)
					(mid 283.249878 -42.653966)
					(end 283.795978 -43.200066)
				)
				(xy 284.817566 -43.200066)
			)
		)
	)
	(zone
		(layers "F.Cu" "B.Cu" "In2.Cu" "In4.Cu" "In7.Cu")
		(hatch none 0.5)
		(connect_pads
			(clearance 0)
		)
		(min_thickness 0.25)
		(keepout
			(tracks not_allowed)
			(vias allowed)
			(pads allowed)
			(copperpour not_allowed)
			(footprints allowed)
		)
		(placement
			(enabled no)
			(sheetname "")
		)
		(fill yes
			(thermal_gap 0.5)
			(thermal_bridge_width 0.5)
			(island_removal_mode 0)
		)
		(polygon
			(pts
				(arc
					(start 283.563314 -74.572876)
					(mid 282.622752 -74.886566)
					(end 282.936442 -75.827128)
				)
				(arc
					(start 284.928056 -76.822808)
					(mid 285.613377 -76.799435)
					(end 285.950914 -76.20254)
				)
				(arc
					(start 285.795974 -76.20254)
					(mid 285.249874 -76.746106)
					(end 284.703774 -76.20254)
				)
				(arc
					(start 284.703774 -76.2)
					(mid 285.249874 -75.6539)
					(end 285.795974 -76.2)
				)
				(arc
					(start 285.950914 -76.2)
					(mid 285.846184 -75.831393)
					(end 285.56331 -75.572874)
				)
				(xy 284.822646 -75.202542)
				(arc
					(start 283.795978 -75.202542)
					(mid 283.249878 -75.746108)
					(end 282.703778 -75.202542)
				)
				(arc
					(start 282.703778 -75.200002)
					(mid 283.249878 -74.653902)
					(end 283.795978 -75.200002)
				)
				(xy 284.817566 -75.200002)
			)
		)
	)
	(zone
		(layers "F.Cu" "B.Cu" "In2.Cu" "In4.Cu" "In7.Cu")
		(hatch none 0.5)
		(connect_pads
			(clearance 0)
		)
		(min_thickness 0.25)
		(keepout
			(tracks not_allowed)
			(vias allowed)
			(pads allowed)
			(copperpour not_allowed)
			(footprints allowed)
		)
		(placement
			(enabled no)
			(sheetname "")
		)
		(fill yes
			(thermal_gap 0.5)
			(thermal_bridge_width 0.5)
			(island_removal_mode 0)
		)
		(polygon
			(pts
				(arc
					(start 214.14867 -414.200086)
					(mid 213.60003 -413.651446)
					(end 213.05139 -414.200086)
				)
				(arc
					(start 213.05139 -415.600134)
					(mid 213.59876 -416.148773)
					(end 214.14867 -415.602674)
				)
				(arc
					(start 213.99373 -415.602674)
					(mid 213.60003 -415.993842)
					(end 213.20633 -415.602674)
				)
				(arc
					(start 213.20633 -415.600134)
					(mid 213.60003 -415.206434)
					(end 213.99373 -415.600134)
				)
				(xy 214.14867 -415.600134) (xy 214.14867 -414.202626)
				(arc
					(start 213.99373 -414.202626)
					(mid 213.60003 -414.593794)
					(end 213.20633 -414.202626)
				)
				(arc
					(start 213.20633 -414.200086)
					(mid 213.60003 -413.806386)
					(end 213.99373 -414.200086)
				)
			)
		)
	)
	(zone
		(layers "F.Cu" "B.Cu" "In2.Cu" "In4.Cu" "In7.Cu")
		(hatch none 0.5)
		(connect_pads
			(clearance 0)
		)
		(min_thickness 0.25)
		(keepout
			(tracks not_allowed)
			(vias allowed)
			(pads allowed)
			(copperpour not_allowed)
			(footprints allowed)
		)
		(placement
			(enabled no)
			(sheetname "")
		)
		(fill yes
			(thermal_gap 0.5)
			(thermal_bridge_width 0.5)
			(island_removal_mode 0)
		)
		(polygon
			(pts
				(arc
					(start 240.863374 -50.572924)
					(mid 239.922812 -50.886614)
					(end 240.236502 -51.827176)
				)
				(arc
					(start 242.228116 -52.822856)
					(mid 242.913437 -52.799483)
					(end 243.250974 -52.202588)
				)
				(arc
					(start 243.096034 -52.202588)
					(mid 242.549934 -52.746154)
					(end 242.003834 -52.202588)
				)
				(arc
					(start 242.003834 -52.200048)
					(mid 242.549934 -51.653948)
					(end 243.096034 -52.200048)
				)
				(arc
					(start 243.250974 -52.200048)
					(mid 243.146244 -51.831441)
					(end 242.86337 -51.572922)
				)
				(xy 242.122706 -51.20259)
				(arc
					(start 241.096038 -51.20259)
					(mid 240.549938 -51.746156)
					(end 240.003838 -51.20259)
				)
				(arc
					(start 240.003838 -51.20005)
					(mid 240.549938 -50.65395)
					(end 241.096038 -51.20005)
				)
				(xy 242.117626 -51.20005)
			)
		)
	)
	(zone
		(layers "F.Cu" "B.Cu" "In2.Cu" "In4.Cu" "In7.Cu")
		(hatch none 0.5)
		(connect_pads
			(clearance 0)
		)
		(min_thickness 0.25)
		(keepout
			(tracks not_allowed)
			(vias allowed)
			(pads allowed)
			(copperpour not_allowed)
			(footprints allowed)
		)
		(placement
			(enabled no)
			(sheetname "")
		)
		(fill yes
			(thermal_gap 0.5)
			(thermal_bridge_width 0.5)
			(island_removal_mode 0)
		)
		(polygon
			(pts
				(arc
					(start 283.563314 -170.872658)
					(mid 282.622752 -171.186348)
					(end 282.936442 -172.12691)
				)
				(arc
					(start 284.928056 -173.12259)
					(mid 285.613377 -173.099217)
					(end 285.950914 -172.502322)
				)
				(arc
					(start 285.795974 -172.502322)
					(mid 285.249874 -173.045888)
					(end 284.703774 -172.502322)
				)
				(arc
					(start 284.703774 -172.499782)
					(mid 285.249874 -171.953682)
					(end 285.795974 -172.499782)
				)
				(arc
					(start 285.950914 -172.499782)
					(mid 285.846184 -172.131175)
					(end 285.56331 -171.872656)
				)
				(xy 284.822646 -171.502324)
				(arc
					(start 283.795978 -171.502324)
					(mid 283.249878 -172.04589)
					(end 282.703778 -171.502324)
				)
				(arc
					(start 282.703778 -171.499784)
					(mid 283.249878 -170.953684)
					(end 283.795978 -171.499784)
				)
				(xy 284.817566 -171.499784)
			)
		)
	)
	(zone
		(layers "F.Cu" "B.Cu" "In2.Cu" "In4.Cu" "In7.Cu")
		(hatch none 0.5)
		(connect_pads
			(clearance 0)
		)
		(min_thickness 0.25)
		(keepout
			(tracks not_allowed)
			(vias allowed)
			(pads allowed)
			(copperpour not_allowed)
			(footprints allowed)
		)
		(placement
			(enabled no)
			(sheetname "")
		)
		(fill yes
			(thermal_gap 0.5)
			(thermal_bridge_width 0.5)
			(island_removal_mode 0)
		)
		(polygon
			(pts
				(arc
					(start 278.23668 -319.356486)
					(mid 277.68804 -319.905126)
					(end 278.23668 -320.453766)
				)
				(arc
					(start 279.636728 -320.453766)
					(mid 280.023776 -320.29397)
					(end 280.185368 -319.907666)
				)
				(arc
					(start 280.030428 -319.907666)
					(mid 279.636728 -320.298834)
					(end 279.243028 -319.907666)
				)
				(arc
					(start 278.63038 -319.907666)
					(mid 278.23668 -320.298834)
					(end 277.84298 -319.907666)
				)
				(arc
					(start 277.84298 -319.905126)
					(mid 278.23668 -319.511426)
					(end 278.63038 -319.905126)
				)
				(arc
					(start 279.243028 -319.905126)
					(mid 279.636728 -319.511426)
					(end 280.030428 -319.905126)
				)
				(arc
					(start 280.185368 -319.905126)
					(mid 280.024675 -319.517179)
					(end 279.636728 -319.356486)
				)
				(xy 278.236934 -319.356486)
			)
		)
	)
	(zone
		(layers "F.Cu" "B.Cu" "In2.Cu" "In4.Cu" "In7.Cu")
		(hatch none 0.5)
		(connect_pads
			(clearance 0)
		)
		(min_thickness 0.25)
		(keepout
			(tracks not_allowed)
			(vias allowed)
			(pads allowed)
			(copperpour not_allowed)
			(footprints allowed)
		)
		(placement
			(enabled no)
			(sheetname "")
		)
		(fill yes
			(thermal_gap 0.5)
			(thermal_bridge_width 0.5)
			(island_removal_mode 0)
		)
		(polygon
			(pts
				(arc
					(start 278.23668 -337.35645)
					(mid 277.68804 -337.90509)
					(end 278.23668 -338.45373)
				)
				(arc
					(start 279.636728 -338.45373)
					(mid 280.023776 -338.293934)
					(end 280.185368 -337.90763)
				)
				(arc
					(start 280.030428 -337.90763)
					(mid 279.636728 -338.298798)
					(end 279.243028 -337.90763)
				)
				(arc
					(start 278.63038 -337.90763)
					(mid 278.23668 -338.298798)
					(end 277.84298 -337.90763)
				)
				(arc
					(start 277.84298 -337.90509)
					(mid 278.23668 -337.51139)
					(end 278.63038 -337.90509)
				)
				(arc
					(start 279.243028 -337.90509)
					(mid 279.636728 -337.51139)
					(end 280.030428 -337.90509)
				)
				(arc
					(start 280.185368 -337.90509)
					(mid 280.024675 -337.517143)
					(end 279.636728 -337.35645)
				)
				(xy 278.236934 -337.35645)
			)
		)
	)
	(zone
		(layers "F.Cu" "B.Cu" "In2.Cu" "In4.Cu" "In7.Cu")
		(hatch none 0.5)
		(connect_pads
			(clearance 0)
		)
		(min_thickness 0.25)
		(keepout
			(tracks not_allowed)
			(vias allowed)
			(pads allowed)
			(copperpour not_allowed)
			(footprints allowed)
		)
		(placement
			(enabled no)
			(sheetname "")
		)
		(fill yes
			(thermal_gap 0.5)
			(thermal_bridge_width 0.5)
			(island_removal_mode 0)
		)
		(polygon
			(pts
				(arc
					(start 283.563314 -150.872698)
					(mid 282.622752 -151.186388)
					(end 282.936442 -152.12695)
				)
				(arc
					(start 284.928056 -153.12263)
					(mid 285.613377 -153.099257)
					(end 285.950914 -152.502362)
				)
				(arc
					(start 285.795974 -152.502362)
					(mid 285.249874 -153.045928)
					(end 284.703774 -152.502362)
				)
				(arc
					(start 284.703774 -152.499822)
					(mid 285.249874 -151.953722)
					(end 285.795974 -152.499822)
				)
				(arc
					(start 285.950914 -152.499822)
					(mid 285.846184 -152.131215)
					(end 285.56331 -151.872696)
				)
				(xy 284.822646 -151.502364)
				(arc
					(start 283.795978 -151.502364)
					(mid 283.249878 -152.04593)
					(end 282.703778 -151.502364)
				)
				(arc
					(start 282.703778 -151.499824)
					(mid 283.249878 -150.953724)
					(end 283.795978 -151.499824)
				)
				(xy 284.817566 -151.499824)
			)
		)
	)
	(zone
		(layers "F.Cu" "B.Cu" "In2.Cu" "In4.Cu" "In7.Cu")
		(hatch none 0.5)
		(connect_pads
			(clearance 0)
		)
		(min_thickness 0.25)
		(keepout
			(tracks not_allowed)
			(vias allowed)
			(pads allowed)
			(copperpour not_allowed)
			(footprints allowed)
		)
		(placement
			(enabled no)
			(sheetname "")
		)
		(fill yes
			(thermal_gap 0.5)
			(thermal_bridge_width 0.5)
			(island_removal_mode 0)
		)
		(polygon
			(pts
				(arc
					(start 281.45105 -113.4999)
					(mid 281.118617 -112.90359)
					(end 280.436574 -112.872774)
				)
				(arc
					(start 278.44496 -113.868708)
					(mid 278.120865 -114.809139)
					(end 279.06345 -115.127024)
				)
				(xy 280.312622 -114.502438)
				(arc
					(start 279.296114 -114.502438)
					(mid 278.750014 -115.046004)
					(end 278.203914 -114.502438)
				)
				(arc
					(start 278.203914 -114.499898)
					(mid 278.750014 -113.953798)
					(end 279.296114 -114.499898)
				)
				(xy 280.317702 -114.499898)
				(arc
					(start 281.063446 -114.127026)
					(mid 281.345695 -113.869614)
					(end 281.45105 -113.50244)
				)
				(arc
					(start 281.29611 -113.50244)
					(mid 280.75001 -114.046006)
					(end 280.20391 -113.50244)
				)
				(arc
					(start 280.20391 -113.4999)
					(mid 280.75001 -112.9538)
					(end 281.29611 -113.4999)
				)
			)
		)
	)
	(zone
		(layers "F.Cu" "B.Cu" "In2.Cu" "In4.Cu" "In7.Cu")
		(hatch none 0.5)
		(connect_pads
			(clearance 0)
		)
		(min_thickness 0.25)
		(keepout
			(tracks not_allowed)
			(vias allowed)
			(pads allowed)
			(copperpour not_allowed)
			(footprints allowed)
		)
		(placement
			(enabled no)
			(sheetname "")
		)
		(fill yes
			(thermal_gap 0.5)
			(thermal_bridge_width 0.5)
			(island_removal_mode 0)
		)
		(polygon
			(pts
				(arc
					(start 278.23668 -315.756544)
					(mid 277.68804 -316.305184)
					(end 278.23668 -316.853824)
				)
				(arc
					(start 279.636728 -316.853824)
					(mid 280.023776 -316.694028)
					(end 280.185368 -316.307724)
				)
				(arc
					(start 280.030428 -316.307724)
					(mid 279.636728 -316.698892)
					(end 279.243028 -316.307724)
				)
				(arc
					(start 278.63038 -316.307724)
					(mid 278.23668 -316.698892)
					(end 277.84298 -316.307724)
				)
				(arc
					(start 277.84298 -316.305184)
					(mid 278.23668 -315.911484)
					(end 278.63038 -316.305184)
				)
				(arc
					(start 279.243028 -316.305184)
					(mid 279.636728 -315.911484)
					(end 280.030428 -316.305184)
				)
				(arc
					(start 280.185368 -316.305184)
					(mid 280.024675 -315.917237)
					(end 279.636728 -315.756544)
				)
				(xy 278.236934 -315.756544)
			)
		)
	)
	(zone
		(layers "F.Cu" "B.Cu" "In2.Cu" "In4.Cu" "In7.Cu")
		(hatch none 0.5)
		(connect_pads
			(clearance 0)
		)
		(min_thickness 0.25)
		(keepout
			(tracks not_allowed)
			(vias allowed)
			(pads allowed)
			(copperpour not_allowed)
			(footprints allowed)
		)
		(placement
			(enabled no)
			(sheetname "")
		)
		(fill yes
			(thermal_gap 0.5)
			(thermal_bridge_width 0.5)
			(island_removal_mode 0)
		)
		(polygon
			(pts
				(arc
					(start 283.563314 -82.57286)
					(mid 282.622752 -82.88655)
					(end 282.936442 -83.827112)
				)
				(arc
					(start 284.928056 -84.822792)
					(mid 285.613377 -84.799419)
					(end 285.950914 -84.202524)
				)
				(arc
					(start 285.795974 -84.202524)
					(mid 285.249874 -84.74609)
					(end 284.703774 -84.202524)
				)
				(arc
					(start 284.703774 -84.199984)
					(mid 285.249874 -83.653884)
					(end 285.795974 -84.199984)
				)
				(arc
					(start 285.950914 -84.199984)
					(mid 285.846184 -83.831377)
					(end 285.56331 -83.572858)
				)
				(xy 284.822646 -83.202526)
				(arc
					(start 283.795978 -83.202526)
					(mid 283.249878 -83.746092)
					(end 282.703778 -83.202526)
				)
				(arc
					(start 282.703778 -83.199986)
					(mid 283.249878 -82.653886)
					(end 283.795978 -83.199986)
				)
				(xy 284.817566 -83.199986)
			)
		)
	)
	(zone
		(layers "F.Cu" "B.Cu" "In2.Cu" "In4.Cu" "In7.Cu")
		(hatch none 0.5)
		(connect_pads
			(clearance 0)
		)
		(min_thickness 0.25)
		(keepout
			(tracks not_allowed)
			(vias allowed)
			(pads allowed)
			(copperpour not_allowed)
			(footprints allowed)
		)
		(placement
			(enabled no)
			(sheetname "")
		)
		(fill yes
			(thermal_gap 0.5)
			(thermal_bridge_width 0.5)
			(island_removal_mode 0)
		)
		(polygon
			(pts
				(arc
					(start 219.54871 -416.80003)
					(mid 219.00007 -416.25139)
					(end 218.45143 -416.80003)
				)
				(arc
					(start 218.45143 -418.200078)
					(mid 218.9988 -418.748717)
					(end 219.54871 -418.202618)
				)
				(arc
					(start 219.39377 -418.202618)
					(mid 219.00007 -418.593786)
					(end 218.60637 -418.202618)
				)
				(arc
					(start 218.60637 -418.200078)
					(mid 219.00007 -417.806378)
					(end 219.39377 -418.200078)
				)
				(xy 219.54871 -418.200078) (xy 219.54871 -416.80257)
				(arc
					(start 219.39377 -416.80257)
					(mid 219.00007 -417.193738)
					(end 218.60637 -416.80257)
				)
				(arc
					(start 218.60637 -416.80003)
					(mid 219.00007 -416.40633)
					(end 219.39377 -416.80003)
				)
			)
		)
	)
	(zone
		(layers "F.Cu" "B.Cu" "In2.Cu" "In4.Cu" "In7.Cu")
		(hatch none 0.5)
		(connect_pads
			(clearance 0)
		)
		(min_thickness 0.25)
		(keepout
			(tracks not_allowed)
			(vias allowed)
			(pads allowed)
			(copperpour not_allowed)
			(footprints allowed)
		)
		(placement
			(enabled no)
			(sheetname "")
		)
		(fill yes
			(thermal_gap 0.5)
			(thermal_bridge_width 0.5)
			(island_removal_mode 0)
		)
		(polygon
			(pts
				(arc
					(start 223.148652 -416.80003)
					(mid 222.600012 -416.25139)
					(end 222.051372 -416.80003)
				)
				(arc
					(start 222.051372 -418.200078)
					(mid 222.598742 -418.748717)
					(end 223.148652 -418.202618)
				)
				(arc
					(start 222.993712 -418.202618)
					(mid 222.600012 -418.593786)
					(end 222.206312 -418.202618)
				)
				(arc
					(start 222.206312 -418.200078)
					(mid 222.600012 -417.806378)
					(end 222.993712 -418.200078)
				)
				(xy 223.148652 -418.200078) (xy 223.148652 -416.80257)
				(arc
					(start 222.993712 -416.80257)
					(mid 222.600012 -417.193738)
					(end 222.206312 -416.80257)
				)
				(arc
					(start 222.206312 -416.80003)
					(mid 222.600012 -416.40633)
					(end 222.993712 -416.80003)
				)
			)
		)
	)
	(zone
		(layers "F.Cu" "B.Cu" "In2.Cu" "In4.Cu" "In7.Cu")
		(hatch none 0.5)
		(connect_pads
			(clearance 0)
		)
		(min_thickness 0.25)
		(keepout
			(tracks not_allowed)
			(vias allowed)
			(pads allowed)
			(copperpour not_allowed)
			(footprints allowed)
		)
		(placement
			(enabled no)
			(sheetname "")
		)
		(fill yes
			(thermal_gap 0.5)
			(thermal_bridge_width 0.5)
			(island_removal_mode 0)
		)
		(polygon
			(pts
				(arc
					(start 283.563314 -166.872666)
					(mid 282.622752 -167.186356)
					(end 282.936442 -168.126918)
				)
				(arc
					(start 284.928056 -169.122598)
					(mid 285.613377 -169.099225)
					(end 285.950914 -168.50233)
				)
				(arc
					(start 285.795974 -168.50233)
					(mid 285.249874 -169.045896)
					(end 284.703774 -168.50233)
				)
				(arc
					(start 284.703774 -168.49979)
					(mid 285.249874 -167.95369)
					(end 285.795974 -168.49979)
				)
				(arc
					(start 285.950914 -168.49979)
					(mid 285.846184 -168.131183)
					(end 285.56331 -167.872664)
				)
				(xy 284.822646 -167.502332)
				(arc
					(start 283.795978 -167.502332)
					(mid 283.249878 -168.045898)
					(end 282.703778 -167.502332)
				)
				(arc
					(start 282.703778 -167.499792)
					(mid 283.249878 -166.953692)
					(end 283.795978 -167.499792)
				)
				(xy 284.817566 -167.499792)
			)
		)
	)
	(zone
		(layers "F.Cu" "B.Cu" "In2.Cu" "In4.Cu" "In7.Cu")
		(hatch none 0.5)
		(connect_pads
			(clearance 0)
		)
		(min_thickness 0.25)
		(keepout
			(tracks not_allowed)
			(vias allowed)
			(pads allowed)
			(copperpour not_allowed)
			(footprints allowed)
		)
		(placement
			(enabled no)
			(sheetname "")
		)
		(fill yes
			(thermal_gap 0.5)
			(thermal_bridge_width 0.5)
			(island_removal_mode 0)
		)
		(polygon
			(pts
				(arc
					(start 240.871756 -178.87696)
					(mid 239.92498 -179.182145)
					(end 240.236502 -180.126894)
				)
				(arc
					(start 242.236498 -181.126892)
					(mid 242.917487 -181.096787)
					(end 243.250974 -180.502306)
				)
				(arc
					(start 243.096034 -180.502306)
					(mid 242.549934 -181.045872)
					(end 242.003834 -180.502306)
				)
				(arc
					(start 242.003834 -180.499766)
					(mid 242.549934 -179.953666)
					(end 243.096034 -180.499766)
				)
				(arc
					(start 243.250974 -180.499766)
					(mid 243.146244 -180.131159)
					(end 242.86337 -179.87264)
				)
				(xy 242.122706 -179.502308)
				(arc
					(start 241.096038 -179.502308)
					(mid 240.549938 -180.045874)
					(end 240.003838 -179.502308)
				)
				(arc
					(start 240.003838 -179.499768)
					(mid 240.549938 -178.953668)
					(end 241.096038 -179.499768)
				)
				(xy 242.117626 -179.499768)
			)
		)
	)
	(zone
		(layers "F.Cu" "B.Cu" "In2.Cu" "In4.Cu" "In7.Cu")
		(hatch none 0.5)
		(connect_pads
			(clearance 0)
		)
		(min_thickness 0.25)
		(keepout
			(tracks not_allowed)
			(vias allowed)
			(pads allowed)
			(copperpour not_allowed)
			(footprints allowed)
		)
		(placement
			(enabled no)
			(sheetname "")
		)
		(fill yes
			(thermal_gap 0.5)
			(thermal_bridge_width 0.5)
			(island_removal_mode 0)
		)
		(polygon
			(pts
				(arc
					(start 283.563314 -58.572908)
					(mid 282.622752 -58.886598)
					(end 282.936442 -59.82716)
				)
				(arc
					(start 284.928056 -60.82284)
					(mid 285.613377 -60.799467)
					(end 285.950914 -60.202572)
				)
				(arc
					(start 285.795974 -60.202572)
					(mid 285.249874 -60.746138)
					(end 284.703774 -60.202572)
				)
				(arc
					(start 284.703774 -60.200032)
					(mid 285.249874 -59.653932)
					(end 285.795974 -60.200032)
				)
				(arc
					(start 285.950914 -60.200032)
					(mid 285.846184 -59.831425)
					(end 285.56331 -59.572906)
				)
				(xy 284.822646 -59.202574)
				(arc
					(start 283.795978 -59.202574)
					(mid 283.249878 -59.74614)
					(end 282.703778 -59.202574)
				)
				(arc
					(start 282.703778 -59.200034)
					(mid 283.249878 -58.653934)
					(end 283.795978 -59.200034)
				)
				(xy 284.817566 -59.200034)
			)
		)
	)
	(zone
		(layers "F.Cu" "B.Cu" "In2.Cu" "In4.Cu" "In7.Cu")
		(hatch none 0.5)
		(connect_pads
			(clearance 0)
		)
		(min_thickness 0.25)
		(keepout
			(tracks not_allowed)
			(vias allowed)
			(pads allowed)
			(copperpour not_allowed)
			(footprints allowed)
		)
		(placement
			(enabled no)
			(sheetname "")
		)
		(fill yes
			(thermal_gap 0.5)
			(thermal_bridge_width 0.5)
			(island_removal_mode 0)
		)
		(polygon
			(pts
				(arc
					(start 240.871756 -54.577234)
					(mid 239.92498 -54.882419)
					(end 240.236502 -55.827168)
				)
				(arc
					(start 242.236498 -56.827166)
					(mid 242.917487 -56.797061)
					(end 243.250974 -56.20258)
				)
				(arc
					(start 243.096034 -56.20258)
					(mid 242.549934 -56.746146)
					(end 242.003834 -56.20258)
				)
				(arc
					(start 242.003834 -56.20004)
					(mid 242.549934 -55.65394)
					(end 243.096034 -56.20004)
				)
				(arc
					(start 243.250974 -56.20004)
					(mid 243.146244 -55.831433)
					(end 242.86337 -55.572914)
				)
				(xy 242.122706 -55.202582)
				(arc
					(start 241.096038 -55.202582)
					(mid 240.549938 -55.746148)
					(end 240.003838 -55.202582)
				)
				(arc
					(start 240.003838 -55.200042)
					(mid 240.549938 -54.653942)
					(end 241.096038 -55.200042)
				)
				(xy 242.117626 -55.200042)
			)
		)
	)
	(zone
		(layers "F.Cu" "B.Cu" "In2.Cu" "In4.Cu" "In7.Cu")
		(hatch none 0.5)
		(connect_pads
			(clearance 0)
		)
		(min_thickness 0.25)
		(keepout
			(tracks not_allowed)
			(vias allowed)
			(pads allowed)
			(copperpour not_allowed)
			(footprints allowed)
		)
		(placement
			(enabled no)
			(sheetname "")
		)
		(fill yes
			(thermal_gap 0.5)
			(thermal_bridge_width 0.5)
			(island_removal_mode 0)
		)
		(polygon
			(pts
				(arc
					(start 278.23668 -340.956392)
					(mid 277.68804 -341.505032)
					(end 278.23668 -342.053672)
				)
				(arc
					(start 279.636728 -342.053672)
					(mid 280.023776 -341.893876)
					(end 280.185368 -341.507572)
				)
				(arc
					(start 280.030428 -341.507572)
					(mid 279.636728 -341.89874)
					(end 279.243028 -341.507572)
				)
				(arc
					(start 278.63038 -341.507572)
					(mid 278.23668 -341.89874)
					(end 277.84298 -341.507572)
				)
				(arc
					(start 277.84298 -341.505032)
					(mid 278.23668 -341.111332)
					(end 278.63038 -341.505032)
				)
				(arc
					(start 279.243028 -341.505032)
					(mid 279.636728 -341.111332)
					(end 280.030428 -341.505032)
				)
				(arc
					(start 280.185368 -341.505032)
					(mid 280.024675 -341.117085)
					(end 279.636728 -340.956392)
				)
				(xy 278.236934 -340.956392)
			)
		)
	)
	(zone
		(layers "F.Cu" "B.Cu" "In2.Cu" "In4.Cu" "In7.Cu")
		(hatch none 0.5)
		(connect_pads
			(clearance 0)
		)
		(min_thickness 0.25)
		(keepout
			(tracks not_allowed)
			(vias allowed)
			(pads allowed)
			(copperpour not_allowed)
			(footprints allowed)
		)
		(placement
			(enabled no)
			(sheetname "")
		)
		(fill yes
			(thermal_gap 0.5)
			(thermal_bridge_width 0.5)
			(island_removal_mode 0)
		)
		(polygon
			(pts
				(arc
					(start 278.23668 -344.556588)
					(mid 277.68804 -345.105228)
					(end 278.23668 -345.653868)
				)
				(arc
					(start 279.636728 -345.653868)
					(mid 280.023776 -345.494072)
					(end 280.185368 -345.107768)
				)
				(arc
					(start 280.030428 -345.107768)
					(mid 279.636728 -345.498936)
					(end 279.243028 -345.107768)
				)
				(arc
					(start 278.63038 -345.107768)
					(mid 278.23668 -345.498936)
					(end 277.84298 -345.107768)
				)
				(arc
					(start 277.84298 -345.105228)
					(mid 278.23668 -344.711528)
					(end 278.63038 -345.105228)
				)
				(arc
					(start 279.243028 -345.105228)
					(mid 279.636728 -344.711528)
					(end 280.030428 -345.105228)
				)
				(arc
					(start 280.185368 -345.105228)
					(mid 280.024675 -344.717281)
					(end 279.636728 -344.556588)
				)
				(xy 278.236934 -344.556588)
			)
		)
	)
	(zone
		(layers "F.Cu" "B.Cu" "In2.Cu" "In4.Cu" "In7.Cu")
		(hatch none 0.5)
		(connect_pads
			(clearance 0)
		)
		(min_thickness 0.25)
		(keepout
			(tracks not_allowed)
			(vias allowed)
			(pads allowed)
			(copperpour not_allowed)
			(footprints allowed)
		)
		(placement
			(enabled no)
			(sheetname "")
		)
		(fill yes
			(thermal_gap 0.5)
			(thermal_bridge_width 0.5)
			(island_removal_mode 0)
		)
		(polygon
			(pts
				(arc
					(start 278.23668 -297.75658)
					(mid 277.68804 -298.30522)
					(end 278.23668 -298.85386)
				)
				(arc
					(start 279.636728 -298.85386)
					(mid 280.023776 -298.694064)
					(end 280.185368 -298.30776)
				)
				(arc
					(start 280.030428 -298.30776)
					(mid 279.636728 -298.698928)
					(end 279.243028 -298.30776)
				)
				(arc
					(start 278.63038 -298.30776)
					(mid 278.23668 -298.698928)
					(end 277.84298 -298.30776)
				)
				(arc
					(start 277.84298 -298.30522)
					(mid 278.23668 -297.91152)
					(end 278.63038 -298.30522)
				)
				(arc
					(start 279.243028 -298.30522)
					(mid 279.636728 -297.91152)
					(end 280.030428 -298.30522)
				)
				(arc
					(start 280.185368 -298.30522)
					(mid 280.024675 -297.917273)
					(end 279.636728 -297.75658)
				)
				(xy 278.236934 -297.75658)
			)
		)
	)
	(zone
		(layers "F.Cu" "B.Cu" "In2.Cu" "In4.Cu" "In7.Cu")
		(hatch none 0.5)
		(connect_pads
			(clearance 0)
		)
		(min_thickness 0.25)
		(keepout
			(tracks not_allowed)
			(vias allowed)
			(pads allowed)
			(copperpour not_allowed)
			(footprints allowed)
		)
		(placement
			(enabled no)
			(sheetname "")
		)
		(fill yes
			(thermal_gap 0.5)
			(thermal_bridge_width 0.5)
			(island_removal_mode 0)
		)
		(polygon
			(pts
				(arc
					(start 283.563314 -38.572948)
					(mid 282.622752 -38.886638)
					(end 282.936442 -39.8272)
				)
				(arc
					(start 284.928056 -40.82288)
					(mid 285.613377 -40.799507)
					(end 285.950914 -40.202612)
				)
				(arc
					(start 285.795974 -40.202612)
					(mid 285.249874 -40.746178)
					(end 284.703774 -40.202612)
				)
				(arc
					(start 284.703774 -40.200072)
					(mid 285.249874 -39.653972)
					(end 285.795974 -40.200072)
				)
				(arc
					(start 285.950914 -40.200072)
					(mid 285.846184 -39.831465)
					(end 285.56331 -39.572946)
				)
				(xy 284.822646 -39.202614)
				(arc
					(start 283.795978 -39.202614)
					(mid 283.249878 -39.74618)
					(end 282.703778 -39.202614)
				)
				(arc
					(start 282.703778 -39.200074)
					(mid 283.249878 -38.653974)
					(end 283.795978 -39.200074)
				)
				(xy 284.817566 -39.200074)
			)
		)
	)
	(zone
		(layers "F.Cu" "B.Cu" "In2.Cu" "In4.Cu" "In7.Cu")
		(hatch none 0.5)
		(connect_pads
			(clearance 0)
		)
		(min_thickness 0.25)
		(keepout
			(tracks not_allowed)
			(vias allowed)
			(pads allowed)
			(copperpour not_allowed)
			(footprints allowed)
		)
		(placement
			(enabled no)
			(sheetname "")
		)
		(fill yes
			(thermal_gap 0.5)
			(thermal_bridge_width 0.5)
			(island_removal_mode 0)
		)
		(polygon
			(pts
				(arc
					(start 221.348808 -414.200086)
					(mid 220.800168 -413.651446)
					(end 220.251528 -414.200086)
				)
				(arc
					(start 220.251528 -415.600134)
					(mid 220.798898 -416.148773)
					(end 221.348808 -415.602674)
				)
				(arc
					(start 221.193868 -415.602674)
					(mid 220.800168 -415.993842)
					(end 220.406468 -415.602674)
				)
				(arc
					(start 220.406468 -415.600134)
					(mid 220.800168 -415.206434)
					(end 221.193868 -415.600134)
				)
				(xy 221.348808 -415.600134) (xy 221.348808 -414.202626)
				(arc
					(start 221.193868 -414.202626)
					(mid 220.800168 -414.593794)
					(end 220.406468 -414.202626)
				)
				(arc
					(start 220.406468 -414.200086)
					(mid 220.800168 -413.806386)
					(end 221.193868 -414.200086)
				)
			)
		)
	)
	(zone
		(layers "F.Cu" "B.Cu" "In2.Cu" "In4.Cu" "In7.Cu")
		(hatch none 0.5)
		(connect_pads
			(clearance 0)
		)
		(min_thickness 0.25)
		(keepout
			(tracks not_allowed)
			(vias allowed)
			(pads allowed)
			(copperpour not_allowed)
			(footprints allowed)
		)
		(placement
			(enabled no)
			(sheetname "")
		)
		(fill yes
			(thermal_gap 0.5)
			(thermal_bridge_width 0.5)
			(island_removal_mode 0)
		)
		(polygon
			(pts
				(arc
					(start 283.563314 -70.572884)
					(mid 282.622752 -70.886574)
					(end 282.936442 -71.827136)
				)
				(arc
					(start 284.928056 -72.822816)
					(mid 285.613377 -72.799443)
					(end 285.950914 -72.202548)
				)
				(arc
					(start 285.795974 -72.202548)
					(mid 285.249874 -72.746114)
					(end 284.703774 -72.202548)
				)
				(arc
					(start 284.703774 -72.200008)
					(mid 285.249874 -71.653908)
					(end 285.795974 -72.200008)
				)
				(arc
					(start 285.950914 -72.200008)
					(mid 285.846184 -71.831401)
					(end 285.56331 -71.572882)
				)
				(xy 284.822646 -71.20255)
				(arc
					(start 283.795978 -71.20255)
					(mid 283.249878 -71.746116)
					(end 282.703778 -71.20255)
				)
				(arc
					(start 282.703778 -71.20001)
					(mid 283.249878 -70.65391)
					(end 283.795978 -71.20001)
				)
				(xy 284.817566 -71.20001)
			)
		)
	)
	(zone
		(layers "F.Cu" "B.Cu" "In2.Cu" "In4.Cu" "In7.Cu")
		(hatch none 0.5)
		(connect_pads
			(clearance 0)
		)
		(min_thickness 0.25)
		(keepout
			(tracks not_allowed)
			(vias allowed)
			(pads allowed)
			(copperpour not_allowed)
			(footprints allowed)
		)
		(placement
			(enabled no)
			(sheetname "")
		)
		(fill yes
			(thermal_gap 0.5)
			(thermal_bridge_width 0.5)
			(island_removal_mode 0)
		)
		(polygon
			(pts
				(arc
					(start 283.563314 -46.572932)
					(mid 282.622752 -46.886622)
					(end 282.936442 -47.827184)
				)
				(arc
					(start 284.928056 -48.822864)
					(mid 285.613377 -48.799491)
					(end 285.950914 -48.202596)
				)
				(arc
					(start 285.795974 -48.202596)
					(mid 285.249874 -48.746162)
					(end 284.703774 -48.202596)
				)
				(arc
					(start 284.703774 -48.200056)
					(mid 285.249874 -47.653956)
					(end 285.795974 -48.200056)
				)
				(arc
					(start 285.950914 -48.200056)
					(mid 285.846184 -47.831449)
					(end 285.56331 -47.57293)
				)
				(xy 284.822646 -47.202598)
				(arc
					(start 283.795978 -47.202598)
					(mid 283.249878 -47.746164)
					(end 282.703778 -47.202598)
				)
				(arc
					(start 282.703778 -47.200058)
					(mid 283.249878 -46.653958)
					(end 283.795978 -47.200058)
				)
				(xy 284.817566 -47.200058)
			)
		)
	)
	(zone
		(layers "F.Cu" "B.Cu" "In2.Cu" "In4.Cu" "In7.Cu")
		(hatch none 0.5)
		(connect_pads
			(clearance 0)
		)
		(min_thickness 0.25)
		(keepout
			(tracks not_allowed)
			(vias allowed)
			(pads allowed)
			(copperpour not_allowed)
			(footprints allowed)
		)
		(placement
			(enabled no)
			(sheetname "")
		)
		(fill yes
			(thermal_gap 0.5)
			(thermal_bridge_width 0.5)
			(island_removal_mode 0)
		)
		(polygon
			(pts
				(arc
					(start 283.563314 -154.87269)
					(mid 282.622752 -155.18638)
					(end 282.936442 -156.126942)
				)
				(arc
					(start 284.928056 -157.122622)
					(mid 285.613377 -157.099249)
					(end 285.950914 -156.502354)
				)
				(arc
					(start 285.795974 -156.502354)
					(mid 285.249874 -157.04592)
					(end 284.703774 -156.502354)
				)
				(arc
					(start 284.703774 -156.499814)
					(mid 285.249874 -155.953714)
					(end 285.795974 -156.499814)
				)
				(arc
					(start 285.950914 -156.499814)
					(mid 285.846184 -156.131207)
					(end 285.56331 -155.872688)
				)
				(xy 284.822646 -155.502356)
				(arc
					(start 283.795978 -155.502356)
					(mid 283.249878 -156.045922)
					(end 282.703778 -155.502356)
				)
				(arc
					(start 282.703778 -155.499816)
					(mid 283.249878 -154.953716)
					(end 283.795978 -155.499816)
				)
				(xy 284.817566 -155.499816)
			)
		)
	)
	(zone
		(layers "F.Cu" "B.Cu" "In2.Cu" "In4.Cu" "In7.Cu")
		(hatch none 0.5)
		(connect_pads
			(clearance 0)
		)
		(min_thickness 0.25)
		(keepout
			(tracks not_allowed)
			(vias allowed)
			(pads allowed)
			(copperpour not_allowed)
			(footprints allowed)
		)
		(placement
			(enabled no)
			(sheetname "")
		)
		(fill yes
			(thermal_gap 0.5)
			(thermal_bridge_width 0.5)
			(island_removal_mode 0)
		)
		(polygon
			(pts
				(arc
					(start 240.871756 -62.577218)
					(mid 239.92498 -62.882403)
					(end 240.236502 -63.827152)
				)
				(arc
					(start 242.236498 -64.82715)
					(mid 242.917487 -64.797045)
					(end 243.250974 -64.202564)
				)
				(arc
					(start 243.096034 -64.202564)
					(mid 242.549934 -64.74613)
					(end 242.003834 -64.202564)
				)
				(arc
					(start 242.003834 -64.200024)
					(mid 242.549934 -63.653924)
					(end 243.096034 -64.200024)
				)
				(arc
					(start 243.250974 -64.200024)
					(mid 243.146244 -63.831417)
					(end 242.86337 -63.572898)
				)
				(xy 242.122706 -63.202566)
				(arc
					(start 241.096038 -63.202566)
					(mid 240.549938 -63.746132)
					(end 240.003838 -63.202566)
				)
				(arc
					(start 240.003838 -63.200026)
					(mid 240.549938 -62.653926)
					(end 241.096038 -63.200026)
				)
				(xy 242.117626 -63.200026)
			)
		)
	)
	(zone
		(layers "F.Cu" "B.Cu" "In2.Cu" "In4.Cu" "In7.Cu")
		(hatch none 0.5)
		(connect_pads
			(clearance 0)
		)
		(min_thickness 0.25)
		(keepout
			(tracks not_allowed)
			(vias allowed)
			(pads allowed)
			(copperpour not_allowed)
			(footprints allowed)
		)
		(placement
			(enabled no)
			(sheetname "")
		)
		(fill yes
			(thermal_gap 0.5)
			(thermal_bridge_width 0.5)
			(island_removal_mode 0)
		)
		(polygon
			(pts
				(arc
					(start 240.871756 -170.876976)
					(mid 239.92498 -171.182161)
					(end 240.236502 -172.12691)
				)
				(arc
					(start 242.236498 -173.126908)
					(mid 242.917487 -173.096803)
					(end 243.250974 -172.502322)
				)
				(arc
					(start 243.096034 -172.502322)
					(mid 242.549934 -173.045888)
					(end 242.003834 -172.502322)
				)
				(arc
					(start 242.003834 -172.499782)
					(mid 242.549934 -171.953682)
					(end 243.096034 -172.499782)
				)
				(arc
					(start 243.250974 -172.499782)
					(mid 243.146244 -172.131175)
					(end 242.86337 -171.872656)
				)
				(xy 242.122706 -171.502324)
				(arc
					(start 241.096038 -171.502324)
					(mid 240.549938 -172.04589)
					(end 240.003838 -171.502324)
				)
				(arc
					(start 240.003838 -171.499784)
					(mid 240.549938 -170.953684)
					(end 241.096038 -171.499784)
				)
				(xy 242.117626 -171.499784)
			)
		)
	)
	(zone
		(layers "F.Cu" "B.Cu" "In2.Cu" "In4.Cu" "In7.Cu")
		(hatch none 0.5)
		(connect_pads
			(clearance 0)
		)
		(min_thickness 0.25)
		(keepout
			(tracks not_allowed)
			(vias allowed)
			(pads allowed)
			(copperpour not_allowed)
			(footprints allowed)
		)
		(placement
			(enabled no)
			(sheetname "")
		)
		(fill yes
			(thermal_gap 0.5)
			(thermal_bridge_width 0.5)
			(island_removal_mode 0)
		)
		(polygon
			(pts
				(arc
					(start 283.563314 -174.87265)
					(mid 282.622752 -175.18634)
					(end 282.936442 -176.126902)
				)
				(arc
					(start 284.928056 -177.122582)
					(mid 285.613377 -177.099209)
					(end 285.950914 -176.502314)
				)
				(arc
					(start 285.795974 -176.502314)
					(mid 285.249874 -177.04588)
					(end 284.703774 -176.502314)
				)
				(arc
					(start 284.703774 -176.499774)
					(mid 285.249874 -175.953674)
					(end 285.795974 -176.499774)
				)
				(arc
					(start 285.950914 -176.499774)
					(mid 285.846184 -176.131167)
					(end 285.56331 -175.872648)
				)
				(xy 284.822646 -175.502316)
				(arc
					(start 283.795978 -175.502316)
					(mid 283.249878 -176.045882)
					(end 282.703778 -175.502316)
				)
				(arc
					(start 282.703778 -175.499776)
					(mid 283.249878 -174.953676)
					(end 283.795978 -175.499776)
				)
				(xy 284.817566 -175.499776)
			)
		)
	)
	(zone
		(layers "F.Cu" "B.Cu" "In2.Cu" "In4.Cu" "In7.Cu")
		(hatch none 0.5)
		(connect_pads
			(clearance 0)
		)
		(min_thickness 0.25)
		(keepout
			(tracks not_allowed)
			(vias allowed)
			(pads allowed)
			(copperpour not_allowed)
			(footprints allowed)
		)
		(placement
			(enabled no)
			(sheetname "")
		)
		(fill yes
			(thermal_gap 0.5)
			(thermal_bridge_width 0.5)
			(island_removal_mode 0)
		)
		(polygon
			(pts
				(arc
					(start 283.563314 -50.572924)
					(mid 282.622752 -50.886614)
					(end 282.936442 -51.827176)
				)
				(arc
					(start 284.928056 -52.822856)
					(mid 285.613377 -52.799483)
					(end 285.950914 -52.202588)
				)
				(arc
					(start 285.795974 -52.202588)
					(mid 285.249874 -52.746154)
					(end 284.703774 -52.202588)
				)
				(arc
					(start 284.703774 -52.200048)
					(mid 285.249874 -51.653948)
					(end 285.795974 -52.200048)
				)
				(arc
					(start 285.950914 -52.200048)
					(mid 285.846184 -51.831441)
					(end 285.56331 -51.572922)
				)
				(xy 284.822646 -51.20259)
				(arc
					(start 283.795978 -51.20259)
					(mid 283.249878 -51.746156)
					(end 282.703778 -51.20259)
				)
				(arc
					(start 282.703778 -51.20005)
					(mid 283.249878 -50.65395)
					(end 283.795978 -51.20005)
				)
				(xy 284.817566 -51.20005)
			)
		)
	)
	(zone
		(layers "F.Cu" "B.Cu" "In2.Cu" "In4.Cu" "In7.Cu" "In9.Cu")
		(hatch none 0.5)
		(connect_pads
			(clearance 0)
		)
		(min_thickness 0.25)
		(keepout
			(tracks not_allowed)
			(vias allowed)
			(pads allowed)
			(copperpour not_allowed)
			(footprints allowed)
		)
		(placement
			(enabled no)
			(sheetname "")
		)
		(fill yes
			(thermal_gap 0.5)
			(thermal_bridge_width 0.5)
			(island_removal_mode 0)
		)
		(polygon
			(pts
				(arc
					(start 421.431974 -39.034974)
					(mid 418.968174 -39.034974)
					(end 421.431974 -39.034974)
				)
			)
		)
	)
	(zone
		(layers "F.Cu" "B.Cu" "In2.Cu" "In4.Cu" "In7.Cu" "In9.Cu")
		(hatch none 0.5)
		(connect_pads
			(clearance 0)
		)
		(min_thickness 0.25)
		(keepout
			(tracks not_allowed)
			(vias allowed)
			(pads allowed)
			(copperpour not_allowed)
			(footprints allowed)
		)
		(placement
			(enabled no)
			(sheetname "")
		)
		(fill yes
			(thermal_gap 0.5)
			(thermal_bridge_width 0.5)
			(island_removal_mode 0)
		)
		(polygon
			(pts
				(arc
					(start 234.108244 6.500114)
					(mid 225.592132 6.500114)
					(end 234.108244 6.500114)
				)
			)
		)
	)
	(zone
		(layers "F.Cu" "B.Cu" "In2.Cu" "In4.Cu" "In7.Cu" "In9.Cu")
		(hatch none 0.5)
		(connect_pads
			(clearance 0)
		)
		(min_thickness 0.25)
		(keepout
			(tracks not_allowed)
			(vias allowed)
			(pads allowed)
			(copperpour not_allowed)
			(footprints allowed)
		)
		(placement
			(enabled no)
			(sheetname "")
		)
		(fill yes
			(thermal_gap 0.5)
			(thermal_bridge_width 0.5)
			(island_removal_mode 0)
		)
		(polygon
			(pts
				(arc
					(start 326.781922 -39.034974)
					(mid 324.318122 -39.034974)
					(end 326.781922 -39.034974)
				)
			)
		)
	)
	(zone
		(layers "F.Cu" "B.Cu" "In2.Cu" "In4.Cu" "In7.Cu" "In9.Cu")
		(hatch none 0.5)
		(connect_pads
			(clearance 0)
		)
		(min_thickness 0.25)
		(keepout
			(tracks not_allowed)
			(vias allowed)
			(pads allowed)
			(copperpour not_allowed)
			(footprints allowed)
		)
		(placement
			(enabled no)
			(sheetname "")
		)
		(fill yes
			(thermal_gap 0.5)
			(thermal_bridge_width 0.5)
			(island_removal_mode 0)
		)
		(polygon
			(pts
				(arc
					(start 389.881872 -269.035022)
					(mid 387.418072 -269.035022)
					(end 389.881872 -269.035022)
				)
			)
		)
	)
	(zone
		(layers "F.Cu" "B.Cu" "In2.Cu" "In4.Cu" "In7.Cu" "In9.Cu")
		(hatch none 0.5)
		(connect_pads
			(clearance 0)
		)
		(min_thickness 0.25)
		(keepout
			(tracks not_allowed)
			(vias allowed)
			(pads allowed)
			(copperpour not_allowed)
			(footprints allowed)
		)
		(placement
			(enabled no)
			(sheetname "")
		)
		(fill yes
			(thermal_gap 0.5)
			(thermal_bridge_width 0.5)
			(island_removal_mode 0)
		)
		(polygon
			(pts
				(arc
					(start 49.257966 -270.000476)
					(mid 44.000166 -264.742676)
					(end 38.742112 -270.000476)
				)
				(arc
					(start 38.742112 -270.000476)
					(mid 44.000166 -275.25853)
					(end 49.257966 -270.000476)
				)
			)
		)
	)
	(zone
		(layers "F.Cu" "B.Cu" "In2.Cu" "In4.Cu" "In7.Cu" "In9.Cu")
		(hatch none 0.5)
		(connect_pads
			(clearance 0)
		)
		(min_thickness 0.25)
		(keepout
			(tracks not_allowed)
			(vias allowed)
			(pads allowed)
			(copperpour not_allowed)
			(footprints allowed)
		)
		(placement
			(enabled no)
			(sheetname "")
		)
		(fill yes
			(thermal_gap 0.5)
			(thermal_bridge_width 0.5)
			(island_removal_mode 0)
		)
		(polygon
			(pts
				(arc
					(start 241.039904 -184.29986)
					(mid 237.560104 -184.29986)
					(end 241.039904 -184.29986)
				)
			)
		)
	)
	(zone
		(layers "F.Cu" "B.Cu" "In2.Cu" "In4.Cu" "In7.Cu" "In9.Cu")
		(hatch none 0.5)
		(connect_pads
			(clearance 0)
		)
		(min_thickness 0.25)
		(keepout
			(tracks not_allowed)
			(vias allowed)
			(pads allowed)
			(copperpour not_allowed)
			(footprints allowed)
		)
		(placement
			(enabled no)
			(sheetname "")
		)
		(fill yes
			(thermal_gap 0.5)
			(thermal_bridge_width 0.5)
			(island_removal_mode 0)
		)
		(polygon
			(pts
				(arc
					(start 155.631896 -191.784986)
					(mid 153.168096 -191.784986)
					(end 155.631896 -191.784986)
				)
			)
		)
	)
	(zone
		(layers "F.Cu" "B.Cu" "In2.Cu" "In4.Cu" "In7.Cu" "In9.Cu")
		(hatch none 0.5)
		(connect_pads
			(clearance 0)
		)
		(min_thickness 0.25)
		(keepout
			(tracks not_allowed)
			(vias allowed)
			(pads allowed)
			(copperpour not_allowed)
			(footprints allowed)
		)
		(placement
			(enabled no)
			(sheetname "")
		)
		(fill yes
			(thermal_gap 0.5)
			(thermal_bridge_width 0.5)
			(island_removal_mode 0)
		)
		(polygon
			(pts
				(arc
					(start 166.833042 -92.800424)
					(mid 159.325056 -85.292438)
					(end 151.81707 -92.800424)
				)
				(arc
					(start 151.81707 -98.800412)
					(mid 159.325056 -106.308398)
					(end 166.833042 -98.800412)
				)
			)
		)
	)
	(zone
		(layers "F.Cu" "B.Cu" "In2.Cu" "In4.Cu" "In7.Cu" "In9.Cu")
		(hatch none 0.5)
		(connect_pads
			(clearance 0)
		)
		(min_thickness 0.25)
		(keepout
			(tracks not_allowed)
			(vias allowed)
			(pads allowed)
			(copperpour not_allowed)
			(footprints allowed)
		)
		(placement
			(enabled no)
			(sheetname "")
		)
		(fill yes
			(thermal_gap 0.5)
			(thermal_bridge_width 0.5)
			(island_removal_mode 0)
		)
		(polygon
			(pts
				(arc
					(start 326.781922 -154.034998)
					(mid 324.318122 -154.034998)
					(end 326.781922 -154.034998)
				)
			)
		)
	)
	(zone
		(layers "F.Cu" "B.Cu" "In2.Cu" "In4.Cu" "In7.Cu" "In9.Cu")
		(hatch none 0.5)
		(connect_pads
			(clearance 0)
		)
		(min_thickness 0.25)
		(keepout
			(tracks not_allowed)
			(vias allowed)
			(pads allowed)
			(copperpour not_allowed)
			(footprints allowed)
		)
		(placement
			(enabled no)
			(sheetname "")
		)
		(fill yes
			(thermal_gap 0.5)
			(thermal_bridge_width 0.5)
			(island_removal_mode 0)
		)
		(polygon
			(pts
				(arc
					(start 472.758008 -270.000476)
					(mid 467.500208 -264.742676)
					(end 462.242154 -270.000476)
				)
				(arc
					(start 462.242154 -270.000476)
					(mid 467.500208 -275.25853)
					(end 472.758008 -270.000476)
				)
			)
		)
	)
	(zone
		(layers "F.Cu" "B.Cu" "In2.Cu" "In4.Cu" "In7.Cu" "In9.Cu")
		(hatch none 0.5)
		(connect_pads
			(clearance 0)
		)
		(min_thickness 0.25)
		(keepout
			(tracks not_allowed)
			(vias allowed)
			(pads allowed)
			(copperpour not_allowed)
			(footprints allowed)
		)
		(placement
			(enabled no)
			(sheetname "")
		)
		(fill yes
			(thermal_gap 0.5)
			(thermal_bridge_width 0.5)
			(island_removal_mode 0)
		)
		(polygon
			(pts
				(arc
					(start 452.981822 -39.034974)
					(mid 450.518022 -39.034974)
					(end 452.981822 -39.034974)
				)
			)
		)
	)
	(zone
		(layers "F.Cu" "B.Cu" "In2.Cu" "In4.Cu" "In7.Cu" "In9.Cu")
		(hatch none 0.5)
		(connect_pads
			(clearance 0)
		)
		(min_thickness 0.25)
		(keepout
			(tracks not_allowed)
			(vias allowed)
			(pads allowed)
			(copperpour not_allowed)
			(footprints allowed)
		)
		(placement
			(enabled no)
			(sheetname "")
		)
		(fill yes
			(thermal_gap 0.5)
			(thermal_bridge_width 0.5)
			(island_removal_mode 0)
		)
		(polygon
			(pts
				(arc
					(start 209.808064 -183.799988)
					(mid 202.300078 -176.292002)
					(end 194.792092 -183.799988)
				)
				(arc
					(start 194.792092 -189.799976)
					(mid 202.300078 -197.307962)
					(end 209.808064 -189.799976)
				)
			)
		)
	)
	(zone
		(layers "F.Cu" "B.Cu" "In2.Cu" "In4.Cu" "In7.Cu" "In9.Cu")
		(hatch none 0.5)
		(connect_pads
			(clearance 0)
		)
		(min_thickness 0.25)
		(keepout
			(tracks not_allowed)
			(vias allowed)
			(pads allowed)
			(copperpour not_allowed)
			(footprints allowed)
		)
		(placement
			(enabled no)
			(sheetname "")
		)
		(fill yes
			(thermal_gap 0.5)
			(thermal_bridge_width 0.5)
			(island_removal_mode 0)
		)
		(polygon
			(pts
				(arc
					(start 338.182966 -207.800448)
					(mid 330.67498 -200.292462)
					(end 323.166994 -207.800448)
				)
				(arc
					(start 323.166994 -213.800436)
					(mid 330.67498 -221.308422)
					(end 338.182966 -213.800436)
				)
			)
		)
	)
	(zone
		(layers "F.Cu" "B.Cu" "In2.Cu" "In4.Cu" "In7.Cu" "In9.Cu")
		(hatch none 0.5)
		(connect_pads
			(clearance 0)
		)
		(min_thickness 0.25)
		(keepout
			(tracks not_allowed)
			(vias allowed)
			(pads allowed)
			(copperpour not_allowed)
			(footprints allowed)
		)
		(placement
			(enabled no)
			(sheetname "")
		)
		(fill yes
			(thermal_gap 0.5)
			(thermal_bridge_width 0.5)
			(island_removal_mode 0)
		)
		(polygon
			(pts
				(arc
					(start 358.332024 -269.035022)
					(mid 355.868224 -269.035022)
					(end 358.332024 -269.035022)
				)
			)
		)
	)
	(zone
		(layers "F.Cu" "B.Cu" "In2.Cu" "In4.Cu" "In7.Cu" "In9.Cu")
		(hatch none 0.5)
		(connect_pads
			(clearance 0)
		)
		(min_thickness 0.25)
		(keepout
			(tracks not_allowed)
			(vias allowed)
			(pads allowed)
			(copperpour not_allowed)
			(footprints allowed)
		)
		(placement
			(enabled no)
			(sheetname "")
		)
		(fill yes
			(thermal_gap 0.5)
			(thermal_bridge_width 0.5)
			(island_removal_mode 0)
		)
		(polygon
			(pts
				(arc
					(start 29.431996 -76.784962)
					(mid 26.968196 -76.784962)
					(end 29.431996 -76.784962)
				)
			)
		)
	)
	(zone
		(layers "F.Cu" "B.Cu" "In2.Cu" "In4.Cu" "In7.Cu" "In9.Cu")
		(hatch none 0.5)
		(connect_pads
			(clearance 0)
		)
		(min_thickness 0.25)
		(keepout
			(tracks not_allowed)
			(vias allowed)
			(pads allowed)
			(copperpour not_allowed)
			(footprints allowed)
		)
		(placement
			(enabled no)
			(sheetname "")
		)
		(fill yes
			(thermal_gap 0.5)
			(thermal_bridge_width 0.5)
			(island_removal_mode 0)
		)
		(polygon
			(pts
				(arc
					(start 421.431974 -191.784986)
					(mid 418.968174 -191.784986)
					(end 421.431974 -191.784986)
				)
			)
		)
	)
	(zone
		(layers "F.Cu" "B.Cu" "In2.Cu" "In4.Cu" "In7.Cu" "In9.Cu")
		(hatch none 0.5)
		(connect_pads
			(clearance 0)
		)
		(min_thickness 0.25)
		(keepout
			(tracks not_allowed)
			(vias allowed)
			(pads allowed)
			(copperpour not_allowed)
			(footprints allowed)
		)
		(placement
			(enabled no)
			(sheetname "")
		)
		(fill yes
			(thermal_gap 0.5)
			(thermal_bridge_width 0.5)
			(island_removal_mode 0)
		)
		(polygon
			(pts
				(arc
					(start 452.981822 -154.034998)
					(mid 450.518022 -154.034998)
					(end 452.981822 -154.034998)
				)
			)
		)
	)
	(zone
		(layers "F.Cu" "B.Cu" "In2.Cu" "In4.Cu" "In7.Cu" "In9.Cu")
		(hatch none 0.5)
		(connect_pads
			(clearance 0)
		)
		(min_thickness 0.25)
		(keepout
			(tracks not_allowed)
			(vias allowed)
			(pads allowed)
			(copperpour not_allowed)
			(footprints allowed)
		)
		(placement
			(enabled no)
			(sheetname "")
		)
		(fill yes
			(thermal_gap 0.5)
			(thermal_bridge_width 0.5)
			(island_removal_mode 0)
		)
		(polygon
			(pts
				(arc
					(start 124.081794 -39.034974)
					(mid 121.617994 -39.034974)
					(end 124.081794 -39.034974)
				)
			)
		)
	)
	(zone
		(layers "F.Cu" "B.Cu" "In2.Cu" "In4.Cu" "In7.Cu" "In9.Cu")
		(hatch none 0.5)
		(connect_pads
			(clearance 0)
		)
		(min_thickness 0.25)
		(keepout
			(tracks not_allowed)
			(vias allowed)
			(pads allowed)
			(copperpour not_allowed)
			(footprints allowed)
		)
		(placement
			(enabled no)
			(sheetname "")
		)
		(fill yes
			(thermal_gap 0.5)
			(thermal_bridge_width 0.5)
			(island_removal_mode 0)
		)
		(polygon
			(pts
				(arc
					(start 92.531946 -269.035022)
					(mid 90.068146 -269.035022)
					(end 92.531946 -269.035022)
				)
			)
		)
	)
	(zone
		(layers "F.Cu" "B.Cu" "In2.Cu" "In4.Cu" "In7.Cu" "In9.Cu")
		(hatch none 0.5)
		(connect_pads
			(clearance 0)
		)
		(min_thickness 0.25)
		(keepout
			(tracks not_allowed)
			(vias allowed)
			(pads allowed)
			(copperpour not_allowed)
			(footprints allowed)
		)
		(placement
			(enabled no)
			(sheetname "")
		)
		(fill yes
			(thermal_gap 0.5)
			(thermal_bridge_width 0.5)
			(island_removal_mode 0)
		)
		(polygon
			(pts
				(arc
					(start 209.808064 -63.800482)
					(mid 202.300078 -56.292496)
					(end 194.792092 -63.800482)
				)
				(arc
					(start 194.792092 -69.80047)
					(mid 202.300078 -77.308456)
					(end 209.808064 -69.80047)
				)
			)
		)
	)
	(zone
		(layers "F.Cu" "B.Cu" "In2.Cu" "In4.Cu" "In7.Cu" "In9.Cu")
		(hatch none 0.5)
		(connect_pads
			(clearance 0)
		)
		(min_thickness 0.25)
		(keepout
			(tracks not_allowed)
			(vias allowed)
			(pads allowed)
			(copperpour not_allowed)
			(footprints allowed)
		)
		(placement
			(enabled no)
			(sheetname "")
		)
		(fill yes
			(thermal_gap 0.5)
			(thermal_bridge_width 0.5)
			(island_removal_mode 0)
		)
		(polygon
			(pts
				(arc
					(start 251.707904 -360.19994)
					(mid 244.199918 -352.691954)
					(end 236.691932 -360.19994)
				)
				(arc
					(start 236.691932 -366.199928)
					(mid 244.199918 -373.707914)
					(end 251.707904 -366.199928)
				)
			)
		)
	)
	(zone
		(layers "F.Cu" "B.Cu" "In2.Cu" "In4.Cu" "In7.Cu" "In9.Cu")
		(hatch none 0.5)
		(connect_pads
			(clearance 0)
		)
		(min_thickness 0.25)
		(keepout
			(tracks not_allowed)
			(vias allowed)
			(pads allowed)
			(copperpour not_allowed)
			(footprints allowed)
		)
		(placement
			(enabled no)
			(sheetname "")
		)
		(fill yes
			(thermal_gap 0.5)
			(thermal_bridge_width 0.5)
			(island_removal_mode 0)
		)
		(polygon
			(pts
				(arc
					(start 155.631896 -269.035022)
					(mid 153.168096 -269.035022)
					(end 155.631896 -269.035022)
				)
			)
		)
	)
	(zone
		(layers "F.Cu" "B.Cu" "In2.Cu" "In4.Cu" "In7.Cu" "In9.Cu")
		(hatch none 0.5)
		(connect_pads
			(clearance 0)
		)
		(min_thickness 0.25)
		(keepout
			(tracks not_allowed)
			(vias allowed)
			(pads allowed)
			(copperpour not_allowed)
			(footprints allowed)
		)
		(placement
			(enabled no)
			(sheetname "")
		)
		(fill yes
			(thermal_gap 0.5)
			(thermal_bridge_width 0.5)
			(island_removal_mode 0)
		)
		(polygon
			(pts
				(arc
					(start 60.981844 -306.78501)
					(mid 58.518044 -306.78501)
					(end 60.981844 -306.78501)
				)
			)
		)
	)
	(zone
		(layers "F.Cu" "B.Cu" "In2.Cu" "In4.Cu" "In7.Cu" "In9.Cu")
		(hatch none 0.5)
		(connect_pads
			(clearance 0)
		)
		(min_thickness 0.25)
		(keepout
			(tracks not_allowed)
			(vias allowed)
			(pads allowed)
			(copperpour not_allowed)
			(footprints allowed)
		)
		(placement
			(enabled no)
			(sheetname "")
		)
		(fill yes
			(thermal_gap 0.5)
			(thermal_bridge_width 0.5)
			(island_removal_mode 0)
		)
		(polygon
			(pts
				(arc
					(start 166.833042 -322.800472)
					(mid 159.325056 -315.292486)
					(end 151.81707 -322.800472)
				)
				(arc
					(start 151.81707 -328.80046)
					(mid 159.325056 -336.308446)
					(end 166.833042 -328.80046)
				)
			)
		)
	)
	(zone
		(layers "F.Cu" "B.Cu" "In2.Cu" "In4.Cu" "In7.Cu" "In9.Cu")
		(hatch none 0.5)
		(connect_pads
			(clearance 0)
		)
		(min_thickness 0.25)
		(keepout
			(tracks not_allowed)
			(vias allowed)
			(pads allowed)
			(copperpour not_allowed)
			(footprints allowed)
		)
		(placement
			(enabled no)
			(sheetname "")
		)
		(fill yes
			(thermal_gap 0.5)
			(thermal_bridge_width 0.5)
			(island_removal_mode 0)
		)
		(polygon
			(pts
				(arc
					(start 464.182968 -322.800472)
					(mid 456.674982 -315.292486)
					(end 449.166996 -322.800472)
				)
				(arc
					(start 449.166996 -328.80046)
					(mid 456.674982 -336.308446)
					(end 464.182968 -328.80046)
				)
			)
		)
	)
	(zone
		(layers "F.Cu" "B.Cu" "In2.Cu" "In4.Cu" "In7.Cu" "In9.Cu")
		(hatch none 0.5)
		(connect_pads
			(clearance 0)
		)
		(min_thickness 0.25)
		(keepout
			(tracks not_allowed)
			(vias allowed)
			(pads allowed)
			(copperpour not_allowed)
			(footprints allowed)
		)
		(placement
			(enabled no)
			(sheetname "")
		)
		(fill yes
			(thermal_gap 0.5)
			(thermal_bridge_width 0.5)
			(island_removal_mode 0)
		)
		(polygon
			(pts
				(arc
					(start 29.431996 -191.784986)
					(mid 26.968196 -191.784986)
					(end 29.431996 -191.784986)
				)
			)
		)
	)
	(zone
		(layers "F.Cu" "B.Cu" "In2.Cu" "In4.Cu" "In7.Cu" "In9.Cu")
		(hatch none 0.5)
		(connect_pads
			(clearance 0)
		)
		(min_thickness 0.25)
		(keepout
			(tracks not_allowed)
			(vias allowed)
			(pads allowed)
			(copperpour not_allowed)
			(footprints allowed)
		)
		(placement
			(enabled no)
			(sheetname "")
		)
		(fill yes
			(thermal_gap 0.5)
			(thermal_bridge_width 0.5)
			(island_removal_mode 0)
		)
		(polygon
			(pts
				(arc
					(start 175.45812 -270.000476)
					(mid 170.20032 -264.742676)
					(end 164.942266 -270.000476)
				)
				(arc
					(start 164.942266 -270.000476)
					(mid 170.20032 -275.25853)
					(end 175.45812 -270.000476)
				)
			)
		)
	)
	(zone
		(layers "F.Cu" "B.Cu" "In2.Cu" "In4.Cu" "In7.Cu" "In9.Cu")
		(hatch none 0.5)
		(connect_pads
			(clearance 0)
		)
		(min_thickness 0.25)
		(keepout
			(tracks not_allowed)
			(vias allowed)
			(pads allowed)
			(copperpour not_allowed)
			(footprints allowed)
		)
		(placement
			(enabled no)
			(sheetname "")
		)
		(fill yes
			(thermal_gap 0.5)
			(thermal_bridge_width 0.5)
			(island_removal_mode 0)
		)
		(polygon
			(pts
				(arc
					(start 452.981822 -306.78501)
					(mid 450.518022 -306.78501)
					(end 452.981822 -306.78501)
				)
			)
		)
	)
	(zone
		(layers "F.Cu" "B.Cu" "In2.Cu" "In4.Cu" "In7.Cu" "In9.Cu")
		(hatch none 0.5)
		(connect_pads
			(clearance 0)
		)
		(min_thickness 0.25)
		(keepout
			(tracks not_allowed)
			(vias allowed)
			(pads allowed)
			(copperpour not_allowed)
			(footprints allowed)
		)
		(placement
			(enabled no)
			(sheetname "")
		)
		(fill yes
			(thermal_gap 0.5)
			(thermal_bridge_width 0.5)
			(island_removal_mode 0)
		)
		(polygon
			(pts
				(arc
					(start 326.781922 -306.78501)
					(mid 324.318122 -306.78501)
					(end 326.781922 -306.78501)
				)
			)
		)
	)
	(zone
		(layers "F.Cu" "B.Cu" "In2.Cu" "In4.Cu" "In7.Cu" "In9.Cu")
		(hatch none 0.5)
		(connect_pads
			(clearance 0)
		)
		(min_thickness 0.25)
		(keepout
			(tracks not_allowed)
			(vias allowed)
			(pads allowed)
			(copperpour not_allowed)
			(footprints allowed)
		)
		(placement
			(enabled no)
			(sheetname "")
		)
		(fill yes
			(thermal_gap 0.5)
			(thermal_bridge_width 0.5)
			(island_removal_mode 0)
		)
		(polygon
			(pts
				(arc
					(start 358.332024 -154.034998)
					(mid 355.868224 -154.034998)
					(end 358.332024 -154.034998)
				)
			)
		)
	)
	(zone
		(layers "F.Cu" "B.Cu" "In2.Cu" "In4.Cu" "In7.Cu" "In9.Cu")
		(hatch none 0.5)
		(connect_pads
			(clearance 0)
		)
		(min_thickness 0.25)
		(keepout
			(tracks not_allowed)
			(vias allowed)
			(pads allowed)
			(copperpour not_allowed)
			(footprints allowed)
		)
		(placement
			(enabled no)
			(sheetname "")
		)
		(fill yes
			(thermal_gap 0.5)
			(thermal_bridge_width 0.5)
			(island_removal_mode 0)
		)
		(polygon
			(pts
				(arc
					(start 464.182968 -92.800424)
					(mid 456.674982 -85.292438)
					(end 449.166996 -92.800424)
				)
				(arc
					(start 449.166996 -98.800412)
					(mid 456.674982 -106.308398)
					(end 464.182968 -98.800412)
				)
			)
		)
	)
	(zone
		(layers "F.Cu" "B.Cu" "In2.Cu" "In4.Cu" "In7.Cu" "In9.Cu")
		(hatch none 0.5)
		(connect_pads
			(clearance 0)
		)
		(min_thickness 0.25)
		(keepout
			(tracks not_allowed)
			(vias allowed)
			(pads allowed)
			(copperpour not_allowed)
			(footprints allowed)
		)
		(placement
			(enabled no)
			(sheetname "")
		)
		(fill yes
			(thermal_gap 0.5)
			(thermal_bridge_width 0.5)
			(island_removal_mode 0)
		)
		(polygon
			(pts
				(arc
					(start 92.531946 -306.78501)
					(mid 90.068146 -306.78501)
					(end 92.531946 -306.78501)
				)
			)
		)
	)
	(zone
		(layers "F.Cu" "B.Cu" "In2.Cu" "In4.Cu" "In7.Cu" "In9.Cu")
		(hatch none 0.5)
		(connect_pads
			(clearance 0)
		)
		(min_thickness 0.25)
		(keepout
			(tracks not_allowed)
			(vias allowed)
			(pads allowed)
			(copperpour not_allowed)
			(footprints allowed)
		)
		(placement
			(enabled no)
			(sheetname "")
		)
		(fill yes
			(thermal_gap 0.5)
			(thermal_bridge_width 0.5)
			(island_removal_mode 0)
		)
		(polygon
			(pts
				(arc
					(start 29.431996 -306.78501)
					(mid 26.968196 -306.78501)
					(end 29.431996 -306.78501)
				)
			)
		)
	)
	(zone
		(layers "F.Cu" "B.Cu" "In2.Cu" "In4.Cu" "In7.Cu" "In9.Cu")
		(hatch none 0.5)
		(connect_pads
			(clearance 0)
		)
		(min_thickness 0.25)
		(keepout
			(tracks not_allowed)
			(vias allowed)
			(pads allowed)
			(copperpour not_allowed)
			(footprints allowed)
		)
		(placement
			(enabled no)
			(sheetname "")
		)
		(fill yes
			(thermal_gap 0.5)
			(thermal_bridge_width 0.5)
			(island_removal_mode 0)
		)
		(polygon
			(pts
				(arc
					(start 124.081794 -76.784962)
					(mid 121.617994 -76.784962)
					(end 124.081794 -76.784962)
				)
			)
		)
	)
	(zone
		(layers "F.Cu" "B.Cu" "In2.Cu" "In4.Cu" "In7.Cu" "In9.Cu")
		(hatch none 0.5)
		(connect_pads
			(clearance 0)
		)
		(min_thickness 0.25)
		(keepout
			(tracks not_allowed)
			(vias allowed)
			(pads allowed)
			(copperpour not_allowed)
			(footprints allowed)
		)
		(placement
			(enabled no)
			(sheetname "")
		)
		(fill yes
			(thermal_gap 0.5)
			(thermal_bridge_width 0.5)
			(island_removal_mode 0)
		)
		(polygon
			(pts
				(arc
					(start 92.531946 -191.784986)
					(mid 90.068146 -191.784986)
					(end 92.531946 -191.784986)
				)
			)
		)
	)
	(zone
		(layers "F.Cu" "B.Cu" "In2.Cu" "In4.Cu" "In7.Cu" "In9.Cu")
		(hatch none 0.5)
		(connect_pads
			(clearance 0)
		)
		(min_thickness 0.25)
		(keepout
			(tracks not_allowed)
			(vias allowed)
			(pads allowed)
			(copperpour not_allowed)
			(footprints allowed)
		)
		(placement
			(enabled no)
			(sheetname "")
		)
		(fill yes
			(thermal_gap 0.5)
			(thermal_bridge_width 0.5)
			(island_removal_mode 0)
		)
		(polygon
			(pts
				(arc
					(start 452.981822 -191.784986)
					(mid 450.518022 -191.784986)
					(end 452.981822 -191.784986)
				)
			)
		)
	)
	(zone
		(layers "F.Cu" "B.Cu" "In2.Cu" "In4.Cu" "In7.Cu" "In9.Cu")
		(hatch none 0.5)
		(connect_pads
			(clearance 0)
		)
		(min_thickness 0.25)
		(keepout
			(tracks not_allowed)
			(vias allowed)
			(pads allowed)
			(copperpour not_allowed)
			(footprints allowed)
		)
		(placement
			(enabled no)
			(sheetname "")
		)
		(fill yes
			(thermal_gap 0.5)
			(thermal_bridge_width 0.5)
			(island_removal_mode 0)
		)
		(polygon
			(pts
				(arc
					(start 103.832914 -207.800448)
					(mid 96.324928 -200.292462)
					(end 88.816942 -207.800448)
				)
				(arc
					(start 88.816942 -213.800436)
					(mid 96.324928 -221.308422)
					(end 103.832914 -213.800436)
				)
			)
		)
	)
	(zone
		(layers "F.Cu" "B.Cu" "In2.Cu" "In4.Cu" "In7.Cu" "In9.Cu")
		(hatch none 0.5)
		(connect_pads
			(clearance 0)
		)
		(min_thickness 0.25)
		(keepout
			(tracks not_allowed)
			(vias allowed)
			(pads allowed)
			(copperpour not_allowed)
			(footprints allowed)
		)
		(placement
			(enabled no)
			(sheetname "")
		)
		(fill yes
			(thermal_gap 0.5)
			(thermal_bridge_width 0.5)
			(island_removal_mode 0)
		)
		(polygon
			(pts
				(arc
					(start 124.081794 -154.034998)
					(mid 121.617994 -154.034998)
					(end 124.081794 -154.034998)
				)
			)
		)
	)
	(zone
		(layers "F.Cu" "B.Cu" "In2.Cu" "In4.Cu" "In7.Cu" "In9.Cu")
		(hatch none 0.5)
		(connect_pads
			(clearance 0)
		)
		(min_thickness 0.25)
		(keepout
			(tracks not_allowed)
			(vias allowed)
			(pads allowed)
			(copperpour not_allowed)
			(footprints allowed)
		)
		(placement
			(enabled no)
			(sheetname "")
		)
		(fill yes
			(thermal_gap 0.5)
			(thermal_bridge_width 0.5)
			(island_removal_mode 0)
		)
		(polygon
			(pts
				(arc
					(start 401.183094 -92.800424)
					(mid 393.675108 -85.292438)
					(end 386.167122 -92.800424)
				)
				(arc
					(start 386.167122 -98.800412)
					(mid 393.675108 -106.308398)
					(end 401.183094 -98.800412)
				)
			)
		)
	)
	(zone
		(layers "F.Cu" "B.Cu" "In2.Cu" "In4.Cu" "In7.Cu" "In9.Cu")
		(hatch none 0.5)
		(connect_pads
			(clearance 0)
		)
		(min_thickness 0.25)
		(keepout
			(tracks not_allowed)
			(vias allowed)
			(pads allowed)
			(copperpour not_allowed)
			(footprints allowed)
		)
		(placement
			(enabled no)
			(sheetname "")
		)
		(fill yes
			(thermal_gap 0.5)
			(thermal_bridge_width 0.5)
			(island_removal_mode 0)
		)
		(polygon
			(pts
				(arc
					(start 484.531924 -191.784986)
					(mid 482.068124 -191.784986)
					(end 484.531924 -191.784986)
				)
			)
		)
	)
	(zone
		(layers "F.Cu" "B.Cu" "In2.Cu" "In4.Cu" "In7.Cu" "In9.Cu")
		(hatch none 0.5)
		(connect_pads
			(clearance 0)
		)
		(min_thickness 0.25)
		(keepout
			(tracks not_allowed)
			(vias allowed)
			(pads allowed)
			(copperpour not_allowed)
			(footprints allowed)
		)
		(placement
			(enabled no)
			(sheetname "")
		)
		(fill yes
			(thermal_gap 0.5)
			(thermal_bridge_width 0.5)
			(island_removal_mode 0)
		)
		(polygon
			(pts
				(arc
					(start 358.332024 -39.034974)
					(mid 355.868224 -39.034974)
					(end 358.332024 -39.034974)
				)
			)
		)
	)
	(zone
		(layers "F.Cu" "B.Cu" "In2.Cu" "In4.Cu" "In7.Cu" "In9.Cu")
		(hatch none 0.5)
		(connect_pads
			(clearance 0)
		)
		(min_thickness 0.25)
		(keepout
			(tracks not_allowed)
			(vias allowed)
			(pads allowed)
			(copperpour not_allowed)
			(footprints allowed)
		)
		(placement
			(enabled no)
			(sheetname "")
		)
		(fill yes
			(thermal_gap 0.5)
			(thermal_bridge_width 0.5)
			(island_removal_mode 0)
		)
		(polygon
			(pts
				(arc
					(start 484.531924 -39.034974)
					(mid 482.068124 -39.034974)
					(end 484.531924 -39.034974)
				)
			)
		)
	)
	(zone
		(layers "F.Cu" "B.Cu" "In2.Cu" "In4.Cu" "In7.Cu" "In9.Cu")
		(hatch none 0.5)
		(connect_pads
			(clearance 0)
		)
		(min_thickness 0.25)
		(keepout
			(tracks not_allowed)
			(vias allowed)
			(pads allowed)
			(copperpour not_allowed)
			(footprints allowed)
		)
		(placement
			(enabled no)
			(sheetname "")
		)
		(fill yes
			(thermal_gap 0.5)
			(thermal_bridge_width 0.5)
			(island_removal_mode 0)
		)
		(polygon
			(pts
				(arc
					(start 155.631896 -306.78501)
					(mid 153.168096 -306.78501)
					(end 155.631896 -306.78501)
				)
			)
		)
	)
	(zone
		(layers "F.Cu" "B.Cu" "In2.Cu" "In4.Cu" "In7.Cu" "In9.Cu")
		(hatch none 0.5)
		(connect_pads
			(clearance 0)
		)
		(min_thickness 0.25)
		(keepout
			(tracks not_allowed)
			(vias allowed)
			(pads allowed)
			(copperpour not_allowed)
			(footprints allowed)
		)
		(placement
			(enabled no)
			(sheetname "")
		)
		(fill yes
			(thermal_gap 0.5)
			(thermal_bridge_width 0.5)
			(island_removal_mode 0)
		)
		(polygon
			(pts
				(arc
					(start 252.108208 6.500114)
					(mid 243.592096 6.500114)
					(end 252.108208 6.500114)
				)
			)
		)
	)
	(zone
		(layers "F.Cu" "B.Cu" "In2.Cu" "In4.Cu" "In7.Cu" "In9.Cu")
		(hatch none 0.5)
		(connect_pads
			(clearance 0)
		)
		(min_thickness 0.25)
		(keepout
			(tracks not_allowed)
			(vias allowed)
			(pads allowed)
			(copperpour not_allowed)
			(footprints allowed)
		)
		(placement
			(enabled no)
			(sheetname "")
		)
		(fill yes
			(thermal_gap 0.5)
			(thermal_bridge_width 0.5)
			(island_removal_mode 0)
		)
		(polygon
			(pts
				(arc
					(start 60.981844 -191.784986)
					(mid 58.518044 -191.784986)
					(end 60.981844 -191.784986)
				)
			)
		)
	)
	(zone
		(layers "F.Cu" "B.Cu" "In2.Cu" "In4.Cu" "In7.Cu" "In9.Cu")
		(hatch none 0.5)
		(connect_pads
			(clearance 0)
		)
		(min_thickness 0.25)
		(keepout
			(tracks not_allowed)
			(vias allowed)
			(pads allowed)
			(copperpour not_allowed)
			(footprints allowed)
		)
		(placement
			(enabled no)
			(sheetname "")
		)
		(fill yes
			(thermal_gap 0.5)
			(thermal_bridge_width 0.5)
			(island_removal_mode 0)
		)
		(polygon
			(pts
				(arc
					(start 40.83304 -322.800472)
					(mid 33.325054 -315.292486)
					(end 25.817068 -322.800472)
				)
				(arc
					(start 25.817068 -328.80046)
					(mid 33.325054 -336.308446)
					(end 40.83304 -328.80046)
				)
			)
		)
	)
	(zone
		(layers "F.Cu" "B.Cu" "In2.Cu" "In4.Cu" "In7.Cu" "In9.Cu")
		(hatch none 0.5)
		(connect_pads
			(clearance 0)
		)
		(min_thickness 0.25)
		(keepout
			(tracks not_allowed)
			(vias allowed)
			(pads allowed)
			(copperpour not_allowed)
			(footprints allowed)
		)
		(placement
			(enabled no)
			(sheetname "")
		)
		(fill yes
			(thermal_gap 0.5)
			(thermal_bridge_width 0.5)
			(island_removal_mode 0)
		)
		(polygon
			(pts
				(arc
					(start 421.431974 -154.034998)
					(mid 418.968174 -154.034998)
					(end 421.431974 -154.034998)
				)
			)
		)
	)
	(zone
		(layers "F.Cu" "B.Cu" "In2.Cu" "In4.Cu" "In7.Cu" "In9.Cu")
		(hatch none 0.5)
		(connect_pads
			(clearance 0)
		)
		(min_thickness 0.25)
		(keepout
			(tracks not_allowed)
			(vias allowed)
			(pads allowed)
			(copperpour not_allowed)
			(footprints allowed)
		)
		(placement
			(enabled no)
			(sheetname "")
		)
		(fill yes
			(thermal_gap 0.5)
			(thermal_bridge_width 0.5)
			(island_removal_mode 0)
		)
		(polygon
			(pts
				(arc
					(start 155.631896 -76.784962)
					(mid 153.168096 -76.784962)
					(end 155.631896 -76.784962)
				)
			)
		)
	)
	(zone
		(layers "F.Cu" "B.Cu" "In2.Cu" "In4.Cu" "In7.Cu" "In9.Cu")
		(hatch none 0.5)
		(connect_pads
			(clearance 0)
		)
		(min_thickness 0.25)
		(keepout
			(tracks not_allowed)
			(vias allowed)
			(pads allowed)
			(copperpour not_allowed)
			(footprints allowed)
		)
		(placement
			(enabled no)
			(sheetname "")
		)
		(fill yes
			(thermal_gap 0.5)
			(thermal_bridge_width 0.5)
			(island_removal_mode 0)
		)
		(polygon
			(pts
				(arc
					(start 307.708046 -138.200384)
					(mid 300.20006 -130.692398)
					(end 292.692074 -138.200384)
				)
				(arc
					(start 292.692074 -144.200372)
					(mid 300.20006 -151.708358)
					(end 307.708046 -144.200372)
				)
			)
		)
	)
	(zone
		(layers "F.Cu" "B.Cu" "In2.Cu" "In4.Cu" "In7.Cu" "In9.Cu")
		(hatch none 0.5)
		(connect_pads
			(clearance 0)
		)
		(min_thickness 0.25)
		(keepout
			(tracks not_allowed)
			(vias allowed)
			(pads allowed)
			(copperpour not_allowed)
			(footprints allowed)
		)
		(placement
			(enabled no)
			(sheetname "")
		)
		(fill yes
			(thermal_gap 0.5)
			(thermal_bridge_width 0.5)
			(island_removal_mode 0)
		)
		(polygon
			(pts
				(arc
					(start 112.357916 -290.000436)
					(mid 107.100116 -284.742636)
					(end 101.842062 -290.000436)
				)
				(arc
					(start 101.842062 -290.000436)
					(mid 107.100116 -295.25849)
					(end 112.357916 -290.000436)
				)
			)
		)
	)
	(zone
		(layers "F.Cu" "B.Cu" "In2.Cu" "In4.Cu" "In7.Cu" "In9.Cu")
		(hatch none 0.5)
		(connect_pads
			(clearance 0)
		)
		(min_thickness 0.25)
		(keepout
			(tracks not_allowed)
			(vias allowed)
			(pads allowed)
			(copperpour not_allowed)
			(footprints allowed)
		)
		(placement
			(enabled no)
			(sheetname "")
		)
		(fill yes
			(thermal_gap 0.5)
			(thermal_bridge_width 0.5)
			(island_removal_mode 0)
		)
		(polygon
			(pts
				(arc
					(start 124.081794 -269.035022)
					(mid 121.617994 -269.035022)
					(end 124.081794 -269.035022)
				)
			)
		)
	)
	(zone
		(layers "F.Cu" "B.Cu" "In2.Cu" "In4.Cu" "In7.Cu" "In9.Cu")
		(hatch none 0.5)
		(connect_pads
			(clearance 0)
		)
		(min_thickness 0.25)
		(keepout
			(tracks not_allowed)
			(vias allowed)
			(pads allowed)
			(copperpour not_allowed)
			(footprints allowed)
		)
		(placement
			(enabled no)
			(sheetname "")
		)
		(fill yes
			(thermal_gap 0.5)
			(thermal_bridge_width 0.5)
			(island_removal_mode 0)
		)
		(polygon
			(pts
				(arc
					(start 283.739844 -88.000078)
					(mid 280.260044 -88.000078)
					(end 283.739844 -88.000078)
				)
			)
		)
	)
	(zone
		(layers "F.Cu" "B.Cu" "In2.Cu" "In4.Cu" "In7.Cu" "In9.Cu")
		(hatch none 0.5)
		(connect_pads
			(clearance 0)
		)
		(min_thickness 0.25)
		(keepout
			(tracks not_allowed)
			(vias allowed)
			(pads allowed)
			(copperpour not_allowed)
			(footprints allowed)
		)
		(placement
			(enabled no)
			(sheetname "")
		)
		(fill yes
			(thermal_gap 0.5)
			(thermal_bridge_width 0.5)
			(island_removal_mode 0)
		)
		(polygon
			(pts
				(arc
					(start 401.183094 -322.800472)
					(mid 393.675108 -315.292486)
					(end 386.167122 -322.800472)
				)
				(arc
					(start 386.167122 -328.80046)
					(mid 393.675108 -336.308446)
					(end 401.183094 -328.80046)
				)
			)
		)
	)
	(zone
		(layers "F.Cu" "B.Cu" "In2.Cu" "In4.Cu" "In7.Cu" "In9.Cu")
		(hatch none 0.5)
		(connect_pads
			(clearance 0)
		)
		(min_thickness 0.25)
		(keepout
			(tracks not_allowed)
			(vias allowed)
			(pads allowed)
			(copperpour not_allowed)
			(footprints allowed)
		)
		(placement
			(enabled no)
			(sheetname "")
		)
		(fill yes
			(thermal_gap 0.5)
			(thermal_bridge_width 0.5)
			(island_removal_mode 0)
		)
		(polygon
			(pts
				(arc
					(start 29.431996 -269.035022)
					(mid 26.968196 -269.035022)
					(end 29.431996 -269.035022)
				)
			)
		)
	)
	(zone
		(layers "F.Cu" "B.Cu" "In2.Cu" "In4.Cu" "In7.Cu" "In9.Cu")
		(hatch none 0.5)
		(connect_pads
			(clearance 0)
		)
		(min_thickness 0.25)
		(keepout
			(tracks not_allowed)
			(vias allowed)
			(pads allowed)
			(copperpour not_allowed)
			(footprints allowed)
		)
		(placement
			(enabled no)
			(sheetname "")
		)
		(fill yes
			(thermal_gap 0.5)
			(thermal_bridge_width 0.5)
			(island_removal_mode 0)
		)
		(polygon
			(pts
				(arc
					(start 401.183094 -207.800448)
					(mid 393.675108 -200.292462)
					(end 386.167122 -207.800448)
				)
				(arc
					(start 386.167122 -213.800436)
					(mid 393.675108 -221.308422)
					(end 401.183094 -213.800436)
				)
			)
		)
	)
	(zone
		(layers "F.Cu" "B.Cu" "In2.Cu" "In4.Cu" "In7.Cu" "In9.Cu")
		(hatch none 0.5)
		(connect_pads
			(clearance 0)
		)
		(min_thickness 0.25)
		(keepout
			(tracks not_allowed)
			(vias allowed)
			(pads allowed)
			(copperpour not_allowed)
			(footprints allowed)
		)
		(placement
			(enabled no)
			(sheetname "")
		)
		(fill yes
			(thermal_gap 0.5)
			(thermal_bridge_width 0.5)
			(island_removal_mode 0)
		)
		(polygon
			(pts
				(arc
					(start 155.631896 -154.034998)
					(mid 153.168096 -154.034998)
					(end 155.631896 -154.034998)
				)
			)
		)
	)
	(zone
		(layers "F.Cu" "B.Cu" "In2.Cu" "In4.Cu" "In7.Cu" "In9.Cu")
		(hatch none 0.5)
		(connect_pads
			(clearance 0)
		)
		(min_thickness 0.25)
		(keepout
			(tracks not_allowed)
			(vias allowed)
			(pads allowed)
			(copperpour not_allowed)
			(footprints allowed)
		)
		(placement
			(enabled no)
			(sheetname "")
		)
		(fill yes
			(thermal_gap 0.5)
			(thermal_bridge_width 0.5)
			(island_removal_mode 0)
		)
		(polygon
			(pts
				(arc
					(start 60.981844 -154.034998)
					(mid 58.518044 -154.034998)
					(end 60.981844 -154.034998)
				)
			)
		)
	)
	(zone
		(layers "F.Cu" "B.Cu" "In2.Cu" "In4.Cu" "In7.Cu" "In9.Cu")
		(hatch none 0.5)
		(connect_pads
			(clearance 0)
		)
		(min_thickness 0.25)
		(keepout
			(tracks not_allowed)
			(vias allowed)
			(pads allowed)
			(copperpour not_allowed)
			(footprints allowed)
		)
		(placement
			(enabled no)
			(sheetname "")
		)
		(fill yes
			(thermal_gap 0.5)
			(thermal_bridge_width 0.5)
			(island_removal_mode 0)
		)
		(polygon
			(pts
				(arc
					(start 421.431974 -269.035022)
					(mid 418.968174 -269.035022)
					(end 421.431974 -269.035022)
				)
			)
		)
	)
	(zone
		(layers "F.Cu" "B.Cu" "In2.Cu" "In4.Cu" "In7.Cu" "In9.Cu")
		(hatch none 0.5)
		(connect_pads
			(clearance 0)
		)
		(min_thickness 0.25)
		(keepout
			(tracks not_allowed)
			(vias allowed)
			(pads allowed)
			(copperpour not_allowed)
			(footprints allowed)
		)
		(placement
			(enabled no)
			(sheetname "")
		)
		(fill yes
			(thermal_gap 0.5)
			(thermal_bridge_width 0.5)
			(island_removal_mode 0)
		)
		(polygon
			(pts
				(arc
					(start 421.431974 -306.78501)
					(mid 418.968174 -306.78501)
					(end 421.431974 -306.78501)
				)
			)
		)
	)
	(zone
		(layers "F.Cu" "B.Cu" "In2.Cu" "In4.Cu" "In7.Cu" "In9.Cu")
		(hatch none 0.5)
		(connect_pads
			(clearance 0)
		)
		(min_thickness 0.25)
		(keepout
			(tracks not_allowed)
			(vias allowed)
			(pads allowed)
			(copperpour not_allowed)
			(footprints allowed)
		)
		(placement
			(enabled no)
			(sheetname "")
		)
		(fill yes
			(thermal_gap 0.5)
			(thermal_bridge_width 0.5)
			(island_removal_mode 0)
		)
		(polygon
			(pts
				(arc
					(start 187.181998 -39.034974)
					(mid 184.718198 -39.034974)
					(end 187.181998 -39.034974)
				)
			)
		)
	)
	(zone
		(layers "F.Cu" "B.Cu" "In2.Cu" "In4.Cu" "In7.Cu" "In9.Cu")
		(hatch none 0.5)
		(connect_pads
			(clearance 0)
		)
		(min_thickness 0.25)
		(keepout
			(tracks not_allowed)
			(vias allowed)
			(pads allowed)
			(copperpour not_allowed)
			(footprints allowed)
		)
		(placement
			(enabled no)
			(sheetname "")
		)
		(fill yes
			(thermal_gap 0.5)
			(thermal_bridge_width 0.5)
			(island_removal_mode 0)
		)
		(polygon
			(pts
				(arc
					(start 124.081794 -191.784986)
					(mid 121.617994 -191.784986)
					(end 124.081794 -191.784986)
				)
			)
		)
	)
	(zone
		(layers "F.Cu" "B.Cu" "In2.Cu" "In4.Cu" "In7.Cu" "In9.Cu")
		(hatch none 0.5)
		(connect_pads
			(clearance 0)
		)
		(min_thickness 0.25)
		(keepout
			(tracks not_allowed)
			(vias allowed)
			(pads allowed)
			(copperpour not_allowed)
			(footprints allowed)
		)
		(placement
			(enabled no)
			(sheetname "")
		)
		(fill yes
			(thermal_gap 0.5)
			(thermal_bridge_width 0.5)
			(island_removal_mode 0)
		)
		(polygon
			(pts
				(arc
					(start 187.181998 -191.784986)
					(mid 184.718198 -191.784986)
					(end 187.181998 -191.784986)
				)
			)
		)
	)
	(zone
		(layers "F.Cu" "B.Cu" "In2.Cu" "In4.Cu" "In7.Cu" "In9.Cu")
		(hatch none 0.5)
		(connect_pads
			(clearance 0)
		)
		(min_thickness 0.25)
		(keepout
			(tracks not_allowed)
			(vias allowed)
			(pads allowed)
			(copperpour not_allowed)
			(footprints allowed)
		)
		(placement
			(enabled no)
			(sheetname "")
		)
		(fill yes
			(thermal_gap 0.5)
			(thermal_bridge_width 0.5)
			(island_removal_mode 0)
		)
		(polygon
			(pts
				(arc
					(start 358.332024 -76.784962)
					(mid 355.868224 -76.784962)
					(end 358.332024 -76.784962)
				)
			)
		)
	)
	(zone
		(layers "F.Cu" "B.Cu" "In2.Cu" "In4.Cu" "In7.Cu" "In9.Cu")
		(hatch none 0.5)
		(connect_pads
			(clearance 0)
		)
		(min_thickness 0.25)
		(keepout
			(tracks not_allowed)
			(vias allowed)
			(pads allowed)
			(copperpour not_allowed)
			(footprints allowed)
		)
		(placement
			(enabled no)
			(sheetname "")
		)
		(fill yes
			(thermal_gap 0.5)
			(thermal_bridge_width 0.5)
			(island_removal_mode 0)
		)
		(polygon
			(pts
				(arc
					(start 484.531924 -306.78501)
					(mid 482.068124 -306.78501)
					(end 484.531924 -306.78501)
				)
			)
		)
	)
	(zone
		(layers "F.Cu" "B.Cu" "In2.Cu" "In4.Cu" "In7.Cu" "In9.Cu")
		(hatch none 0.5)
		(connect_pads
			(clearance 0)
		)
		(min_thickness 0.25)
		(keepout
			(tracks not_allowed)
			(vias allowed)
			(pads allowed)
			(copperpour not_allowed)
			(footprints allowed)
		)
		(placement
			(enabled no)
			(sheetname "")
		)
		(fill yes
			(thermal_gap 0.5)
			(thermal_bridge_width 0.5)
			(island_removal_mode 0)
		)
		(polygon
			(pts
				(arc
					(start 283.739844 -184.29986)
					(mid 280.260044 -184.29986)
					(end 283.739844 -184.29986)
				)
			)
		)
	)
	(zone
		(layers "F.Cu" "B.Cu" "In2.Cu" "In4.Cu" "In7.Cu" "In9.Cu")
		(hatch none 0.5)
		(connect_pads
			(clearance 0)
		)
		(min_thickness 0.25)
		(keepout
			(tracks not_allowed)
			(vias allowed)
			(pads allowed)
			(copperpour not_allowed)
			(footprints allowed)
		)
		(placement
			(enabled no)
			(sheetname "")
		)
		(fill yes
			(thermal_gap 0.5)
			(thermal_bridge_width 0.5)
			(island_removal_mode 0)
		)
		(polygon
			(pts
				(arc
					(start 40.83304 -207.800448)
					(mid 33.325054 -200.292462)
					(end 25.817068 -207.800448)
				)
				(arc
					(start 25.817068 -213.800436)
					(mid 33.325054 -221.308422)
					(end 40.83304 -213.800436)
				)
			)
		)
	)
	(zone
		(layers "F.Cu" "B.Cu" "In2.Cu" "In4.Cu" "In7.Cu" "In9.Cu")
		(hatch none 0.5)
		(connect_pads
			(clearance 0)
		)
		(min_thickness 0.25)
		(keepout
			(tracks not_allowed)
			(vias allowed)
			(pads allowed)
			(copperpour not_allowed)
			(footprints allowed)
		)
		(placement
			(enabled no)
			(sheetname "")
		)
		(fill yes
			(thermal_gap 0.5)
			(thermal_bridge_width 0.5)
			(island_removal_mode 0)
		)
		(polygon
			(pts
				(arc
					(start 338.182966 -92.800424)
					(mid 330.67498 -85.292438)
					(end 323.166994 -92.800424)
				)
				(arc
					(start 323.166994 -98.800412)
					(mid 330.67498 -106.308398)
					(end 338.182966 -98.800412)
				)
			)
		)
	)
	(zone
		(layers "F.Cu" "B.Cu" "In2.Cu" "In4.Cu" "In7.Cu" "In9.Cu")
		(hatch none 0.5)
		(connect_pads
			(clearance 0)
		)
		(min_thickness 0.25)
		(keepout
			(tracks not_allowed)
			(vias allowed)
			(pads allowed)
			(copperpour not_allowed)
			(footprints allowed)
		)
		(placement
			(enabled no)
			(sheetname "")
		)
		(fill yes
			(thermal_gap 0.5)
			(thermal_bridge_width 0.5)
			(island_removal_mode 0)
		)
		(polygon
			(pts
				(arc
					(start 166.833042 -207.800448)
					(mid 159.325056 -200.292462)
					(end 151.81707 -207.800448)
				)
				(arc
					(start 151.81707 -213.800436)
					(mid 159.325056 -221.308422)
					(end 166.833042 -213.800436)
				)
			)
		)
	)
	(zone
		(layers "F.Cu" "B.Cu" "In2.Cu" "In4.Cu" "In7.Cu" "In9.Cu")
		(hatch none 0.5)
		(connect_pads
			(clearance 0)
		)
		(min_thickness 0.25)
		(keepout
			(tracks not_allowed)
			(vias allowed)
			(pads allowed)
			(copperpour not_allowed)
			(footprints allowed)
		)
		(placement
			(enabled no)
			(sheetname "")
		)
		(fill yes
			(thermal_gap 0.5)
			(thermal_bridge_width 0.5)
			(island_removal_mode 0)
		)
		(polygon
			(pts
				(arc
					(start 389.881872 -154.034998)
					(mid 387.418072 -154.034998)
					(end 389.881872 -154.034998)
				)
			)
		)
	)
	(zone
		(layers "F.Cu" "B.Cu" "In2.Cu" "In4.Cu" "In7.Cu" "In9.Cu")
		(hatch none 0.5)
		(connect_pads
			(clearance 0)
		)
		(min_thickness 0.25)
		(keepout
			(tracks not_allowed)
			(vias allowed)
			(pads allowed)
			(copperpour not_allowed)
			(footprints allowed)
		)
		(placement
			(enabled no)
			(sheetname "")
		)
		(fill yes
			(thermal_gap 0.5)
			(thermal_bridge_width 0.5)
			(island_removal_mode 0)
		)
		(polygon
			(pts
				(arc
					(start 60.981844 -39.034974)
					(mid 58.518044 -39.034974)
					(end 60.981844 -39.034974)
				)
			)
		)
	)
	(zone
		(layers "F.Cu" "B.Cu" "In2.Cu" "In4.Cu" "In7.Cu" "In9.Cu")
		(hatch none 0.5)
		(connect_pads
			(clearance 0)
		)
		(min_thickness 0.25)
		(keepout
			(tracks not_allowed)
			(vias allowed)
			(pads allowed)
			(copperpour not_allowed)
			(footprints allowed)
		)
		(placement
			(enabled no)
			(sheetname "")
		)
		(fill yes
			(thermal_gap 0.5)
			(thermal_bridge_width 0.5)
			(island_removal_mode 0)
		)
		(polygon
			(pts
				(arc
					(start 103.832914 -92.800424)
					(mid 96.324928 -85.292438)
					(end 88.816942 -92.800424)
				)
				(arc
					(start 88.816942 -98.800412)
					(mid 96.324928 -106.308398)
					(end 103.832914 -98.800412)
				)
			)
		)
	)
	(zone
		(layers "F.Cu" "B.Cu" "In2.Cu" "In4.Cu" "In7.Cu" "In9.Cu")
		(hatch none 0.5)
		(connect_pads
			(clearance 0)
		)
		(min_thickness 0.25)
		(keepout
			(tracks not_allowed)
			(vias allowed)
			(pads allowed)
			(copperpour not_allowed)
			(footprints allowed)
		)
		(placement
			(enabled no)
			(sheetname "")
		)
		(fill yes
			(thermal_gap 0.5)
			(thermal_bridge_width 0.5)
			(island_removal_mode 0)
		)
		(polygon
			(pts
				(arc
					(start 484.531924 -269.035022)
					(mid 482.068124 -269.035022)
					(end 484.531924 -269.035022)
				)
			)
		)
	)
	(zone
		(layers "F.Cu" "B.Cu" "In2.Cu" "In4.Cu" "In7.Cu" "In9.Cu")
		(hatch none 0.5)
		(connect_pads
			(clearance 0)
		)
		(min_thickness 0.25)
		(keepout
			(tracks not_allowed)
			(vias allowed)
			(pads allowed)
			(copperpour not_allowed)
			(footprints allowed)
		)
		(placement
			(enabled no)
			(sheetname "")
		)
		(fill yes
			(thermal_gap 0.5)
			(thermal_bridge_width 0.5)
			(island_removal_mode 0)
		)
		(polygon
			(pts
				(arc
					(start 232.991914 11.799824)
					(mid 237.086293 5.426397)
					(end 244.584982 6.500114)
				)
				(arc
					(start 244.608096 6.500114)
					(mid 245.157671 8.305738)
					(end 246.619776 9.499346)
				)
				(arc
					(start 246.619776 9.499346)
					(mid 246.910087 10.632572)
					(end 247.007888 11.7983)
				)
				(arc
					(start 247.007888 17.800066)
					(mid 240.000028 24.807926)
					(end 232.991914 17.800066)
				)
			)
		)
	)
	(zone
		(layers "F.Cu" "B.Cu" "In2.Cu" "In4.Cu" "In7.Cu" "In9.Cu")
		(hatch none 0.5)
		(connect_pads
			(clearance 0)
		)
		(min_thickness 0.25)
		(keepout
			(tracks not_allowed)
			(vias allowed)
			(pads allowed)
			(copperpour not_allowed)
			(footprints allowed)
		)
		(placement
			(enabled no)
			(sheetname "")
		)
		(fill yes
			(thermal_gap 0.5)
			(thermal_bridge_width 0.5)
			(island_removal_mode 0)
		)
		(polygon
			(pts
				(arc
					(start 60.981844 -76.784962)
					(mid 58.518044 -76.784962)
					(end 60.981844 -76.784962)
				)
			)
		)
	)
	(zone
		(layers "F.Cu" "B.Cu" "In2.Cu" "In4.Cu" "In7.Cu" "In9.Cu")
		(hatch none 0.5)
		(connect_pads
			(clearance 0)
		)
		(min_thickness 0.25)
		(keepout
			(tracks not_allowed)
			(vias allowed)
			(pads allowed)
			(copperpour not_allowed)
			(footprints allowed)
		)
		(placement
			(enabled no)
			(sheetname "")
		)
		(fill yes
			(thermal_gap 0.5)
			(thermal_bridge_width 0.5)
			(island_removal_mode 0)
		)
		(polygon
			(pts
				(arc
					(start 452.981822 -269.035022)
					(mid 450.518022 -269.035022)
					(end 452.981822 -269.035022)
				)
			)
		)
	)
	(zone
		(layers "F.Cu" "B.Cu" "In2.Cu" "In4.Cu" "In7.Cu" "In9.Cu")
		(hatch none 0.5)
		(connect_pads
			(clearance 0)
		)
		(min_thickness 0.25)
		(keepout
			(tracks not_allowed)
			(vias allowed)
			(pads allowed)
			(copperpour not_allowed)
			(footprints allowed)
		)
		(placement
			(enabled no)
			(sheetname "")
		)
		(fill yes
			(thermal_gap 0.5)
			(thermal_bridge_width 0.5)
			(island_removal_mode 0)
		)
		(polygon
			(pts
				(arc
					(start 346.558108 -270.000476)
					(mid 341.300308 -264.742676)
					(end 336.042254 -270.000476)
				)
				(arc
					(start 336.042254 -270.000476)
					(mid 341.300308 -275.25853)
					(end 346.558108 -270.000476)
				)
			)
		)
	)
	(zone
		(layers "F.Cu" "B.Cu" "In2.Cu" "In4.Cu" "In7.Cu" "In9.Cu")
		(hatch none 0.5)
		(connect_pads
			(clearance 0)
		)
		(min_thickness 0.25)
		(keepout
			(tracks not_allowed)
			(vias allowed)
			(pads allowed)
			(copperpour not_allowed)
			(footprints allowed)
		)
		(placement
			(enabled no)
			(sheetname "")
		)
		(fill yes
			(thermal_gap 0.5)
			(thermal_bridge_width 0.5)
			(island_removal_mode 0)
		)
		(polygon
			(pts
				(arc
					(start 29.431996 -154.034998)
					(mid 26.968196 -154.034998)
					(end 29.431996 -154.034998)
				)
			)
		)
	)
	(zone
		(layers "F.Cu" "B.Cu" "In2.Cu" "In4.Cu" "In7.Cu" "In9.Cu")
		(hatch none 0.5)
		(connect_pads
			(clearance 0)
		)
		(min_thickness 0.25)
		(keepout
			(tracks not_allowed)
			(vias allowed)
			(pads allowed)
			(copperpour not_allowed)
			(footprints allowed)
		)
		(placement
			(enabled no)
			(sheetname "")
		)
		(fill yes
			(thermal_gap 0.5)
			(thermal_bridge_width 0.5)
			(island_removal_mode 0)
		)
		(polygon
			(pts
				(arc
					(start 171.582842 -9.19988)
					(mid 161.066734 -9.19988)
					(end 171.582842 -9.19988)
				)
			)
		)
	)
	(zone
		(layers "F.Cu" "B.Cu" "In2.Cu" "In4.Cu" "In7.Cu" "In9.Cu")
		(hatch none 0.5)
		(connect_pads
			(clearance 0)
		)
		(min_thickness 0.25)
		(keepout
			(tracks not_allowed)
			(vias allowed)
			(pads allowed)
			(copperpour not_allowed)
			(footprints allowed)
		)
		(placement
			(enabled no)
			(sheetname "")
		)
		(fill yes
			(thermal_gap 0.5)
			(thermal_bridge_width 0.5)
			(island_removal_mode 0)
		)
		(polygon
			(pts
				(arc
					(start 251.707904 -273.200368)
					(mid 244.199918 -265.692382)
					(end 236.691932 -273.200368)
				)
				(arc
					(start 236.691932 -279.200356)
					(mid 244.199918 -286.708342)
					(end 251.707904 -279.200356)
				)
			)
		)
	)
	(zone
		(layers "F.Cu" "B.Cu" "In2.Cu" "In4.Cu" "In7.Cu" "In9.Cu")
		(hatch none 0.5)
		(connect_pads
			(clearance 0)
		)
		(min_thickness 0.25)
		(keepout
			(tracks not_allowed)
			(vias allowed)
			(pads allowed)
			(copperpour not_allowed)
			(footprints allowed)
		)
		(placement
			(enabled no)
			(sheetname "")
		)
		(fill yes
			(thermal_gap 0.5)
			(thermal_bridge_width 0.5)
			(island_removal_mode 0)
		)
		(polygon
			(pts
				(arc
					(start 92.531946 -39.034974)
					(mid 90.068146 -39.034974)
					(end 92.531946 -39.034974)
				)
			)
		)
	)
	(zone
		(layers "F.Cu" "B.Cu" "In2.Cu" "In4.Cu" "In7.Cu" "In9.Cu")
		(hatch none 0.5)
		(connect_pads
			(clearance 0)
		)
		(min_thickness 0.25)
		(keepout
			(tracks not_allowed)
			(vias allowed)
			(pads allowed)
			(copperpour not_allowed)
			(footprints allowed)
		)
		(placement
			(enabled no)
			(sheetname "")
		)
		(fill yes
			(thermal_gap 0.5)
			(thermal_bridge_width 0.5)
			(island_removal_mode 0)
		)
		(polygon
			(pts
				(arc
					(start 8.108188 -120.499886)
					(mid -0.407924 -120.499886)
					(end 8.108188 -120.499886)
				)
			)
		)
	)
	(zone
		(layers "F.Cu" "B.Cu" "In2.Cu" "In4.Cu" "In7.Cu" "In9.Cu")
		(hatch none 0.5)
		(connect_pads
			(clearance 0)
		)
		(min_thickness 0.25)
		(keepout
			(tracks not_allowed)
			(vias allowed)
			(pads allowed)
			(copperpour not_allowed)
			(footprints allowed)
		)
		(placement
			(enabled no)
			(sheetname "")
		)
		(fill yes
			(thermal_gap 0.5)
			(thermal_bridge_width 0.5)
			(island_removal_mode 0)
		)
		(polygon
			(pts
				(arc
					(start 421.431974 -76.784962)
					(mid 418.968174 -76.784962)
					(end 421.431974 -76.784962)
				)
			)
		)
	)
	(zone
		(layers "F.Cu" "B.Cu" "In2.Cu" "In4.Cu" "In7.Cu" "In9.Cu")
		(hatch none 0.5)
		(connect_pads
			(clearance 0)
		)
		(min_thickness 0.25)
		(keepout
			(tracks not_allowed)
			(vias allowed)
			(pads allowed)
			(copperpour not_allowed)
			(footprints allowed)
		)
		(placement
			(enabled no)
			(sheetname "")
		)
		(fill yes
			(thermal_gap 0.5)
			(thermal_bridge_width 0.5)
			(island_removal_mode 0)
		)
		(polygon
			(pts
				(arc
					(start 29.431996 -39.034974)
					(mid 26.968196 -39.034974)
					(end 29.431996 -39.034974)
				)
			)
		)
	)
	(zone
		(layers "F.Cu" "B.Cu" "In2.Cu" "In4.Cu" "In7.Cu" "In9.Cu")
		(hatch none 0.5)
		(connect_pads
			(clearance 0)
		)
		(min_thickness 0.25)
		(keepout
			(tracks not_allowed)
			(vias allowed)
			(pads allowed)
			(copperpour not_allowed)
			(footprints allowed)
		)
		(placement
			(enabled no)
			(sheetname "")
		)
		(fill yes
			(thermal_gap 0.5)
			(thermal_bridge_width 0.5)
			(island_removal_mode 0)
		)
		(polygon
			(pts
				(arc
					(start 326.781922 -269.035022)
					(mid 324.318122 -269.035022)
					(end 326.781922 -269.035022)
				)
			)
		)
	)
	(zone
		(layers "F.Cu" "B.Cu" "In2.Cu" "In4.Cu" "In7.Cu" "In9.Cu")
		(hatch none 0.5)
		(connect_pads
			(clearance 0)
		)
		(min_thickness 0.25)
		(keepout
			(tracks not_allowed)
			(vias allowed)
			(pads allowed)
			(copperpour not_allowed)
			(footprints allowed)
		)
		(placement
			(enabled no)
			(sheetname "")
		)
		(fill yes
			(thermal_gap 0.5)
			(thermal_bridge_width 0.5)
			(island_removal_mode 0)
		)
		(polygon
			(pts
				(arc
					(start 389.881872 -76.784962)
					(mid 387.418072 -76.784962)
					(end 389.881872 -76.784962)
				)
			)
		)
	)
	(zone
		(layers "F.Cu" "B.Cu" "In2.Cu" "In4.Cu" "In7.Cu" "In9.Cu")
		(hatch none 0.5)
		(connect_pads
			(clearance 0)
		)
		(min_thickness 0.25)
		(keepout
			(tracks not_allowed)
			(vias allowed)
			(pads allowed)
			(copperpour not_allowed)
			(footprints allowed)
		)
		(placement
			(enabled no)
			(sheetname "")
		)
		(fill yes
			(thermal_gap 0.5)
			(thermal_bridge_width 0.5)
			(island_removal_mode 0)
		)
		(polygon
			(pts
				(arc
					(start 40.83304 -92.800424)
					(mid 33.325054 -85.292438)
					(end 25.817068 -92.800424)
				)
				(arc
					(start 25.817068 -98.800412)
					(mid 33.325054 -106.308398)
					(end 40.83304 -98.800412)
				)
			)
		)
	)
	(zone
		(layers "F.Cu" "B.Cu" "In2.Cu" "In4.Cu" "In7.Cu" "In9.Cu")
		(hatch none 0.5)
		(connect_pads
			(clearance 0)
		)
		(min_thickness 0.25)
		(keepout
			(tracks not_allowed)
			(vias allowed)
			(pads allowed)
			(copperpour not_allowed)
			(footprints allowed)
		)
		(placement
			(enabled no)
			(sheetname "")
		)
		(fill yes
			(thermal_gap 0.5)
			(thermal_bridge_width 0.5)
			(island_removal_mode 0)
		)
		(polygon
			(pts
				(arc
					(start 187.181998 -154.034998)
					(mid 184.718198 -154.034998)
					(end 187.181998 -154.034998)
				)
			)
		)
	)
	(zone
		(layers "F.Cu" "B.Cu" "In2.Cu" "In4.Cu" "In7.Cu" "In9.Cu")
		(hatch none 0.5)
		(connect_pads
			(clearance 0)
		)
		(min_thickness 0.25)
		(keepout
			(tracks not_allowed)
			(vias allowed)
			(pads allowed)
			(copperpour not_allowed)
			(footprints allowed)
		)
		(placement
			(enabled no)
			(sheetname "")
		)
		(fill yes
			(thermal_gap 0.5)
			(thermal_bridge_width 0.5)
			(island_removal_mode 0)
		)
		(polygon
			(pts
				(arc
					(start 452.981822 -76.784962)
					(mid 450.518022 -76.784962)
					(end 452.981822 -76.784962)
				)
			)
		)
	)
	(zone
		(layers "F.Cu" "B.Cu" "In2.Cu" "In4.Cu" "In7.Cu" "In9.Cu")
		(hatch none 0.5)
		(connect_pads
			(clearance 0)
		)
		(min_thickness 0.25)
		(keepout
			(tracks not_allowed)
			(vias allowed)
			(pads allowed)
			(copperpour not_allowed)
			(footprints allowed)
		)
		(placement
			(enabled no)
			(sheetname "")
		)
		(fill yes
			(thermal_gap 0.5)
			(thermal_bridge_width 0.5)
			(island_removal_mode 0)
		)
		(polygon
			(pts
				(arc
					(start 338.182966 -322.800472)
					(mid 330.67498 -315.292486)
					(end 323.166994 -322.800472)
				)
				(arc
					(start 323.166994 -328.80046)
					(mid 330.67498 -336.308446)
					(end 338.182966 -328.80046)
				)
			)
		)
	)
	(zone
		(layers "F.Cu" "B.Cu" "In2.Cu" "In4.Cu" "In7.Cu" "In9.Cu")
		(hatch none 0.5)
		(connect_pads
			(clearance 0)
		)
		(min_thickness 0.25)
		(keepout
			(tracks not_allowed)
			(vias allowed)
			(pads allowed)
			(copperpour not_allowed)
			(footprints allowed)
		)
		(placement
			(enabled no)
			(sheetname "")
		)
		(fill yes
			(thermal_gap 0.5)
			(thermal_bridge_width 0.5)
			(island_removal_mode 0)
		)
		(polygon
			(pts
				(arc
					(start 483.300024 -75.553062)
					(mid 483.300024 -78.016862)
					(end 483.300024 -75.553062)
				)
			)
		)
	)
	(zone
		(layers "F.Cu" "B.Cu" "In2.Cu" "In4.Cu" "In7.Cu" "In9.Cu")
		(hatch none 0.5)
		(connect_pads
			(clearance 0)
		)
		(min_thickness 0.25)
		(keepout
			(tracks not_allowed)
			(vias allowed)
			(pads allowed)
			(copperpour not_allowed)
			(footprints allowed)
		)
		(placement
			(enabled no)
			(sheetname "")
		)
		(fill yes
			(thermal_gap 0.5)
			(thermal_bridge_width 0.5)
			(island_removal_mode 0)
		)
		(polygon
			(pts
				(arc
					(start 389.881872 -39.034974)
					(mid 387.418072 -39.034974)
					(end 389.881872 -39.034974)
				)
			)
		)
	)
	(zone
		(layers "F.Cu" "B.Cu" "In2.Cu" "In4.Cu" "In7.Cu" "In9.Cu")
		(hatch none 0.5)
		(connect_pads
			(clearance 0)
		)
		(min_thickness 0.25)
		(keepout
			(tracks not_allowed)
			(vias allowed)
			(pads allowed)
			(copperpour not_allowed)
			(footprints allowed)
		)
		(placement
			(enabled no)
			(sheetname "")
		)
		(fill yes
			(thermal_gap 0.5)
			(thermal_bridge_width 0.5)
			(island_removal_mode 0)
		)
		(polygon
			(pts
				(arc
					(start 187.181998 -76.784962)
					(mid 184.718198 -76.784962)
					(end 187.181998 -76.784962)
				)
			)
		)
	)
	(zone
		(layers "F.Cu" "B.Cu" "In2.Cu" "In4.Cu" "In7.Cu" "In9.Cu")
		(hatch none 0.5)
		(connect_pads
			(clearance 0)
		)
		(min_thickness 0.25)
		(keepout
			(tracks not_allowed)
			(vias allowed)
			(pads allowed)
			(copperpour not_allowed)
			(footprints allowed)
		)
		(placement
			(enabled no)
			(sheetname "")
		)
		(fill yes
			(thermal_gap 0.5)
			(thermal_bridge_width 0.5)
			(island_removal_mode 0)
		)
		(polygon
			(pts
				(arc
					(start 187.181998 -306.78501)
					(mid 184.718198 -306.78501)
					(end 187.181998 -306.78501)
				)
			)
		)
	)
	(zone
		(layers "F.Cu" "B.Cu" "In2.Cu" "In4.Cu" "In7.Cu" "In9.Cu")
		(hatch none 0.5)
		(connect_pads
			(clearance 0)
		)
		(min_thickness 0.25)
		(keepout
			(tracks not_allowed)
			(vias allowed)
			(pads allowed)
			(copperpour not_allowed)
			(footprints allowed)
		)
		(placement
			(enabled no)
			(sheetname "")
		)
		(fill yes
			(thermal_gap 0.5)
			(thermal_bridge_width 0.5)
			(island_removal_mode 0)
		)
		(polygon
			(pts
				(arc
					(start 92.531946 -76.784962)
					(mid 90.068146 -76.784962)
					(end 92.531946 -76.784962)
				)
			)
		)
	)
	(zone
		(layers "F.Cu" "B.Cu" "In2.Cu" "In4.Cu" "In7.Cu" "In9.Cu")
		(hatch none 0.5)
		(connect_pads
			(clearance 0)
		)
		(min_thickness 0.25)
		(keepout
			(tracks not_allowed)
			(vias allowed)
			(pads allowed)
			(copperpour not_allowed)
			(footprints allowed)
		)
		(placement
			(enabled no)
			(sheetname "")
		)
		(fill yes
			(thermal_gap 0.5)
			(thermal_bridge_width 0.5)
			(island_removal_mode 0)
		)
		(polygon
			(pts
				(arc
					(start 103.832914 -322.800472)
					(mid 96.324928 -315.292486)
					(end 88.816942 -322.800472)
				)
				(arc
					(start 88.816942 -328.80046)
					(mid 96.324928 -336.308446)
					(end 103.832914 -328.80046)
				)
			)
		)
	)
	(zone
		(layers "F.Cu" "B.Cu" "In2.Cu" "In4.Cu" "In7.Cu" "In9.Cu")
		(hatch none 0.5)
		(connect_pads
			(clearance 0)
		)
		(min_thickness 0.25)
		(keepout
			(tracks not_allowed)
			(vias allowed)
			(pads allowed)
			(copperpour not_allowed)
			(footprints allowed)
		)
		(placement
			(enabled no)
			(sheetname "")
		)
		(fill yes
			(thermal_gap 0.5)
			(thermal_bridge_width 0.5)
			(island_removal_mode 0)
		)
		(polygon
			(pts
				(arc
					(start 464.182968 -207.800448)
					(mid 456.674982 -200.292462)
					(end 449.166996 -207.800448)
				)
				(arc
					(start 449.166996 -213.800436)
					(mid 456.674982 -221.308422)
					(end 464.182968 -213.800436)
				)
			)
		)
	)
	(zone
		(layers "F.Cu" "B.Cu" "In2.Cu" "In4.Cu" "In7.Cu" "In9.Cu")
		(hatch none 0.5)
		(connect_pads
			(clearance 0)
		)
		(min_thickness 0.25)
		(keepout
			(tracks not_allowed)
			(vias allowed)
			(pads allowed)
			(copperpour not_allowed)
			(footprints allowed)
		)
		(placement
			(enabled no)
			(sheetname "")
		)
		(fill yes
			(thermal_gap 0.5)
			(thermal_bridge_width 0.5)
			(island_removal_mode 0)
		)
		(polygon
			(pts
				(arc
					(start 389.881872 -306.78501)
					(mid 387.418072 -306.78501)
					(end 389.881872 -306.78501)
				)
			)
		)
	)
	(zone
		(layers "F.Cu" "B.Cu" "In2.Cu" "In4.Cu" "In7.Cu" "In9.Cu")
		(hatch none 0.5)
		(connect_pads
			(clearance 0)
		)
		(min_thickness 0.25)
		(keepout
			(tracks not_allowed)
			(vias allowed)
			(pads allowed)
			(copperpour not_allowed)
			(footprints allowed)
		)
		(placement
			(enabled no)
			(sheetname "")
		)
		(fill yes
			(thermal_gap 0.5)
			(thermal_bridge_width 0.5)
			(island_removal_mode 0)
		)
		(polygon
			(pts
				(arc
					(start 326.781922 -191.784986)
					(mid 324.318122 -191.784986)
					(end 326.781922 -191.784986)
				)
			)
		)
	)
	(zone
		(layers "F.Cu" "B.Cu" "In2.Cu" "In4.Cu" "In7.Cu" "In9.Cu")
		(hatch none 0.5)
		(connect_pads
			(clearance 0)
		)
		(min_thickness 0.25)
		(keepout
			(tracks not_allowed)
			(vias allowed)
			(pads allowed)
			(copperpour not_allowed)
			(footprints allowed)
		)
		(placement
			(enabled no)
			(sheetname "")
		)
		(fill yes
			(thermal_gap 0.5)
			(thermal_bridge_width 0.5)
			(island_removal_mode 0)
		)
		(polygon
			(pts
				(arc
					(start 389.881872 -191.784986)
					(mid 387.418072 -191.784986)
					(end 389.881872 -191.784986)
				)
			)
		)
	)
	(zone
		(layers "F.Cu" "B.Cu" "In2.Cu" "In4.Cu" "In7.Cu" "In9.Cu")
		(hatch none 0.5)
		(connect_pads
			(clearance 0)
		)
		(min_thickness 0.25)
		(keepout
			(tracks not_allowed)
			(vias allowed)
			(pads allowed)
			(copperpour not_allowed)
			(footprints allowed)
		)
		(placement
			(enabled no)
			(sheetname "")
		)
		(fill yes
			(thermal_gap 0.5)
			(thermal_bridge_width 0.5)
			(island_removal_mode 0)
		)
		(polygon
			(pts
				(arc
					(start 358.332024 -306.78501)
					(mid 355.868224 -306.78501)
					(end 358.332024 -306.78501)
				)
			)
		)
	)
	(zone
		(layers "F.Cu" "B.Cu" "In2.Cu" "In4.Cu" "In7.Cu" "In9.Cu")
		(hatch none 0.5)
		(connect_pads
			(clearance 0)
		)
		(min_thickness 0.25)
		(keepout
			(tracks not_allowed)
			(vias allowed)
			(pads allowed)
			(copperpour not_allowed)
			(footprints allowed)
		)
		(placement
			(enabled no)
			(sheetname "")
		)
		(fill yes
			(thermal_gap 0.5)
			(thermal_bridge_width 0.5)
			(island_removal_mode 0)
		)
		(polygon
			(pts
				(arc
					(start 60.981844 -269.035022)
					(mid 58.518044 -269.035022)
					(end 60.981844 -269.035022)
				)
			)
		)
	)
	(zone
		(layers "F.Cu" "B.Cu" "In2.Cu" "In4.Cu" "In7.Cu" "In9.Cu")
		(hatch none 0.5)
		(connect_pads
			(clearance 0)
		)
		(min_thickness 0.25)
		(keepout
			(tracks not_allowed)
			(vias allowed)
			(pads allowed)
			(copperpour not_allowed)
			(footprints allowed)
		)
		(placement
			(enabled no)
			(sheetname "")
		)
		(fill yes
			(thermal_gap 0.5)
			(thermal_bridge_width 0.5)
			(island_removal_mode 0)
		)
		(polygon
			(pts
				(arc
					(start 307.708046 -393.200382)
					(mid 300.20006 -385.692396)
					(end 292.692074 -393.200382)
				)
				(arc
					(start 292.692074 -399.20037)
					(mid 300.20006 -406.708356)
					(end 307.708046 -399.20037)
				)
			)
		)
	)
	(zone
		(layers "F.Cu" "B.Cu" "In2.Cu" "In4.Cu" "In7.Cu" "In9.Cu")
		(hatch none 0.5)
		(connect_pads
			(clearance 0)
		)
		(min_thickness 0.25)
		(keepout
			(tracks not_allowed)
			(vias allowed)
			(pads allowed)
			(copperpour not_allowed)
			(footprints allowed)
		)
		(placement
			(enabled no)
			(sheetname "")
		)
		(fill yes
			(thermal_gap 0.5)
			(thermal_bridge_width 0.5)
			(island_removal_mode 0)
		)
		(polygon
			(pts
				(arc
					(start 124.081794 -306.78501)
					(mid 121.617994 -306.78501)
					(end 124.081794 -306.78501)
				)
			)
		)
	)
	(zone
		(layers "F.Cu" "B.Cu" "In2.Cu" "In4.Cu" "In7.Cu" "In9.Cu")
		(hatch none 0.5)
		(connect_pads
			(clearance 0)
		)
		(min_thickness 0.25)
		(keepout
			(tracks not_allowed)
			(vias allowed)
			(pads allowed)
			(copperpour not_allowed)
			(footprints allowed)
		)
		(placement
			(enabled no)
			(sheetname "")
		)
		(fill yes
			(thermal_gap 0.5)
			(thermal_bridge_width 0.5)
			(island_removal_mode 0)
		)
		(polygon
			(pts
				(arc
					(start 481.24999 -124.757942)
					(mid 481.24999 -116.24183)
					(end 481.24999 -124.757942)
				)
			)
		)
	)
	(zone
		(layers "F.Cu" "B.Cu" "In2.Cu" "In4.Cu" "In7.Cu" "In9.Cu")
		(hatch none 0.5)
		(connect_pads
			(clearance 0)
		)
		(min_thickness 0.25)
		(keepout
			(tracks not_allowed)
			(vias allowed)
			(pads allowed)
			(copperpour not_allowed)
			(footprints allowed)
		)
		(placement
			(enabled no)
			(sheetname "")
		)
		(fill yes
			(thermal_gap 0.5)
			(thermal_bridge_width 0.5)
			(island_removal_mode 0)
		)
		(polygon
			(pts
				(arc
					(start 187.181998 -269.035022)
					(mid 184.718198 -269.035022)
					(end 187.181998 -269.035022)
				)
			)
		)
	)
	(zone
		(layers "F.Cu" "B.Cu" "In2.Cu" "In4.Cu" "In7.Cu" "In9.Cu")
		(hatch none 0.5)
		(connect_pads
			(clearance 0)
		)
		(min_thickness 0.25)
		(keepout
			(tracks not_allowed)
			(vias allowed)
			(pads allowed)
			(copperpour not_allowed)
			(footprints allowed)
		)
		(placement
			(enabled no)
			(sheetname "")
		)
		(fill yes
			(thermal_gap 0.5)
			(thermal_bridge_width 0.5)
			(island_removal_mode 0)
		)
		(polygon
			(pts
				(arc
					(start 484.531924 -154.034998)
					(mid 482.068124 -154.034998)
					(end 484.531924 -154.034998)
				)
			)
		)
	)
	(zone
		(layers "F.Cu" "B.Cu" "In2.Cu" "In4.Cu" "In7.Cu" "In9.Cu")
		(hatch none 0.5)
		(connect_pads
			(clearance 0)
		)
		(min_thickness 0.25)
		(keepout
			(tracks not_allowed)
			(vias allowed)
			(pads allowed)
			(copperpour not_allowed)
			(footprints allowed)
		)
		(placement
			(enabled no)
			(sheetname "")
		)
		(fill yes
			(thermal_gap 0.5)
			(thermal_bridge_width 0.5)
			(island_removal_mode 0)
		)
		(polygon
			(pts
				(arc
					(start 92.531946 -154.034998)
					(mid 90.068146 -154.034998)
					(end 92.531946 -154.034998)
				)
			)
		)
	)
	(zone
		(layers "F.Cu" "B.Cu" "In2.Cu" "In4.Cu" "In7.Cu" "In9.Cu")
		(hatch none 0.5)
		(connect_pads
			(clearance 0)
		)
		(min_thickness 0.25)
		(keepout
			(tracks not_allowed)
			(vias allowed)
			(pads allowed)
			(copperpour not_allowed)
			(footprints allowed)
		)
		(placement
			(enabled no)
			(sheetname "")
		)
		(fill yes
			(thermal_gap 0.5)
			(thermal_bridge_width 0.5)
			(island_removal_mode 0)
		)
		(polygon
			(pts
				(arc
					(start 326.781922 -76.784962)
					(mid 324.318122 -76.784962)
					(end 326.781922 -76.784962)
				)
			)
		)
	)
	(zone
		(layers "F.Cu" "B.Cu" "In2.Cu" "In4.Cu" "In7.Cu" "In9.Cu")
		(hatch none 0.5)
		(connect_pads
			(clearance 0)
		)
		(min_thickness 0.25)
		(keepout
			(tracks not_allowed)
			(vias allowed)
			(pads allowed)
			(copperpour not_allowed)
			(footprints allowed)
		)
		(placement
			(enabled no)
			(sheetname "")
		)
		(fill yes
			(thermal_gap 0.5)
			(thermal_bridge_width 0.5)
			(island_removal_mode 0)
		)
		(polygon
			(pts
				(arc
					(start 155.631896 -39.034974)
					(mid 153.168096 -39.034974)
					(end 155.631896 -39.034974)
				)
			)
		)
	)
	(zone
		(layers "F.Cu" "B.Cu" "In2.Cu" "In4.Cu" "In7.Cu" "In9.Cu")
		(hatch none 0.5)
		(connect_pads
			(clearance 0)
		)
		(min_thickness 0.25)
		(keepout
			(tracks not_allowed)
			(vias allowed)
			(pads allowed)
			(copperpour not_allowed)
			(footprints allowed)
		)
		(placement
			(enabled no)
			(sheetname "")
		)
		(fill yes
			(thermal_gap 0.5)
			(thermal_bridge_width 0.5)
			(island_removal_mode 0)
		)
		(polygon
			(pts
				(arc
					(start 358.332024 -191.784986)
					(mid 355.868224 -191.784986)
					(end 358.332024 -191.784986)
				)
			)
		)
	)
	(zone
		(layers "F.Cu" "B.Cu" "In2.Cu" "In4.Cu" "In9.Cu")
		(hatch none 0.5)
		(connect_pads
			(clearance 0)
		)
		(min_thickness 0.25)
		(keepout
			(tracks not_allowed)
			(vias allowed)
			(pads allowed)
			(copperpour not_allowed)
			(footprints allowed)
		)
		(placement
			(enabled no)
			(sheetname "")
		)
		(fill yes
			(thermal_gap 0.5)
			(thermal_bridge_width 0.5)
			(island_removal_mode 0)
		)
		(polygon
			(pts
				(arc
					(start 286.436562 -357.153972)
					(mid 285.885382 -357.705152)
					(end 286.436562 -358.256332)
				)
				(arc
					(start 287.83661 -358.256332)
					(mid 288.225454 -358.095792)
					(end 288.38779 -357.707692)
				)
				(arc
					(start 288.23031 -357.707692)
					(mid 287.83661 -358.09886)
					(end 287.44291 -357.707692)
				)
				(arc
					(start 286.830262 -357.707692)
					(mid 286.436562 -358.09886)
					(end 286.042862 -357.707692)
				)
				(arc
					(start 286.042862 -357.705152)
					(mid 286.436562 -357.311452)
					(end 286.830262 -357.705152)
				)
				(arc
					(start 287.44291 -357.705152)
					(mid 287.83661 -357.311452)
					(end 288.23031 -357.705152)
				)
				(arc
					(start 288.38779 -357.705152)
					(mid 288.226353 -357.315409)
					(end 287.83661 -357.153972)
				)
				(xy 286.436816 -357.153972)
			)
		)
	)
	(zone
		(layers "F.Cu" "B.Cu" "In2.Cu" "In4.Cu" "In9.Cu")
		(hatch none 0.5)
		(connect_pads
			(clearance 0)
		)
		(min_thickness 0.25)
		(keepout
			(tracks not_allowed)
			(vias allowed)
			(pads allowed)
			(copperpour not_allowed)
			(footprints allowed)
		)
		(placement
			(enabled no)
			(sheetname "")
		)
		(fill yes
			(thermal_gap 0.5)
			(thermal_bridge_width 0.5)
			(island_removal_mode 0)
		)
		(polygon
			(pts
				(arc
					(start 122.301254 -29.150056)
					(mid 121.750074 -28.598876)
					(end 121.198894 -29.150056)
				)
				(arc
					(start 121.198894 -30.54985)
					(mid 121.748677 -31.101282)
					(end 122.301254 -30.552644)
				)
				(arc
					(start 122.143774 -30.552644)
					(mid 121.750074 -30.943812)
					(end 121.356374 -30.552644)
				)
				(arc
					(start 121.356374 -30.550104)
					(mid 121.750074 -30.156404)
					(end 122.143774 -30.550104)
				)
				(xy 122.301254 -30.550104) (xy 122.301254 -29.152596)
				(arc
					(start 122.143774 -29.152596)
					(mid 121.750074 -29.543764)
					(end 121.356374 -29.152596)
				)
				(arc
					(start 121.356374 -29.150056)
					(mid 121.750074 -28.756356)
					(end 122.143774 -29.150056)
				)
			)
		)
	)
	(zone
		(layers "F.Cu" "B.Cu" "In2.Cu" "In4.Cu" "In9.Cu")
		(hatch none 0.5)
		(connect_pads
			(clearance 0)
		)
		(min_thickness 0.25)
		(keepout
			(tracks not_allowed)
			(vias allowed)
			(pads allowed)
			(copperpour not_allowed)
			(footprints allowed)
		)
		(placement
			(enabled no)
			(sheetname "")
		)
		(fill yes
			(thermal_gap 0.5)
			(thermal_bridge_width 0.5)
			(island_removal_mode 0)
		)
		(polygon
			(pts
				(arc
					(start 278.23668 -261.351014)
					(mid 277.6855 -261.902194)
					(end 278.23668 -262.453374)
				)
				(arc
					(start 279.636728 -262.453374)
					(mid 280.025572 -262.292834)
					(end 280.187908 -261.904734)
				)
				(arc
					(start 280.030428 -261.904734)
					(mid 279.636728 -262.295902)
					(end 279.243028 -261.904734)
				)
				(arc
					(start 278.63038 -261.904734)
					(mid 278.23668 -262.295902)
					(end 277.84298 -261.904734)
				)
				(arc
					(start 277.84298 -261.902194)
					(mid 278.23668 -261.508494)
					(end 278.63038 -261.902194)
				)
				(arc
					(start 279.243028 -261.902194)
					(mid 279.636728 -261.508494)
					(end 280.030428 -261.902194)
				)
				(arc
					(start 280.187908 -261.902194)
					(mid 280.026471 -261.512451)
					(end 279.636728 -261.351014)
				)
				(xy 278.236934 -261.351014)
			)
		)
	)
	(zone
		(layers "F.Cu" "B.Cu" "In2.Cu" "In4.Cu" "In9.Cu")
		(hatch none 0.5)
		(connect_pads
			(clearance 0)
		)
		(min_thickness 0.25)
		(keepout
			(tracks not_allowed)
			(vias allowed)
			(pads allowed)
			(copperpour not_allowed)
			(footprints allowed)
		)
		(placement
			(enabled no)
			(sheetname "")
		)
		(fill yes
			(thermal_gap 0.5)
			(thermal_bridge_width 0.5)
			(island_removal_mode 0)
		)
		(polygon
			(pts
				(arc
					(start 285.436564 -254.15113)
					(mid 284.885384 -254.70231)
					(end 285.436564 -255.25349)
				)
				(arc
					(start 286.836612 -255.25349)
					(mid 287.225456 -255.09295)
					(end 287.387792 -254.70485)
				)
				(arc
					(start 287.230312 -254.70485)
					(mid 286.836612 -255.096018)
					(end 286.442912 -254.70485)
				)
				(arc
					(start 285.830264 -254.70485)
					(mid 285.436564 -255.096018)
					(end 285.042864 -254.70485)
				)
				(arc
					(start 285.042864 -254.70231)
					(mid 285.436564 -254.30861)
					(end 285.830264 -254.70231)
				)
				(arc
					(start 286.442912 -254.70231)
					(mid 286.836612 -254.30861)
					(end 287.230312 -254.70231)
				)
				(arc
					(start 287.387792 -254.70231)
					(mid 287.226355 -254.312567)
					(end 286.836612 -254.15113)
				)
				(xy 285.436818 -254.15113)
			)
		)
	)
	(zone
		(layers "F.Cu" "B.Cu" "In2.Cu" "In4.Cu" "In9.Cu")
		(hatch none 0.5)
		(connect_pads
			(clearance 0)
		)
		(min_thickness 0.25)
		(keepout
			(tracks not_allowed)
			(vias allowed)
			(pads allowed)
			(copperpour not_allowed)
			(footprints allowed)
		)
		(placement
			(enabled no)
			(sheetname "")
		)
		(fill yes
			(thermal_gap 0.5)
			(thermal_bridge_width 0.5)
			(island_removal_mode 0)
		)
		(polygon
			(pts
				(arc
					(start 285.436564 -333.753968)
					(mid 284.885384 -334.305148)
					(end 285.436564 -334.856328)
				)
				(arc
					(start 286.836612 -334.856328)
					(mid 287.225456 -334.695788)
					(end 287.387792 -334.307688)
				)
				(arc
					(start 287.230312 -334.307688)
					(mid 286.836612 -334.698856)
					(end 286.442912 -334.307688)
				)
				(arc
					(start 285.830264 -334.307688)
					(mid 285.436564 -334.698856)
					(end 285.042864 -334.307688)
				)
				(arc
					(start 285.042864 -334.305148)
					(mid 285.436564 -333.911448)
					(end 285.830264 -334.305148)
				)
				(arc
					(start 286.442912 -334.305148)
					(mid 286.836612 -333.911448)
					(end 287.230312 -334.305148)
				)
				(arc
					(start 287.387792 -334.305148)
					(mid 287.226355 -333.915405)
					(end 286.836612 -333.753968)
				)
				(xy 285.436818 -333.753968)
			)
		)
	)
	(zone
		(layers "F.Cu" "B.Cu" "In2.Cu" "In4.Cu" "In9.Cu")
		(hatch none 0.5)
		(connect_pads
			(clearance 0)
		)
		(min_thickness 0.25)
		(keepout
			(tracks not_allowed)
			(vias allowed)
			(pads allowed)
			(copperpour not_allowed)
			(footprints allowed)
		)
		(placement
			(enabled no)
			(sheetname "")
		)
		(fill yes
			(thermal_gap 0.5)
			(thermal_bridge_width 0.5)
			(island_removal_mode 0)
		)
		(polygon
			(pts
				(arc
					(start 281.48153 -11.20013)
					(mid 281.134593 -10.577862)
					(end 280.422858 -10.545826)
				)
				(arc
					(start 278.433784 -11.54049)
					(mid 278.093387 -12.52152)
					(end 279.077166 -12.854432)
				)
				(xy 280.380694 -12.202668)
				(arc
					(start 279.296114 -12.202668)
					(mid 278.750014 -12.746234)
					(end 278.203914 -12.202668)
				)
				(arc
					(start 278.203914 -12.200128)
					(mid 278.750014 -11.654028)
					(end 279.296114 -12.200128)
				)
				(xy 280.385774 -12.200128)
				(arc
					(start 281.077162 -11.854434)
					(mid 281.371621 -11.5858)
					(end 281.48153 -11.20267)
				)
				(arc
					(start 281.29611 -11.20267)
					(mid 280.75001 -11.746236)
					(end 280.20391 -11.20267)
				)
				(arc
					(start 280.20391 -11.20013)
					(mid 280.75001 -10.65403)
					(end 281.29611 -11.20013)
				)
			)
		)
	)
	(zone
		(layers "F.Cu" "B.Cu" "In2.Cu" "In4.Cu" "In9.Cu")
		(hatch none 0.5)
		(connect_pads
			(clearance 0)
		)
		(min_thickness 0.25)
		(keepout
			(tracks not_allowed)
			(vias allowed)
			(pads allowed)
			(copperpour not_allowed)
			(footprints allowed)
		)
		(placement
			(enabled no)
			(sheetname "")
		)
		(fill yes
			(thermal_gap 0.5)
			(thermal_bridge_width 0.5)
			(island_removal_mode 0)
		)
		(polygon
			(pts
				(arc
					(start 240.87709 -118.845584)
					(mid 239.895634 -119.172736)
					(end 240.222786 -120.154192)
				)
				(arc
					(start 242.222528 -121.15419)
					(mid 242.933406 -121.122989)
					(end 243.281454 -120.502426)
				)
				(arc
					(start 243.096034 -120.502426)
					(mid 242.549934 -121.045992)
					(end 242.003834 -120.502426)
				)
				(arc
					(start 242.003834 -120.499886)
					(mid 242.549934 -119.953786)
					(end 243.096034 -120.499886)
				)
				(arc
					(start 243.281454 -120.499886)
					(mid 243.172202 -120.115303)
					(end 242.877086 -119.845582)
				)
				(xy 242.190778 -119.502428)
				(arc
					(start 241.096038 -119.502428)
					(mid 240.549938 -120.045994)
					(end 240.003838 -119.502428)
				)
				(arc
					(start 240.003838 -119.499888)
					(mid 240.549938 -118.953788)
					(end 241.096038 -119.499888)
				)
				(xy 242.185698 -119.499888)
			)
		)
	)
	(zone
		(layers "F.Cu" "B.Cu" "In2.Cu" "In4.Cu" "In9.Cu")
		(hatch none 0.5)
		(connect_pads
			(clearance 0)
		)
		(min_thickness 0.25)
		(keepout
			(tracks not_allowed)
			(vias allowed)
			(pads allowed)
			(copperpour not_allowed)
			(footprints allowed)
		)
		(placement
			(enabled no)
			(sheetname "")
		)
		(fill yes
			(thermal_gap 0.5)
			(thermal_bridge_width 0.5)
			(island_removal_mode 0)
		)
		(polygon
			(pts
				(arc
					(start 368.30127 -29.150056)
					(mid 367.75009 -28.598876)
					(end 367.19891 -29.150056)
				)
				(arc
					(start 367.19891 -30.54985)
					(mid 367.748693 -31.101282)
					(end 368.30127 -30.552644)
				)
				(arc
					(start 368.14379 -30.552644)
					(mid 367.75009 -30.943812)
					(end 367.35639 -30.552644)
				)
				(arc
					(start 367.35639 -30.550104)
					(mid 367.75009 -30.156404)
					(end 368.14379 -30.550104)
				)
				(xy 368.30127 -30.550104) (xy 368.30127 -29.152596)
				(arc
					(start 368.14379 -29.152596)
					(mid 367.75009 -29.543764)
					(end 367.35639 -29.152596)
				)
				(arc
					(start 367.35639 -29.150056)
					(mid 367.75009 -28.756356)
					(end 368.14379 -29.150056)
				)
			)
		)
	)
	(zone
		(layers "F.Cu" "B.Cu" "In2.Cu" "In4.Cu" "In9.Cu")
		(hatch none 0.5)
		(connect_pads
			(clearance 0)
		)
		(min_thickness 0.25)
		(keepout
			(tracks not_allowed)
			(vias allowed)
			(pads allowed)
			(copperpour not_allowed)
			(footprints allowed)
		)
		(placement
			(enabled no)
			(sheetname "")
		)
		(fill yes
			(thermal_gap 0.5)
			(thermal_bridge_width 0.5)
			(island_removal_mode 0)
		)
		(polygon
			(pts
				(arc
					(start 238.78159 -11.20013)
					(mid 238.434653 -10.577862)
					(end 237.722918 -10.545826)
				)
				(arc
					(start 235.733844 -11.54049)
					(mid 235.393447 -12.52152)
					(end 236.377226 -12.854432)
				)
				(xy 237.680754 -12.202668)
				(arc
					(start 236.596174 -12.202668)
					(mid 236.050074 -12.746234)
					(end 235.503974 -12.202668)
				)
				(arc
					(start 235.503974 -12.200128)
					(mid 236.050074 -11.654028)
					(end 236.596174 -12.200128)
				)
				(xy 237.685834 -12.200128)
				(arc
					(start 238.377222 -11.854434)
					(mid 238.671681 -11.5858)
					(end 238.78159 -11.20267)
				)
				(arc
					(start 238.59617 -11.20267)
					(mid 238.05007 -11.746236)
					(end 237.50397 -11.20267)
				)
				(arc
					(start 237.50397 -11.20013)
					(mid 238.05007 -10.65403)
					(end 238.59617 -11.20013)
				)
			)
		)
	)
	(zone
		(layers "F.Cu" "B.Cu" "In2.Cu" "In4.Cu" "In9.Cu")
		(hatch none 0.5)
		(connect_pads
			(clearance 0)
		)
		(min_thickness 0.25)
		(keepout
			(tracks not_allowed)
			(vias allowed)
			(pads allowed)
			(copperpour not_allowed)
			(footprints allowed)
		)
		(placement
			(enabled no)
			(sheetname "")
		)
		(fill yes
			(thermal_gap 0.5)
			(thermal_bridge_width 0.5)
			(island_removal_mode 0)
		)
		(polygon
			(pts
				(arc
					(start 279.236678 -295.956482)
					(mid 278.688038 -296.505122)
					(end 279.236678 -297.053762)
				)
				(arc
					(start 280.636726 -297.053762)
					(mid 281.023774 -296.893966)
					(end 281.185366 -296.507662)
				)
				(arc
					(start 281.030426 -296.507662)
					(mid 280.636726 -296.89883)
					(end 280.243026 -296.507662)
				)
				(arc
					(start 279.630378 -296.507662)
					(mid 279.236678 -296.89883)
					(end 278.842978 -296.507662)
				)
				(arc
					(start 278.842978 -296.505122)
					(mid 279.236678 -296.111422)
					(end 279.630378 -296.505122)
				)
				(arc
					(start 280.243026 -296.505122)
					(mid 280.636726 -296.111422)
					(end 281.030426 -296.505122)
				)
				(arc
					(start 281.185366 -296.505122)
					(mid 281.024673 -296.117175)
					(end 280.636726 -295.956482)
				)
				(xy 279.236932 -295.956482)
			)
		)
	)
	(zone
		(layers "F.Cu" "B.Cu" "In2.Cu" "In4.Cu" "In9.Cu")
		(hatch none 0.5)
		(connect_pads
			(clearance 0)
		)
		(min_thickness 0.25)
		(keepout
			(tracks not_allowed)
			(vias allowed)
			(pads allowed)
			(copperpour not_allowed)
			(footprints allowed)
		)
		(placement
			(enabled no)
			(sheetname "")
		)
		(fill yes
			(thermal_gap 0.5)
			(thermal_bridge_width 0.5)
			(island_removal_mode 0)
		)
		(polygon
			(pts
				(arc
					(start 286.436562 -353.55403)
					(mid 285.885382 -354.10521)
					(end 286.436562 -354.65639)
				)
				(arc
					(start 287.83661 -354.65639)
					(mid 288.225454 -354.49585)
					(end 288.38779 -354.10775)
				)
				(arc
					(start 288.23031 -354.10775)
					(mid 287.83661 -354.498918)
					(end 287.44291 -354.10775)
				)
				(arc
					(start 286.830262 -354.10775)
					(mid 286.436562 -354.498918)
					(end 286.042862 -354.10775)
				)
				(arc
					(start 286.042862 -354.10521)
					(mid 286.436562 -353.71151)
					(end 286.830262 -354.10521)
				)
				(arc
					(start 287.44291 -354.10521)
					(mid 287.83661 -353.71151)
					(end 288.23031 -354.10521)
				)
				(arc
					(start 288.38779 -354.10521)
					(mid 288.226353 -353.715467)
					(end 287.83661 -353.55403)
				)
				(xy 286.436816 -353.55403)
			)
		)
	)
	(zone
		(layers "F.Cu" "B.Cu" "In2.Cu" "In4.Cu" "In9.Cu")
		(hatch none 0.5)
		(connect_pads
			(clearance 0)
		)
		(min_thickness 0.25)
		(keepout
			(tracks not_allowed)
			(vias allowed)
			(pads allowed)
			(copperpour not_allowed)
			(footprints allowed)
		)
		(placement
			(enabled no)
			(sheetname "")
		)
		(fill yes
			(thermal_gap 0.5)
			(thermal_bridge_width 0.5)
			(island_removal_mode 0)
		)
		(polygon
			(pts
				(arc
					(start 238.78159 -121.499884)
					(mid 238.434653 -120.877616)
					(end 237.722918 -120.84558)
				)
				(arc
					(start 235.722922 -121.845578)
					(mid 235.39577 -122.827034)
					(end 236.377226 -123.154186)
				)
				(xy 237.6805 -122.502422)
				(arc
					(start 236.596174 -122.502422)
					(mid 236.050074 -123.045988)
					(end 235.503974 -122.502422)
				)
				(arc
					(start 235.503974 -122.499882)
					(mid 236.050074 -121.953782)
					(end 236.596174 -122.499882)
				)
				(xy 237.68558 -122.499882)
				(arc
					(start 238.3663 -122.159522)
					(mid 238.668445 -121.890698)
					(end 238.78159 -121.502424)
				)
				(arc
					(start 238.59617 -121.502424)
					(mid 238.05007 -122.04599)
					(end 237.50397 -121.502424)
				)
				(arc
					(start 237.50397 -121.499884)
					(mid 238.05007 -120.953784)
					(end 238.59617 -121.499884)
				)
			)
		)
	)
	(zone
		(layers "F.Cu" "B.Cu" "In2.Cu" "In4.Cu" "In9.Cu")
		(hatch none 0.5)
		(connect_pads
			(clearance 0)
		)
		(min_thickness 0.25)
		(keepout
			(tracks not_allowed)
			(vias allowed)
			(pads allowed)
			(copperpour not_allowed)
			(footprints allowed)
		)
		(placement
			(enabled no)
			(sheetname "")
		)
		(fill yes
			(thermal_gap 0.5)
			(thermal_bridge_width 0.5)
			(island_removal_mode 0)
		)
		(polygon
			(pts
				(arc
					(start 286.436562 -349.954088)
					(mid 285.885382 -350.505268)
					(end 286.436562 -351.056448)
				)
				(arc
					(start 287.83661 -351.056448)
					(mid 288.225454 -350.895908)
					(end 288.38779 -350.507808)
				)
				(arc
					(start 288.23031 -350.507808)
					(mid 287.83661 -350.898976)
					(end 287.44291 -350.507808)
				)
				(arc
					(start 286.830262 -350.507808)
					(mid 286.436562 -350.898976)
					(end 286.042862 -350.507808)
				)
				(arc
					(start 286.042862 -350.505268)
					(mid 286.436562 -350.111568)
					(end 286.830262 -350.505268)
				)
				(arc
					(start 287.44291 -350.505268)
					(mid 287.83661 -350.111568)
					(end 288.23031 -350.505268)
				)
				(arc
					(start 288.38779 -350.505268)
					(mid 288.226353 -350.115525)
					(end 287.83661 -349.954088)
				)
				(xy 286.436816 -349.954088)
			)
		)
	)
	(zone
		(layers "F.Cu" "B.Cu" "In2.Cu" "In4.Cu" "In9.Cu")
		(hatch none 0.5)
		(connect_pads
			(clearance 0)
		)
		(min_thickness 0.25)
		(keepout
			(tracks not_allowed)
			(vias allowed)
			(pads allowed)
			(copperpour not_allowed)
			(footprints allowed)
		)
		(placement
			(enabled no)
			(sheetname "")
		)
		(fill yes
			(thermal_gap 0.5)
			(thermal_bridge_width 0.5)
			(island_removal_mode 0)
		)
		(polygon
			(pts
				(arc
					(start 285.436564 -355.353874)
					(mid 284.885384 -355.905054)
					(end 285.436564 -356.456234)
				)
				(arc
					(start 286.836612 -356.456234)
					(mid 287.225456 -356.295694)
					(end 287.387792 -355.907594)
				)
				(arc
					(start 287.230312 -355.907594)
					(mid 286.836612 -356.298762)
					(end 286.442912 -355.907594)
				)
				(arc
					(start 285.830264 -355.907594)
					(mid 285.436564 -356.298762)
					(end 285.042864 -355.907594)
				)
				(arc
					(start 285.042864 -355.905054)
					(mid 285.436564 -355.511354)
					(end 285.830264 -355.905054)
				)
				(arc
					(start 286.442912 -355.905054)
					(mid 286.836612 -355.511354)
					(end 287.230312 -355.905054)
				)
				(arc
					(start 287.387792 -355.905054)
					(mid 287.226355 -355.515311)
					(end 286.836612 -355.353874)
				)
				(xy 285.436818 -355.353874)
			)
		)
	)
	(zone
		(layers "F.Cu" "B.Cu" "In2.Cu" "In4.Cu" "In9.Cu")
		(hatch none 0.5)
		(connect_pads
			(clearance 0)
		)
		(min_thickness 0.25)
		(keepout
			(tracks not_allowed)
			(vias allowed)
			(pads allowed)
			(copperpour not_allowed)
			(footprints allowed)
		)
		(placement
			(enabled no)
			(sheetname "")
		)
		(fill yes
			(thermal_gap 0.5)
			(thermal_bridge_width 0.5)
			(island_removal_mode 0)
		)
		(polygon
			(pts
				(arc
					(start 285.436564 -312.154062)
					(mid 284.885384 -312.705242)
					(end 285.436564 -313.256422)
				)
				(arc
					(start 286.836612 -313.256422)
					(mid 287.225456 -313.095882)
					(end 287.387792 -312.707782)
				)
				(arc
					(start 287.230312 -312.707782)
					(mid 286.836612 -313.09895)
					(end 286.442912 -312.707782)
				)
				(arc
					(start 285.830264 -312.707782)
					(mid 285.436564 -313.09895)
					(end 285.042864 -312.707782)
				)
				(arc
					(start 285.042864 -312.705242)
					(mid 285.436564 -312.311542)
					(end 285.830264 -312.705242)
				)
				(arc
					(start 286.442912 -312.705242)
					(mid 286.836612 -312.311542)
					(end 287.230312 -312.705242)
				)
				(arc
					(start 287.387792 -312.705242)
					(mid 287.226355 -312.315499)
					(end 286.836612 -312.154062)
				)
				(xy 285.436818 -312.154062)
			)
		)
	)
	(zone
		(layers "F.Cu" "B.Cu" "In2.Cu" "In4.Cu" "In9.Cu")
		(hatch none 0.5)
		(connect_pads
			(clearance 0)
		)
		(min_thickness 0.25)
		(keepout
			(tracks not_allowed)
			(vias allowed)
			(pads allowed)
			(copperpour not_allowed)
			(footprints allowed)
		)
		(placement
			(enabled no)
			(sheetname "")
		)
		(fill yes
			(thermal_gap 0.5)
			(thermal_bridge_width 0.5)
			(island_removal_mode 0)
		)
		(polygon
			(pts
				(arc
					(start 278.23668 -294.156638)
					(mid 277.68804 -294.705278)
					(end 278.23668 -295.253918)
				)
				(arc
					(start 279.636728 -295.253918)
					(mid 280.023776 -295.094122)
					(end 280.185368 -294.707818)
				)
				(arc
					(start 280.030428 -294.707818)
					(mid 279.636728 -295.098986)
					(end 279.243028 -294.707818)
				)
				(arc
					(start 278.63038 -294.707818)
					(mid 278.23668 -295.098986)
					(end 277.84298 -294.707818)
				)
				(arc
					(start 277.84298 -294.705278)
					(mid 278.23668 -294.311578)
					(end 278.63038 -294.705278)
				)
				(arc
					(start 279.243028 -294.705278)
					(mid 279.636728 -294.311578)
					(end 280.030428 -294.705278)
				)
				(arc
					(start 280.185368 -294.705278)
					(mid 280.024675 -294.317331)
					(end 279.636728 -294.156638)
				)
				(xy 278.236934 -294.156638)
			)
		)
	)
	(zone
		(layers "F.Cu" "B.Cu" "In2.Cu" "In4.Cu" "In9.Cu")
		(hatch none 0.5)
		(connect_pads
			(clearance 0)
		)
		(min_thickness 0.25)
		(keepout
			(tracks not_allowed)
			(vias allowed)
			(pads allowed)
			(copperpour not_allowed)
			(footprints allowed)
		)
		(placement
			(enabled no)
			(sheetname "")
		)
		(fill yes
			(thermal_gap 0.5)
			(thermal_bridge_width 0.5)
			(island_removal_mode 0)
		)
		(polygon
			(pts
				(arc
					(start 285.436564 -326.554084)
					(mid 284.885384 -327.105264)
					(end 285.436564 -327.656444)
				)
				(arc
					(start 286.836612 -327.656444)
					(mid 287.225456 -327.495904)
					(end 287.387792 -327.107804)
				)
				(arc
					(start 287.230312 -327.107804)
					(mid 286.836612 -327.498972)
					(end 286.442912 -327.107804)
				)
				(arc
					(start 285.830264 -327.107804)
					(mid 285.436564 -327.498972)
					(end 285.042864 -327.107804)
				)
				(arc
					(start 285.042864 -327.105264)
					(mid 285.436564 -326.711564)
					(end 285.830264 -327.105264)
				)
				(arc
					(start 286.442912 -327.105264)
					(mid 286.836612 -326.711564)
					(end 287.230312 -327.105264)
				)
				(arc
					(start 287.387792 -327.105264)
					(mid 287.226355 -326.715521)
					(end 286.836612 -326.554084)
				)
				(xy 285.436818 -326.554084)
			)
		)
	)
	(zone
		(layers "F.Cu" "B.Cu" "In2.Cu" "In4.Cu" "In9.Cu")
		(hatch none 0.5)
		(connect_pads
			(clearance 0)
		)
		(min_thickness 0.25)
		(keepout
			(tracks not_allowed)
			(vias allowed)
			(pads allowed)
			(copperpour not_allowed)
			(footprints allowed)
		)
		(placement
			(enabled no)
			(sheetname "")
		)
		(fill yes
			(thermal_gap 0.5)
			(thermal_bridge_width 0.5)
			(island_removal_mode 0)
		)
		(polygon
			(pts
				(arc
					(start 240.877344 -114.845592)
					(mid 239.895939 -115.172642)
					(end 240.222786 -116.1542)
				)
				(arc
					(start 242.222782 -117.154198)
					(mid 242.933443 -117.122841)
					(end 243.281454 -116.502434)
				)
				(arc
					(start 243.096034 -116.502434)
					(mid 242.549934 -117.046)
					(end 242.003834 -116.502434)
				)
				(arc
					(start 242.003834 -116.499894)
					(mid 242.549934 -115.953794)
					(end 243.096034 -116.499894)
				)
				(arc
					(start 243.281454 -116.499894)
					(mid 243.172202 -116.115311)
					(end 242.877086 -115.84559)
				)
				(xy 242.190778 -115.502436)
				(arc
					(start 241.096038 -115.502436)
					(mid 240.549938 -116.046002)
					(end 240.003838 -115.502436)
				)
				(arc
					(start 240.003838 -115.499896)
					(mid 240.549938 -114.953796)
					(end 241.096038 -115.499896)
				)
				(xy 242.185698 -115.499896)
			)
		)
	)
	(zone
		(layers "F.Cu" "B.Cu" "In2.Cu" "In4.Cu" "In9.Cu")
		(hatch none 0.5)
		(connect_pads
			(clearance 0)
		)
		(min_thickness 0.25)
		(keepout
			(tracks not_allowed)
			(vias allowed)
			(pads allowed)
			(copperpour not_allowed)
			(footprints allowed)
		)
		(placement
			(enabled no)
			(sheetname "")
		)
		(fill yes
			(thermal_gap 0.5)
			(thermal_bridge_width 0.5)
			(island_removal_mode 0)
		)
		(polygon
			(pts
				(arc
					(start 285.436564 -257.751072)
					(mid 284.885384 -258.302252)
					(end 285.436564 -258.853432)
				)
				(arc
					(start 286.836612 -258.853432)
					(mid 287.225456 -258.692892)
					(end 287.387792 -258.304792)
				)
				(arc
					(start 287.230312 -258.304792)
					(mid 286.836612 -258.69596)
					(end 286.442912 -258.304792)
				)
				(arc
					(start 285.830264 -258.304792)
					(mid 285.436564 -258.69596)
					(end 285.042864 -258.304792)
				)
				(arc
					(start 285.042864 -258.302252)
					(mid 285.436564 -257.908552)
					(end 285.830264 -258.302252)
				)
				(arc
					(start 286.442912 -258.302252)
					(mid 286.836612 -257.908552)
					(end 287.230312 -258.302252)
				)
				(arc
					(start 287.387792 -258.302252)
					(mid 287.226355 -257.912509)
					(end 286.836612 -257.751072)
				)
				(xy 285.436818 -257.751072)
			)
		)
	)
	(zone
		(layers "F.Cu" "B.Cu" "In2.Cu" "In4.Cu" "In9.Cu")
		(hatch none 0.5)
		(connect_pads
			(clearance 0)
		)
		(min_thickness 0.25)
		(keepout
			(tracks not_allowed)
			(vias allowed)
			(pads allowed)
			(copperpour not_allowed)
			(footprints allowed)
		)
		(placement
			(enabled no)
			(sheetname "")
		)
		(fill yes
			(thermal_gap 0.5)
			(thermal_bridge_width 0.5)
			(island_removal_mode 0)
		)
		(polygon
			(pts
				(arc
					(start 238.78159 -153.49982)
					(mid 238.434653 -152.877552)
					(end 237.722918 -152.845516)
				)
				(arc
					(start 235.733844 -153.84018)
					(mid 235.393447 -154.82121)
					(end 236.377226 -155.154122)
				)
				(xy 237.680754 -154.502358)
				(arc
					(start 236.596174 -154.502358)
					(mid 236.050074 -155.045924)
					(end 235.503974 -154.502358)
				)
				(arc
					(start 235.503974 -154.499818)
					(mid 236.050074 -153.953718)
					(end 236.596174 -154.499818)
				)
				(xy 237.685834 -154.499818)
				(arc
					(start 238.377222 -154.154124)
					(mid 238.671681 -153.88549)
					(end 238.78159 -153.50236)
				)
				(arc
					(start 238.59617 -153.50236)
					(mid 238.05007 -154.045926)
					(end 237.50397 -153.50236)
				)
				(arc
					(start 237.50397 -153.49982)
					(mid 238.05007 -152.95372)
					(end 238.59617 -153.49982)
				)
			)
		)
	)
	(zone
		(layers "F.Cu" "B.Cu" "In2.Cu" "In4.Cu" "In9.Cu")
		(hatch none 0.5)
		(connect_pads
			(clearance 0)
		)
		(min_thickness 0.25)
		(keepout
			(tracks not_allowed)
			(vias allowed)
			(pads allowed)
			(copperpour not_allowed)
			(footprints allowed)
		)
		(placement
			(enabled no)
			(sheetname "")
		)
		(fill yes
			(thermal_gap 0.5)
			(thermal_bridge_width 0.5)
			(island_removal_mode 0)
		)
		(polygon
			(pts
				(arc
					(start 238.78159 -157.499812)
					(mid 238.434653 -156.877544)
					(end 237.722918 -156.845508)
				)
				(arc
					(start 235.733844 -157.840172)
					(mid 235.393447 -158.821202)
					(end 236.377226 -159.154114)
				)
				(xy 237.680754 -158.50235)
				(arc
					(start 236.596174 -158.50235)
					(mid 236.050074 -159.045916)
					(end 235.503974 -158.50235)
				)
				(arc
					(start 235.503974 -158.49981)
					(mid 236.050074 -157.95371)
					(end 236.596174 -158.49981)
				)
				(xy 237.685834 -158.49981)
				(arc
					(start 238.377222 -158.154116)
					(mid 238.671681 -157.885482)
					(end 238.78159 -157.502352)
				)
				(arc
					(start 238.59617 -157.502352)
					(mid 238.05007 -158.045918)
					(end 237.50397 -157.502352)
				)
				(arc
					(start 237.50397 -157.499812)
					(mid 238.05007 -156.953712)
					(end 238.59617 -157.499812)
				)
			)
		)
	)
	(zone
		(layers "F.Cu" "B.Cu" "In2.Cu" "In4.Cu" "In9.Cu")
		(hatch none 0.5)
		(connect_pads
			(clearance 0)
		)
		(min_thickness 0.25)
		(keepout
			(tracks not_allowed)
			(vias allowed)
			(pads allowed)
			(copperpour not_allowed)
			(footprints allowed)
		)
		(placement
			(enabled no)
			(sheetname "")
		)
		(fill yes
			(thermal_gap 0.5)
			(thermal_bridge_width 0.5)
			(island_removal_mode 0)
		)
		(polygon
			(pts
				(arc
					(start 240.880392 -122.838718)
					(mid 239.888776 -123.169426)
					(end 240.219484 -124.161042)
				)
				(arc
					(start 242.20805 -125.155198)
					(mid 242.932011 -125.132607)
					(end 243.289074 -124.502418)
				)
				(arc
					(start 243.096034 -124.502418)
					(mid 242.549934 -125.045984)
					(end 242.003834 -124.502418)
				)
				(arc
					(start 242.003834 -124.499878)
					(mid 242.549934 -123.953778)
					(end 243.096034 -124.499878)
				)
				(arc
					(start 243.289074 -124.499878)
					(mid 243.178654 -124.111241)
					(end 242.880388 -123.838716)
				)
				(xy 242.207796 -123.50242)
				(arc
					(start 241.096038 -123.50242)
					(mid 240.549938 -124.045986)
					(end 240.003838 -123.50242)
				)
				(arc
					(start 240.003838 -123.49988)
					(mid 240.549938 -122.95378)
					(end 241.096038 -123.49988)
				)
				(xy 242.202716 -123.49988)
			)
		)
	)
	(zone
		(layers "F.Cu" "B.Cu" "In2.Cu" "In4.Cu" "In9.Cu")
		(hatch none 0.5)
		(connect_pads
			(clearance 0)
		)
		(min_thickness 0.25)
		(keepout
			(tracks not_allowed)
			(vias allowed)
			(pads allowed)
			(copperpour not_allowed)
			(footprints allowed)
		)
		(placement
			(enabled no)
			(sheetname "")
		)
		(fill yes
			(thermal_gap 0.5)
			(thermal_bridge_width 0.5)
			(island_removal_mode 0)
		)
		(polygon
			(pts
				(arc
					(start 285.436564 -308.553866)
					(mid 284.885384 -309.105046)
					(end 285.436564 -309.656226)
				)
				(arc
					(start 286.836612 -309.656226)
					(mid 287.225456 -309.495686)
					(end 287.387792 -309.107586)
				)
				(arc
					(start 287.230312 -309.107586)
					(mid 286.836612 -309.498754)
					(end 286.442912 -309.107586)
				)
				(arc
					(start 285.830264 -309.107586)
					(mid 285.436564 -309.498754)
					(end 285.042864 -309.107586)
				)
				(arc
					(start 285.042864 -309.105046)
					(mid 285.436564 -308.711346)
					(end 285.830264 -309.105046)
				)
				(arc
					(start 286.442912 -309.105046)
					(mid 286.836612 -308.711346)
					(end 287.230312 -309.105046)
				)
				(arc
					(start 287.387792 -309.105046)
					(mid 287.226355 -308.715303)
					(end 286.836612 -308.553866)
				)
				(xy 285.436818 -308.553866)
			)
		)
	)
	(zone
		(layers "F.Cu" "B.Cu" "In2.Cu" "In4.Cu" "In9.Cu")
		(hatch none 0.5)
		(connect_pads
			(clearance 0)
		)
		(min_thickness 0.25)
		(keepout
			(tracks not_allowed)
			(vias allowed)
			(pads allowed)
			(copperpour not_allowed)
			(footprints allowed)
		)
		(placement
			(enabled no)
			(sheetname "")
		)
		(fill yes
			(thermal_gap 0.5)
			(thermal_bridge_width 0.5)
			(island_removal_mode 0)
		)
		(polygon
			(pts
				(arc
					(start 286.436562 -313.953906)
					(mid 285.885382 -314.505086)
					(end 286.436562 -315.056266)
				)
				(arc
					(start 287.83661 -315.056266)
					(mid 288.225454 -314.895726)
					(end 288.38779 -314.507626)
				)
				(arc
					(start 288.23031 -314.507626)
					(mid 287.83661 -314.898794)
					(end 287.44291 -314.507626)
				)
				(arc
					(start 286.830262 -314.507626)
					(mid 286.436562 -314.898794)
					(end 286.042862 -314.507626)
				)
				(arc
					(start 286.042862 -314.505086)
					(mid 286.436562 -314.111386)
					(end 286.830262 -314.505086)
				)
				(arc
					(start 287.44291 -314.505086)
					(mid 287.83661 -314.111386)
					(end 288.23031 -314.505086)
				)
				(arc
					(start 288.38779 -314.505086)
					(mid 288.226353 -314.115343)
					(end 287.83661 -313.953906)
				)
				(xy 286.436816 -313.953906)
			)
		)
	)
	(zone
		(layers "F.Cu" "B.Cu" "In2.Cu" "In4.Cu" "In9.Cu")
		(hatch none 0.5)
		(connect_pads
			(clearance 0)
		)
		(min_thickness 0.25)
		(keepout
			(tracks not_allowed)
			(vias allowed)
			(pads allowed)
			(copperpour not_allowed)
			(footprints allowed)
		)
		(placement
			(enabled no)
			(sheetname "")
		)
		(fill yes
			(thermal_gap 0.5)
			(thermal_bridge_width 0.5)
			(island_removal_mode 0)
		)
		(polygon
			(pts
				(arc
					(start 283.57703 -34.545778)
					(mid 282.595574 -34.87293)
					(end 282.922726 -35.854386)
				)
				(arc
					(start 284.922468 -36.854384)
					(mid 285.633346 -36.823183)
					(end 285.981394 -36.20262)
				)
				(arc
					(start 285.795974 -36.20262)
					(mid 285.249874 -36.746186)
					(end 284.703774 -36.20262)
				)
				(arc
					(start 284.703774 -36.20008)
					(mid 285.249874 -35.65398)
					(end 285.795974 -36.20008)
				)
				(arc
					(start 285.981394 -36.20008)
					(mid 285.872142 -35.815497)
					(end 285.577026 -35.545776)
				)
				(xy 284.890718 -35.202622)
				(arc
					(start 283.795978 -35.202622)
					(mid 283.249878 -35.746188)
					(end 282.703778 -35.202622)
				)
				(arc
					(start 282.703778 -35.200082)
					(mid 283.249878 -34.653982)
					(end 283.795978 -35.200082)
				)
				(xy 284.885638 -35.200082)
			)
		)
	)
	(zone
		(layers "F.Cu" "B.Cu" "In2.Cu" "In4.Cu" "In9.Cu")
		(hatch none 0.5)
		(connect_pads
			(clearance 0)
		)
		(min_thickness 0.25)
		(keepout
			(tracks not_allowed)
			(vias allowed)
			(pads allowed)
			(copperpour not_allowed)
			(footprints allowed)
		)
		(placement
			(enabled no)
			(sheetname "")
		)
		(fill yes
			(thermal_gap 0.5)
			(thermal_bridge_width 0.5)
			(island_removal_mode 0)
		)
		(polygon
			(pts
				(arc
					(start 238.78159 -149.499828)
					(mid 238.434653 -148.87756)
					(end 237.722918 -148.845524)
				)
				(arc
					(start 235.733844 -149.840188)
					(mid 235.393447 -150.821218)
					(end 236.377226 -151.15413)
				)
				(xy 237.680754 -150.502366)
				(arc
					(start 236.596174 -150.502366)
					(mid 236.050074 -151.045932)
					(end 235.503974 -150.502366)
				)
				(arc
					(start 235.503974 -150.499826)
					(mid 236.050074 -149.953726)
					(end 236.596174 -150.499826)
				)
				(xy 237.685834 -150.499826)
				(arc
					(start 238.377222 -150.154132)
					(mid 238.671681 -149.885498)
					(end 238.78159 -149.502368)
				)
				(arc
					(start 238.59617 -149.502368)
					(mid 238.05007 -150.045934)
					(end 237.50397 -149.502368)
				)
				(arc
					(start 237.50397 -149.499828)
					(mid 238.05007 -148.953728)
					(end 238.59617 -149.499828)
				)
			)
		)
	)
	(zone
		(layers "F.Cu" "B.Cu" "In2.Cu" "In4.Cu" "In9.Cu")
		(hatch none 0.5)
		(connect_pads
			(clearance 0)
		)
		(min_thickness 0.25)
		(keepout
			(tracks not_allowed)
			(vias allowed)
			(pads allowed)
			(copperpour not_allowed)
			(footprints allowed)
		)
		(placement
			(enabled no)
			(sheetname "")
		)
		(fill yes
			(thermal_gap 0.5)
			(thermal_bridge_width 0.5)
			(island_removal_mode 0)
		)
		(polygon
			(pts
				(arc
					(start 278.23668 -250.551188)
					(mid 277.6855 -251.102368)
					(end 278.23668 -251.653548)
				)
				(arc
					(start 279.636728 -251.653548)
					(mid 280.025572 -251.493008)
					(end 280.187908 -251.104908)
				)
				(arc
					(start 280.030428 -251.104908)
					(mid 279.636728 -251.496076)
					(end 279.243028 -251.104908)
				)
				(arc
					(start 278.63038 -251.104908)
					(mid 278.23668 -251.496076)
					(end 277.84298 -251.104908)
				)
				(arc
					(start 277.84298 -251.102368)
					(mid 278.23668 -250.708668)
					(end 278.63038 -251.102368)
				)
				(arc
					(start 279.243028 -251.102368)
					(mid 279.636728 -250.708668)
					(end 280.030428 -251.102368)
				)
				(arc
					(start 280.187908 -251.102368)
					(mid 280.026471 -250.712625)
					(end 279.636728 -250.551188)
				)
				(xy 278.236934 -250.551188)
			)
		)
	)
	(zone
		(layers "F.Cu" "B.Cu" "In2.Cu" "In4.Cu" "In9.Cu")
		(hatch none 0.5)
		(connect_pads
			(clearance 0)
		)
		(min_thickness 0.25)
		(keepout
			(tracks not_allowed)
			(vias allowed)
			(pads allowed)
			(copperpour not_allowed)
			(footprints allowed)
		)
		(placement
			(enabled no)
			(sheetname "")
		)
		(fill yes
			(thermal_gap 0.5)
			(thermal_bridge_width 0.5)
			(island_removal_mode 0)
		)
		(polygon
			(pts
				(arc
					(start 286.436562 -255.951228)
					(mid 285.885382 -256.502408)
					(end 286.436562 -257.053588)
				)
				(arc
					(start 287.83661 -257.053588)
					(mid 288.225454 -256.893048)
					(end 288.38779 -256.504948)
				)
				(arc
					(start 288.23031 -256.504948)
					(mid 287.83661 -256.896116)
					(end 287.44291 -256.504948)
				)
				(arc
					(start 286.830262 -256.504948)
					(mid 286.436562 -256.896116)
					(end 286.042862 -256.504948)
				)
				(arc
					(start 286.042862 -256.502408)
					(mid 286.436562 -256.108708)
					(end 286.830262 -256.502408)
				)
				(arc
					(start 287.44291 -256.502408)
					(mid 287.83661 -256.108708)
					(end 288.23031 -256.502408)
				)
				(arc
					(start 288.38779 -256.502408)
					(mid 288.226353 -256.112665)
					(end 287.83661 -255.951228)
				)
				(xy 286.436816 -255.951228)
			)
		)
	)
	(zone
		(layers "F.Cu" "B.Cu" "In2.Cu" "In4.Cu" "In9.Cu")
		(hatch none 0.5)
		(connect_pads
			(clearance 0)
		)
		(min_thickness 0.25)
		(keepout
			(tracks not_allowed)
			(vias allowed)
			(pads allowed)
			(copperpour not_allowed)
			(footprints allowed)
		)
		(placement
			(enabled no)
			(sheetname "")
		)
		(fill yes
			(thermal_gap 0.5)
			(thermal_bridge_width 0.5)
			(island_removal_mode 0)
		)
		(polygon
			(pts
				(arc
					(start 240.877344 -150.84552)
					(mid 239.895939 -151.17257)
					(end 240.222786 -152.154128)
				)
				(arc
					(start 242.222782 -153.154126)
					(mid 242.933443 -153.122769)
					(end 243.281454 -152.502362)
				)
				(arc
					(start 243.096034 -152.502362)
					(mid 242.549934 -153.045928)
					(end 242.003834 -152.502362)
				)
				(arc
					(start 242.003834 -152.499822)
					(mid 242.549934 -151.953722)
					(end 243.096034 -152.499822)
				)
				(arc
					(start 243.281454 -152.499822)
					(mid 243.172202 -152.115239)
					(end 242.877086 -151.845518)
				)
				(xy 242.190778 -151.502364)
				(arc
					(start 241.096038 -151.502364)
					(mid 240.549938 -152.04593)
					(end 240.003838 -151.502364)
				)
				(arc
					(start 240.003838 -151.499824)
					(mid 240.549938 -150.953724)
					(end 241.096038 -151.499824)
				)
				(xy 242.185698 -151.499824)
			)
		)
	)
	(zone
		(layers "F.Cu" "B.Cu" "In2.Cu" "In4.Cu" "In9.Cu")
		(hatch none 0.5)
		(connect_pads
			(clearance 0)
		)
		(min_thickness 0.25)
		(keepout
			(tracks not_allowed)
			(vias allowed)
			(pads allowed)
			(copperpour not_allowed)
			(footprints allowed)
		)
		(placement
			(enabled no)
			(sheetname "")
		)
		(fill yes
			(thermal_gap 0.5)
			(thermal_bridge_width 0.5)
			(island_removal_mode 0)
		)
		(polygon
			(pts
				(arc
					(start 382.701292 -29.150056)
					(mid 382.150112 -28.598876)
					(end 381.598932 -29.150056)
				)
				(arc
					(start 381.598932 -30.550104)
					(mid 382.148842 -31.101283)
					(end 382.701292 -30.552644)
				)
				(arc
					(start 382.543812 -30.552644)
					(mid 382.150112 -30.943812)
					(end 381.756412 -30.552644)
				)
				(arc
					(start 381.756412 -30.550104)
					(mid 382.150112 -30.156404)
					(end 382.543812 -30.550104)
				)
				(xy 382.701292 -30.550104) (xy 382.701292 -29.152596)
				(arc
					(start 382.543812 -29.152596)
					(mid 382.150112 -29.543764)
					(end 381.756412 -29.152596)
				)
				(arc
					(start 381.756412 -29.150056)
					(mid 382.150112 -28.756356)
					(end 382.543812 -29.150056)
				)
			)
		)
	)
	(zone
		(layers "F.Cu" "B.Cu" "In2.Cu" "In4.Cu" "In9.Cu")
		(hatch none 0.5)
		(connect_pads
			(clearance 0)
		)
		(min_thickness 0.25)
		(keepout
			(tracks not_allowed)
			(vias allowed)
			(pads allowed)
			(copperpour not_allowed)
			(footprints allowed)
		)
		(placement
			(enabled no)
			(sheetname "")
		)
		(fill yes
			(thermal_gap 0.5)
			(thermal_bridge_width 0.5)
			(island_removal_mode 0)
		)
		(polygon
			(pts
				(arc
					(start 286.436562 -263.151112)
					(mid 285.885382 -263.702292)
					(end 286.436562 -264.253472)
				)
				(arc
					(start 287.83661 -264.253472)
					(mid 288.225454 -264.092932)
					(end 288.38779 -263.704832)
				)
				(arc
					(start 288.23031 -263.704832)
					(mid 287.83661 -264.096)
					(end 287.44291 -263.704832)
				)
				(arc
					(start 286.830262 -263.704832)
					(mid 286.436562 -264.096)
					(end 286.042862 -263.704832)
				)
				(arc
					(start 286.042862 -263.702292)
					(mid 286.436562 -263.308592)
					(end 286.830262 -263.702292)
				)
				(arc
					(start 287.44291 -263.702292)
					(mid 287.83661 -263.308592)
					(end 288.23031 -263.702292)
				)
				(arc
					(start 288.38779 -263.702292)
					(mid 288.226353 -263.312549)
					(end 287.83661 -263.151112)
				)
				(xy 286.436816 -263.151112)
			)
		)
	)
	(zone
		(layers "F.Cu" "B.Cu" "In2.Cu" "In4.Cu" "In9.Cu")
		(hatch none 0.5)
		(connect_pads
			(clearance 0)
		)
		(min_thickness 0.25)
		(keepout
			(tracks not_allowed)
			(vias allowed)
			(pads allowed)
			(copperpour not_allowed)
			(footprints allowed)
		)
		(placement
			(enabled no)
			(sheetname "")
		)
		(fill yes
			(thermal_gap 0.5)
			(thermal_bridge_width 0.5)
			(island_removal_mode 0)
		)
		(polygon
			(pts
				(arc
					(start 286.436562 -310.353964)
					(mid 285.885382 -310.905144)
					(end 286.436562 -311.456324)
				)
				(arc
					(start 287.83661 -311.456324)
					(mid 288.225454 -311.295784)
					(end 288.38779 -310.907684)
				)
				(arc
					(start 288.23031 -310.907684)
					(mid 287.83661 -311.298852)
					(end 287.44291 -310.907684)
				)
				(arc
					(start 286.830262 -310.907684)
					(mid 286.436562 -311.298852)
					(end 286.042862 -310.907684)
				)
				(arc
					(start 286.042862 -310.905144)
					(mid 286.436562 -310.511444)
					(end 286.830262 -310.905144)
				)
				(arc
					(start 287.44291 -310.905144)
					(mid 287.83661 -310.511444)
					(end 288.23031 -310.905144)
				)
				(arc
					(start 288.38779 -310.905144)
					(mid 288.226353 -310.515401)
					(end 287.83661 -310.353964)
				)
				(xy 286.436816 -310.353964)
			)
		)
	)
	(zone
		(layers "F.Cu" "B.Cu" "In2.Cu" "In4.Cu" "In9.Cu")
		(hatch none 0.5)
		(connect_pads
			(clearance 0)
		)
		(min_thickness 0.25)
		(keepout
			(tracks not_allowed)
			(vias allowed)
			(pads allowed)
			(copperpour not_allowed)
			(footprints allowed)
		)
		(placement
			(enabled no)
			(sheetname "")
		)
		(fill yes
			(thermal_gap 0.5)
			(thermal_bridge_width 0.5)
			(island_removal_mode 0)
		)
		(polygon
			(pts
				(arc
					(start 240.87709 -154.845512)
					(mid 239.895634 -155.172664)
					(end 240.222786 -156.15412)
				)
				(arc
					(start 242.222528 -157.154118)
					(mid 242.933406 -157.122917)
					(end 243.281454 -156.502354)
				)
				(arc
					(start 243.096034 -156.502354)
					(mid 242.549934 -157.04592)
					(end 242.003834 -156.502354)
				)
				(arc
					(start 242.003834 -156.499814)
					(mid 242.549934 -155.953714)
					(end 243.096034 -156.499814)
				)
				(arc
					(start 243.281454 -156.499814)
					(mid 243.172202 -156.115231)
					(end 242.877086 -155.84551)
				)
				(xy 242.190778 -155.502356)
				(arc
					(start 241.096038 -155.502356)
					(mid 240.549938 -156.045922)
					(end 240.003838 -155.502356)
				)
				(arc
					(start 240.003838 -155.499816)
					(mid 240.549938 -154.953716)
					(end 241.096038 -155.499816)
				)
				(xy 242.185698 -155.499816)
			)
		)
	)
	(zone
		(layers "F.Cu" "B.Cu" "In2.Cu" "In4.Cu" "In9.Cu")
		(hatch none 0.5)
		(connect_pads
			(clearance 0)
		)
		(min_thickness 0.25)
		(keepout
			(tracks not_allowed)
			(vias allowed)
			(pads allowed)
			(copperpour not_allowed)
			(footprints allowed)
		)
		(placement
			(enabled no)
			(sheetname "")
		)
		(fill yes
			(thermal_gap 0.5)
			(thermal_bridge_width 0.5)
			(island_removal_mode 0)
		)
		(polygon
			(pts
				(arc
					(start 285.436564 -250.551188)
					(mid 284.885384 -251.102368)
					(end 285.436564 -251.653548)
				)
				(arc
					(start 286.836612 -251.653548)
					(mid 287.225456 -251.493008)
					(end 287.387792 -251.104908)
				)
				(arc
					(start 287.230312 -251.104908)
					(mid 286.836612 -251.496076)
					(end 286.442912 -251.104908)
				)
				(arc
					(start 285.830264 -251.104908)
					(mid 285.436564 -251.496076)
					(end 285.042864 -251.104908)
				)
				(arc
					(start 285.042864 -251.102368)
					(mid 285.436564 -250.708668)
					(end 285.830264 -251.102368)
				)
				(arc
					(start 286.442912 -251.102368)
					(mid 286.836612 -250.708668)
					(end 287.230312 -251.102368)
				)
				(arc
					(start 287.387792 -251.102368)
					(mid 287.226355 -250.712625)
					(end 286.836612 -250.551188)
				)
				(xy 285.436818 -250.551188)
			)
		)
	)
	(zone
		(layers "F.Cu" "B.Cu" "In2.Cu" "In4.Cu" "In9.Cu")
		(hatch none 0.5)
		(connect_pads
			(clearance 0)
		)
		(min_thickness 0.25)
		(keepout
			(tracks not_allowed)
			(vias allowed)
			(pads allowed)
			(copperpour not_allowed)
			(footprints allowed)
		)
		(placement
			(enabled no)
			(sheetname "")
		)
		(fill yes
			(thermal_gap 0.5)
			(thermal_bridge_width 0.5)
			(island_removal_mode 0)
		)
		(polygon
			(pts
				(arc
					(start 278.23668 -257.751072)
					(mid 277.6855 -258.302252)
					(end 278.23668 -258.853432)
				)
				(arc
					(start 279.636728 -258.853432)
					(mid 280.025572 -258.692892)
					(end 280.187908 -258.304792)
				)
				(arc
					(start 280.030428 -258.304792)
					(mid 279.636728 -258.69596)
					(end 279.243028 -258.304792)
				)
				(arc
					(start 278.63038 -258.304792)
					(mid 278.23668 -258.69596)
					(end 277.84298 -258.304792)
				)
				(arc
					(start 277.84298 -258.302252)
					(mid 278.23668 -257.908552)
					(end 278.63038 -258.302252)
				)
				(arc
					(start 279.243028 -258.302252)
					(mid 279.636728 -257.908552)
					(end 280.030428 -258.302252)
				)
				(arc
					(start 280.187908 -258.302252)
					(mid 280.026471 -257.912509)
					(end 279.636728 -257.751072)
				)
				(xy 278.236934 -257.751072)
			)
		)
	)
	(zone
		(layers "F.Cu" "B.Cu" "In2.Cu" "In4.Cu" "In9.Cu")
		(hatch none 0.5)
		(connect_pads
			(clearance 0)
		)
		(min_thickness 0.25)
		(keepout
			(tracks not_allowed)
			(vias allowed)
			(pads allowed)
			(copperpour not_allowed)
			(footprints allowed)
		)
		(placement
			(enabled no)
			(sheetname "")
		)
		(fill yes
			(thermal_gap 0.5)
			(thermal_bridge_width 0.5)
			(island_removal_mode 0)
		)
		(polygon
			(pts
				(arc
					(start 285.436564 -351.753932)
					(mid 284.885384 -352.305112)
					(end 285.436564 -352.856292)
				)
				(arc
					(start 286.836612 -352.856292)
					(mid 287.225456 -352.695752)
					(end 287.387792 -352.307652)
				)
				(arc
					(start 287.230312 -352.307652)
					(mid 286.836612 -352.69882)
					(end 286.442912 -352.307652)
				)
				(arc
					(start 285.830264 -352.307652)
					(mid 285.436564 -352.69882)
					(end 285.042864 -352.307652)
				)
				(arc
					(start 285.042864 -352.305112)
					(mid 285.436564 -351.911412)
					(end 285.830264 -352.305112)
				)
				(arc
					(start 286.442912 -352.305112)
					(mid 286.836612 -351.911412)
					(end 287.230312 -352.305112)
				)
				(arc
					(start 287.387792 -352.305112)
					(mid 287.226355 -351.915369)
					(end 286.836612 -351.753932)
				)
				(xy 285.436818 -351.753932)
			)
		)
	)
	(zone
		(layers "F.Cu" "B.Cu" "In2.Cu" "In4.Cu" "In9.Cu")
		(hatch none 0.5)
		(connect_pads
			(clearance 0)
		)
		(min_thickness 0.25)
		(keepout
			(tracks not_allowed)
			(vias allowed)
			(pads allowed)
			(copperpour not_allowed)
			(footprints allowed)
		)
		(placement
			(enabled no)
			(sheetname "")
		)
		(fill yes
			(thermal_gap 0.5)
			(thermal_bridge_width 0.5)
			(island_removal_mode 0)
		)
		(polygon
			(pts
				(arc
					(start 286.436562 -335.554066)
					(mid 285.885382 -336.105246)
					(end 286.436562 -336.656426)
				)
				(arc
					(start 287.83661 -336.656426)
					(mid 288.225454 -336.495886)
					(end 288.38779 -336.107786)
				)
				(arc
					(start 288.23031 -336.107786)
					(mid 287.83661 -336.498954)
					(end 287.44291 -336.107786)
				)
				(arc
					(start 286.830262 -336.107786)
					(mid 286.436562 -336.498954)
					(end 286.042862 -336.107786)
				)
				(arc
					(start 286.042862 -336.105246)
					(mid 286.436562 -335.711546)
					(end 286.830262 -336.105246)
				)
				(arc
					(start 287.44291 -336.105246)
					(mid 287.83661 -335.711546)
					(end 288.23031 -336.105246)
				)
				(arc
					(start 288.38779 -336.105246)
					(mid 288.226353 -335.715503)
					(end 287.83661 -335.554066)
				)
				(xy 286.436816 -335.554066)
			)
		)
	)
	(zone
		(layers "F.Cu" "B.Cu" "In2.Cu" "In4.Cu" "In9.Cu")
		(hatch none 0.5)
		(connect_pads
			(clearance 0)
		)
		(min_thickness 0.25)
		(keepout
			(tracks not_allowed)
			(vias allowed)
			(pads allowed)
			(copperpour not_allowed)
			(footprints allowed)
		)
		(placement
			(enabled no)
			(sheetname "")
		)
		(fill yes
			(thermal_gap 0.5)
			(thermal_bridge_width 0.5)
			(island_removal_mode 0)
		)
		(polygon
			(pts
				(arc
					(start 279.236678 -255.951228)
					(mid 278.685498 -256.502408)
					(end 279.236678 -257.053588)
				)
				(arc
					(start 280.636726 -257.053588)
					(mid 281.02557 -256.893048)
					(end 281.187906 -256.504948)
				)
				(arc
					(start 281.030426 -256.504948)
					(mid 280.636726 -256.896116)
					(end 280.243026 -256.504948)
				)
				(arc
					(start 279.630378 -256.504948)
					(mid 279.236678 -256.896116)
					(end 278.842978 -256.504948)
				)
				(arc
					(start 278.842978 -256.502408)
					(mid 279.236678 -256.108708)
					(end 279.630378 -256.502408)
				)
				(arc
					(start 280.243026 -256.502408)
					(mid 280.636726 -256.108708)
					(end 281.030426 -256.502408)
				)
				(arc
					(start 281.187906 -256.502408)
					(mid 281.026469 -256.112665)
					(end 280.636726 -255.951228)
				)
				(xy 279.236932 -255.951228)
			)
		)
	)
	(zone
		(layers "F.Cu" "B.Cu" "In2.Cu" "In4.Cu" "In9.Cu")
		(hatch none 0.5)
		(connect_pads
			(clearance 0)
		)
		(min_thickness 0.25)
		(keepout
			(tracks not_allowed)
			(vias allowed)
			(pads allowed)
			(copperpour not_allowed)
			(footprints allowed)
		)
		(placement
			(enabled no)
			(sheetname "")
		)
		(fill yes
			(thermal_gap 0.5)
			(thermal_bridge_width 0.5)
			(island_removal_mode 0)
		)
		(polygon
			(pts
				(arc
					(start 286.436562 -306.754022)
					(mid 285.885382 -307.305202)
					(end 286.436562 -307.856382)
				)
				(arc
					(start 287.83661 -307.856382)
					(mid 288.225454 -307.695842)
					(end 288.38779 -307.307742)
				)
				(arc
					(start 288.23031 -307.307742)
					(mid 287.83661 -307.69891)
					(end 287.44291 -307.307742)
				)
				(arc
					(start 286.830262 -307.307742)
					(mid 286.436562 -307.69891)
					(end 286.042862 -307.307742)
				)
				(arc
					(start 286.042862 -307.305202)
					(mid 286.436562 -306.911502)
					(end 286.830262 -307.305202)
				)
				(arc
					(start 287.44291 -307.305202)
					(mid 287.83661 -306.911502)
					(end 288.23031 -307.305202)
				)
				(arc
					(start 288.38779 -307.305202)
					(mid 288.226353 -306.915459)
					(end 287.83661 -306.754022)
				)
				(xy 286.436816 -306.754022)
			)
		)
	)
	(zone
		(layers "F.Cu" "B.Cu" "In2.Cu" "In4.Cu" "In9.Cu")
		(hatch none 0.5)
		(connect_pads
			(clearance 0)
		)
		(min_thickness 0.25)
		(keepout
			(tracks not_allowed)
			(vias allowed)
			(pads allowed)
			(copperpour not_allowed)
			(footprints allowed)
		)
		(placement
			(enabled no)
			(sheetname "")
		)
		(fill yes
			(thermal_gap 0.5)
			(thermal_bridge_width 0.5)
			(island_removal_mode 0)
		)
		(polygon
			(pts
				(arc
					(start 279.236678 -252.351032)
					(mid 278.685498 -252.902212)
					(end 279.236678 -253.453392)
				)
				(arc
					(start 280.636726 -253.453392)
					(mid 281.02557 -253.292852)
					(end 281.187906 -252.904752)
				)
				(arc
					(start 281.030426 -252.904752)
					(mid 280.636726 -253.29592)
					(end 280.243026 -252.904752)
				)
				(arc
					(start 279.630378 -252.904752)
					(mid 279.236678 -253.29592)
					(end 278.842978 -252.904752)
				)
				(arc
					(start 278.842978 -252.902212)
					(mid 279.236678 -252.508512)
					(end 279.630378 -252.902212)
				)
				(arc
					(start 280.243026 -252.902212)
					(mid 280.636726 -252.508512)
					(end 281.030426 -252.902212)
				)
				(arc
					(start 281.187906 -252.902212)
					(mid 281.026469 -252.512469)
					(end 280.636726 -252.351032)
				)
				(xy 279.236932 -252.351032)
			)
		)
	)
	(zone
		(layers "F.Cu" "B.Cu" "In2.Cu" "In4.Cu" "In9.Cu")
		(hatch none 0.5)
		(connect_pads
			(clearance 0)
		)
		(min_thickness 0.25)
		(keepout
			(tracks not_allowed)
			(vias allowed)
			(pads allowed)
			(copperpour not_allowed)
			(footprints allowed)
		)
		(placement
			(enabled no)
			(sheetname "")
		)
		(fill yes
			(thermal_gap 0.5)
			(thermal_bridge_width 0.5)
			(island_removal_mode 0)
		)
		(polygon
			(pts
				(arc
					(start 285.436564 -304.953924)
					(mid 284.885384 -305.505104)
					(end 285.436564 -306.056284)
				)
				(arc
					(start 286.836612 -306.056284)
					(mid 287.225456 -305.895744)
					(end 287.387792 -305.507644)
				)
				(arc
					(start 287.230312 -305.507644)
					(mid 286.836612 -305.898812)
					(end 286.442912 -305.507644)
				)
				(arc
					(start 285.830264 -305.507644)
					(mid 285.436564 -305.898812)
					(end 285.042864 -305.507644)
				)
				(arc
					(start 285.042864 -305.505104)
					(mid 285.436564 -305.111404)
					(end 285.830264 -305.505104)
				)
				(arc
					(start 286.442912 -305.505104)
					(mid 286.836612 -305.111404)
					(end 287.230312 -305.505104)
				)
				(arc
					(start 287.387792 -305.505104)
					(mid 287.226355 -305.115361)
					(end 286.836612 -304.953924)
				)
				(xy 285.436818 -304.953924)
			)
		)
	)
	(zone
		(layers "F.Cu" "B.Cu" "In2.Cu" "In4.Cu" "In9.Cu")
		(hatch none 0.5)
		(connect_pads
			(clearance 0)
		)
		(min_thickness 0.25)
		(keepout
			(tracks not_allowed)
			(vias allowed)
			(pads allowed)
			(copperpour not_allowed)
			(footprints allowed)
		)
		(placement
			(enabled no)
			(sheetname "")
		)
		(fill yes
			(thermal_gap 0.5)
			(thermal_bridge_width 0.5)
			(island_removal_mode 0)
		)
		(polygon
			(pts
				(arc
					(start 238.78159 -117.499892)
					(mid 238.434653 -116.877624)
					(end 237.722918 -116.845588)
				)
				(arc
					(start 235.733844 -117.840252)
					(mid 235.393447 -118.821282)
					(end 236.377226 -119.154194)
				)
				(xy 237.680754 -118.50243)
				(arc
					(start 236.596174 -118.50243)
					(mid 236.050074 -119.045996)
					(end 235.503974 -118.50243)
				)
				(arc
					(start 235.503974 -118.49989)
					(mid 236.050074 -117.95379)
					(end 236.596174 -118.49989)
				)
				(xy 237.685834 -118.49989)
				(arc
					(start 238.377222 -118.154196)
					(mid 238.671681 -117.885562)
					(end 238.78159 -117.502432)
				)
				(arc
					(start 238.59617 -117.502432)
					(mid 238.05007 -118.045998)
					(end 237.50397 -117.502432)
				)
				(arc
					(start 237.50397 -117.499892)
					(mid 238.05007 -116.953792)
					(end 238.59617 -117.499892)
				)
			)
		)
	)
	(zone
		(layers "F.Cu" "B.Cu" "In2.Cu" "In4.Cu" "In9.Cu")
		(hatch none 0.5)
		(connect_pads
			(clearance 0)
		)
		(min_thickness 0.25)
		(keepout
			(tracks not_allowed)
			(vias allowed)
			(pads allowed)
			(copperpour not_allowed)
			(footprints allowed)
		)
		(placement
			(enabled no)
			(sheetname "")
		)
		(fill yes
			(thermal_gap 0.5)
			(thermal_bridge_width 0.5)
			(island_removal_mode 0)
		)
		(polygon
			(pts
				(arc
					(start 285.436564 -330.154026)
					(mid 284.885384 -330.705206)
					(end 285.436564 -331.256386)
				)
				(arc
					(start 286.836612 -331.256386)
					(mid 287.225456 -331.095846)
					(end 287.387792 -330.707746)
				)
				(arc
					(start 287.230312 -330.707746)
					(mid 286.836612 -331.098914)
					(end 286.442912 -330.707746)
				)
				(arc
					(start 285.830264 -330.707746)
					(mid 285.436564 -331.098914)
					(end 285.042864 -330.707746)
				)
				(arc
					(start 285.042864 -330.705206)
					(mid 285.436564 -330.311506)
					(end 285.830264 -330.705206)
				)
				(arc
					(start 286.442912 -330.705206)
					(mid 286.836612 -330.311506)
					(end 287.230312 -330.705206)
				)
				(arc
					(start 287.387792 -330.705206)
					(mid 287.226355 -330.315463)
					(end 286.836612 -330.154026)
				)
				(xy 285.436818 -330.154026)
			)
		)
	)
	(zone
		(layers "F.Cu" "B.Cu" "In2.Cu" "In4.Cu" "In9.Cu")
		(hatch none 0.5)
		(connect_pads
			(clearance 0)
		)
		(min_thickness 0.25)
		(keepout
			(tracks not_allowed)
			(vias allowed)
			(pads allowed)
			(copperpour not_allowed)
			(footprints allowed)
		)
		(placement
			(enabled no)
			(sheetname "")
		)
		(fill yes
			(thermal_gap 0.5)
			(thermal_bridge_width 0.5)
			(island_removal_mode 0)
		)
		(polygon
			(pts
				(arc
					(start 286.436562 -295.953942)
					(mid 285.885382 -296.505122)
					(end 286.436562 -297.056302)
				)
				(arc
					(start 287.83661 -297.056302)
					(mid 288.225454 -296.895762)
					(end 288.38779 -296.507662)
				)
				(arc
					(start 288.23031 -296.507662)
					(mid 287.83661 -296.89883)
					(end 287.44291 -296.507662)
				)
				(arc
					(start 286.830262 -296.507662)
					(mid 286.436562 -296.89883)
					(end 286.042862 -296.507662)
				)
				(arc
					(start 286.042862 -296.505122)
					(mid 286.436562 -296.111422)
					(end 286.830262 -296.505122)
				)
				(arc
					(start 287.44291 -296.505122)
					(mid 287.83661 -296.111422)
					(end 288.23031 -296.505122)
				)
				(arc
					(start 288.38779 -296.505122)
					(mid 288.226353 -296.115379)
					(end 287.83661 -295.953942)
				)
				(xy 286.436816 -295.953942)
			)
		)
	)
	(zone
		(layers "F.Cu" "B.Cu" "In2.Cu" "In4.Cu" "In9.Cu")
		(hatch none 0.5)
		(connect_pads
			(clearance 0)
		)
		(min_thickness 0.25)
		(keepout
			(tracks not_allowed)
			(vias allowed)
			(pads allowed)
			(copperpour not_allowed)
			(footprints allowed)
		)
		(placement
			(enabled no)
			(sheetname "")
		)
		(fill yes
			(thermal_gap 0.5)
			(thermal_bridge_width 0.5)
			(island_removal_mode 0)
		)
		(polygon
			(pts
				(arc
					(start 238.78159 -129.499868)
					(mid 238.434653 -128.8776)
					(end 237.722918 -128.845564)
				)
				(arc
					(start 235.733844 -129.840228)
					(mid 235.393447 -130.821258)
					(end 236.377226 -131.15417)
				)
				(xy 237.680754 -130.502406)
				(arc
					(start 236.596174 -130.502406)
					(mid 236.050074 -131.045972)
					(end 235.503974 -130.502406)
				)
				(arc
					(start 235.503974 -130.499866)
					(mid 236.050074 -129.953766)
					(end 236.596174 -130.499866)
				)
				(xy 237.685834 -130.499866)
				(arc
					(start 238.377222 -130.154172)
					(mid 238.671681 -129.885538)
					(end 238.78159 -129.502408)
				)
				(arc
					(start 238.59617 -129.502408)
					(mid 238.05007 -130.045974)
					(end 237.50397 -129.502408)
				)
				(arc
					(start 237.50397 -129.499868)
					(mid 238.05007 -128.953768)
					(end 238.59617 -129.499868)
				)
			)
		)
	)
	(zone
		(layers "F.Cu" "B.Cu" "In2.Cu" "In4.Cu" "In9.Cu")
		(hatch none 0.5)
		(connect_pads
			(clearance 0)
		)
		(min_thickness 0.25)
		(keepout
			(tracks not_allowed)
			(vias allowed)
			(pads allowed)
			(copperpour not_allowed)
			(footprints allowed)
		)
		(placement
			(enabled no)
			(sheetname "")
		)
		(fill yes
			(thermal_gap 0.5)
			(thermal_bridge_width 0.5)
			(island_removal_mode 0)
		)
		(polygon
			(pts
				(arc
					(start 286.436562 -259.55117)
					(mid 285.885382 -260.10235)
					(end 286.436562 -260.65353)
				)
				(arc
					(start 287.83661 -260.65353)
					(mid 288.225454 -260.49299)
					(end 288.38779 -260.10489)
				)
				(arc
					(start 288.23031 -260.10489)
					(mid 287.83661 -260.496058)
					(end 287.44291 -260.10489)
				)
				(arc
					(start 286.830262 -260.10489)
					(mid 286.436562 -260.496058)
					(end 286.042862 -260.10489)
				)
				(arc
					(start 286.042862 -260.10235)
					(mid 286.436562 -259.70865)
					(end 286.830262 -260.10235)
				)
				(arc
					(start 287.44291 -260.10235)
					(mid 287.83661 -259.70865)
					(end 288.23031 -260.10235)
				)
				(arc
					(start 288.38779 -260.10235)
					(mid 288.226353 -259.712607)
					(end 287.83661 -259.55117)
				)
				(xy 286.436816 -259.55117)
			)
		)
	)
	(zone
		(layers "F.Cu" "B.Cu" "In2.Cu" "In4.Cu" "In9.Cu")
		(hatch none 0.5)
		(connect_pads
			(clearance 0)
		)
		(min_thickness 0.25)
		(keepout
			(tracks not_allowed)
			(vias allowed)
			(pads allowed)
			(copperpour not_allowed)
			(footprints allowed)
		)
		(placement
			(enabled no)
			(sheetname "")
		)
		(fill yes
			(thermal_gap 0.5)
			(thermal_bridge_width 0.5)
			(island_removal_mode 0)
		)
		(polygon
			(pts
				(arc
					(start 285.436564 -294.154098)
					(mid 284.885384 -294.705278)
					(end 285.436564 -295.256458)
				)
				(arc
					(start 286.836612 -295.256458)
					(mid 287.225456 -295.095918)
					(end 287.387792 -294.707818)
				)
				(arc
					(start 287.230312 -294.707818)
					(mid 286.836612 -295.098986)
					(end 286.442912 -294.707818)
				)
				(arc
					(start 285.830264 -294.707818)
					(mid 285.436564 -295.098986)
					(end 285.042864 -294.707818)
				)
				(arc
					(start 285.042864 -294.705278)
					(mid 285.436564 -294.311578)
					(end 285.830264 -294.705278)
				)
				(arc
					(start 286.442912 -294.705278)
					(mid 286.836612 -294.311578)
					(end 287.230312 -294.705278)
				)
				(arc
					(start 287.387792 -294.705278)
					(mid 287.226355 -294.315535)
					(end 286.836612 -294.154098)
				)
				(xy 285.436818 -294.154098)
			)
		)
	)
	(zone
		(layers "F.Cu" "B.Cu" "In2.Cu" "In4.Cu" "In9.Cu")
		(hatch none 0.5)
		(connect_pads
			(clearance 0)
		)
		(min_thickness 0.25)
		(keepout
			(tracks not_allowed)
			(vias allowed)
			(pads allowed)
			(copperpour not_allowed)
			(footprints allowed)
		)
		(placement
			(enabled no)
			(sheetname "")
		)
		(fill yes
			(thermal_gap 0.5)
			(thermal_bridge_width 0.5)
			(island_removal_mode 0)
		)
		(polygon
			(pts
				(arc
					(start 279.236678 -263.151112)
					(mid 278.685498 -263.702292)
					(end 279.236678 -264.253472)
				)
				(arc
					(start 280.636726 -264.253472)
					(mid 281.02557 -264.092932)
					(end 281.187906 -263.704832)
				)
				(arc
					(start 281.030426 -263.704832)
					(mid 280.636726 -264.096)
					(end 280.243026 -263.704832)
				)
				(arc
					(start 279.630378 -263.704832)
					(mid 279.236678 -264.096)
					(end 278.842978 -263.704832)
				)
				(arc
					(start 278.842978 -263.702292)
					(mid 279.236678 -263.308592)
					(end 279.630378 -263.702292)
				)
				(arc
					(start 280.243026 -263.702292)
					(mid 280.636726 -263.308592)
					(end 281.030426 -263.702292)
				)
				(arc
					(start 281.187906 -263.702292)
					(mid 281.026469 -263.312549)
					(end 280.636726 -263.151112)
				)
				(xy 279.236932 -263.151112)
			)
		)
	)
	(zone
		(layers "F.Cu" "B.Cu" "In2.Cu" "In4.Cu" "In9.Cu")
		(hatch none 0.5)
		(connect_pads
			(clearance 0)
		)
		(min_thickness 0.25)
		(keepout
			(tracks not_allowed)
			(vias allowed)
			(pads allowed)
			(copperpour not_allowed)
			(footprints allowed)
		)
		(placement
			(enabled no)
			(sheetname "")
		)
		(fill yes
			(thermal_gap 0.5)
			(thermal_bridge_width 0.5)
			(island_removal_mode 0)
		)
		(polygon
			(pts
				(arc
					(start 279.236678 -259.55117)
					(mid 278.685498 -260.10235)
					(end 279.236678 -260.65353)
				)
				(arc
					(start 280.636726 -260.65353)
					(mid 281.02557 -260.49299)
					(end 281.187906 -260.10489)
				)
				(arc
					(start 281.030426 -260.10489)
					(mid 280.636726 -260.496058)
					(end 280.243026 -260.10489)
				)
				(arc
					(start 279.630378 -260.10489)
					(mid 279.236678 -260.496058)
					(end 278.842978 -260.10489)
				)
				(arc
					(start 278.842978 -260.10235)
					(mid 279.236678 -259.70865)
					(end 279.630378 -260.10235)
				)
				(arc
					(start 280.243026 -260.10235)
					(mid 280.636726 -259.70865)
					(end 281.030426 -260.10235)
				)
				(arc
					(start 281.187906 -260.10235)
					(mid 281.026469 -259.712607)
					(end 280.636726 -259.55117)
				)
				(xy 279.236932 -259.55117)
			)
		)
	)
	(zone
		(layers "F.Cu" "B.Cu" "In2.Cu" "In4.Cu" "In9.Cu")
		(hatch none 0.5)
		(connect_pads
			(clearance 0)
		)
		(min_thickness 0.25)
		(keepout
			(tracks not_allowed)
			(vias allowed)
			(pads allowed)
			(copperpour not_allowed)
			(footprints allowed)
		)
		(placement
			(enabled no)
			(sheetname "")
		)
		(fill yes
			(thermal_gap 0.5)
			(thermal_bridge_width 0.5)
			(island_removal_mode 0)
		)
		(polygon
			(pts
				(arc
					(start 240.87709 -158.845504)
					(mid 239.895634 -159.172656)
					(end 240.222786 -160.154112)
				)
				(arc
					(start 242.222528 -161.15411)
					(mid 242.933406 -161.122909)
					(end 243.281454 -160.502346)
				)
				(arc
					(start 243.096034 -160.502346)
					(mid 242.549934 -161.045912)
					(end 242.003834 -160.502346)
				)
				(arc
					(start 242.003834 -160.499806)
					(mid 242.549934 -159.953706)
					(end 243.096034 -160.499806)
				)
				(arc
					(start 243.281454 -160.499806)
					(mid 243.172202 -160.115223)
					(end 242.877086 -159.845502)
				)
				(xy 242.190778 -159.502348)
				(arc
					(start 241.096038 -159.502348)
					(mid 240.549938 -160.045914)
					(end 240.003838 -159.502348)
				)
				(arc
					(start 240.003838 -159.499808)
					(mid 240.549938 -158.953708)
					(end 241.096038 -159.499808)
				)
				(xy 242.185698 -159.499808)
			)
		)
	)
	(zone
		(layers "F.Cu" "B.Cu" "In2.Cu" "In4.Cu" "In9.Cu")
		(hatch none 0.5)
		(connect_pads
			(clearance 0)
		)
		(min_thickness 0.25)
		(keepout
			(tracks not_allowed)
			(vias allowed)
			(pads allowed)
			(copperpour not_allowed)
			(footprints allowed)
		)
		(placement
			(enabled no)
			(sheetname "")
		)
		(fill yes
			(thermal_gap 0.5)
			(thermal_bridge_width 0.5)
			(island_removal_mode 0)
		)
		(polygon
			(pts
				(arc
					(start 238.78159 -161.499804)
					(mid 238.434653 -160.877536)
					(end 237.722918 -160.8455)
				)
				(arc
					(start 235.733844 -161.840164)
					(mid 235.393447 -162.821194)
					(end 236.377226 -163.154106)
				)
				(xy 237.680754 -162.502342)
				(arc
					(start 236.596174 -162.502342)
					(mid 236.050074 -163.045908)
					(end 235.503974 -162.502342)
				)
				(arc
					(start 235.503974 -162.499802)
					(mid 236.050074 -161.953702)
					(end 236.596174 -162.499802)
				)
				(xy 237.685834 -162.499802)
				(arc
					(start 238.377222 -162.154108)
					(mid 238.671681 -161.885474)
					(end 238.78159 -161.502344)
				)
				(arc
					(start 238.59617 -161.502344)
					(mid 238.05007 -162.04591)
					(end 237.50397 -161.502344)
				)
				(arc
					(start 237.50397 -161.499804)
					(mid 238.05007 -160.953704)
					(end 238.59617 -161.499804)
				)
			)
		)
	)
	(zone
		(layers "F.Cu" "B.Cu" "In2.Cu" "In4.Cu" "In9.Cu")
		(hatch none 0.5)
		(connect_pads
			(clearance 0)
		)
		(min_thickness 0.25)
		(keepout
			(tracks not_allowed)
			(vias allowed)
			(pads allowed)
			(copperpour not_allowed)
			(footprints allowed)
		)
		(placement
			(enabled no)
			(sheetname "")
		)
		(fill yes
			(thermal_gap 0.5)
			(thermal_bridge_width 0.5)
			(island_removal_mode 0)
		)
		(polygon
			(pts
				(arc
					(start 240.891822 -126.844552)
					(mid 239.891674 -127.163691)
					(end 240.219484 -128.161034)
				)
				(arc
					(start 242.21948 -129.161032)
					(mid 242.937493 -129.129261)
					(end 243.289074 -128.50241)
				)
				(arc
					(start 243.096034 -128.50241)
					(mid 242.549934 -129.045976)
					(end 242.003834 -128.50241)
				)
				(arc
					(start 242.003834 -128.49987)
					(mid 242.549934 -127.95377)
					(end 243.096034 -128.49987)
				)
				(arc
					(start 243.289074 -128.49987)
					(mid 243.178654 -128.111233)
					(end 242.880388 -127.838708)
				)
				(xy 242.207796 -127.502412)
				(arc
					(start 241.096038 -127.502412)
					(mid 240.549938 -128.045978)
					(end 240.003838 -127.502412)
				)
				(arc
					(start 240.003838 -127.499872)
					(mid 240.549938 -126.953772)
					(end 241.096038 -127.499872)
				)
				(xy 242.202716 -127.499872)
			)
		)
	)
	(zone
		(layers "F.Cu" "B.Cu" "In2.Cu" "In4.Cu" "In9.Cu")
		(hatch none 0.5)
		(connect_pads
			(clearance 0)
		)
		(min_thickness 0.25)
		(keepout
			(tracks not_allowed)
			(vias allowed)
			(pads allowed)
			(copperpour not_allowed)
			(footprints allowed)
		)
		(placement
			(enabled no)
			(sheetname "")
		)
		(fill yes
			(thermal_gap 0.5)
			(thermal_bridge_width 0.5)
			(island_removal_mode 0)
		)
		(polygon
			(pts
				(arc
					(start 286.436562 -331.95387)
					(mid 285.885382 -332.50505)
					(end 286.436562 -333.05623)
				)
				(arc
					(start 287.83661 -333.05623)
					(mid 288.225454 -332.89569)
					(end 288.38779 -332.50759)
				)
				(arc
					(start 288.23031 -332.50759)
					(mid 287.83661 -332.898758)
					(end 287.44291 -332.50759)
				)
				(arc
					(start 286.830262 -332.50759)
					(mid 286.436562 -332.898758)
					(end 286.042862 -332.50759)
				)
				(arc
					(start 286.042862 -332.50505)
					(mid 286.436562 -332.11135)
					(end 286.830262 -332.50505)
				)
				(arc
					(start 287.44291 -332.50505)
					(mid 287.83661 -332.11135)
					(end 288.23031 -332.50505)
				)
				(arc
					(start 288.38779 -332.50505)
					(mid 288.226353 -332.115307)
					(end 287.83661 -331.95387)
				)
				(xy 286.436816 -331.95387)
			)
		)
	)
	(zone
		(layers "F.Cu" "B.Cu" "In2.Cu" "In4.Cu" "In9.Cu")
		(hatch none 0.5)
		(connect_pads
			(clearance 0)
		)
		(min_thickness 0.25)
		(keepout
			(tracks not_allowed)
			(vias allowed)
			(pads allowed)
			(copperpour not_allowed)
			(footprints allowed)
		)
		(placement
			(enabled no)
			(sheetname "")
		)
		(fill yes
			(thermal_gap 0.5)
			(thermal_bridge_width 0.5)
			(island_removal_mode 0)
		)
		(polygon
			(pts
				(arc
					(start 286.436562 -328.353928)
					(mid 285.885382 -328.905108)
					(end 286.436562 -329.456288)
				)
				(arc
					(start 287.83661 -329.456288)
					(mid 288.225454 -329.295748)
					(end 288.38779 -328.907648)
				)
				(arc
					(start 288.23031 -328.907648)
					(mid 287.83661 -329.298816)
					(end 287.44291 -328.907648)
				)
				(arc
					(start 286.830262 -328.907648)
					(mid 286.436562 -329.298816)
					(end 286.042862 -328.907648)
				)
				(arc
					(start 286.042862 -328.905108)
					(mid 286.436562 -328.511408)
					(end 286.830262 -328.905108)
				)
				(arc
					(start 287.44291 -328.905108)
					(mid 287.83661 -328.511408)
					(end 288.23031 -328.905108)
				)
				(arc
					(start 288.38779 -328.905108)
					(mid 288.226353 -328.515365)
					(end 287.83661 -328.353928)
				)
				(xy 286.436816 -328.353928)
			)
		)
	)
	(zone
		(layers "F.Cu" "B.Cu" "In2.Cu" "In4.Cu" "In9.Cu")
		(hatch none 0.5)
		(connect_pads
			(clearance 0)
		)
		(min_thickness 0.25)
		(keepout
			(tracks not_allowed)
			(vias allowed)
			(pads allowed)
			(copperpour not_allowed)
			(footprints allowed)
		)
		(placement
			(enabled no)
			(sheetname "")
		)
		(fill yes
			(thermal_gap 0.5)
			(thermal_bridge_width 0.5)
			(island_removal_mode 0)
		)
		(polygon
			(pts
				(arc
					(start 285.436564 -348.15399)
					(mid 284.885384 -348.70517)
					(end 285.436564 -349.25635)
				)
				(arc
					(start 286.836612 -349.25635)
					(mid 287.225456 -349.09581)
					(end 287.387792 -348.70771)
				)
				(arc
					(start 287.230312 -348.70771)
					(mid 286.836612 -349.098878)
					(end 286.442912 -348.70771)
				)
				(arc
					(start 285.830264 -348.70771)
					(mid 285.436564 -349.098878)
					(end 285.042864 -348.70771)
				)
				(arc
					(start 285.042864 -348.70517)
					(mid 285.436564 -348.31147)
					(end 285.830264 -348.70517)
				)
				(arc
					(start 286.442912 -348.70517)
					(mid 286.836612 -348.31147)
					(end 287.230312 -348.70517)
				)
				(arc
					(start 287.387792 -348.70517)
					(mid 287.226355 -348.315427)
					(end 286.836612 -348.15399)
				)
				(xy 285.436818 -348.15399)
			)
		)
	)
	(zone
		(layers "F.Cu" "B.Cu" "In2.Cu" "In4.Cu" "In9.Cu")
		(hatch none 0.5)
		(connect_pads
			(clearance 0)
		)
		(min_thickness 0.25)
		(keepout
			(tracks not_allowed)
			(vias allowed)
			(pads allowed)
			(copperpour not_allowed)
			(footprints allowed)
		)
		(placement
			(enabled no)
			(sheetname "")
		)
		(fill yes
			(thermal_gap 0.5)
			(thermal_bridge_width 0.5)
			(island_removal_mode 0)
		)
		(polygon
			(pts
				(arc
					(start 286.436562 -252.351032)
					(mid 285.885382 -252.902212)
					(end 286.436562 -253.453392)
				)
				(arc
					(start 287.83661 -253.453392)
					(mid 288.225454 -253.292852)
					(end 288.38779 -252.904752)
				)
				(arc
					(start 288.23031 -252.904752)
					(mid 287.83661 -253.29592)
					(end 287.44291 -252.904752)
				)
				(arc
					(start 286.830262 -252.904752)
					(mid 286.436562 -253.29592)
					(end 286.042862 -252.904752)
				)
				(arc
					(start 286.042862 -252.902212)
					(mid 286.436562 -252.508512)
					(end 286.830262 -252.902212)
				)
				(arc
					(start 287.44291 -252.902212)
					(mid 287.83661 -252.508512)
					(end 288.23031 -252.902212)
				)
				(arc
					(start 288.38779 -252.902212)
					(mid 288.226353 -252.512469)
					(end 287.83661 -252.351032)
				)
				(xy 286.436816 -252.351032)
			)
		)
	)
	(zone
		(layers "F.Cu" "B.Cu" "In2.Cu" "In4.Cu" "In9.Cu")
		(hatch none 0.5)
		(connect_pads
			(clearance 0)
		)
		(min_thickness 0.25)
		(keepout
			(tracks not_allowed)
			(vias allowed)
			(pads allowed)
			(copperpour not_allowed)
			(footprints allowed)
		)
		(placement
			(enabled no)
			(sheetname "")
		)
		(fill yes
			(thermal_gap 0.5)
			(thermal_bridge_width 0.5)
			(island_removal_mode 0)
		)
		(polygon
			(pts
				(arc
					(start 240.877344 -162.845496)
					(mid 239.895939 -163.172546)
					(end 240.222786 -164.154104)
				)
				(arc
					(start 242.222782 -165.154102)
					(mid 242.933443 -165.122745)
					(end 243.281454 -164.502338)
				)
				(arc
					(start 243.096034 -164.502338)
					(mid 242.549934 -165.045904)
					(end 242.003834 -164.502338)
				)
				(arc
					(start 242.003834 -164.499798)
					(mid 242.549934 -163.953698)
					(end 243.096034 -164.499798)
				)
				(arc
					(start 243.281454 -164.499798)
					(mid 243.172202 -164.115215)
					(end 242.877086 -163.845494)
				)
				(xy 242.190778 -163.50234)
				(arc
					(start 241.096038 -163.50234)
					(mid 240.549938 -164.045906)
					(end 240.003838 -163.50234)
				)
				(arc
					(start 240.003838 -163.4998)
					(mid 240.549938 -162.9537)
					(end 241.096038 -163.4998)
				)
				(xy 242.185698 -163.4998)
			)
		)
	)
	(zone
		(layers "F.Cu" "B.Cu" "In2.Cu" "In4.Cu" "In9.Cu")
		(hatch none 0.5)
		(connect_pads
			(clearance 0)
		)
		(min_thickness 0.25)
		(keepout
			(tracks not_allowed)
			(vias allowed)
			(pads allowed)
			(copperpour not_allowed)
			(footprints allowed)
		)
		(placement
			(enabled no)
			(sheetname "")
		)
		(fill yes
			(thermal_gap 0.5)
			(thermal_bridge_width 0.5)
			(island_removal_mode 0)
		)
		(polygon
			(pts
				(arc
					(start 238.78159 -125.499876)
					(mid 238.434653 -124.877608)
					(end 237.722918 -124.845572)
				)
				(arc
					(start 235.733844 -125.840236)
					(mid 235.393447 -126.821266)
					(end 236.377226 -127.154178)
				)
				(xy 237.680754 -126.502414)
				(arc
					(start 236.596174 -126.502414)
					(mid 236.050074 -127.04598)
					(end 235.503974 -126.502414)
				)
				(arc
					(start 235.503974 -126.499874)
					(mid 236.050074 -125.953774)
					(end 236.596174 -126.499874)
				)
				(xy 237.685834 -126.499874)
				(arc
					(start 238.377222 -126.15418)
					(mid 238.671681 -125.885546)
					(end 238.78159 -125.502416)
				)
				(arc
					(start 238.59617 -125.502416)
					(mid 238.05007 -126.045982)
					(end 237.50397 -125.502416)
				)
				(arc
					(start 237.50397 -125.499876)
					(mid 238.05007 -124.953776)
					(end 238.59617 -125.499876)
				)
			)
		)
	)
	(zone
		(layers "F.Cu" "B.Cu" "In2.Cu" "In4.Cu" "In9.Cu")
		(hatch none 0.5)
		(connect_pads
			(clearance 0)
		)
		(min_thickness 0.25)
		(keepout
			(tracks not_allowed)
			(vias allowed)
			(pads allowed)
			(copperpour not_allowed)
			(footprints allowed)
		)
		(placement
			(enabled no)
			(sheetname "")
		)
		(fill yes
			(thermal_gap 0.5)
			(thermal_bridge_width 0.5)
			(island_removal_mode 0)
		)
		(polygon
			(pts
				(arc
					(start 278.23668 -254.15113)
					(mid 277.6855 -254.70231)
					(end 278.23668 -255.25349)
				)
				(arc
					(start 279.636728 -255.25349)
					(mid 280.025572 -255.09295)
					(end 280.187908 -254.70485)
				)
				(arc
					(start 280.030428 -254.70485)
					(mid 279.636728 -255.096018)
					(end 279.243028 -254.70485)
				)
				(arc
					(start 278.63038 -254.70485)
					(mid 278.23668 -255.096018)
					(end 277.84298 -254.70485)
				)
				(arc
					(start 277.84298 -254.70231)
					(mid 278.23668 -254.30861)
					(end 278.63038 -254.70231)
				)
				(arc
					(start 279.243028 -254.70231)
					(mid 279.636728 -254.30861)
					(end 280.030428 -254.70231)
				)
				(arc
					(start 280.187908 -254.70231)
					(mid 280.026471 -254.312567)
					(end 279.636728 -254.15113)
				)
				(xy 278.236934 -254.15113)
			)
		)
	)
	(zone
		(layers "F.Cu" "B.Cu" "In2.Cu" "In4.Cu" "In9.Cu")
		(hatch none 0.5)
		(connect_pads
			(clearance 0)
		)
		(min_thickness 0.25)
		(keepout
			(tracks not_allowed)
			(vias allowed)
			(pads allowed)
			(copperpour not_allowed)
			(footprints allowed)
		)
		(placement
			(enabled no)
			(sheetname "")
		)
		(fill yes
			(thermal_gap 0.5)
			(thermal_bridge_width 0.5)
			(island_removal_mode 0)
		)
		(polygon
			(pts
				(arc
					(start 307.708046 -243.200428)
					(mid 300.20006 -235.692442)
					(end 292.692074 -243.200428)
				)
				(arc
					(start 292.692074 -249.200416)
					(mid 300.20006 -256.708402)
					(end 307.708046 -249.200416)
				)
			)
		)
	)
	(zone
		(layers "F.Cu" "B.Cu" "In2.Cu" "In4.Cu" "In9.Cu")
		(hatch none 0.5)
		(connect_pads
			(clearance 0)
		)
		(min_thickness 0.25)
		(keepout
			(tracks not_allowed)
			(vias allowed)
			(pads allowed)
			(copperpour not_allowed)
			(footprints allowed)
		)
		(placement
			(enabled no)
			(sheetname "")
		)
		(fill yes
			(thermal_gap 0.5)
			(thermal_bridge_width 0.5)
			(island_removal_mode 0)
		)
		(polygon
			(pts
				(arc
					(start 285.436564 -261.351014)
					(mid 284.885384 -261.902194)
					(end 285.436564 -262.453374)
				)
				(arc
					(start 286.836612 -262.453374)
					(mid 287.225456 -262.292834)
					(end 287.387792 -261.904734)
				)
				(arc
					(start 287.230312 -261.904734)
					(mid 286.836612 -262.295902)
					(end 286.442912 -261.904734)
				)
				(arc
					(start 285.830264 -261.904734)
					(mid 285.436564 -262.295902)
					(end 285.042864 -261.904734)
				)
				(arc
					(start 285.042864 -261.902194)
					(mid 285.436564 -261.508494)
					(end 285.830264 -261.902194)
				)
				(arc
					(start 286.442912 -261.902194)
					(mid 286.836612 -261.508494)
					(end 287.230312 -261.902194)
				)
				(arc
					(start 287.387792 -261.902194)
					(mid 287.226355 -261.512451)
					(end 286.836612 -261.351014)
				)
				(xy 285.436818 -261.351014)
			)
		)
	)
	(zone
		(layers "F.Cu" "B.Cu" "In4.Cu" "In7.Cu")
		(hatch none 0.5)
		(connect_pads
			(clearance 0)
		)
		(min_thickness 0.25)
		(keepout
			(tracks not_allowed)
			(vias allowed)
			(pads allowed)
			(copperpour not_allowed)
			(footprints allowed)
		)
		(placement
			(enabled no)
			(sheetname "")
		)
		(fill yes
			(thermal_gap 0.5)
			(thermal_bridge_width 0.5)
			(island_removal_mode 0)
		)
		(polygon
			(pts
				(arc
					(start 237.072932 -279.200102)
					(mid 244.199918 -286.327088)
					(end 251.326904 -279.200102)
				)
				(arc
					(start 251.326904 -273.19986)
					(mid 244.199918 -266.073128)
					(end 237.072932 -273.19986)
				)
			)
		)
	)
	(zone
		(layers "F.Cu" "B.Cu" "In4.Cu" "In7.Cu")
		(hatch none 0.5)
		(connect_pads
			(clearance 0)
		)
		(min_thickness 0.25)
		(keepout
			(tracks not_allowed)
			(vias allowed)
			(pads allowed)
			(copperpour not_allowed)
			(footprints allowed)
		)
		(placement
			(enabled no)
			(sheetname "")
		)
		(fill yes
			(thermal_gap 0.5)
			(thermal_bridge_width 0.5)
			(island_removal_mode 0)
		)
		(polygon
			(pts
				(arc
					(start 400.802094 -207.79994)
					(mid 393.675108 -200.672954)
					(end 386.548122 -207.79994)
				)
				(arc
					(start 386.548122 -213.800182)
					(mid 393.675108 -220.926914)
					(end 400.802094 -213.800182)
				)
			)
		)
	)
	(zone
		(layers "F.Cu" "B.Cu" "In4.Cu" "In7.Cu")
		(hatch none 0.5)
		(connect_pads
			(clearance 0)
		)
		(min_thickness 0.25)
		(keepout
			(tracks not_allowed)
			(vias allowed)
			(pads allowed)
			(copperpour not_allowed)
			(footprints allowed)
		)
		(placement
			(enabled no)
			(sheetname "")
		)
		(fill yes
			(thermal_gap 0.5)
			(thermal_bridge_width 0.5)
			(island_removal_mode 0)
		)
		(polygon
			(pts
				(arc
					(start 166.452042 -207.79994)
					(mid 159.325056 -200.672954)
					(end 152.19807 -207.79994)
				)
				(arc
					(start 152.19807 -213.800182)
					(mid 159.325056 -220.926914)
					(end 166.452042 -213.800182)
				)
			)
		)
	)
	(zone
		(layers "F.Cu" "B.Cu" "In4.Cu" "In7.Cu")
		(hatch none 0.5)
		(connect_pads
			(clearance 0)
		)
		(min_thickness 0.25)
		(keepout
			(tracks not_allowed)
			(vias allowed)
			(pads allowed)
			(copperpour not_allowed)
			(footprints allowed)
		)
		(placement
			(enabled no)
			(sheetname "")
		)
		(fill yes
			(thermal_gap 0.5)
			(thermal_bridge_width 0.5)
			(island_removal_mode 0)
		)
		(polygon
			(pts
				(arc
					(start 337.801966 -322.799964)
					(mid 330.67498 -315.672978)
					(end 323.547994 -322.799964)
				)
				(arc
					(start 323.547994 -328.799952)
					(mid 330.67498 -335.926938)
					(end 337.801966 -328.799952)
				)
			)
		)
	)
	(zone
		(layers "F.Cu" "B.Cu" "In4.Cu" "In7.Cu")
		(hatch none 0.5)
		(connect_pads
			(clearance 0)
		)
		(min_thickness 0.25)
		(keepout
			(tracks not_allowed)
			(vias allowed)
			(pads allowed)
			(copperpour not_allowed)
			(footprints allowed)
		)
		(placement
			(enabled no)
			(sheetname "")
		)
		(fill yes
			(thermal_gap 0.5)
			(thermal_bridge_width 0.5)
			(island_removal_mode 0)
		)
		(polygon
			(pts
				(arc
					(start 40.45204 -322.799964)
					(mid 33.325054 -315.672978)
					(end 26.198068 -322.799964)
				)
				(arc
					(start 26.198068 -328.799952)
					(mid 33.325054 -335.926938)
					(end 40.45204 -328.799952)
				)
			)
		)
	)
	(zone
		(layers "F.Cu" "B.Cu" "In4.Cu" "In7.Cu")
		(hatch none 0.5)
		(connect_pads
			(clearance 0)
		)
		(min_thickness 0.25)
		(keepout
			(tracks not_allowed)
			(vias allowed)
			(pads allowed)
			(copperpour not_allowed)
			(footprints allowed)
		)
		(placement
			(enabled no)
			(sheetname "")
		)
		(fill yes
			(thermal_gap 0.5)
			(thermal_bridge_width 0.5)
			(island_removal_mode 0)
		)
		(polygon
			(pts
				(arc
					(start 400.802094 -92.799916)
					(mid 393.675108 -85.67293)
					(end 386.548122 -92.799916)
				)
				(arc
					(start 386.548122 -98.800158)
					(mid 393.675108 -105.92689)
					(end 400.802094 -98.800158)
				)
			)
		)
	)
	(zone
		(layers "F.Cu" "B.Cu" "In4.Cu" "In7.Cu")
		(hatch none 0.5)
		(connect_pads
			(clearance 0)
		)
		(min_thickness 0.25)
		(keepout
			(tracks not_allowed)
			(vias allowed)
			(pads allowed)
			(copperpour not_allowed)
			(footprints allowed)
		)
		(placement
			(enabled no)
			(sheetname "")
		)
		(fill yes
			(thermal_gap 0.5)
			(thermal_bridge_width 0.5)
			(island_removal_mode 0)
		)
		(polygon
			(pts
				(arc
					(start 166.452042 -322.799964)
					(mid 159.325056 -315.672978)
					(end 152.19807 -322.799964)
				)
				(arc
					(start 152.19807 -328.799952)
					(mid 159.325056 -335.926938)
					(end 166.452042 -328.799952)
				)
			)
		)
	)
	(zone
		(layers "F.Cu" "B.Cu" "In4.Cu" "In7.Cu")
		(hatch none 0.5)
		(connect_pads
			(clearance 0)
		)
		(min_thickness 0.25)
		(keepout
			(tracks not_allowed)
			(vias allowed)
			(pads allowed)
			(copperpour not_allowed)
			(footprints allowed)
		)
		(placement
			(enabled no)
			(sheetname "")
		)
		(fill yes
			(thermal_gap 0.5)
			(thermal_bridge_width 0.5)
			(island_removal_mode 0)
		)
		(polygon
			(pts
				(arc
					(start 195.173092 -69.799962)
					(mid 202.300078 -76.926948)
					(end 209.427064 -69.799962)
				)
				(arc
					(start 209.427064 -63.799974)
					(mid 202.300078 -56.672988)
					(end 195.173092 -63.799974)
				)
			)
		)
	)
	(zone
		(layers "F.Cu" "B.Cu" "In4.Cu" "In7.Cu")
		(hatch none 0.5)
		(connect_pads
			(clearance 0)
		)
		(min_thickness 0.25)
		(keepout
			(tracks not_allowed)
			(vias allowed)
			(pads allowed)
			(copperpour not_allowed)
			(footprints allowed)
		)
		(placement
			(enabled no)
			(sheetname "")
		)
		(fill yes
			(thermal_gap 0.5)
			(thermal_bridge_width 0.5)
			(island_removal_mode 0)
		)
		(polygon
			(pts
				(arc
					(start 463.801968 -322.799964)
					(mid 456.674982 -315.672978)
					(end 449.547996 -322.799964)
				)
				(arc
					(start 449.547996 -328.799952)
					(mid 456.674982 -335.926938)
					(end 463.801968 -328.799952)
				)
			)
		)
	)
	(zone
		(layers "F.Cu" "B.Cu" "In4.Cu" "In7.Cu")
		(hatch none 0.5)
		(connect_pads
			(clearance 0)
		)
		(min_thickness 0.25)
		(keepout
			(tracks not_allowed)
			(vias allowed)
			(pads allowed)
			(copperpour not_allowed)
			(footprints allowed)
		)
		(placement
			(enabled no)
			(sheetname "")
		)
		(fill yes
			(thermal_gap 0.5)
			(thermal_bridge_width 0.5)
			(island_removal_mode 0)
		)
		(polygon
			(pts
				(arc
					(start 400.802094 -322.799964)
					(mid 393.675108 -315.672978)
					(end 386.548122 -322.799964)
				)
				(arc
					(start 386.548122 -328.799952)
					(mid 393.675108 -335.926938)
					(end 400.802094 -328.799952)
				)
			)
		)
	)
	(zone
		(layers "F.Cu" "B.Cu" "In4.Cu" "In7.Cu")
		(hatch none 0.5)
		(connect_pads
			(clearance 0)
		)
		(min_thickness 0.25)
		(keepout
			(tracks not_allowed)
			(vias allowed)
			(pads allowed)
			(copperpour not_allowed)
			(footprints allowed)
		)
		(placement
			(enabled no)
			(sheetname "")
		)
		(fill yes
			(thermal_gap 0.5)
			(thermal_bridge_width 0.5)
			(island_removal_mode 0)
		)
		(polygon
			(pts
				(arc
					(start 293.073074 -144.200118)
					(mid 300.20006 -151.327104)
					(end 307.327046 -144.200118)
				)
				(arc
					(start 307.327046 -138.199876)
					(mid 300.20006 -131.07289)
					(end 293.073074 -138.199876)
				)
			)
		)
	)
	(zone
		(layers "F.Cu" "B.Cu" "In4.Cu" "In7.Cu")
		(hatch none 0.5)
		(connect_pads
			(clearance 0)
		)
		(min_thickness 0.25)
		(keepout
			(tracks not_allowed)
			(vias allowed)
			(pads allowed)
			(copperpour not_allowed)
			(footprints allowed)
		)
		(placement
			(enabled no)
			(sheetname "")
		)
		(fill yes
			(thermal_gap 0.5)
			(thermal_bridge_width 0.5)
			(island_removal_mode 0)
		)
		(polygon
			(pts
				(arc
					(start 307.327046 -243.19992)
					(mid 300.20006 -236.072934)
					(end 293.073074 -243.19992)
				)
				(arc
					(start 293.073074 -249.200162)
					(mid 300.20006 -256.326894)
					(end 307.327046 -249.200162)
				)
			)
		)
	)
	(zone
		(layers "F.Cu" "B.Cu" "In4.Cu" "In7.Cu")
		(hatch none 0.5)
		(connect_pads
			(clearance 0)
		)
		(min_thickness 0.25)
		(keepout
			(tracks not_allowed)
			(vias allowed)
			(pads allowed)
			(copperpour not_allowed)
			(footprints allowed)
		)
		(placement
			(enabled no)
			(sheetname "")
		)
		(fill yes
			(thermal_gap 0.5)
			(thermal_bridge_width 0.5)
			(island_removal_mode 0)
		)
		(polygon
			(pts
				(arc
					(start 48.876966 -269.999968)
					(mid 44.000166 -265.123168)
					(end 39.123112 -269.999968)
				)
				(arc
					(start 39.123112 -269.999968)
					(mid 44.000166 -274.877022)
					(end 48.876966 -269.999968)
				)
			)
		)
	)
	(zone
		(layers "F.Cu" "B.Cu" "In4.Cu" "In7.Cu")
		(hatch none 0.5)
		(connect_pads
			(clearance 0)
		)
		(min_thickness 0.25)
		(keepout
			(tracks not_allowed)
			(vias allowed)
			(pads allowed)
			(copperpour not_allowed)
			(footprints allowed)
		)
		(placement
			(enabled no)
			(sheetname "")
		)
		(fill yes
			(thermal_gap 0.5)
			(thermal_bridge_width 0.5)
			(island_removal_mode 0)
		)
		(polygon
			(pts
				(arc
					(start 103.451914 -207.79994)
					(mid 96.324928 -200.672954)
					(end 89.197942 -207.79994)
				)
				(arc
					(start 89.197942 -213.800182)
					(mid 96.324928 -220.926914)
					(end 103.451914 -213.800182)
				)
			)
		)
	)
	(zone
		(layers "F.Cu" "B.Cu" "In4.Cu" "In7.Cu")
		(hatch none 0.5)
		(connect_pads
			(clearance 0)
		)
		(min_thickness 0.25)
		(keepout
			(tracks not_allowed)
			(vias allowed)
			(pads allowed)
			(copperpour not_allowed)
			(footprints allowed)
		)
		(placement
			(enabled no)
			(sheetname "")
		)
		(fill yes
			(thermal_gap 0.5)
			(thermal_bridge_width 0.5)
			(island_removal_mode 0)
		)
		(polygon
			(pts
				(arc
					(start 111.976916 -289.999928)
					(mid 102.223316 -289.999928)
					(end 111.976916 -289.999928)
				)
			)
		)
	)
	(zone
		(layers "F.Cu" "B.Cu" "In4.Cu" "In7.Cu")
		(hatch none 0.5)
		(connect_pads
			(clearance 0)
		)
		(min_thickness 0.25)
		(keepout
			(tracks not_allowed)
			(vias allowed)
			(pads allowed)
			(copperpour not_allowed)
			(footprints allowed)
		)
		(placement
			(enabled no)
			(sheetname "")
		)
		(fill yes
			(thermal_gap 0.5)
			(thermal_bridge_width 0.5)
			(island_removal_mode 0)
		)
		(polygon
			(pts
				(arc
					(start 103.451914 -322.799964)
					(mid 96.324928 -315.672978)
					(end 89.197942 -322.799964)
				)
				(arc
					(start 89.197942 -328.799952)
					(mid 96.324928 -335.926938)
					(end 103.451914 -328.799952)
				)
			)
		)
	)
	(zone
		(layers "F.Cu" "B.Cu" "In4.Cu" "In7.Cu")
		(hatch none 0.5)
		(connect_pads
			(clearance 0)
		)
		(min_thickness 0.25)
		(keepout
			(tracks not_allowed)
			(vias allowed)
			(pads allowed)
			(copperpour not_allowed)
			(footprints allowed)
		)
		(placement
			(enabled no)
			(sheetname "")
		)
		(fill yes
			(thermal_gap 0.5)
			(thermal_bridge_width 0.5)
			(island_removal_mode 0)
		)
		(polygon
			(pts
				(arc
					(start 337.801966 -207.79994)
					(mid 330.67498 -200.672954)
					(end 323.547994 -207.79994)
				)
				(arc
					(start 323.547994 -213.800182)
					(mid 330.67498 -220.926914)
					(end 337.801966 -213.800182)
				)
			)
		)
	)
	(zone
		(layers "F.Cu" "B.Cu" "In4.Cu" "In7.Cu")
		(hatch none 0.5)
		(connect_pads
			(clearance 0)
		)
		(min_thickness 0.25)
		(keepout
			(tracks not_allowed)
			(vias allowed)
			(pads allowed)
			(copperpour not_allowed)
			(footprints allowed)
		)
		(placement
			(enabled no)
			(sheetname "")
		)
		(fill yes
			(thermal_gap 0.5)
			(thermal_bridge_width 0.5)
			(island_removal_mode 0)
		)
		(polygon
			(pts
				(arc
					(start 463.801968 -92.799916)
					(mid 456.674982 -85.67293)
					(end 449.547996 -92.799916)
				)
				(arc
					(start 449.547996 -98.800158)
					(mid 456.674982 -105.92689)
					(end 463.801968 -98.800158)
				)
			)
		)
	)
	(zone
		(layers "F.Cu" "B.Cu" "In4.Cu" "In7.Cu")
		(hatch none 0.5)
		(connect_pads
			(clearance 0)
		)
		(min_thickness 0.25)
		(keepout
			(tracks not_allowed)
			(vias allowed)
			(pads allowed)
			(copperpour not_allowed)
			(footprints allowed)
		)
		(placement
			(enabled no)
			(sheetname "")
		)
		(fill yes
			(thermal_gap 0.5)
			(thermal_bridge_width 0.5)
			(island_removal_mode 0)
		)
		(polygon
			(pts
				(arc
					(start 337.801966 -92.799916)
					(mid 330.67498 -85.67293)
					(end 323.547994 -92.799916)
				)
				(arc
					(start 323.547994 -98.800158)
					(mid 330.67498 -105.92689)
					(end 337.801966 -98.800158)
				)
			)
		)
	)
	(zone
		(layers "F.Cu" "B.Cu" "In4.Cu" "In7.Cu")
		(hatch none 0.5)
		(connect_pads
			(clearance 0)
		)
		(min_thickness 0.25)
		(keepout
			(tracks not_allowed)
			(vias allowed)
			(pads allowed)
			(copperpour not_allowed)
			(footprints allowed)
		)
		(placement
			(enabled no)
			(sheetname "")
		)
		(fill yes
			(thermal_gap 0.5)
			(thermal_bridge_width 0.5)
			(island_removal_mode 0)
		)
		(polygon
			(pts
				(arc
					(start 166.452042 -92.799916)
					(mid 159.325056 -85.67293)
					(end 152.19807 -92.799916)
				)
				(arc
					(start 152.19807 -98.800158)
					(mid 159.325056 -105.92689)
					(end 166.452042 -98.800158)
				)
			)
		)
	)
	(zone
		(layers "F.Cu" "B.Cu" "In4.Cu" "In7.Cu")
		(hatch none 0.5)
		(connect_pads
			(clearance 0)
		)
		(min_thickness 0.25)
		(keepout
			(tracks not_allowed)
			(vias allowed)
			(pads allowed)
			(copperpour not_allowed)
			(footprints allowed)
		)
		(placement
			(enabled no)
			(sheetname "")
		)
		(fill yes
			(thermal_gap 0.5)
			(thermal_bridge_width 0.5)
			(island_removal_mode 0)
		)
		(polygon
			(pts
				(arc
					(start 103.451914 -92.799916)
					(mid 96.324928 -85.67293)
					(end 89.197942 -92.799916)
				)
				(arc
					(start 89.197942 -98.800158)
					(mid 96.324928 -105.92689)
					(end 103.451914 -98.800158)
				)
			)
		)
	)
	(zone
		(layers "F.Cu" "B.Cu" "In4.Cu" "In7.Cu")
		(hatch none 0.5)
		(connect_pads
			(clearance 0)
		)
		(min_thickness 0.25)
		(keepout
			(tracks not_allowed)
			(vias allowed)
			(pads allowed)
			(copperpour not_allowed)
			(footprints allowed)
		)
		(placement
			(enabled no)
			(sheetname "")
		)
		(fill yes
			(thermal_gap 0.5)
			(thermal_bridge_width 0.5)
			(island_removal_mode 0)
		)
		(polygon
			(pts
				(arc
					(start 195.173092 -189.799468)
					(mid 202.300078 -196.926454)
					(end 209.427064 -189.799468)
				)
				(arc
					(start 209.427064 -183.79948)
					(mid 202.300078 -176.672494)
					(end 195.173092 -183.79948)
				)
			)
		)
	)
	(zone
		(layers "F.Cu" "B.Cu" "In4.Cu" "In7.Cu")
		(hatch none 0.5)
		(connect_pads
			(clearance 0)
		)
		(min_thickness 0.25)
		(keepout
			(tracks not_allowed)
			(vias allowed)
			(pads allowed)
			(copperpour not_allowed)
			(footprints allowed)
		)
		(placement
			(enabled no)
			(sheetname "")
		)
		(fill yes
			(thermal_gap 0.5)
			(thermal_bridge_width 0.5)
			(island_removal_mode 0)
		)
		(polygon
			(pts
				(arc
					(start 40.45204 -92.799916)
					(mid 33.325054 -85.67293)
					(end 26.198068 -92.799916)
				)
				(arc
					(start 26.198068 -98.800158)
					(mid 33.325054 -105.92689)
					(end 40.45204 -98.800158)
				)
			)
		)
	)
	(zone
		(layers "F.Cu" "B.Cu" "In4.Cu" "In7.Cu")
		(hatch none 0.5)
		(connect_pads
			(clearance 0)
		)
		(min_thickness 0.25)
		(keepout
			(tracks not_allowed)
			(vias allowed)
			(pads allowed)
			(copperpour not_allowed)
			(footprints allowed)
		)
		(placement
			(enabled no)
			(sheetname "")
		)
		(fill yes
			(thermal_gap 0.5)
			(thermal_bridge_width 0.5)
			(island_removal_mode 0)
		)
		(polygon
			(pts
				(arc
					(start 293.073074 -399.200116)
					(mid 300.20006 -406.327102)
					(end 307.327046 -399.200116)
				)
				(arc
					(start 307.327046 -393.199874)
					(mid 300.20006 -386.072888)
					(end 293.073074 -393.199874)
				)
			)
		)
	)
	(zone
		(layers "F.Cu" "B.Cu" "In4.Cu" "In7.Cu")
		(hatch none 0.5)
		(connect_pads
			(clearance 0)
		)
		(min_thickness 0.25)
		(keepout
			(tracks not_allowed)
			(vias allowed)
			(pads allowed)
			(copperpour not_allowed)
			(footprints allowed)
		)
		(placement
			(enabled no)
			(sheetname "")
		)
		(fill yes
			(thermal_gap 0.5)
			(thermal_bridge_width 0.5)
			(island_removal_mode 0)
		)
		(polygon
			(pts
				(arc
					(start 40.45204 -207.79994)
					(mid 33.325054 -200.672954)
					(end 26.198068 -207.79994)
				)
				(arc
					(start 26.198068 -213.800182)
					(mid 33.325054 -220.926914)
					(end 40.45204 -213.800182)
				)
			)
		)
	)
	(zone
		(layers "F.Cu" "B.Cu" "In4.Cu" "In7.Cu")
		(hatch none 0.5)
		(connect_pads
			(clearance 0)
		)
		(min_thickness 0.25)
		(keepout
			(tracks not_allowed)
			(vias allowed)
			(pads allowed)
			(copperpour not_allowed)
			(footprints allowed)
		)
		(placement
			(enabled no)
			(sheetname "")
		)
		(fill yes
			(thermal_gap 0.5)
			(thermal_bridge_width 0.5)
			(island_removal_mode 0)
		)
		(polygon
			(pts
				(arc
					(start 463.801968 -207.79994)
					(mid 456.674982 -200.672954)
					(end 449.547996 -207.79994)
				)
				(arc
					(start 449.547996 -213.800182)
					(mid 456.674982 -220.926914)
					(end 463.801968 -213.800182)
				)
			)
		)
	)
	(zone
		(layers "F.Cu" "B.Cu" "In4.Cu" "In7.Cu" "In9.Cu")
		(hatch none 0.5)
		(connect_pads
			(clearance 0)
		)
		(min_thickness 0.25)
		(keepout
			(tracks not_allowed)
			(vias allowed)
			(pads allowed)
			(copperpour not_allowed)
			(footprints allowed)
		)
		(placement
			(enabled no)
			(sheetname "")
		)
		(fill yes
			(thermal_gap 0.5)
			(thermal_bridge_width 0.5)
			(island_removal_mode 0)
		)
		(polygon
			(pts
				(arc
					(start 240.876074 -34.548064)
					(mid 239.89792 -34.873946)
					(end 240.223802 -35.8521)
				)
				(arc
					(start 242.223798 -36.852098)
					(mid 242.932081 -36.820931)
					(end 243.278914 -36.20262)
				)
				(arc
					(start 243.096034 -36.20262)
					(mid 242.549934 -36.746186)
					(end 242.003834 -36.20262)
				)
				(arc
					(start 242.003834 -36.20008)
					(mid 242.549934 -35.65398)
					(end 243.096034 -36.20008)
				)
				(arc
					(start 243.278914 -36.20008)
					(mid 243.170071 -35.816881)
					(end 242.87607 -35.548062)
				)
				(xy 242.18519 -35.202622)
				(arc
					(start 241.096038 -35.202622)
					(mid 240.549938 -35.746188)
					(end 240.003838 -35.202622)
				)
				(arc
					(start 240.003838 -35.200082)
					(mid 240.549938 -34.653982)
					(end 241.096038 -35.200082)
				)
				(xy 242.18011 -35.200082)
			)
		)
	)
	(zone
		(layers "F.Cu" "B.Cu" "In4.Cu" "In7.Cu" "In9.Cu")
		(hatch none 0.5)
		(connect_pads
			(clearance 0)
		)
		(min_thickness 0.25)
		(keepout
			(tracks not_allowed)
			(vias allowed)
			(pads allowed)
			(copperpour not_allowed)
			(footprints allowed)
		)
		(placement
			(enabled no)
			(sheetname "")
		)
		(fill yes
			(thermal_gap 0.5)
			(thermal_bridge_width 0.5)
			(island_removal_mode 0)
		)
		(polygon
			(pts
				(arc
					(start 136.698736 -29.150056)
					(mid 136.150096 -28.601416)
					(end 135.601456 -29.150056)
				)
				(arc
					(start 135.601456 -30.550104)
					(mid 136.148826 -31.098743)
					(end 136.698736 -30.552644)
				)
				(arc
					(start 136.543796 -30.552644)
					(mid 136.150096 -30.943812)
					(end 135.756396 -30.552644)
				)
				(arc
					(start 135.756396 -30.550104)
					(mid 136.150096 -30.156404)
					(end 136.543796 -30.550104)
				)
				(xy 136.698736 -30.550104) (xy 136.698736 -29.152596)
				(arc
					(start 136.543796 -29.152596)
					(mid 136.150096 -29.543764)
					(end 135.756396 -29.152596)
				)
				(arc
					(start 135.756396 -29.150056)
					(mid 136.150096 -28.756356)
					(end 136.543796 -29.150056)
				)
			)
		)
	)
	(zone
		(layers "F.Cu" "In2.Cu")
		(hatch none 0.5)
		(connect_pads
			(clearance 0)
		)
		(min_thickness 0.25)
		(keepout
			(tracks not_allowed)
			(vias allowed)
			(pads allowed)
			(copperpour not_allowed)
			(footprints allowed)
		)
		(placement
			(enabled no)
			(sheetname "")
		)
		(fill yes
			(thermal_gap 0.5)
			(thermal_bridge_width 0.5)
			(island_removal_mode 0)
		)
		(polygon
			(pts
				(xy 204.387196 -420.437056) (xy 204.387196 -419.514274) (xy 272.003266 -419.514274) (xy 272.003266 -420.437056)
			)
		)
	)
	(zone
		(layers "F.Cu" "In2.Cu" "In4.Cu")
		(hatch none 0.5)
		(connect_pads
			(clearance 0)
		)
		(min_thickness 0.25)
		(keepout
			(tracks not_allowed)
			(vias allowed)
			(pads allowed)
			(copperpour not_allowed)
			(footprints allowed)
		)
		(placement
			(enabled no)
			(sheetname "")
		)
		(fill yes
			(thermal_gap 0.5)
			(thermal_bridge_width 0.5)
			(island_removal_mode 0)
		)
		(polygon
			(pts
				(arc
					(start 386.298694 -21.950172)
					(mid 385.750054 -21.401532)
					(end 385.201414 -21.950172)
				)
				(arc
					(start 385.201414 -23.35022)
					(mid 385.748784 -23.898859)
					(end 386.298694 -23.35276)
				)
				(arc
					(start 386.09524 -23.35276)
					(mid 385.750054 -23.695415)
					(end 385.404868 -23.35276)
				)
				(arc
					(start 385.404868 -23.35022)
					(mid 385.750054 -23.005034)
					(end 386.09524 -23.35022)
				)
				(xy 386.298694 -23.35022) (xy 386.298694 -21.952712)
				(arc
					(start 386.09524 -21.952712)
					(mid 385.750054 -22.295367)
					(end 385.404868 -21.952712)
				)
				(arc
					(start 385.404868 -21.950172)
					(mid 385.750054 -21.604986)
					(end 386.09524 -21.950172)
				)
			)
		)
	)
	(zone
		(layers "F.Cu" "In2.Cu" "In4.Cu")
		(hatch none 0.5)
		(connect_pads
			(clearance 0)
		)
		(min_thickness 0.25)
		(keepout
			(tracks not_allowed)
			(vias allowed)
			(pads allowed)
			(copperpour not_allowed)
			(footprints allowed)
		)
		(placement
			(enabled no)
			(sheetname "")
		)
		(fill yes
			(thermal_gap 0.5)
			(thermal_bridge_width 0.5)
			(island_removal_mode 0)
		)
		(polygon
			(pts
				(arc
					(start 111.498634 -18.35023)
					(mid 110.949994 -17.80159)
					(end 110.401354 -18.35023)
				)
				(arc
					(start 110.401354 -19.750024)
					(mid 110.948724 -20.298663)
					(end 111.498634 -19.752564)
				)
				(arc
					(start 111.29518 -19.752564)
					(mid 110.949994 -20.095219)
					(end 110.604808 -19.752564)
				)
				(arc
					(start 110.604808 -19.750024)
					(mid 110.949994 -19.404838)
					(end 111.29518 -19.750024)
				)
				(xy 111.498634 -19.750024) (xy 111.498634 -18.35277)
				(arc
					(start 111.29518 -18.35277)
					(mid 110.949994 -18.695425)
					(end 110.604808 -18.35277)
				)
				(arc
					(start 110.604808 -18.35023)
					(mid 110.949994 -18.005044)
					(end 111.29518 -18.35023)
				)
			)
		)
	)
	(zone
		(layers "F.Cu" "In2.Cu" "In4.Cu")
		(hatch none 0.5)
		(connect_pads
			(clearance 0)
		)
		(min_thickness 0.25)
		(keepout
			(tracks not_allowed)
			(vias allowed)
			(pads allowed)
			(copperpour not_allowed)
			(footprints allowed)
		)
		(placement
			(enabled no)
			(sheetname "")
		)
		(fill yes
			(thermal_gap 0.5)
			(thermal_bridge_width 0.5)
			(island_removal_mode 0)
		)
		(polygon
			(pts
				(arc
					(start 377.298712 -20.950174)
					(mid 376.750072 -20.401534)
					(end 376.201432 -20.950174)
				)
				(arc
					(start 376.201432 -22.350222)
					(mid 376.748802 -22.898861)
					(end 377.298712 -22.352762)
				)
				(arc
					(start 377.095258 -22.352762)
					(mid 376.750072 -22.695417)
					(end 376.404886 -22.352762)
				)
				(arc
					(start 376.404886 -22.350222)
					(mid 376.750072 -22.005036)
					(end 377.095258 -22.350222)
				)
				(xy 377.298712 -22.350222) (xy 377.298712 -20.952714)
				(arc
					(start 377.095258 -20.952714)
					(mid 376.750072 -21.295369)
					(end 376.404886 -20.952714)
				)
				(arc
					(start 376.404886 -20.950174)
					(mid 376.750072 -20.604988)
					(end 377.095258 -20.950174)
				)
			)
		)
	)
	(zone
		(layers "F.Cu" "In2.Cu" "In4.Cu")
		(hatch none 0.5)
		(connect_pads
			(clearance 0)
		)
		(min_thickness 0.25)
		(keepout
			(tracks not_allowed)
			(vias allowed)
			(pads allowed)
			(copperpour not_allowed)
			(footprints allowed)
		)
		(placement
			(enabled no)
			(sheetname "")
		)
		(fill yes
			(thermal_gap 0.5)
			(thermal_bridge_width 0.5)
			(island_removal_mode 0)
		)
		(polygon
			(pts
				(arc
					(start 122.298714 -21.950172)
					(mid 121.750074 -21.401532)
					(end 121.201434 -21.950172)
				)
				(arc
					(start 121.201434 -23.35022)
					(mid 121.748804 -23.898859)
					(end 122.298714 -23.35276)
				)
				(arc
					(start 122.09526 -23.35276)
					(mid 121.750074 -23.695415)
					(end 121.404888 -23.35276)
				)
				(arc
					(start 121.404888 -23.35022)
					(mid 121.750074 -23.005034)
					(end 122.09526 -23.35022)
				)
				(xy 122.298714 -23.35022) (xy 122.298714 -21.952712)
				(arc
					(start 122.09526 -21.952712)
					(mid 121.750074 -22.295367)
					(end 121.404888 -21.952712)
				)
				(arc
					(start 121.404888 -21.950172)
					(mid 121.750074 -21.604986)
					(end 122.09526 -21.950172)
				)
			)
		)
	)
	(zone
		(layers "F.Cu" "In2.Cu" "In4.Cu")
		(hatch none 0.5)
		(connect_pads
			(clearance 0)
		)
		(min_thickness 0.25)
		(keepout
			(tracks not_allowed)
			(vias allowed)
			(pads allowed)
			(copperpour not_allowed)
			(footprints allowed)
		)
		(placement
			(enabled no)
			(sheetname "")
		)
		(fill yes
			(thermal_gap 0.5)
			(thermal_bridge_width 0.5)
			(island_removal_mode 0)
		)
		(polygon
			(pts
				(arc
					(start 355.698552 -20.950174)
					(mid 355.149912 -20.401534)
					(end 354.601272 -20.950174)
				)
				(arc
					(start 354.601272 -22.350222)
					(mid 355.148642 -22.898861)
					(end 355.698552 -22.352762)
				)
				(arc
					(start 355.495098 -22.352762)
					(mid 355.149912 -22.695417)
					(end 354.804726 -22.352762)
				)
				(arc
					(start 354.804726 -22.350222)
					(mid 355.149912 -22.005036)
					(end 355.495098 -22.350222)
				)
				(xy 355.698552 -22.350222) (xy 355.698552 -20.952714)
				(arc
					(start 355.495098 -20.952714)
					(mid 355.149912 -21.295369)
					(end 354.804726 -20.952714)
				)
				(arc
					(start 354.804726 -20.950174)
					(mid 355.149912 -20.604988)
					(end 355.495098 -20.950174)
				)
			)
		)
	)
	(zone
		(layers "F.Cu" "In2.Cu" "In4.Cu")
		(hatch none 0.5)
		(connect_pads
			(clearance 0)
		)
		(min_thickness 0.25)
		(keepout
			(tracks not_allowed)
			(vias allowed)
			(pads allowed)
			(copperpour not_allowed)
			(footprints allowed)
		)
		(placement
			(enabled no)
			(sheetname "")
		)
		(fill yes
			(thermal_gap 0.5)
			(thermal_bridge_width 0.5)
			(island_removal_mode 0)
		)
		(polygon
			(pts
				(arc
					(start 113.298732 -17.349978)
					(mid 112.750092 -16.801338)
					(end 112.201452 -17.349978)
				)
				(arc
					(start 112.201452 -18.750026)
					(mid 112.748822 -19.298665)
					(end 113.298732 -18.752566)
				)
				(arc
					(start 113.095278 -18.752566)
					(mid 112.750092 -19.095221)
					(end 112.404906 -18.752566)
				)
				(arc
					(start 112.404906 -18.750026)
					(mid 112.750092 -18.40484)
					(end 113.095278 -18.750026)
				)
				(xy 113.298732 -18.750026) (xy 113.298732 -17.352518)
				(arc
					(start 113.095278 -17.352518)
					(mid 112.750092 -17.695173)
					(end 112.404906 -17.352518)
				)
				(arc
					(start 112.404906 -17.349978)
					(mid 112.750092 -17.004792)
					(end 113.095278 -17.349978)
				)
			)
		)
	)
	(zone
		(layers "F.Cu" "In2.Cu" "In4.Cu")
		(hatch none 0.5)
		(connect_pads
			(clearance 0)
		)
		(min_thickness 0.25)
		(keepout
			(tracks not_allowed)
			(vias allowed)
			(pads allowed)
			(copperpour not_allowed)
			(footprints allowed)
		)
		(placement
			(enabled no)
			(sheetname "")
		)
		(fill yes
			(thermal_gap 0.5)
			(thermal_bridge_width 0.5)
			(island_removal_mode 0)
		)
		(polygon
			(pts
				(arc
					(start 118.698518 -21.950172)
					(mid 118.149878 -21.401532)
					(end 117.601238 -21.950172)
				)
				(arc
					(start 117.601238 -23.35022)
					(mid 118.148608 -23.898859)
					(end 118.698518 -23.35276)
				)
				(arc
					(start 118.495064 -23.35276)
					(mid 118.149878 -23.695415)
					(end 117.804692 -23.35276)
				)
				(arc
					(start 117.804692 -23.35022)
					(mid 118.149878 -23.005034)
					(end 118.495064 -23.35022)
				)
				(xy 118.698518 -23.35022) (xy 118.698518 -21.952712)
				(arc
					(start 118.495064 -21.952712)
					(mid 118.149878 -22.295367)
					(end 117.804692 -21.952712)
				)
				(arc
					(start 117.804692 -21.950172)
					(mid 118.149878 -21.604986)
					(end 118.495064 -21.950172)
				)
			)
		)
	)
	(zone
		(layers "F.Cu" "In2.Cu" "In4.Cu")
		(hatch none 0.5)
		(connect_pads
			(clearance 0)
		)
		(min_thickness 0.25)
		(keepout
			(tracks not_allowed)
			(vias allowed)
			(pads allowed)
			(copperpour not_allowed)
			(footprints allowed)
		)
		(placement
			(enabled no)
			(sheetname "")
		)
		(fill yes
			(thermal_gap 0.5)
			(thermal_bridge_width 0.5)
			(island_removal_mode 0)
		)
		(polygon
			(pts
				(arc
					(start 109.698536 -17.349978)
					(mid 109.149896 -16.801338)
					(end 108.601256 -17.349978)
				)
				(arc
					(start 108.601256 -18.750026)
					(mid 109.148626 -19.298665)
					(end 109.698536 -18.752566)
				)
				(arc
					(start 109.495082 -18.752566)
					(mid 109.149896 -19.095221)
					(end 108.80471 -18.752566)
				)
				(arc
					(start 108.80471 -18.750026)
					(mid 109.149896 -18.40484)
					(end 109.495082 -18.750026)
				)
				(xy 109.698536 -18.750026) (xy 109.698536 -17.352518)
				(arc
					(start 109.495082 -17.352518)
					(mid 109.149896 -17.695173)
					(end 108.80471 -17.352518)
				)
				(arc
					(start 108.80471 -17.349978)
					(mid 109.149896 -17.004792)
					(end 109.495082 -17.349978)
				)
			)
		)
	)
	(zone
		(layers "F.Cu" "In2.Cu" "In4.Cu")
		(hatch none 0.5)
		(connect_pads
			(clearance 0)
		)
		(min_thickness 0.25)
		(keepout
			(tracks not_allowed)
			(vias allowed)
			(pads allowed)
			(copperpour not_allowed)
			(footprints allowed)
		)
		(placement
			(enabled no)
			(sheetname "")
		)
		(fill yes
			(thermal_gap 0.5)
			(thermal_bridge_width 0.5)
			(island_removal_mode 0)
		)
		(polygon
			(pts
				(arc
					(start 388.098538 -20.950174)
					(mid 387.549898 -20.401534)
					(end 387.001258 -20.950174)
				)
				(arc
					(start 387.001258 -22.350222)
					(mid 387.548628 -22.898861)
					(end 388.098538 -22.352762)
				)
				(arc
					(start 387.895084 -22.352762)
					(mid 387.549898 -22.695417)
					(end 387.204712 -22.352762)
				)
				(arc
					(start 387.204712 -22.350222)
					(mid 387.549898 -22.005036)
					(end 387.895084 -22.350222)
				)
				(xy 388.098538 -22.350222) (xy 388.098538 -20.952714)
				(arc
					(start 387.895084 -20.952714)
					(mid 387.549898 -21.295369)
					(end 387.204712 -20.952714)
				)
				(arc
					(start 387.204712 -20.950174)
					(mid 387.549898 -20.604988)
					(end 387.895084 -20.950174)
				)
			)
		)
	)
	(zone
		(layers "F.Cu" "In2.Cu" "In4.Cu")
		(hatch none 0.5)
		(connect_pads
			(clearance 0)
		)
		(min_thickness 0.25)
		(keepout
			(tracks not_allowed)
			(vias allowed)
			(pads allowed)
			(copperpour not_allowed)
			(footprints allowed)
		)
		(placement
			(enabled no)
			(sheetname "")
		)
		(fill yes
			(thermal_gap 0.5)
			(thermal_bridge_width 0.5)
			(island_removal_mode 0)
		)
		(polygon
			(pts
				(arc
					(start 134.898638 -20.950174)
					(mid 134.349998 -20.401534)
					(end 133.801358 -20.950174)
				)
				(arc
					(start 133.801358 -22.350222)
					(mid 134.348728 -22.898861)
					(end 134.898638 -22.352762)
				)
				(arc
					(start 134.695184 -22.352762)
					(mid 134.349998 -22.695417)
					(end 134.004812 -22.352762)
				)
				(arc
					(start 134.004812 -22.350222)
					(mid 134.349998 -22.005036)
					(end 134.695184 -22.350222)
				)
				(xy 134.898638 -22.350222) (xy 134.898638 -20.952714)
				(arc
					(start 134.695184 -20.952714)
					(mid 134.349998 -21.295369)
					(end 134.004812 -20.952714)
				)
				(arc
					(start 134.004812 -20.950174)
					(mid 134.349998 -20.604988)
					(end 134.695184 -20.950174)
				)
			)
		)
	)
	(zone
		(layers "F.Cu" "In2.Cu" "In4.Cu")
		(hatch none 0.5)
		(connect_pads
			(clearance 0)
		)
		(min_thickness 0.25)
		(keepout
			(tracks not_allowed)
			(vias allowed)
			(pads allowed)
			(copperpour not_allowed)
			(footprints allowed)
		)
		(placement
			(enabled no)
			(sheetname "")
		)
		(fill yes
			(thermal_gap 0.5)
			(thermal_bridge_width 0.5)
			(island_removal_mode 0)
		)
		(polygon
			(pts
				(arc
					(start 380.898654 -17.349978)
					(mid 380.350014 -16.801338)
					(end 379.801374 -17.349978)
				)
				(arc
					(start 379.801374 -18.750026)
					(mid 380.348744 -19.298665)
					(end 380.898654 -18.752566)
				)
				(arc
					(start 380.6952 -18.752566)
					(mid 380.350014 -19.095221)
					(end 380.004828 -18.752566)
				)
				(arc
					(start 380.004828 -18.750026)
					(mid 380.350014 -18.40484)
					(end 380.6952 -18.750026)
				)
				(xy 380.898654 -18.750026) (xy 380.898654 -17.352518)
				(arc
					(start 380.6952 -17.352518)
					(mid 380.350014 -17.695173)
					(end 380.004828 -17.352518)
				)
				(arc
					(start 380.004828 -17.349978)
					(mid 380.350014 -17.004792)
					(end 380.6952 -17.349978)
				)
			)
		)
	)
	(zone
		(layers "F.Cu" "In2.Cu" "In4.Cu")
		(hatch none 0.5)
		(connect_pads
			(clearance 0)
		)
		(min_thickness 0.25)
		(keepout
			(tracks not_allowed)
			(vias allowed)
			(pads allowed)
			(copperpour not_allowed)
			(footprints allowed)
		)
		(placement
			(enabled no)
			(sheetname "")
		)
		(fill yes
			(thermal_gap 0.5)
			(thermal_bridge_width 0.5)
			(island_removal_mode 0)
		)
		(polygon
			(pts
				(arc
					(start 143.89862 -18.35023)
					(mid 143.34998 -17.80159)
					(end 142.80134 -18.35023)
				)
				(arc
					(start 142.80134 -19.750024)
					(mid 143.34871 -20.298663)
					(end 143.89862 -19.752564)
				)
				(arc
					(start 143.695166 -19.752564)
					(mid 143.34998 -20.095219)
					(end 143.004794 -19.752564)
				)
				(arc
					(start 143.004794 -19.750024)
					(mid 143.34998 -19.404838)
					(end 143.695166 -19.750024)
				)
				(xy 143.89862 -19.750024) (xy 143.89862 -18.35277)
				(arc
					(start 143.695166 -18.35277)
					(mid 143.34998 -18.695425)
					(end 143.004794 -18.35277)
				)
				(arc
					(start 143.004794 -18.35023)
					(mid 143.34998 -18.005044)
					(end 143.695166 -18.35023)
				)
			)
		)
	)
	(zone
		(layers "F.Cu" "In2.Cu" "In4.Cu")
		(hatch none 0.5)
		(connect_pads
			(clearance 0)
		)
		(min_thickness 0.25)
		(keepout
			(tracks not_allowed)
			(vias allowed)
			(pads allowed)
			(copperpour not_allowed)
			(footprints allowed)
		)
		(placement
			(enabled no)
			(sheetname "")
		)
		(fill yes
			(thermal_gap 0.5)
			(thermal_bridge_width 0.5)
			(island_removal_mode 0)
		)
		(polygon
			(pts
				(arc
					(start 368.29873 -21.950172)
					(mid 367.75009 -21.401532)
					(end 367.20145 -21.950172)
				)
				(arc
					(start 367.20145 -23.35022)
					(mid 367.74882 -23.898859)
					(end 368.29873 -23.35276)
				)
				(arc
					(start 368.095276 -23.35276)
					(mid 367.75009 -23.695415)
					(end 367.404904 -23.35276)
				)
				(arc
					(start 367.404904 -23.35022)
					(mid 367.75009 -23.005034)
					(end 368.095276 -23.35022)
				)
				(xy 368.29873 -23.35022) (xy 368.29873 -21.952712)
				(arc
					(start 368.095276 -21.952712)
					(mid 367.75009 -22.295367)
					(end 367.404904 -21.952712)
				)
				(arc
					(start 367.404904 -21.950172)
					(mid 367.75009 -21.604986)
					(end 368.095276 -21.950172)
				)
			)
		)
	)
	(zone
		(layers "F.Cu" "In2.Cu" "In4.Cu")
		(hatch none 0.5)
		(connect_pads
			(clearance 0)
		)
		(min_thickness 0.25)
		(keepout
			(tracks not_allowed)
			(vias allowed)
			(pads allowed)
			(copperpour not_allowed)
			(footprints allowed)
		)
		(placement
			(enabled no)
			(sheetname "")
		)
		(fill yes
			(thermal_gap 0.5)
			(thermal_bridge_width 0.5)
			(island_removal_mode 0)
		)
		(polygon
			(pts
				(arc
					(start 359.298748 -20.950174)
					(mid 358.750108 -20.401534)
					(end 358.201468 -20.950174)
				)
				(arc
					(start 358.201468 -22.350222)
					(mid 358.748838 -22.898861)
					(end 359.298748 -22.352762)
				)
				(arc
					(start 359.095294 -22.352762)
					(mid 358.750108 -22.695417)
					(end 358.404922 -22.352762)
				)
				(arc
					(start 358.404922 -22.350222)
					(mid 358.750108 -22.005036)
					(end 359.095294 -22.350222)
				)
				(xy 359.298748 -22.350222) (xy 359.298748 -20.952714)
				(arc
					(start 359.095294 -20.952714)
					(mid 358.750108 -21.295369)
					(end 358.404922 -20.952714)
				)
				(arc
					(start 358.404922 -20.950174)
					(mid 358.750108 -20.604988)
					(end 359.095294 -20.950174)
				)
			)
		)
	)
	(zone
		(layers "F.Cu" "In2.Cu" "In4.Cu")
		(hatch none 0.5)
		(connect_pads
			(clearance 0)
		)
		(min_thickness 0.25)
		(keepout
			(tracks not_allowed)
			(vias allowed)
			(pads allowed)
			(copperpour not_allowed)
			(footprints allowed)
		)
		(placement
			(enabled no)
			(sheetname "")
		)
		(fill yes
			(thermal_gap 0.5)
			(thermal_bridge_width 0.5)
			(island_removal_mode 0)
		)
		(polygon
			(pts
				(arc
					(start 368.29873 -18.35023)
					(mid 367.75009 -17.80159)
					(end 367.20145 -18.35023)
				)
				(arc
					(start 367.20145 -19.750024)
					(mid 367.74882 -20.298663)
					(end 368.29873 -19.752564)
				)
				(arc
					(start 368.095276 -19.752564)
					(mid 367.75009 -20.095219)
					(end 367.404904 -19.752564)
				)
				(arc
					(start 367.404904 -19.750024)
					(mid 367.75009 -19.404838)
					(end 368.095276 -19.750024)
				)
				(xy 368.29873 -19.750024) (xy 368.29873 -18.35277)
				(arc
					(start 368.095276 -18.35277)
					(mid 367.75009 -18.695425)
					(end 367.404904 -18.35277)
				)
				(arc
					(start 367.404904 -18.35023)
					(mid 367.75009 -18.005044)
					(end 368.095276 -18.35023)
				)
			)
		)
	)
	(zone
		(layers "F.Cu" "In2.Cu" "In4.Cu")
		(hatch none 0.5)
		(connect_pads
			(clearance 0)
		)
		(min_thickness 0.25)
		(keepout
			(tracks not_allowed)
			(vias allowed)
			(pads allowed)
			(copperpour not_allowed)
			(footprints allowed)
		)
		(placement
			(enabled no)
			(sheetname "")
		)
		(fill yes
			(thermal_gap 0.5)
			(thermal_bridge_width 0.5)
			(island_removal_mode 0)
		)
		(polygon
			(pts
				(arc
					(start 366.498632 -17.349978)
					(mid 365.949992 -16.801338)
					(end 365.401352 -17.349978)
				)
				(arc
					(start 365.401352 -18.750026)
					(mid 365.948722 -19.298665)
					(end 366.498632 -18.752566)
				)
				(arc
					(start 366.295178 -18.752566)
					(mid 365.949992 -19.095221)
					(end 365.604806 -18.752566)
				)
				(arc
					(start 365.604806 -18.750026)
					(mid 365.949992 -18.40484)
					(end 366.295178 -18.750026)
				)
				(xy 366.498632 -18.750026) (xy 366.498632 -17.352518)
				(arc
					(start 366.295178 -17.352518)
					(mid 365.949992 -17.695173)
					(end 365.604806 -17.352518)
				)
				(arc
					(start 365.604806 -17.349978)
					(mid 365.949992 -17.004792)
					(end 366.295178 -17.349978)
				)
			)
		)
	)
	(zone
		(layers "F.Cu" "In2.Cu" "In4.Cu")
		(hatch none 0.5)
		(connect_pads
			(clearance 0)
		)
		(min_thickness 0.25)
		(keepout
			(tracks not_allowed)
			(vias allowed)
			(pads allowed)
			(copperpour not_allowed)
			(footprints allowed)
		)
		(placement
			(enabled no)
			(sheetname "")
		)
		(fill yes
			(thermal_gap 0.5)
			(thermal_bridge_width 0.5)
			(island_removal_mode 0)
		)
		(polygon
			(pts
				(arc
					(start 377.298712 -17.349978)
					(mid 376.750072 -16.801338)
					(end 376.201432 -17.349978)
				)
				(arc
					(start 376.201432 -18.750026)
					(mid 376.748802 -19.298665)
					(end 377.298712 -18.752566)
				)
				(arc
					(start 377.095258 -18.752566)
					(mid 376.750072 -19.095221)
					(end 376.404886 -18.752566)
				)
				(arc
					(start 376.404886 -18.750026)
					(mid 376.750072 -18.40484)
					(end 377.095258 -18.750026)
				)
				(xy 377.298712 -18.750026) (xy 377.298712 -17.352518)
				(arc
					(start 377.095258 -17.352518)
					(mid 376.750072 -17.695173)
					(end 376.404886 -17.352518)
				)
				(arc
					(start 376.404886 -17.349978)
					(mid 376.750072 -17.004792)
					(end 377.095258 -17.349978)
				)
			)
		)
	)
	(zone
		(layers "F.Cu" "In2.Cu" "In4.Cu")
		(hatch none 0.5)
		(connect_pads
			(clearance 0)
		)
		(min_thickness 0.25)
		(keepout
			(tracks not_allowed)
			(vias allowed)
			(pads allowed)
			(copperpour not_allowed)
			(footprints allowed)
		)
		(placement
			(enabled no)
			(sheetname "")
		)
		(fill yes
			(thermal_gap 0.5)
			(thermal_bridge_width 0.5)
			(island_removal_mode 0)
		)
		(polygon
			(pts
				(arc
					(start 138.49858 -17.349978)
					(mid 137.94994 -16.801338)
					(end 137.4013 -17.349978)
				)
				(arc
					(start 137.4013 -18.750026)
					(mid 137.94867 -19.298665)
					(end 138.49858 -18.752566)
				)
				(arc
					(start 138.295126 -18.752566)
					(mid 137.94994 -19.095221)
					(end 137.604754 -18.752566)
				)
				(arc
					(start 137.604754 -18.750026)
					(mid 137.94994 -18.40484)
					(end 138.295126 -18.750026)
				)
				(xy 138.49858 -18.750026) (xy 138.49858 -17.352518)
				(arc
					(start 138.295126 -17.352518)
					(mid 137.94994 -17.695173)
					(end 137.604754 -17.352518)
				)
				(arc
					(start 137.604754 -17.349978)
					(mid 137.94994 -17.004792)
					(end 138.295126 -17.349978)
				)
			)
		)
	)
	(zone
		(layers "F.Cu" "In2.Cu" "In4.Cu")
		(hatch none 0.5)
		(connect_pads
			(clearance 0)
		)
		(min_thickness 0.25)
		(keepout
			(tracks not_allowed)
			(vias allowed)
			(pads allowed)
			(copperpour not_allowed)
			(footprints allowed)
		)
		(placement
			(enabled no)
			(sheetname "")
		)
		(fill yes
			(thermal_gap 0.5)
			(thermal_bridge_width 0.5)
			(island_removal_mode 0)
		)
		(polygon
			(pts
				(arc
					(start 142.098522 -20.950174)
					(mid 141.549882 -20.401534)
					(end 141.001242 -20.950174)
				)
				(arc
					(start 141.001242 -22.350222)
					(mid 141.548612 -22.898861)
					(end 142.098522 -22.352762)
				)
				(arc
					(start 141.895068 -22.352762)
					(mid 141.549882 -22.695417)
					(end 141.204696 -22.352762)
				)
				(arc
					(start 141.204696 -22.350222)
					(mid 141.549882 -22.005036)
					(end 141.895068 -22.350222)
				)
				(xy 142.098522 -22.350222) (xy 142.098522 -20.952714)
				(arc
					(start 141.895068 -20.952714)
					(mid 141.549882 -21.295369)
					(end 141.204696 -20.952714)
				)
				(arc
					(start 141.204696 -20.950174)
					(mid 141.549882 -20.604988)
					(end 141.895068 -20.950174)
				)
			)
		)
	)
	(zone
		(layers "F.Cu" "In2.Cu" "In4.Cu")
		(hatch none 0.5)
		(connect_pads
			(clearance 0)
		)
		(min_thickness 0.25)
		(keepout
			(tracks not_allowed)
			(vias allowed)
			(pads allowed)
			(copperpour not_allowed)
			(footprints allowed)
		)
		(placement
			(enabled no)
			(sheetname "")
		)
		(fill yes
			(thermal_gap 0.5)
			(thermal_bridge_width 0.5)
			(island_removal_mode 0)
		)
		(polygon
			(pts
				(arc
					(start 379.098556 -18.35023)
					(mid 378.549916 -17.80159)
					(end 378.001276 -18.35023)
				)
				(arc
					(start 378.001276 -19.750024)
					(mid 378.548646 -20.298663)
					(end 379.098556 -19.752564)
				)
				(arc
					(start 378.895102 -19.752564)
					(mid 378.549916 -20.095219)
					(end 378.20473 -19.752564)
				)
				(arc
					(start 378.20473 -19.750024)
					(mid 378.549916 -19.404838)
					(end 378.895102 -19.750024)
				)
				(xy 379.098556 -19.750024) (xy 379.098556 -18.35277)
				(arc
					(start 378.895102 -18.35277)
					(mid 378.549916 -18.695425)
					(end 378.20473 -18.35277)
				)
				(arc
					(start 378.20473 -18.35023)
					(mid 378.549916 -18.005044)
					(end 378.895102 -18.35023)
				)
			)
		)
	)
	(zone
		(layers "F.Cu" "In2.Cu" "In4.Cu")
		(hatch none 0.5)
		(connect_pads
			(clearance 0)
		)
		(min_thickness 0.25)
		(keepout
			(tracks not_allowed)
			(vias allowed)
			(pads allowed)
			(copperpour not_allowed)
			(footprints allowed)
		)
		(placement
			(enabled no)
			(sheetname "")
		)
		(fill yes
			(thermal_gap 0.5)
			(thermal_bridge_width 0.5)
			(island_removal_mode 0)
		)
		(polygon
			(pts
				(arc
					(start 140.298678 -18.35023)
					(mid 139.750038 -17.80159)
					(end 139.201398 -18.35023)
				)
				(arc
					(start 139.201398 -19.750024)
					(mid 139.748768 -20.298663)
					(end 140.298678 -19.752564)
				)
				(arc
					(start 140.095224 -19.752564)
					(mid 139.750038 -20.095219)
					(end 139.404852 -19.752564)
				)
				(arc
					(start 139.404852 -19.750024)
					(mid 139.750038 -19.404838)
					(end 140.095224 -19.750024)
				)
				(xy 140.298678 -19.750024) (xy 140.298678 -18.35277)
				(arc
					(start 140.095224 -18.35277)
					(mid 139.750038 -18.695425)
					(end 139.404852 -18.35277)
				)
				(arc
					(start 139.404852 -18.35023)
					(mid 139.750038 -18.005044)
					(end 140.095224 -18.35023)
				)
			)
		)
	)
	(zone
		(layers "F.Cu" "In2.Cu" "In4.Cu")
		(hatch none 0.5)
		(connect_pads
			(clearance 0)
		)
		(min_thickness 0.25)
		(keepout
			(tracks not_allowed)
			(vias allowed)
			(pads allowed)
			(copperpour not_allowed)
			(footprints allowed)
		)
		(placement
			(enabled no)
			(sheetname "")
		)
		(fill yes
			(thermal_gap 0.5)
			(thermal_bridge_width 0.5)
			(island_removal_mode 0)
		)
		(polygon
			(pts
				(arc
					(start 143.89862 -21.950172)
					(mid 143.34998 -21.401532)
					(end 142.80134 -21.950172)
				)
				(arc
					(start 142.80134 -23.35022)
					(mid 143.34871 -23.898859)
					(end 143.89862 -23.35276)
				)
				(arc
					(start 143.695166 -23.35276)
					(mid 143.34998 -23.695415)
					(end 143.004794 -23.35276)
				)
				(arc
					(start 143.004794 -23.35022)
					(mid 143.34998 -23.005034)
					(end 143.695166 -23.35022)
				)
				(xy 143.89862 -23.35022) (xy 143.89862 -21.952712)
				(arc
					(start 143.695166 -21.952712)
					(mid 143.34998 -22.295367)
					(end 143.004794 -21.952712)
				)
				(arc
					(start 143.004794 -21.950172)
					(mid 143.34998 -21.604986)
					(end 143.695166 -21.950172)
				)
			)
		)
	)
	(zone
		(layers "F.Cu" "In2.Cu" "In4.Cu")
		(hatch none 0.5)
		(connect_pads
			(clearance 0)
		)
		(min_thickness 0.25)
		(keepout
			(tracks not_allowed)
			(vias allowed)
			(pads allowed)
			(copperpour not_allowed)
			(footprints allowed)
		)
		(placement
			(enabled no)
			(sheetname "")
		)
		(fill yes
			(thermal_gap 0.5)
			(thermal_bridge_width 0.5)
			(island_removal_mode 0)
		)
		(polygon
			(pts
				(arc
					(start 366.498632 -20.950174)
					(mid 365.949992 -20.401534)
					(end 365.401352 -20.950174)
				)
				(arc
					(start 365.401352 -22.350222)
					(mid 365.948722 -22.898861)
					(end 366.498632 -22.352762)
				)
				(arc
					(start 366.295178 -22.352762)
					(mid 365.949992 -22.695417)
					(end 365.604806 -22.352762)
				)
				(arc
					(start 365.604806 -22.350222)
					(mid 365.949992 -22.005036)
					(end 366.295178 -22.350222)
				)
				(xy 366.498632 -22.350222) (xy 366.498632 -20.952714)
				(arc
					(start 366.295178 -20.952714)
					(mid 365.949992 -21.295369)
					(end 365.604806 -20.952714)
				)
				(arc
					(start 365.604806 -20.950174)
					(mid 365.949992 -20.604988)
					(end 366.295178 -20.950174)
				)
			)
		)
	)
	(zone
		(layers "F.Cu" "In2.Cu" "In4.Cu")
		(hatch none 0.5)
		(connect_pads
			(clearance 0)
		)
		(min_thickness 0.25)
		(keepout
			(tracks not_allowed)
			(vias allowed)
			(pads allowed)
			(copperpour not_allowed)
			(footprints allowed)
		)
		(placement
			(enabled no)
			(sheetname "")
		)
		(fill yes
			(thermal_gap 0.5)
			(thermal_bridge_width 0.5)
			(island_removal_mode 0)
		)
		(polygon
			(pts
				(arc
					(start 364.698534 -21.950172)
					(mid 364.149894 -21.401532)
					(end 363.601254 -21.950172)
				)
				(arc
					(start 363.601254 -23.35022)
					(mid 364.148624 -23.898859)
					(end 364.698534 -23.35276)
				)
				(arc
					(start 364.49508 -23.35276)
					(mid 364.149894 -23.695415)
					(end 363.804708 -23.35276)
				)
				(arc
					(start 363.804708 -23.35022)
					(mid 364.149894 -23.005034)
					(end 364.49508 -23.35022)
				)
				(xy 364.698534 -23.35022) (xy 364.698534 -21.952712)
				(arc
					(start 364.49508 -21.952712)
					(mid 364.149894 -22.295367)
					(end 363.804708 -21.952712)
				)
				(arc
					(start 363.804708 -21.950172)
					(mid 364.149894 -21.604986)
					(end 364.49508 -21.950172)
				)
			)
		)
	)
	(zone
		(layers "F.Cu" "In2.Cu" "In4.Cu")
		(hatch none 0.5)
		(connect_pads
			(clearance 0)
		)
		(min_thickness 0.25)
		(keepout
			(tracks not_allowed)
			(vias allowed)
			(pads allowed)
			(copperpour not_allowed)
			(footprints allowed)
		)
		(placement
			(enabled no)
			(sheetname "")
		)
		(fill yes
			(thermal_gap 0.5)
			(thermal_bridge_width 0.5)
			(island_removal_mode 0)
		)
		(polygon
			(pts
				(arc
					(start 136.698736 -21.950172)
					(mid 136.150096 -21.401532)
					(end 135.601456 -21.950172)
				)
				(arc
					(start 135.601456 -23.35022)
					(mid 136.148826 -23.898859)
					(end 136.698736 -23.35276)
				)
				(arc
					(start 136.495282 -23.35276)
					(mid 136.150096 -23.695415)
					(end 135.80491 -23.35276)
				)
				(arc
					(start 135.80491 -23.35022)
					(mid 136.150096 -23.005034)
					(end 136.495282 -23.35022)
				)
				(xy 136.698736 -23.35022) (xy 136.698736 -21.952712)
				(arc
					(start 136.495282 -21.952712)
					(mid 136.150096 -22.295367)
					(end 135.80491 -21.952712)
				)
				(arc
					(start 135.80491 -21.950172)
					(mid 136.150096 -21.604986)
					(end 136.495282 -21.950172)
				)
			)
		)
	)
	(zone
		(layers "F.Cu" "In2.Cu" "In4.Cu")
		(hatch none 0.5)
		(connect_pads
			(clearance 0)
		)
		(min_thickness 0.25)
		(keepout
			(tracks not_allowed)
			(vias allowed)
			(pads allowed)
			(copperpour not_allowed)
			(footprints allowed)
		)
		(placement
			(enabled no)
			(sheetname "")
		)
		(fill yes
			(thermal_gap 0.5)
			(thermal_bridge_width 0.5)
			(island_removal_mode 0)
		)
		(polygon
			(pts
				(arc
					(start 116.898674 -20.950174)
					(mid 116.350034 -20.401534)
					(end 115.801394 -20.950174)
				)
				(arc
					(start 115.801394 -22.350222)
					(mid 116.348764 -22.898861)
					(end 116.898674 -22.352762)
				)
				(arc
					(start 116.69522 -22.352762)
					(mid 116.350034 -22.695417)
					(end 116.004848 -22.352762)
				)
				(arc
					(start 116.004848 -22.350222)
					(mid 116.350034 -22.005036)
					(end 116.69522 -22.350222)
				)
				(xy 116.898674 -22.350222) (xy 116.898674 -20.952714)
				(arc
					(start 116.69522 -20.952714)
					(mid 116.350034 -21.295369)
					(end 116.004848 -20.952714)
				)
				(arc
					(start 116.004848 -20.950174)
					(mid 116.350034 -20.604988)
					(end 116.69522 -20.950174)
				)
			)
		)
	)
	(zone
		(layers "F.Cu" "In2.Cu" "In4.Cu")
		(hatch none 0.5)
		(connect_pads
			(clearance 0)
		)
		(min_thickness 0.25)
		(keepout
			(tracks not_allowed)
			(vias allowed)
			(pads allowed)
			(copperpour not_allowed)
			(footprints allowed)
		)
		(placement
			(enabled no)
			(sheetname "")
		)
		(fill yes
			(thermal_gap 0.5)
			(thermal_bridge_width 0.5)
			(island_removal_mode 0)
		)
		(polygon
			(pts
				(arc
					(start 133.09854 -18.35023)
					(mid 132.5499 -17.80159)
					(end 132.00126 -18.35023)
				)
				(arc
					(start 132.00126 -19.74977)
					(mid 132.548503 -20.298662)
					(end 133.09854 -19.752564)
				)
				(arc
					(start 132.895086 -19.752564)
					(mid 132.5499 -20.095219)
					(end 132.204714 -19.752564)
				)
				(arc
					(start 132.204714 -19.750024)
					(mid 132.5499 -19.404838)
					(end 132.895086 -19.750024)
				)
				(xy 133.09854 -19.750024) (xy 133.09854 -18.35277)
				(arc
					(start 132.895086 -18.35277)
					(mid 132.5499 -18.695425)
					(end 132.204714 -18.35277)
				)
				(arc
					(start 132.204714 -18.35023)
					(mid 132.5499 -18.005044)
					(end 132.895086 -18.35023)
				)
			)
		)
	)
	(zone
		(layers "F.Cu" "In2.Cu" "In4.Cu")
		(hatch none 0.5)
		(connect_pads
			(clearance 0)
		)
		(min_thickness 0.25)
		(keepout
			(tracks not_allowed)
			(vias allowed)
			(pads allowed)
			(copperpour not_allowed)
			(footprints allowed)
		)
		(placement
			(enabled no)
			(sheetname "")
		)
		(fill yes
			(thermal_gap 0.5)
			(thermal_bridge_width 0.5)
			(island_removal_mode 0)
		)
		(polygon
			(pts
				(arc
					(start 384.498596 -17.349978)
					(mid 383.949956 -16.801338)
					(end 383.401316 -17.349978)
				)
				(arc
					(start 383.401316 -18.750026)
					(mid 383.948686 -19.298665)
					(end 384.498596 -18.752566)
				)
				(arc
					(start 384.295142 -18.752566)
					(mid 383.949956 -19.095221)
					(end 383.60477 -18.752566)
				)
				(arc
					(start 383.60477 -18.750026)
					(mid 383.949956 -18.40484)
					(end 384.295142 -18.750026)
				)
				(xy 384.498596 -18.750026) (xy 384.498596 -17.352518)
				(arc
					(start 384.295142 -17.352518)
					(mid 383.949956 -17.695173)
					(end 383.60477 -17.352518)
				)
				(arc
					(start 383.60477 -17.349978)
					(mid 383.949956 -17.004792)
					(end 384.295142 -17.349978)
				)
			)
		)
	)
	(zone
		(layers "F.Cu" "In2.Cu" "In4.Cu")
		(hatch none 0.5)
		(connect_pads
			(clearance 0)
		)
		(min_thickness 0.25)
		(keepout
			(tracks not_allowed)
			(vias allowed)
			(pads allowed)
			(copperpour not_allowed)
			(footprints allowed)
		)
		(placement
			(enabled no)
			(sheetname "")
		)
		(fill yes
			(thermal_gap 0.5)
			(thermal_bridge_width 0.5)
			(island_removal_mode 0)
		)
		(polygon
			(pts
				(arc
					(start 115.098576 -21.950172)
					(mid 114.549936 -21.401532)
					(end 114.001296 -21.950172)
				)
				(arc
					(start 114.001296 -23.35022)
					(mid 114.548666 -23.898859)
					(end 115.098576 -23.35276)
				)
				(arc
					(start 114.895122 -23.35276)
					(mid 114.549936 -23.695415)
					(end 114.20475 -23.35276)
				)
				(arc
					(start 114.20475 -23.35022)
					(mid 114.549936 -23.005034)
					(end 114.895122 -23.35022)
				)
				(xy 115.098576 -23.35022) (xy 115.098576 -21.952712)
				(arc
					(start 114.895122 -21.952712)
					(mid 114.549936 -22.295367)
					(end 114.20475 -21.952712)
				)
				(arc
					(start 114.20475 -21.950172)
					(mid 114.549936 -21.604986)
					(end 114.895122 -21.950172)
				)
			)
		)
	)
	(zone
		(layers "F.Cu" "In2.Cu" "In4.Cu")
		(hatch none 0.5)
		(connect_pads
			(clearance 0)
		)
		(min_thickness 0.25)
		(keepout
			(tracks not_allowed)
			(vias allowed)
			(pads allowed)
			(copperpour not_allowed)
			(footprints allowed)
		)
		(placement
			(enabled no)
			(sheetname "")
		)
		(fill yes
			(thermal_gap 0.5)
			(thermal_bridge_width 0.5)
			(island_removal_mode 0)
		)
		(polygon
			(pts
				(arc
					(start 384.498596 -20.950174)
					(mid 383.949956 -20.401534)
					(end 383.401316 -20.950174)
				)
				(arc
					(start 383.401316 -22.350222)
					(mid 383.948686 -22.898861)
					(end 384.498596 -22.352762)
				)
				(arc
					(start 384.295142 -22.352762)
					(mid 383.949956 -22.695417)
					(end 383.60477 -22.352762)
				)
				(arc
					(start 383.60477 -22.350222)
					(mid 383.949956 -22.005036)
					(end 384.295142 -22.350222)
				)
				(xy 384.498596 -22.350222) (xy 384.498596 -20.952714)
				(arc
					(start 384.295142 -20.952714)
					(mid 383.949956 -21.295369)
					(end 383.60477 -20.952714)
				)
				(arc
					(start 383.60477 -20.950174)
					(mid 383.949956 -20.604988)
					(end 384.295142 -20.950174)
				)
			)
		)
	)
	(zone
		(layers "F.Cu" "In2.Cu" "In4.Cu")
		(hatch none 0.5)
		(connect_pads
			(clearance 0)
		)
		(min_thickness 0.25)
		(keepout
			(tracks not_allowed)
			(vias allowed)
			(pads allowed)
			(copperpour not_allowed)
			(footprints allowed)
		)
		(placement
			(enabled no)
			(sheetname "")
		)
		(fill yes
			(thermal_gap 0.5)
			(thermal_bridge_width 0.5)
			(island_removal_mode 0)
		)
		(polygon
			(pts
				(arc
					(start 122.298714 -18.35023)
					(mid 121.750074 -17.80159)
					(end 121.201434 -18.35023)
				)
				(arc
					(start 121.201434 -19.750024)
					(mid 121.748804 -20.298663)
					(end 122.298714 -19.752564)
				)
				(arc
					(start 122.09526 -19.752564)
					(mid 121.750074 -20.095219)
					(end 121.404888 -19.752564)
				)
				(arc
					(start 121.404888 -19.750024)
					(mid 121.750074 -19.404838)
					(end 122.09526 -19.750024)
				)
				(xy 122.298714 -19.750024) (xy 122.298714 -18.35277)
				(arc
					(start 122.09526 -18.35277)
					(mid 121.750074 -18.695425)
					(end 121.404888 -18.35277)
				)
				(arc
					(start 121.404888 -18.35023)
					(mid 121.750074 -18.005044)
					(end 122.09526 -18.35023)
				)
			)
		)
	)
	(zone
		(layers "F.Cu" "In2.Cu" "In4.Cu")
		(hatch none 0.5)
		(connect_pads
			(clearance 0)
		)
		(min_thickness 0.25)
		(keepout
			(tracks not_allowed)
			(vias allowed)
			(pads allowed)
			(copperpour not_allowed)
			(footprints allowed)
		)
		(placement
			(enabled no)
			(sheetname "")
		)
		(fill yes
			(thermal_gap 0.5)
			(thermal_bridge_width 0.5)
			(island_removal_mode 0)
		)
		(polygon
			(pts
				(arc
					(start 380.898654 -20.950174)
					(mid 380.350014 -20.401534)
					(end 379.801374 -20.950174)
				)
				(arc
					(start 379.801374 -22.350222)
					(mid 380.348744 -22.898861)
					(end 380.898654 -22.352762)
				)
				(arc
					(start 380.6952 -22.352762)
					(mid 380.350014 -22.695417)
					(end 380.004828 -22.352762)
				)
				(arc
					(start 380.004828 -22.350222)
					(mid 380.350014 -22.005036)
					(end 380.6952 -22.350222)
				)
				(xy 380.898654 -22.350222) (xy 380.898654 -20.952714)
				(arc
					(start 380.6952 -20.952714)
					(mid 380.350014 -21.295369)
					(end 380.004828 -20.952714)
				)
				(arc
					(start 380.004828 -20.950174)
					(mid 380.350014 -20.604988)
					(end 380.6952 -20.950174)
				)
			)
		)
	)
	(zone
		(layers "F.Cu" "In2.Cu" "In4.Cu")
		(hatch none 0.5)
		(connect_pads
			(clearance 0)
		)
		(min_thickness 0.25)
		(keepout
			(tracks not_allowed)
			(vias allowed)
			(pads allowed)
			(copperpour not_allowed)
			(footprints allowed)
		)
		(placement
			(enabled no)
			(sheetname "")
		)
		(fill yes
			(thermal_gap 0.5)
			(thermal_bridge_width 0.5)
			(island_removal_mode 0)
		)
		(polygon
			(pts
				(arc
					(start 355.698552 -17.349978)
					(mid 355.149912 -16.801338)
					(end 354.601272 -17.349978)
				)
				(arc
					(start 354.601272 -18.750026)
					(mid 355.148642 -19.298665)
					(end 355.698552 -18.752566)
				)
				(arc
					(start 355.495098 -18.752566)
					(mid 355.149912 -19.095221)
					(end 354.804726 -18.752566)
				)
				(arc
					(start 354.804726 -18.750026)
					(mid 355.149912 -18.40484)
					(end 355.495098 -18.750026)
				)
				(xy 355.698552 -18.750026) (xy 355.698552 -17.352518)
				(arc
					(start 355.495098 -17.352518)
					(mid 355.149912 -17.695173)
					(end 354.804726 -17.352518)
				)
				(arc
					(start 354.804726 -17.349978)
					(mid 355.149912 -17.004792)
					(end 355.495098 -17.349978)
				)
			)
		)
	)
	(zone
		(layers "F.Cu" "In2.Cu" "In4.Cu")
		(hatch none 0.5)
		(connect_pads
			(clearance 0)
		)
		(min_thickness 0.25)
		(keepout
			(tracks not_allowed)
			(vias allowed)
			(pads allowed)
			(copperpour not_allowed)
			(footprints allowed)
		)
		(placement
			(enabled no)
			(sheetname "")
		)
		(fill yes
			(thermal_gap 0.5)
			(thermal_bridge_width 0.5)
			(island_removal_mode 0)
		)
		(polygon
			(pts
				(arc
					(start 118.698518 -18.35023)
					(mid 118.149878 -17.80159)
					(end 117.601238 -18.35023)
				)
				(arc
					(start 117.601238 -19.750024)
					(mid 118.148608 -20.298663)
					(end 118.698518 -19.752564)
				)
				(arc
					(start 118.495064 -19.752564)
					(mid 118.149878 -20.095219)
					(end 117.804692 -19.752564)
				)
				(arc
					(start 117.804692 -19.750024)
					(mid 118.149878 -19.404838)
					(end 118.495064 -19.750024)
				)
				(xy 118.698518 -19.750024) (xy 118.698518 -18.35277)
				(arc
					(start 118.495064 -18.35277)
					(mid 118.149878 -18.695425)
					(end 117.804692 -18.35277)
				)
				(arc
					(start 117.804692 -18.35023)
					(mid 118.149878 -18.005044)
					(end 118.495064 -18.35023)
				)
			)
		)
	)
	(zone
		(layers "F.Cu" "In2.Cu" "In4.Cu")
		(hatch none 0.5)
		(connect_pads
			(clearance 0)
		)
		(min_thickness 0.25)
		(keepout
			(tracks not_allowed)
			(vias allowed)
			(pads allowed)
			(copperpour not_allowed)
			(footprints allowed)
		)
		(placement
			(enabled no)
			(sheetname "")
		)
		(fill yes
			(thermal_gap 0.5)
			(thermal_bridge_width 0.5)
			(island_removal_mode 0)
		)
		(polygon
			(pts
				(arc
					(start 386.298694 -18.35023)
					(mid 385.750054 -17.80159)
					(end 385.201414 -18.35023)
				)
				(arc
					(start 385.201414 -19.750024)
					(mid 385.748784 -20.298663)
					(end 386.298694 -19.752564)
				)
				(arc
					(start 386.09524 -19.752564)
					(mid 385.750054 -20.095219)
					(end 385.404868 -19.752564)
				)
				(arc
					(start 385.404868 -19.750024)
					(mid 385.750054 -19.404838)
					(end 386.09524 -19.750024)
				)
				(xy 386.298694 -19.750024) (xy 386.298694 -18.35277)
				(arc
					(start 386.09524 -18.35277)
					(mid 385.750054 -18.695425)
					(end 385.404868 -18.35277)
				)
				(arc
					(start 385.404868 -18.35023)
					(mid 385.750054 -18.005044)
					(end 386.09524 -18.35023)
				)
			)
		)
	)
	(zone
		(layers "F.Cu" "In2.Cu" "In4.Cu")
		(hatch none 0.5)
		(connect_pads
			(clearance 0)
		)
		(min_thickness 0.25)
		(keepout
			(tracks not_allowed)
			(vias allowed)
			(pads allowed)
			(copperpour not_allowed)
			(footprints allowed)
		)
		(placement
			(enabled no)
			(sheetname "")
		)
		(fill yes
			(thermal_gap 0.5)
			(thermal_bridge_width 0.5)
			(island_removal_mode 0)
		)
		(polygon
			(pts
				(arc
					(start 364.698534 -18.35023)
					(mid 364.149894 -17.80159)
					(end 363.601254 -18.35023)
				)
				(arc
					(start 363.601254 -19.750024)
					(mid 364.148624 -20.298663)
					(end 364.698534 -19.752564)
				)
				(arc
					(start 364.49508 -19.752564)
					(mid 364.149894 -20.095219)
					(end 363.804708 -19.752564)
				)
				(arc
					(start 363.804708 -19.750024)
					(mid 364.149894 -19.404838)
					(end 364.49508 -19.750024)
				)
				(xy 364.698534 -19.750024) (xy 364.698534 -18.35277)
				(arc
					(start 364.49508 -18.35277)
					(mid 364.149894 -18.695425)
					(end 363.804708 -18.35277)
				)
				(arc
					(start 363.804708 -18.35023)
					(mid 364.149894 -18.005044)
					(end 364.49508 -18.35023)
				)
			)
		)
	)
	(zone
		(layers "F.Cu" "In2.Cu" "In4.Cu")
		(hatch none 0.5)
		(connect_pads
			(clearance 0)
		)
		(min_thickness 0.25)
		(keepout
			(tracks not_allowed)
			(vias allowed)
			(pads allowed)
			(copperpour not_allowed)
			(footprints allowed)
		)
		(placement
			(enabled no)
			(sheetname "")
		)
		(fill yes
			(thermal_gap 0.5)
			(thermal_bridge_width 0.5)
			(island_removal_mode 0)
		)
		(polygon
			(pts
				(arc
					(start 389.898636 -18.35023)
					(mid 389.349996 -17.80159)
					(end 388.801356 -18.35023)
				)
				(arc
					(start 388.801356 -19.750024)
					(mid 389.348726 -20.298663)
					(end 389.898636 -19.752564)
				)
				(arc
					(start 389.695182 -19.752564)
					(mid 389.349996 -20.095219)
					(end 389.00481 -19.752564)
				)
				(arc
					(start 389.00481 -19.750024)
					(mid 389.349996 -19.404838)
					(end 389.695182 -19.750024)
				)
				(xy 389.898636 -19.750024) (xy 389.898636 -18.35277)
				(arc
					(start 389.695182 -18.35277)
					(mid 389.349996 -18.695425)
					(end 389.00481 -18.35277)
				)
				(arc
					(start 389.00481 -18.35023)
					(mid 389.349996 -18.005044)
					(end 389.695182 -18.35023)
				)
			)
		)
	)
	(zone
		(layers "F.Cu" "In2.Cu" "In4.Cu")
		(hatch none 0.5)
		(connect_pads
			(clearance 0)
		)
		(min_thickness 0.25)
		(keepout
			(tracks not_allowed)
			(vias allowed)
			(pads allowed)
			(copperpour not_allowed)
			(footprints allowed)
		)
		(placement
			(enabled no)
			(sheetname "")
		)
		(fill yes
			(thermal_gap 0.5)
			(thermal_bridge_width 0.5)
			(island_removal_mode 0)
		)
		(polygon
			(pts
				(arc
					(start 379.098556 -21.950172)
					(mid 378.549916 -21.401532)
					(end 378.001276 -21.950172)
				)
				(arc
					(start 378.001276 -23.35022)
					(mid 378.548646 -23.898859)
					(end 379.098556 -23.35276)
				)
				(arc
					(start 378.895102 -23.35276)
					(mid 378.549916 -23.695415)
					(end 378.20473 -23.35276)
				)
				(arc
					(start 378.20473 -23.35022)
					(mid 378.549916 -23.005034)
					(end 378.895102 -23.35022)
				)
				(xy 379.098556 -23.35022) (xy 379.098556 -21.952712)
				(arc
					(start 378.895102 -21.952712)
					(mid 378.549916 -22.295367)
					(end 378.20473 -21.952712)
				)
				(arc
					(start 378.20473 -21.950172)
					(mid 378.549916 -21.604986)
					(end 378.895102 -21.950172)
				)
			)
		)
	)
	(zone
		(layers "F.Cu" "In2.Cu" "In4.Cu")
		(hatch none 0.5)
		(connect_pads
			(clearance 0)
		)
		(min_thickness 0.25)
		(keepout
			(tracks not_allowed)
			(vias allowed)
			(pads allowed)
			(copperpour not_allowed)
			(footprints allowed)
		)
		(placement
			(enabled no)
			(sheetname "")
		)
		(fill yes
			(thermal_gap 0.5)
			(thermal_bridge_width 0.5)
			(island_removal_mode 0)
		)
		(polygon
			(pts
				(arc
					(start 362.89869 -20.950174)
					(mid 362.35005 -20.401534)
					(end 361.80141 -20.950174)
				)
				(arc
					(start 361.80141 -22.350222)
					(mid 362.34878 -22.898861)
					(end 362.89869 -22.352762)
				)
				(arc
					(start 362.695236 -22.352762)
					(mid 362.35005 -22.695417)
					(end 362.004864 -22.352762)
				)
				(arc
					(start 362.004864 -22.350222)
					(mid 362.35005 -22.005036)
					(end 362.695236 -22.350222)
				)
				(xy 362.89869 -22.350222) (xy 362.89869 -20.952714)
				(arc
					(start 362.695236 -20.952714)
					(mid 362.35005 -21.295369)
					(end 362.004864 -20.952714)
				)
				(arc
					(start 362.004864 -20.950174)
					(mid 362.35005 -20.604988)
					(end 362.695236 -20.950174)
				)
			)
		)
	)
	(zone
		(layers "F.Cu" "In2.Cu" "In4.Cu")
		(hatch none 0.5)
		(connect_pads
			(clearance 0)
		)
		(min_thickness 0.25)
		(keepout
			(tracks not_allowed)
			(vias allowed)
			(pads allowed)
			(copperpour not_allowed)
			(footprints allowed)
		)
		(placement
			(enabled no)
			(sheetname "")
		)
		(fill yes
			(thermal_gap 0.5)
			(thermal_bridge_width 0.5)
			(island_removal_mode 0)
		)
		(polygon
			(pts
				(arc
					(start 361.098592 -21.950172)
					(mid 360.549952 -21.401532)
					(end 360.001312 -21.950172)
				)
				(arc
					(start 360.001312 -23.35022)
					(mid 360.548682 -23.898859)
					(end 361.098592 -23.35276)
				)
				(arc
					(start 360.895138 -23.35276)
					(mid 360.549952 -23.695415)
					(end 360.204766 -23.35276)
				)
				(arc
					(start 360.204766 -23.35022)
					(mid 360.549952 -23.005034)
					(end 360.895138 -23.35022)
				)
				(xy 361.098592 -23.35022) (xy 361.098592 -21.952712)
				(arc
					(start 360.895138 -21.952712)
					(mid 360.549952 -22.295367)
					(end 360.204766 -21.952712)
				)
				(arc
					(start 360.204766 -21.950172)
					(mid 360.549952 -21.604986)
					(end 360.895138 -21.950172)
				)
			)
		)
	)
	(zone
		(layers "F.Cu" "In2.Cu" "In4.Cu")
		(hatch none 0.5)
		(connect_pads
			(clearance 0)
		)
		(min_thickness 0.25)
		(keepout
			(tracks not_allowed)
			(vias allowed)
			(pads allowed)
			(copperpour not_allowed)
			(footprints allowed)
		)
		(placement
			(enabled no)
			(sheetname "")
		)
		(fill yes
			(thermal_gap 0.5)
			(thermal_bridge_width 0.5)
			(island_removal_mode 0)
		)
		(polygon
			(pts
				(arc
					(start 142.098522 -17.349978)
					(mid 141.549882 -16.801338)
					(end 141.001242 -17.349978)
				)
				(arc
					(start 141.001242 -18.750026)
					(mid 141.548612 -19.298665)
					(end 142.098522 -18.752566)
				)
				(arc
					(start 141.895068 -18.752566)
					(mid 141.549882 -19.095221)
					(end 141.204696 -18.752566)
				)
				(arc
					(start 141.204696 -18.750026)
					(mid 141.549882 -18.40484)
					(end 141.895068 -18.750026)
				)
				(xy 142.098522 -18.750026) (xy 142.098522 -17.352518)
				(arc
					(start 141.895068 -17.352518)
					(mid 141.549882 -17.695173)
					(end 141.204696 -17.352518)
				)
				(arc
					(start 141.204696 -17.349978)
					(mid 141.549882 -17.004792)
					(end 141.895068 -17.349978)
				)
			)
		)
	)
	(zone
		(layers "F.Cu" "In2.Cu" "In4.Cu")
		(hatch none 0.5)
		(connect_pads
			(clearance 0)
		)
		(min_thickness 0.25)
		(keepout
			(tracks not_allowed)
			(vias allowed)
			(pads allowed)
			(copperpour not_allowed)
			(footprints allowed)
		)
		(placement
			(enabled no)
			(sheetname "")
		)
		(fill yes
			(thermal_gap 0.5)
			(thermal_bridge_width 0.5)
			(island_removal_mode 0)
		)
		(polygon
			(pts
				(arc
					(start 357.49865 -18.35023)
					(mid 356.95001 -17.80159)
					(end 356.40137 -18.35023)
				)
				(arc
					(start 356.40137 -19.750024)
					(mid 356.94874 -20.298663)
					(end 357.49865 -19.752564)
				)
				(arc
					(start 357.295196 -19.752564)
					(mid 356.95001 -20.095219)
					(end 356.604824 -19.752564)
				)
				(arc
					(start 356.604824 -19.750024)
					(mid 356.95001 -19.404838)
					(end 357.295196 -19.750024)
				)
				(xy 357.49865 -19.750024) (xy 357.49865 -18.35277)
				(arc
					(start 357.295196 -18.35277)
					(mid 356.95001 -18.695425)
					(end 356.604824 -18.35277)
				)
				(arc
					(start 356.604824 -18.35023)
					(mid 356.95001 -18.005044)
					(end 357.295196 -18.35023)
				)
			)
		)
	)
	(zone
		(layers "F.Cu" "In2.Cu" "In4.Cu")
		(hatch none 0.5)
		(connect_pads
			(clearance 0)
		)
		(min_thickness 0.25)
		(keepout
			(tracks not_allowed)
			(vias allowed)
			(pads allowed)
			(copperpour not_allowed)
			(footprints allowed)
		)
		(placement
			(enabled no)
			(sheetname "")
		)
		(fill yes
			(thermal_gap 0.5)
			(thermal_bridge_width 0.5)
			(island_removal_mode 0)
		)
		(polygon
			(pts
				(arc
					(start 389.898636 -21.950172)
					(mid 389.349996 -21.401532)
					(end 388.801356 -21.950172)
				)
				(arc
					(start 388.801356 -23.35022)
					(mid 389.348726 -23.898859)
					(end 389.898636 -23.35276)
				)
				(arc
					(start 389.695182 -23.35276)
					(mid 389.349996 -23.695415)
					(end 389.00481 -23.35276)
				)
				(arc
					(start 389.00481 -23.35022)
					(mid 389.349996 -23.005034)
					(end 389.695182 -23.35022)
				)
				(xy 389.898636 -23.35022) (xy 389.898636 -21.952712)
				(arc
					(start 389.695182 -21.952712)
					(mid 389.349996 -22.295367)
					(end 389.00481 -21.952712)
				)
				(arc
					(start 389.00481 -21.950172)
					(mid 389.349996 -21.604986)
					(end 389.695182 -21.950172)
				)
			)
		)
	)
	(zone
		(layers "F.Cu" "In2.Cu" "In4.Cu")
		(hatch none 0.5)
		(connect_pads
			(clearance 0)
		)
		(min_thickness 0.25)
		(keepout
			(tracks not_allowed)
			(vias allowed)
			(pads allowed)
			(copperpour not_allowed)
			(footprints allowed)
		)
		(placement
			(enabled no)
			(sheetname "")
		)
		(fill yes
			(thermal_gap 0.5)
			(thermal_bridge_width 0.5)
			(island_removal_mode 0)
		)
		(polygon
			(pts
				(arc
					(start 134.898638 -17.349978)
					(mid 134.349998 -16.801338)
					(end 133.801358 -17.349978)
				)
				(arc
					(start 133.801358 -18.750026)
					(mid 134.348728 -19.298665)
					(end 134.898638 -18.752566)
				)
				(arc
					(start 134.695184 -18.752566)
					(mid 134.349998 -19.095221)
					(end 134.004812 -18.752566)
				)
				(arc
					(start 134.004812 -18.750026)
					(mid 134.349998 -18.40484)
					(end 134.695184 -18.750026)
				)
				(xy 134.898638 -18.750026) (xy 134.898638 -17.352518)
				(arc
					(start 134.695184 -17.352518)
					(mid 134.349998 -17.695173)
					(end 134.004812 -17.352518)
				)
				(arc
					(start 134.004812 -17.349978)
					(mid 134.349998 -17.004792)
					(end 134.695184 -17.349978)
				)
			)
		)
	)
	(zone
		(layers "F.Cu" "In2.Cu" "In4.Cu")
		(hatch none 0.5)
		(connect_pads
			(clearance 0)
		)
		(min_thickness 0.25)
		(keepout
			(tracks not_allowed)
			(vias allowed)
			(pads allowed)
			(copperpour not_allowed)
			(footprints allowed)
		)
		(placement
			(enabled no)
			(sheetname "")
		)
		(fill yes
			(thermal_gap 0.5)
			(thermal_bridge_width 0.5)
			(island_removal_mode 0)
		)
		(polygon
			(pts
				(arc
					(start 136.698736 -18.35023)
					(mid 136.150096 -17.80159)
					(end 135.601456 -18.35023)
				)
				(arc
					(start 135.601456 -19.750024)
					(mid 136.148826 -20.298663)
					(end 136.698736 -19.752564)
				)
				(arc
					(start 136.495282 -19.752564)
					(mid 136.150096 -20.095219)
					(end 135.80491 -19.752564)
				)
				(arc
					(start 135.80491 -19.750024)
					(mid 136.150096 -19.404838)
					(end 136.495282 -19.750024)
				)
				(xy 136.698736 -19.750024) (xy 136.698736 -18.35277)
				(arc
					(start 136.495282 -18.35277)
					(mid 136.150096 -18.695425)
					(end 135.80491 -18.35277)
				)
				(arc
					(start 135.80491 -18.35023)
					(mid 136.150096 -18.005044)
					(end 136.495282 -18.35023)
				)
			)
		)
	)
	(zone
		(layers "F.Cu" "In2.Cu" "In4.Cu")
		(hatch none 0.5)
		(connect_pads
			(clearance 0)
		)
		(min_thickness 0.25)
		(keepout
			(tracks not_allowed)
			(vias allowed)
			(pads allowed)
			(copperpour not_allowed)
			(footprints allowed)
		)
		(placement
			(enabled no)
			(sheetname "")
		)
		(fill yes
			(thermal_gap 0.5)
			(thermal_bridge_width 0.5)
			(island_removal_mode 0)
		)
		(polygon
			(pts
				(arc
					(start 116.898674 -17.349978)
					(mid 116.350034 -16.801338)
					(end 115.801394 -17.349978)
				)
				(arc
					(start 115.801394 -18.750026)
					(mid 116.348764 -19.298665)
					(end 116.898674 -18.752566)
				)
				(arc
					(start 116.69522 -18.752566)
					(mid 116.350034 -19.095221)
					(end 116.004848 -18.752566)
				)
				(arc
					(start 116.004848 -18.750026)
					(mid 116.350034 -18.40484)
					(end 116.69522 -18.750026)
				)
				(xy 116.898674 -18.750026) (xy 116.898674 -17.352518)
				(arc
					(start 116.69522 -17.352518)
					(mid 116.350034 -17.695173)
					(end 116.004848 -17.352518)
				)
				(arc
					(start 116.004848 -17.349978)
					(mid 116.350034 -17.004792)
					(end 116.69522 -17.349978)
				)
			)
		)
	)
	(zone
		(layers "F.Cu" "In2.Cu" "In4.Cu")
		(hatch none 0.5)
		(connect_pads
			(clearance 0)
		)
		(min_thickness 0.25)
		(keepout
			(tracks not_allowed)
			(vias allowed)
			(pads allowed)
			(copperpour not_allowed)
			(footprints allowed)
		)
		(placement
			(enabled no)
			(sheetname "")
		)
		(fill yes
			(thermal_gap 0.5)
			(thermal_bridge_width 0.5)
			(island_removal_mode 0)
		)
		(polygon
			(pts
				(arc
					(start 111.498634 -21.950172)
					(mid 110.949994 -21.401532)
					(end 110.401354 -21.950172)
				)
				(arc
					(start 110.401354 -23.35022)
					(mid 110.948724 -23.898859)
					(end 111.498634 -23.35276)
				)
				(arc
					(start 111.29518 -23.35276)
					(mid 110.949994 -23.695415)
					(end 110.604808 -23.35276)
				)
				(arc
					(start 110.604808 -23.35022)
					(mid 110.949994 -23.005034)
					(end 111.29518 -23.35022)
				)
				(xy 111.498634 -23.35022) (xy 111.498634 -21.952712)
				(arc
					(start 111.29518 -21.952712)
					(mid 110.949994 -22.295367)
					(end 110.604808 -21.952712)
				)
				(arc
					(start 110.604808 -21.950172)
					(mid 110.949994 -21.604986)
					(end 111.29518 -21.950172)
				)
			)
		)
	)
	(zone
		(layers "F.Cu" "In2.Cu" "In4.Cu")
		(hatch none 0.5)
		(connect_pads
			(clearance 0)
		)
		(min_thickness 0.25)
		(keepout
			(tracks not_allowed)
			(vias allowed)
			(pads allowed)
			(copperpour not_allowed)
			(footprints allowed)
		)
		(placement
			(enabled no)
			(sheetname "")
		)
		(fill yes
			(thermal_gap 0.5)
			(thermal_bridge_width 0.5)
			(island_removal_mode 0)
		)
		(polygon
			(pts
				(arc
					(start 120.498616 -20.950174)
					(mid 119.949976 -20.401534)
					(end 119.401336 -20.950174)
				)
				(arc
					(start 119.401336 -22.350222)
					(mid 119.948706 -22.898861)
					(end 120.498616 -22.352762)
				)
				(arc
					(start 120.295162 -22.352762)
					(mid 119.949976 -22.695417)
					(end 119.60479 -22.352762)
				)
				(arc
					(start 119.60479 -22.350222)
					(mid 119.949976 -22.005036)
					(end 120.295162 -22.350222)
				)
				(xy 120.498616 -22.350222) (xy 120.498616 -20.952714)
				(arc
					(start 120.295162 -20.952714)
					(mid 119.949976 -21.295369)
					(end 119.60479 -20.952714)
				)
				(arc
					(start 119.60479 -20.950174)
					(mid 119.949976 -20.604988)
					(end 120.295162 -20.950174)
				)
			)
		)
	)
	(zone
		(layers "F.Cu" "In2.Cu" "In4.Cu")
		(hatch none 0.5)
		(connect_pads
			(clearance 0)
		)
		(min_thickness 0.25)
		(keepout
			(tracks not_allowed)
			(vias allowed)
			(pads allowed)
			(copperpour not_allowed)
			(footprints allowed)
		)
		(placement
			(enabled no)
			(sheetname "")
		)
		(fill yes
			(thermal_gap 0.5)
			(thermal_bridge_width 0.5)
			(island_removal_mode 0)
		)
		(polygon
			(pts
				(arc
					(start 109.698536 -20.950174)
					(mid 109.149896 -20.401534)
					(end 108.601256 -20.950174)
				)
				(arc
					(start 108.601256 -22.350222)
					(mid 109.148626 -22.898861)
					(end 109.698536 -22.352762)
				)
				(arc
					(start 109.495082 -22.352762)
					(mid 109.149896 -22.695417)
					(end 108.80471 -22.352762)
				)
				(arc
					(start 108.80471 -22.350222)
					(mid 109.149896 -22.005036)
					(end 109.495082 -22.350222)
				)
				(xy 109.698536 -22.350222) (xy 109.698536 -20.952714)
				(arc
					(start 109.495082 -20.952714)
					(mid 109.149896 -21.295369)
					(end 108.80471 -20.952714)
				)
				(arc
					(start 108.80471 -20.950174)
					(mid 109.149896 -20.604988)
					(end 109.495082 -20.950174)
				)
			)
		)
	)
	(zone
		(layers "F.Cu" "In2.Cu" "In4.Cu")
		(hatch none 0.5)
		(connect_pads
			(clearance 0)
		)
		(min_thickness 0.25)
		(keepout
			(tracks not_allowed)
			(vias allowed)
			(pads allowed)
			(copperpour not_allowed)
			(footprints allowed)
		)
		(placement
			(enabled no)
			(sheetname "")
		)
		(fill yes
			(thermal_gap 0.5)
			(thermal_bridge_width 0.5)
			(island_removal_mode 0)
		)
		(polygon
			(pts
				(arc
					(start 382.698752 -21.950172)
					(mid 382.150112 -21.401532)
					(end 381.601472 -21.950172)
				)
				(arc
					(start 381.601472 -23.35022)
					(mid 382.148842 -23.898859)
					(end 382.698752 -23.35276)
				)
				(arc
					(start 382.495298 -23.35276)
					(mid 382.150112 -23.695415)
					(end 381.804926 -23.35276)
				)
				(arc
					(start 381.804926 -23.35022)
					(mid 382.150112 -23.005034)
					(end 382.495298 -23.35022)
				)
				(xy 382.698752 -23.35022) (xy 382.698752 -21.952712)
				(arc
					(start 382.495298 -21.952712)
					(mid 382.150112 -22.295367)
					(end 381.804926 -21.952712)
				)
				(arc
					(start 381.804926 -21.950172)
					(mid 382.150112 -21.604986)
					(end 382.495298 -21.950172)
				)
			)
		)
	)
	(zone
		(layers "F.Cu" "In2.Cu" "In4.Cu")
		(hatch none 0.5)
		(connect_pads
			(clearance 0)
		)
		(min_thickness 0.25)
		(keepout
			(tracks not_allowed)
			(vias allowed)
			(pads allowed)
			(copperpour not_allowed)
			(footprints allowed)
		)
		(placement
			(enabled no)
			(sheetname "")
		)
		(fill yes
			(thermal_gap 0.5)
			(thermal_bridge_width 0.5)
			(island_removal_mode 0)
		)
		(polygon
			(pts
				(arc
					(start 115.098576 -18.35023)
					(mid 114.549936 -17.80159)
					(end 114.001296 -18.35023)
				)
				(arc
					(start 114.001296 -19.750024)
					(mid 114.548666 -20.298663)
					(end 115.098576 -19.752564)
				)
				(arc
					(start 114.895122 -19.752564)
					(mid 114.549936 -20.095219)
					(end 114.20475 -19.752564)
				)
				(arc
					(start 114.20475 -19.750024)
					(mid 114.549936 -19.404838)
					(end 114.895122 -19.750024)
				)
				(xy 115.098576 -19.750024) (xy 115.098576 -18.35277)
				(arc
					(start 114.895122 -18.35277)
					(mid 114.549936 -18.695425)
					(end 114.20475 -18.35277)
				)
				(arc
					(start 114.20475 -18.35023)
					(mid 114.549936 -18.005044)
					(end 114.895122 -18.35023)
				)
			)
		)
	)
	(zone
		(layers "F.Cu" "In2.Cu" "In4.Cu")
		(hatch none 0.5)
		(connect_pads
			(clearance 0)
		)
		(min_thickness 0.25)
		(keepout
			(tracks not_allowed)
			(vias allowed)
			(pads allowed)
			(copperpour not_allowed)
			(footprints allowed)
		)
		(placement
			(enabled no)
			(sheetname "")
		)
		(fill yes
			(thermal_gap 0.5)
			(thermal_bridge_width 0.5)
			(island_removal_mode 0)
		)
		(polygon
			(pts
				(arc
					(start 113.298732 -20.950174)
					(mid 112.750092 -20.401534)
					(end 112.201452 -20.950174)
				)
				(arc
					(start 112.201452 -22.350222)
					(mid 112.748822 -22.898861)
					(end 113.298732 -22.352762)
				)
				(arc
					(start 113.095278 -22.352762)
					(mid 112.750092 -22.695417)
					(end 112.404906 -22.352762)
				)
				(arc
					(start 112.404906 -22.350222)
					(mid 112.750092 -22.005036)
					(end 113.095278 -22.350222)
				)
				(xy 113.298732 -22.350222) (xy 113.298732 -20.952714)
				(arc
					(start 113.095278 -20.952714)
					(mid 112.750092 -21.295369)
					(end 112.404906 -20.952714)
				)
				(arc
					(start 112.404906 -20.950174)
					(mid 112.750092 -20.604988)
					(end 113.095278 -20.950174)
				)
			)
		)
	)
	(zone
		(layers "F.Cu" "In2.Cu" "In4.Cu")
		(hatch none 0.5)
		(connect_pads
			(clearance 0)
		)
		(min_thickness 0.25)
		(keepout
			(tracks not_allowed)
			(vias allowed)
			(pads allowed)
			(copperpour not_allowed)
			(footprints allowed)
		)
		(placement
			(enabled no)
			(sheetname "")
		)
		(fill yes
			(thermal_gap 0.5)
			(thermal_bridge_width 0.5)
			(island_removal_mode 0)
		)
		(polygon
			(pts
				(arc
					(start 120.498616 -17.349978)
					(mid 119.949976 -16.801338)
					(end 119.401336 -17.349978)
				)
				(arc
					(start 119.401336 -18.750026)
					(mid 119.948706 -19.298665)
					(end 120.498616 -18.752566)
				)
				(arc
					(start 120.295162 -18.752566)
					(mid 119.949976 -19.095221)
					(end 119.60479 -18.752566)
				)
				(arc
					(start 119.60479 -18.750026)
					(mid 119.949976 -18.40484)
					(end 120.295162 -18.750026)
				)
				(xy 120.498616 -18.750026) (xy 120.498616 -17.352518)
				(arc
					(start 120.295162 -17.352518)
					(mid 119.949976 -17.695173)
					(end 119.60479 -17.352518)
				)
				(arc
					(start 119.60479 -17.349978)
					(mid 119.949976 -17.004792)
					(end 120.295162 -17.349978)
				)
			)
		)
	)
	(zone
		(layers "F.Cu" "In2.Cu" "In4.Cu")
		(hatch none 0.5)
		(connect_pads
			(clearance 0)
		)
		(min_thickness 0.25)
		(keepout
			(tracks not_allowed)
			(vias allowed)
			(pads allowed)
			(copperpour not_allowed)
			(footprints allowed)
		)
		(placement
			(enabled no)
			(sheetname "")
		)
		(fill yes
			(thermal_gap 0.5)
			(thermal_bridge_width 0.5)
			(island_removal_mode 0)
		)
		(polygon
			(pts
				(arc
					(start 388.098538 -17.349978)
					(mid 387.549898 -16.801338)
					(end 387.001258 -17.349978)
				)
				(arc
					(start 387.001258 -18.750026)
					(mid 387.548628 -19.298665)
					(end 388.098538 -18.752566)
				)
				(arc
					(start 387.895084 -18.752566)
					(mid 387.549898 -19.095221)
					(end 387.204712 -18.752566)
				)
				(arc
					(start 387.204712 -18.750026)
					(mid 387.549898 -18.40484)
					(end 387.895084 -18.750026)
				)
				(xy 388.098538 -18.750026) (xy 388.098538 -17.352518)
				(arc
					(start 387.895084 -17.352518)
					(mid 387.549898 -17.695173)
					(end 387.204712 -17.352518)
				)
				(arc
					(start 387.204712 -17.349978)
					(mid 387.549898 -17.004792)
					(end 387.895084 -17.349978)
				)
			)
		)
	)
	(zone
		(layers "F.Cu" "In2.Cu" "In4.Cu")
		(hatch none 0.5)
		(connect_pads
			(clearance 0)
		)
		(min_thickness 0.25)
		(keepout
			(tracks not_allowed)
			(vias allowed)
			(pads allowed)
			(copperpour not_allowed)
			(footprints allowed)
		)
		(placement
			(enabled no)
			(sheetname "")
		)
		(fill yes
			(thermal_gap 0.5)
			(thermal_bridge_width 0.5)
			(island_removal_mode 0)
		)
		(polygon
			(pts
				(arc
					(start 131.298696 -20.950174)
					(mid 130.750056 -20.401534)
					(end 130.201416 -20.950174)
				)
				(arc
					(start 130.201416 -22.350222)
					(mid 130.748786 -22.898861)
					(end 131.298696 -22.352762)
				)
				(arc
					(start 131.095242 -22.352762)
					(mid 130.750056 -22.695417)
					(end 130.40487 -22.352762)
				)
				(arc
					(start 130.40487 -22.350222)
					(mid 130.750056 -22.005036)
					(end 131.095242 -22.350222)
				)
				(xy 131.298696 -22.350222) (xy 131.298696 -20.952714)
				(arc
					(start 131.095242 -20.952714)
					(mid 130.750056 -21.295369)
					(end 130.40487 -20.952714)
				)
				(arc
					(start 130.40487 -20.950174)
					(mid 130.750056 -20.604988)
					(end 131.095242 -20.950174)
				)
			)
		)
	)
	(zone
		(layers "F.Cu" "In2.Cu" "In4.Cu")
		(hatch none 0.5)
		(connect_pads
			(clearance 0)
		)
		(min_thickness 0.25)
		(keepout
			(tracks not_allowed)
			(vias allowed)
			(pads allowed)
			(copperpour not_allowed)
			(footprints allowed)
		)
		(placement
			(enabled no)
			(sheetname "")
		)
		(fill yes
			(thermal_gap 0.5)
			(thermal_bridge_width 0.5)
			(island_removal_mode 0)
		)
		(polygon
			(pts
				(arc
					(start 131.298696 -17.349978)
					(mid 130.750056 -16.801338)
					(end 130.201416 -17.349978)
				)
				(arc
					(start 130.201416 -18.750026)
					(mid 130.748786 -19.298665)
					(end 131.298696 -18.752566)
				)
				(arc
					(start 131.095242 -18.752566)
					(mid 130.750056 -19.095221)
					(end 130.40487 -18.752566)
				)
				(arc
					(start 130.40487 -18.750026)
					(mid 130.750056 -18.40484)
					(end 131.095242 -18.750026)
				)
				(xy 131.298696 -18.750026) (xy 131.298696 -17.352518)
				(arc
					(start 131.095242 -17.352518)
					(mid 130.750056 -17.695173)
					(end 130.40487 -17.352518)
				)
				(arc
					(start 130.40487 -17.349978)
					(mid 130.750056 -17.004792)
					(end 131.095242 -17.349978)
				)
			)
		)
	)
	(zone
		(layers "F.Cu" "In2.Cu" "In4.Cu")
		(hatch none 0.5)
		(connect_pads
			(clearance 0)
		)
		(min_thickness 0.25)
		(keepout
			(tracks not_allowed)
			(vias allowed)
			(pads allowed)
			(copperpour not_allowed)
			(footprints allowed)
		)
		(placement
			(enabled no)
			(sheetname "")
		)
		(fill yes
			(thermal_gap 0.5)
			(thermal_bridge_width 0.5)
			(island_removal_mode 0)
		)
		(polygon
			(pts
				(arc
					(start 140.298678 -21.950172)
					(mid 139.750038 -21.401532)
					(end 139.201398 -21.950172)
				)
				(arc
					(start 139.201398 -23.35022)
					(mid 139.748768 -23.898859)
					(end 140.298678 -23.35276)
				)
				(arc
					(start 140.095224 -23.35276)
					(mid 139.750038 -23.695415)
					(end 139.404852 -23.35276)
				)
				(arc
					(start 139.404852 -23.35022)
					(mid 139.750038 -23.005034)
					(end 140.095224 -23.35022)
				)
				(xy 140.298678 -23.35022) (xy 140.298678 -21.952712)
				(arc
					(start 140.095224 -21.952712)
					(mid 139.750038 -22.295367)
					(end 139.404852 -21.952712)
				)
				(arc
					(start 139.404852 -21.950172)
					(mid 139.750038 -21.604986)
					(end 140.095224 -21.950172)
				)
			)
		)
	)
	(zone
		(layers "F.Cu" "In2.Cu" "In4.Cu")
		(hatch none 0.5)
		(connect_pads
			(clearance 0)
		)
		(min_thickness 0.25)
		(keepout
			(tracks not_allowed)
			(vias allowed)
			(pads allowed)
			(copperpour not_allowed)
			(footprints allowed)
		)
		(placement
			(enabled no)
			(sheetname "")
		)
		(fill yes
			(thermal_gap 0.5)
			(thermal_bridge_width 0.5)
			(island_removal_mode 0)
		)
		(polygon
			(pts
				(arc
					(start 382.698752 -18.35023)
					(mid 382.150112 -17.80159)
					(end 381.601472 -18.35023)
				)
				(arc
					(start 381.601472 -19.750024)
					(mid 382.148842 -20.298663)
					(end 382.698752 -19.752564)
				)
				(arc
					(start 382.495298 -19.752564)
					(mid 382.150112 -20.095219)
					(end 381.804926 -19.752564)
				)
				(arc
					(start 381.804926 -19.750024)
					(mid 382.150112 -19.404838)
					(end 382.495298 -19.750024)
				)
				(xy 382.698752 -19.750024) (xy 382.698752 -18.35277)
				(arc
					(start 382.495298 -18.35277)
					(mid 382.150112 -18.695425)
					(end 381.804926 -18.35277)
				)
				(arc
					(start 381.804926 -18.35023)
					(mid 382.150112 -18.005044)
					(end 382.495298 -18.35023)
				)
			)
		)
	)
	(zone
		(layers "F.Cu" "In2.Cu" "In4.Cu")
		(hatch none 0.5)
		(connect_pads
			(clearance 0)
		)
		(min_thickness 0.25)
		(keepout
			(tracks not_allowed)
			(vias allowed)
			(pads allowed)
			(copperpour not_allowed)
			(footprints allowed)
		)
		(placement
			(enabled no)
			(sheetname "")
		)
		(fill yes
			(thermal_gap 0.5)
			(thermal_bridge_width 0.5)
			(island_removal_mode 0)
		)
		(polygon
			(pts
				(arc
					(start 359.298748 -17.349978)
					(mid 358.750108 -16.801338)
					(end 358.201468 -17.349978)
				)
				(arc
					(start 358.201468 -18.750026)
					(mid 358.748838 -19.298665)
					(end 359.298748 -18.752566)
				)
				(arc
					(start 359.095294 -18.752566)
					(mid 358.750108 -19.095221)
					(end 358.404922 -18.752566)
				)
				(arc
					(start 358.404922 -18.750026)
					(mid 358.750108 -18.40484)
					(end 359.095294 -18.750026)
				)
				(xy 359.298748 -18.750026) (xy 359.298748 -17.352518)
				(arc
					(start 359.095294 -17.352518)
					(mid 358.750108 -17.695173)
					(end 358.404922 -17.352518)
				)
				(arc
					(start 358.404922 -17.349978)
					(mid 358.750108 -17.004792)
					(end 359.095294 -17.349978)
				)
			)
		)
	)
	(zone
		(layers "F.Cu" "In2.Cu" "In4.Cu")
		(hatch none 0.5)
		(connect_pads
			(clearance 0)
		)
		(min_thickness 0.25)
		(keepout
			(tracks not_allowed)
			(vias allowed)
			(pads allowed)
			(copperpour not_allowed)
			(footprints allowed)
		)
		(placement
			(enabled no)
			(sheetname "")
		)
		(fill yes
			(thermal_gap 0.5)
			(thermal_bridge_width 0.5)
			(island_removal_mode 0)
		)
		(polygon
			(pts
				(arc
					(start 361.098592 -18.35023)
					(mid 360.549952 -17.80159)
					(end 360.001312 -18.35023)
				)
				(arc
					(start 360.001312 -19.750024)
					(mid 360.548682 -20.298663)
					(end 361.098592 -19.752564)
				)
				(arc
					(start 360.895138 -19.752564)
					(mid 360.549952 -20.095219)
					(end 360.204766 -19.752564)
				)
				(arc
					(start 360.204766 -19.750024)
					(mid 360.549952 -19.404838)
					(end 360.895138 -19.750024)
				)
				(xy 361.098592 -19.750024) (xy 361.098592 -18.35277)
				(arc
					(start 360.895138 -18.35277)
					(mid 360.549952 -18.695425)
					(end 360.204766 -18.35277)
				)
				(arc
					(start 360.204766 -18.35023)
					(mid 360.549952 -18.005044)
					(end 360.895138 -18.35023)
				)
			)
		)
	)
	(zone
		(layers "F.Cu" "In2.Cu" "In4.Cu")
		(hatch none 0.5)
		(connect_pads
			(clearance 0)
		)
		(min_thickness 0.25)
		(keepout
			(tracks not_allowed)
			(vias allowed)
			(pads allowed)
			(copperpour not_allowed)
			(footprints allowed)
		)
		(placement
			(enabled no)
			(sheetname "")
		)
		(fill yes
			(thermal_gap 0.5)
			(thermal_bridge_width 0.5)
			(island_removal_mode 0)
		)
		(polygon
			(pts
				(arc
					(start 357.49865 -21.950172)
					(mid 356.95001 -21.401532)
					(end 356.40137 -21.950172)
				)
				(arc
					(start 356.40137 -23.35022)
					(mid 356.94874 -23.898859)
					(end 357.49865 -23.35276)
				)
				(arc
					(start 357.295196 -23.35276)
					(mid 356.95001 -23.695415)
					(end 356.604824 -23.35276)
				)
				(arc
					(start 356.604824 -23.35022)
					(mid 356.95001 -23.005034)
					(end 357.295196 -23.35022)
				)
				(xy 357.49865 -23.35022) (xy 357.49865 -21.952712)
				(arc
					(start 357.295196 -21.952712)
					(mid 356.95001 -22.295367)
					(end 356.604824 -21.952712)
				)
				(arc
					(start 356.604824 -21.950172)
					(mid 356.95001 -21.604986)
					(end 357.295196 -21.950172)
				)
			)
		)
	)
	(zone
		(layers "F.Cu" "In2.Cu" "In4.Cu")
		(hatch none 0.5)
		(connect_pads
			(clearance 0)
		)
		(min_thickness 0.25)
		(keepout
			(tracks not_allowed)
			(vias allowed)
			(pads allowed)
			(copperpour not_allowed)
			(footprints allowed)
		)
		(placement
			(enabled no)
			(sheetname "")
		)
		(fill yes
			(thermal_gap 0.5)
			(thermal_bridge_width 0.5)
			(island_removal_mode 0)
		)
		(polygon
			(pts
				(arc
					(start 133.09854 -21.950172)
					(mid 132.5499 -21.401532)
					(end 132.00126 -21.950172)
				)
				(arc
					(start 132.00126 -23.35022)
					(mid 132.54863 -23.898859)
					(end 133.09854 -23.35276)
				)
				(arc
					(start 132.895086 -23.35276)
					(mid 132.5499 -23.695415)
					(end 132.204714 -23.35276)
				)
				(arc
					(start 132.204714 -23.35022)
					(mid 132.5499 -23.005034)
					(end 132.895086 -23.35022)
				)
				(xy 133.09854 -23.35022) (xy 133.09854 -21.952712)
				(arc
					(start 132.895086 -21.952712)
					(mid 132.5499 -22.295367)
					(end 132.204714 -21.952712)
				)
				(arc
					(start 132.204714 -21.950172)
					(mid 132.5499 -21.604986)
					(end 132.895086 -21.950172)
				)
			)
		)
	)
	(zone
		(layers "F.Cu" "In2.Cu" "In4.Cu")
		(hatch none 0.5)
		(connect_pads
			(clearance 0)
		)
		(min_thickness 0.25)
		(keepout
			(tracks not_allowed)
			(vias allowed)
			(pads allowed)
			(copperpour not_allowed)
			(footprints allowed)
		)
		(placement
			(enabled no)
			(sheetname "")
		)
		(fill yes
			(thermal_gap 0.5)
			(thermal_bridge_width 0.5)
			(island_removal_mode 0)
		)
		(polygon
			(pts
				(arc
					(start 138.49858 -20.950174)
					(mid 137.94994 -20.401534)
					(end 137.4013 -20.950174)
				)
				(arc
					(start 137.4013 -22.350222)
					(mid 137.94867 -22.898861)
					(end 138.49858 -22.352762)
				)
				(arc
					(start 138.295126 -22.352762)
					(mid 137.94994 -22.695417)
					(end 137.604754 -22.352762)
				)
				(arc
					(start 137.604754 -22.350222)
					(mid 137.94994 -22.005036)
					(end 138.295126 -22.350222)
				)
				(xy 138.49858 -22.350222) (xy 138.49858 -20.952714)
				(arc
					(start 138.295126 -20.952714)
					(mid 137.94994 -21.295369)
					(end 137.604754 -20.952714)
				)
				(arc
					(start 137.604754 -20.950174)
					(mid 137.94994 -20.604988)
					(end 138.295126 -20.950174)
				)
			)
		)
	)
	(zone
		(layers "F.Cu" "In2.Cu" "In4.Cu")
		(hatch none 0.5)
		(connect_pads
			(clearance 0)
		)
		(min_thickness 0.25)
		(keepout
			(tracks not_allowed)
			(vias allowed)
			(pads allowed)
			(copperpour not_allowed)
			(footprints allowed)
		)
		(placement
			(enabled no)
			(sheetname "")
		)
		(fill yes
			(thermal_gap 0.5)
			(thermal_bridge_width 0.5)
			(island_removal_mode 0)
		)
		(polygon
			(pts
				(arc
					(start 362.89869 -17.349978)
					(mid 362.35005 -16.801338)
					(end 361.80141 -17.349978)
				)
				(arc
					(start 361.80141 -18.750026)
					(mid 362.34878 -19.298665)
					(end 362.89869 -18.752566)
				)
				(arc
					(start 362.695236 -18.752566)
					(mid 362.35005 -19.095221)
					(end 362.004864 -18.752566)
				)
				(arc
					(start 362.004864 -18.750026)
					(mid 362.35005 -18.40484)
					(end 362.695236 -18.750026)
				)
				(xy 362.89869 -18.750026) (xy 362.89869 -17.352518)
				(arc
					(start 362.695236 -17.352518)
					(mid 362.35005 -17.695173)
					(end 362.004864 -17.352518)
				)
				(arc
					(start 362.004864 -17.349978)
					(mid 362.35005 -17.004792)
					(end 362.695236 -17.349978)
				)
			)
		)
	)
	(zone
		(layers "F.Cu" "In2.Cu" "In4.Cu" "In7.Cu" "In9.Cu")
		(hatch none 0.5)
		(connect_pads
			(clearance 0)
		)
		(min_thickness 0.25)
		(keepout
			(tracks not_allowed)
			(vias allowed)
			(pads allowed)
			(copperpour not_allowed)
			(footprints allowed)
		)
		(placement
			(enabled no)
			(sheetname "")
		)
		(fill yes
			(thermal_gap 0.5)
			(thermal_bridge_width 0.5)
			(island_removal_mode 0)
		)
		(polygon
			(pts
				(arc
					(start 278.23668 -348.15653)
					(mid 277.68804 -348.70517)
					(end 278.23668 -349.25381)
				)
				(arc
					(start 279.636728 -349.25381)
					(mid 280.023776 -349.094014)
					(end 280.185368 -348.70771)
				)
				(arc
					(start 280.030428 -348.70771)
					(mid 279.636728 -349.098878)
					(end 279.243028 -348.70771)
				)
				(arc
					(start 278.63038 -348.70771)
					(mid 278.23668 -349.098878)
					(end 277.84298 -348.70771)
				)
				(arc
					(start 277.84298 -348.70517)
					(mid 278.23668 -348.31147)
					(end 278.63038 -348.70517)
				)
				(arc
					(start 279.243028 -348.70517)
					(mid 279.636728 -348.31147)
					(end 280.030428 -348.70517)
				)
				(arc
					(start 280.185368 -348.70517)
					(mid 280.024675 -348.317223)
					(end 279.636728 -348.15653)
				)
				(xy 278.236934 -348.15653)
			)
		)
	)
	(zone
		(layers "F.Cu" "In2.Cu" "In4.Cu" "In7.Cu" "In9.Cu")
		(hatch none 0.5)
		(connect_pads
			(clearance 0)
		)
		(min_thickness 0.25)
		(keepout
			(tracks not_allowed)
			(vias allowed)
			(pads allowed)
			(copperpour not_allowed)
			(footprints allowed)
		)
		(placement
			(enabled no)
			(sheetname "")
		)
		(fill yes
			(thermal_gap 0.5)
			(thermal_bridge_width 0.5)
			(island_removal_mode 0)
		)
		(polygon
			(pts
				(arc
					(start 281.47391 -157.499812)
					(mid 281.130538 -156.883996)
					(end 280.42616 -156.852366)
				)
				(xy 278.426418 -157.85211)
				(arc
					(start 278.426418 -157.852364)
					(mid 278.102619 -158.823508)
					(end 279.073864 -159.147256)
				)
				(xy 280.363676 -158.50235)
				(arc
					(start 279.296114 -158.50235)
					(mid 278.750014 -159.045916)
					(end 278.203914 -158.50235)
				)
				(arc
					(start 278.203914 -158.49981)
					(mid 278.750014 -157.95371)
					(end 279.296114 -158.49981)
				)
				(xy 280.368756 -158.49981)
				(arc
					(start 281.07386 -158.147258)
					(mid 281.365177 -157.881433)
					(end 281.47391 -157.502352)
				)
				(arc
					(start 281.29611 -157.502352)
					(mid 280.75001 -158.045918)
					(end 280.20391 -157.502352)
				)
				(arc
					(start 280.20391 -157.499812)
					(mid 280.75001 -156.953712)
					(end 281.29611 -157.499812)
				)
			)
		)
	)
	(zone
		(layers "F.Cu" "In2.Cu" "In4.Cu" "In7.Cu" "In9.Cu")
		(hatch none 0.5)
		(connect_pads
			(clearance 0)
		)
		(min_thickness 0.25)
		(keepout
			(tracks not_allowed)
			(vias allowed)
			(pads allowed)
			(copperpour not_allowed)
			(footprints allowed)
		)
		(placement
			(enabled no)
			(sheetname "")
		)
		(fill yes
			(thermal_gap 0.5)
			(thermal_bridge_width 0.5)
			(island_removal_mode 0)
		)
		(polygon
			(pts
				(arc
					(start 281.47391 -161.499804)
					(mid 281.130538 -160.883988)
					(end 280.42616 -160.852358)
				)
				(xy 278.426418 -161.852102)
				(arc
					(start 278.426418 -161.852356)
					(mid 278.102619 -162.8235)
					(end 279.073864 -163.147248)
				)
				(xy 280.363676 -162.502342)
				(arc
					(start 279.296114 -162.502342)
					(mid 278.750014 -163.045908)
					(end 278.203914 -162.502342)
				)
				(arc
					(start 278.203914 -162.499802)
					(mid 278.750014 -161.953702)
					(end 279.296114 -162.499802)
				)
				(xy 280.368756 -162.499802)
				(arc
					(start 281.07386 -162.14725)
					(mid 281.365177 -161.881425)
					(end 281.47391 -161.502344)
				)
				(arc
					(start 281.29611 -161.502344)
					(mid 280.75001 -162.04591)
					(end 280.20391 -161.502344)
				)
				(arc
					(start 280.20391 -161.499804)
					(mid 280.75001 -160.953704)
					(end 281.29611 -161.499804)
				)
			)
		)
	)
	(zone
		(layers "F.Cu" "In2.Cu" "In4.Cu" "In7.Cu" "In9.Cu")
		(hatch none 0.5)
		(connect_pads
			(clearance 0)
		)
		(min_thickness 0.25)
		(keepout
			(tracks not_allowed)
			(vias allowed)
			(pads allowed)
			(copperpour not_allowed)
			(footprints allowed)
		)
		(placement
			(enabled no)
			(sheetname "")
		)
		(fill yes
			(thermal_gap 0.5)
			(thermal_bridge_width 0.5)
			(island_removal_mode 0)
		)
		(polygon
			(pts
				(arc
					(start 281.47645 -169.499788)
					(mid 281.131922 -168.881841)
					(end 280.425144 -168.850056)
				)
				(xy 280.423874 -168.84777) (xy 278.424132 -169.847768) (xy 278.424132 -169.848022)
				(arc
					(start 278.425148 -169.850054)
					(mid 278.100282 -170.824652)
					(end 279.07488 -171.149518)
				)
				(xy 279.07615 -171.151804) (xy 280.375106 -170.502326)
				(arc
					(start 279.296114 -170.502326)
					(mid 278.750014 -171.045892)
					(end 278.203914 -170.502326)
				)
				(arc
					(start 278.203914 -170.499786)
					(mid 278.750014 -169.953686)
					(end 279.296114 -170.499786)
				)
				(xy 280.375614 -170.499786) (xy 280.375614 -170.502072) (xy 281.076146 -170.151806)
				(arc
					(start 281.074876 -170.14952)
					(mid 281.367273 -169.882771)
					(end 281.47645 -169.502328)
				)
				(arc
					(start 281.29611 -169.502328)
					(mid 280.75001 -170.045894)
					(end 280.20391 -169.502328)
				)
				(arc
					(start 280.20391 -169.499788)
					(mid 280.75001 -168.953688)
					(end 281.29611 -169.499788)
				)
			)
		)
	)
	(zone
		(layers "F.Cu" "In2.Cu" "In4.Cu" "In7.Cu" "In9.Cu")
		(hatch none 0.5)
		(connect_pads
			(clearance 0)
		)
		(min_thickness 0.25)
		(keepout
			(tracks not_allowed)
			(vias allowed)
			(pads allowed)
			(copperpour not_allowed)
			(footprints allowed)
		)
		(placement
			(enabled no)
			(sheetname "")
		)
		(fill yes
			(thermal_gap 0.5)
			(thermal_bridge_width 0.5)
			(island_removal_mode 0)
		)
		(polygon
			(pts
				(arc
					(start 238.77651 -49.200054)
					(mid 238.431982 -48.582107)
					(end 237.725204 -48.550322)
				)
				(xy 237.723934 -48.548036) (xy 235.724192 -49.548034) (xy 235.724192 -49.548288)
				(arc
					(start 235.725208 -49.55032)
					(mid 235.400342 -50.524918)
					(end 236.37494 -50.849784)
				)
				(xy 236.37621 -50.85207) (xy 237.675166 -50.202592)
				(arc
					(start 236.596174 -50.202592)
					(mid 236.050074 -50.746158)
					(end 235.503974 -50.202592)
				)
				(arc
					(start 235.503974 -50.200052)
					(mid 236.050074 -49.653952)
					(end 236.596174 -50.200052)
				)
				(xy 237.675674 -50.200052) (xy 237.675674 -50.202338) (xy 238.376206 -49.852072)
				(arc
					(start 238.374936 -49.849786)
					(mid 238.667333 -49.583037)
					(end 238.77651 -49.202594)
				)
				(arc
					(start 238.59617 -49.202594)
					(mid 238.05007 -49.74616)
					(end 237.50397 -49.202594)
				)
				(arc
					(start 237.50397 -49.200054)
					(mid 238.05007 -48.653954)
					(end 238.59617 -49.200054)
				)
			)
		)
	)
	(zone
		(layers "F.Cu" "In2.Cu" "In4.Cu" "In7.Cu" "In9.Cu")
		(hatch none 0.5)
		(connect_pads
			(clearance 0)
		)
		(min_thickness 0.25)
		(keepout
			(tracks not_allowed)
			(vias allowed)
			(pads allowed)
			(copperpour not_allowed)
			(footprints allowed)
		)
		(placement
			(enabled no)
			(sheetname "")
		)
		(fill yes
			(thermal_gap 0.5)
			(thermal_bridge_width 0.5)
			(island_removal_mode 0)
		)
		(polygon
			(pts
				(arc
					(start 238.77651 -73.200006)
					(mid 238.431982 -72.582059)
					(end 237.725204 -72.550274)
				)
				(xy 237.723934 -72.547988) (xy 235.724192 -73.547986) (xy 235.724192 -73.54824)
				(arc
					(start 235.725208 -73.550272)
					(mid 235.400342 -74.52487)
					(end 236.37494 -74.849736)
				)
				(xy 236.37621 -74.852022) (xy 237.675166 -74.202544)
				(arc
					(start 236.596174 -74.202544)
					(mid 236.050074 -74.74611)
					(end 235.503974 -74.202544)
				)
				(arc
					(start 235.503974 -74.200004)
					(mid 236.050074 -73.653904)
					(end 236.596174 -74.200004)
				)
				(xy 237.675674 -74.200004) (xy 237.675674 -74.20229) (xy 238.376206 -73.852024)
				(arc
					(start 238.374936 -73.849738)
					(mid 238.667333 -73.582989)
					(end 238.77651 -73.202546)
				)
				(arc
					(start 238.59617 -73.202546)
					(mid 238.05007 -73.746112)
					(end 237.50397 -73.202546)
				)
				(arc
					(start 237.50397 -73.200006)
					(mid 238.05007 -72.653906)
					(end 238.59617 -73.200006)
				)
			)
		)
	)
	(zone
		(layers "F.Cu" "In2.Cu" "In4.Cu" "In7.Cu" "In9.Cu")
		(hatch none 0.5)
		(connect_pads
			(clearance 0)
		)
		(min_thickness 0.25)
		(keepout
			(tracks not_allowed)
			(vias allowed)
			(pads allowed)
			(copperpour not_allowed)
			(footprints allowed)
		)
		(placement
			(enabled no)
			(sheetname "")
		)
		(fill yes
			(thermal_gap 0.5)
			(thermal_bridge_width 0.5)
			(island_removal_mode 0)
		)
		(polygon
			(pts
				(arc
					(start 281.47645 -165.499796)
					(mid 281.131922 -164.881849)
					(end 280.425144 -164.850064)
				)
				(xy 280.423874 -164.847778) (xy 278.424132 -165.847776) (xy 278.424132 -165.84803)
				(arc
					(start 278.425148 -165.850062)
					(mid 278.100282 -166.82466)
					(end 279.07488 -167.149526)
				)
				(xy 279.07615 -167.151812) (xy 280.375106 -166.502334)
				(arc
					(start 279.296114 -166.502334)
					(mid 278.750014 -167.0459)
					(end 278.203914 -166.502334)
				)
				(arc
					(start 278.203914 -166.499794)
					(mid 278.750014 -165.953694)
					(end 279.296114 -166.499794)
				)
				(xy 280.375614 -166.499794) (xy 280.375614 -166.50208) (xy 281.076146 -166.151814)
				(arc
					(start 281.074876 -166.149528)
					(mid 281.367273 -165.882779)
					(end 281.47645 -165.502336)
				)
				(arc
					(start 281.29611 -165.502336)
					(mid 280.75001 -166.045902)
					(end 280.20391 -165.502336)
				)
				(arc
					(start 280.20391 -165.499796)
					(mid 280.75001 -164.953696)
					(end 281.29611 -165.499796)
				)
			)
		)
	)
	(zone
		(layers "F.Cu" "In2.Cu" "In4.Cu" "In7.Cu" "In9.Cu")
		(hatch none 0.5)
		(connect_pads
			(clearance 0)
		)
		(min_thickness 0.25)
		(keepout
			(tracks not_allowed)
			(vias allowed)
			(pads allowed)
			(copperpour not_allowed)
			(footprints allowed)
		)
		(placement
			(enabled no)
			(sheetname "")
		)
		(fill yes
			(thermal_gap 0.5)
			(thermal_bridge_width 0.5)
			(island_removal_mode 0)
		)
		(polygon
			(pts
				(arc
					(start 238.77651 -65.200022)
					(mid 238.431982 -64.582075)
					(end 237.725204 -64.55029)
				)
				(xy 237.723934 -64.548004) (xy 235.723938 -65.548002)
				(arc
					(start 235.725208 -65.550288)
					(mid 235.400342 -66.524886)
					(end 236.37494 -66.849752)
				)
				(xy 236.37621 -66.852038) (xy 237.674912 -66.20256)
				(arc
					(start 236.596174 -66.20256)
					(mid 236.050074 -66.746126)
					(end 235.503974 -66.20256)
				)
				(arc
					(start 235.503974 -66.20002)
					(mid 236.050074 -65.65392)
					(end 236.596174 -66.20002)
				)
				(xy 237.675674 -66.20002) (xy 237.675674 -66.202306) (xy 238.375952 -65.85204) (xy 238.375952 -65.851786)
				(arc
					(start 238.374936 -65.849754)
					(mid 238.667333 -65.583005)
					(end 238.77651 -65.202562)
				)
				(arc
					(start 238.59617 -65.202562)
					(mid 238.05007 -65.746128)
					(end 237.50397 -65.202562)
				)
				(arc
					(start 237.50397 -65.200022)
					(mid 238.05007 -64.653922)
					(end 238.59617 -65.200022)
				)
			)
		)
	)
	(zone
		(layers "F.Cu" "In2.Cu" "In4.Cu" "In7.Cu" "In9.Cu")
		(hatch none 0.5)
		(connect_pads
			(clearance 0)
		)
		(min_thickness 0.25)
		(keepout
			(tracks not_allowed)
			(vias allowed)
			(pads allowed)
			(copperpour not_allowed)
			(footprints allowed)
		)
		(placement
			(enabled no)
			(sheetname "")
		)
		(fill yes
			(thermal_gap 0.5)
			(thermal_bridge_width 0.5)
			(island_removal_mode 0)
		)
		(polygon
			(pts
				(arc
					(start 278.23668 -326.556624)
					(mid 277.68804 -327.105264)
					(end 278.23668 -327.653904)
				)
				(arc
					(start 279.636728 -327.653904)
					(mid 280.023776 -327.494108)
					(end 280.185368 -327.107804)
				)
				(arc
					(start 280.030428 -327.107804)
					(mid 279.636728 -327.498972)
					(end 279.243028 -327.107804)
				)
				(arc
					(start 278.63038 -327.107804)
					(mid 278.23668 -327.498972)
					(end 277.84298 -327.107804)
				)
				(arc
					(start 277.84298 -327.105264)
					(mid 278.23668 -326.711564)
					(end 278.63038 -327.105264)
				)
				(arc
					(start 279.243028 -327.105264)
					(mid 279.636728 -326.711564)
					(end 280.030428 -327.105264)
				)
				(arc
					(start 280.185368 -327.105264)
					(mid 280.024675 -326.717317)
					(end 279.636728 -326.556624)
				)
				(xy 278.236934 -326.556624)
			)
		)
	)
	(zone
		(layers "F.Cu" "In2.Cu" "In4.Cu" "In7.Cu" "In9.Cu")
		(hatch none 0.5)
		(connect_pads
			(clearance 0)
		)
		(min_thickness 0.25)
		(keepout
			(tracks not_allowed)
			(vias allowed)
			(pads allowed)
			(copperpour not_allowed)
			(footprints allowed)
		)
		(placement
			(enabled no)
			(sheetname "")
		)
		(fill yes
			(thermal_gap 0.5)
			(thermal_bridge_width 0.5)
			(island_removal_mode 0)
		)
		(polygon
			(pts
				(arc
					(start 279.236678 -349.956628)
					(mid 278.688038 -350.505268)
					(end 279.236678 -351.053908)
				)
				(arc
					(start 280.636726 -351.053908)
					(mid 281.023774 -350.894112)
					(end 281.185366 -350.507808)
				)
				(arc
					(start 281.030426 -350.507808)
					(mid 280.636726 -350.898976)
					(end 280.243026 -350.507808)
				)
				(arc
					(start 279.630378 -350.507808)
					(mid 279.236678 -350.898976)
					(end 278.842978 -350.507808)
				)
				(arc
					(start 278.842978 -350.505268)
					(mid 279.236678 -350.111568)
					(end 279.630378 -350.505268)
				)
				(arc
					(start 280.243026 -350.505268)
					(mid 280.636726 -350.111568)
					(end 281.030426 -350.505268)
				)
				(arc
					(start 281.185366 -350.505268)
					(mid 281.024673 -350.117321)
					(end 280.636726 -349.956628)
				)
				(xy 279.236932 -349.956628)
			)
		)
	)
	(zone
		(layers "F.Cu" "In2.Cu" "In4.Cu" "In7.Cu" "In9.Cu")
		(hatch none 0.5)
		(connect_pads
			(clearance 0)
		)
		(min_thickness 0.25)
		(keepout
			(tracks not_allowed)
			(vias allowed)
			(pads allowed)
			(copperpour not_allowed)
			(footprints allowed)
		)
		(placement
			(enabled no)
			(sheetname "")
		)
		(fill yes
			(thermal_gap 0.5)
			(thermal_bridge_width 0.5)
			(island_removal_mode 0)
		)
		(polygon
			(pts
				(arc
					(start 286.436562 -321.156584)
					(mid 285.887922 -321.705224)
					(end 286.436562 -322.253864)
				)
				(arc
					(start 287.83661 -322.253864)
					(mid 288.223658 -322.094068)
					(end 288.38525 -321.707764)
				)
				(arc
					(start 288.23031 -321.707764)
					(mid 287.83661 -322.098932)
					(end 287.44291 -321.707764)
				)
				(arc
					(start 286.830262 -321.707764)
					(mid 286.436562 -322.098932)
					(end 286.042862 -321.707764)
				)
				(arc
					(start 286.042862 -321.705224)
					(mid 286.436562 -321.311524)
					(end 286.830262 -321.705224)
				)
				(arc
					(start 287.44291 -321.705224)
					(mid 287.83661 -321.311524)
					(end 288.23031 -321.705224)
				)
				(arc
					(start 288.38525 -321.705224)
					(mid 288.224557 -321.317277)
					(end 287.83661 -321.156584)
				)
				(xy 286.436816 -321.156584)
			)
		)
	)
	(zone
		(layers "F.Cu" "In2.Cu" "In4.Cu" "In7.Cu" "In9.Cu")
		(hatch none 0.5)
		(connect_pads
			(clearance 0)
		)
		(min_thickness 0.25)
		(keepout
			(tracks not_allowed)
			(vias allowed)
			(pads allowed)
			(copperpour not_allowed)
			(footprints allowed)
		)
		(placement
			(enabled no)
			(sheetname "")
		)
		(fill yes
			(thermal_gap 0.5)
			(thermal_bridge_width 0.5)
			(island_removal_mode 0)
		)
		(polygon
			(pts
				(arc
					(start 286.436562 -299.556424)
					(mid 285.887922 -300.105064)
					(end 286.436562 -300.653704)
				)
				(arc
					(start 287.83661 -300.653704)
					(mid 288.223658 -300.493908)
					(end 288.38525 -300.107604)
				)
				(arc
					(start 288.23031 -300.107604)
					(mid 287.83661 -300.498772)
					(end 287.44291 -300.107604)
				)
				(arc
					(start 286.830262 -300.107604)
					(mid 286.436562 -300.498772)
					(end 286.042862 -300.107604)
				)
				(arc
					(start 286.042862 -300.105064)
					(mid 286.436562 -299.711364)
					(end 286.830262 -300.105064)
				)
				(arc
					(start 287.44291 -300.105064)
					(mid 287.83661 -299.711364)
					(end 288.23031 -300.105064)
				)
				(arc
					(start 288.38525 -300.105064)
					(mid 288.224557 -299.717117)
					(end 287.83661 -299.556424)
				)
				(xy 286.436816 -299.556424)
			)
		)
	)
	(zone
		(layers "F.Cu" "In2.Cu" "In4.Cu" "In7.Cu" "In9.Cu")
		(hatch none 0.5)
		(connect_pads
			(clearance 0)
		)
		(min_thickness 0.25)
		(keepout
			(tracks not_allowed)
			(vias allowed)
			(pads allowed)
			(copperpour not_allowed)
			(footprints allowed)
		)
		(placement
			(enabled no)
			(sheetname "")
		)
		(fill yes
			(thermal_gap 0.5)
			(thermal_bridge_width 0.5)
			(island_removal_mode 0)
		)
		(polygon
			(pts
				(arc
					(start 281.47645 -65.200022)
					(mid 281.131922 -64.582075)
					(end 280.425144 -64.55029)
				)
				(xy 280.423874 -64.548004) (xy 278.424132 -65.548002) (xy 278.424132 -65.548256)
				(arc
					(start 278.425148 -65.550288)
					(mid 278.100282 -66.524886)
					(end 279.07488 -66.849752)
				)
				(xy 279.07615 -66.852038) (xy 280.375106 -66.20256)
				(arc
					(start 279.296114 -66.20256)
					(mid 278.750014 -66.746126)
					(end 278.203914 -66.20256)
				)
				(arc
					(start 278.203914 -66.20002)
					(mid 278.750014 -65.65392)
					(end 279.296114 -66.20002)
				)
				(xy 280.375614 -66.20002) (xy 280.375614 -66.202306) (xy 281.076146 -65.85204)
				(arc
					(start 281.074876 -65.849754)
					(mid 281.367273 -65.583005)
					(end 281.47645 -65.202562)
				)
				(arc
					(start 281.29611 -65.202562)
					(mid 280.75001 -65.746128)
					(end 280.20391 -65.202562)
				)
				(arc
					(start 280.20391 -65.200022)
					(mid 280.75001 -64.653922)
					(end 281.29611 -65.200022)
				)
			)
		)
	)
	(zone
		(layers "F.Cu" "In2.Cu" "In4.Cu" "In7.Cu" "In9.Cu")
		(hatch none 0.5)
		(connect_pads
			(clearance 0)
		)
		(min_thickness 0.25)
		(keepout
			(tracks not_allowed)
			(vias allowed)
			(pads allowed)
			(copperpour not_allowed)
			(footprints allowed)
		)
		(placement
			(enabled no)
			(sheetname "")
		)
		(fill yes
			(thermal_gap 0.5)
			(thermal_bridge_width 0.5)
			(island_removal_mode 0)
		)
		(polygon
			(pts
				(arc
					(start 286.436562 -346.356432)
					(mid 285.887922 -346.905072)
					(end 286.436562 -347.453712)
				)
				(arc
					(start 287.83661 -347.453712)
					(mid 288.223658 -347.293916)
					(end 288.38525 -346.907612)
				)
				(arc
					(start 288.23031 -346.907612)
					(mid 287.83661 -347.29878)
					(end 287.44291 -346.907612)
				)
				(arc
					(start 286.830262 -346.907612)
					(mid 286.436562 -347.29878)
					(end 286.042862 -346.907612)
				)
				(arc
					(start 286.042862 -346.905072)
					(mid 286.436562 -346.511372)
					(end 286.830262 -346.905072)
				)
				(arc
					(start 287.44291 -346.905072)
					(mid 287.83661 -346.511372)
					(end 288.23031 -346.905072)
				)
				(arc
					(start 288.38525 -346.905072)
					(mid 288.224557 -346.517125)
					(end 287.83661 -346.356432)
				)
				(xy 286.436816 -346.356432)
			)
		)
	)
	(zone
		(layers "F.Cu" "In2.Cu" "In4.Cu" "In7.Cu" "In9.Cu")
		(hatch none 0.5)
		(connect_pads
			(clearance 0)
		)
		(min_thickness 0.25)
		(keepout
			(tracks not_allowed)
			(vias allowed)
			(pads allowed)
			(copperpour not_allowed)
			(footprints allowed)
		)
		(placement
			(enabled no)
			(sheetname "")
		)
		(fill yes
			(thermal_gap 0.5)
			(thermal_bridge_width 0.5)
			(island_removal_mode 0)
		)
		(polygon
			(pts
				(arc
					(start 286.436562 -342.75649)
					(mid 285.887922 -343.30513)
					(end 286.436562 -343.85377)
				)
				(arc
					(start 287.83661 -343.85377)
					(mid 288.223658 -343.693974)
					(end 288.38525 -343.30767)
				)
				(arc
					(start 288.23031 -343.30767)
					(mid 287.83661 -343.698838)
					(end 287.44291 -343.30767)
				)
				(arc
					(start 286.830262 -343.30767)
					(mid 286.436562 -343.698838)
					(end 286.042862 -343.30767)
				)
				(arc
					(start 286.042862 -343.30513)
					(mid 286.436562 -342.91143)
					(end 286.830262 -343.30513)
				)
				(arc
					(start 287.44291 -343.30513)
					(mid 287.83661 -342.91143)
					(end 288.23031 -343.30513)
				)
				(arc
					(start 288.38525 -343.30513)
					(mid 288.224557 -342.917183)
					(end 287.83661 -342.75649)
				)
				(xy 286.436816 -342.75649)
			)
		)
	)
	(zone
		(layers "F.Cu" "In2.Cu" "In4.Cu" "In7.Cu" "In9.Cu")
		(hatch none 0.5)
		(connect_pads
			(clearance 0)
		)
		(min_thickness 0.25)
		(keepout
			(tracks not_allowed)
			(vias allowed)
			(pads allowed)
			(copperpour not_allowed)
			(footprints allowed)
		)
		(placement
			(enabled no)
			(sheetname "")
		)
		(fill yes
			(thermal_gap 0.5)
			(thermal_bridge_width 0.5)
			(island_removal_mode 0)
		)
		(polygon
			(pts
				(arc
					(start 281.47645 -57.200038)
					(mid 281.131922 -56.582091)
					(end 280.425144 -56.550306)
				)
				(xy 280.423874 -56.54802) (xy 278.424132 -57.548018) (xy 278.424132 -57.548272)
				(arc
					(start 278.425148 -57.550304)
					(mid 278.100282 -58.524902)
					(end 279.07488 -58.849768)
				)
				(xy 279.07615 -58.852054) (xy 280.375106 -58.202576)
				(arc
					(start 279.296114 -58.202576)
					(mid 278.750014 -58.746142)
					(end 278.203914 -58.202576)
				)
				(arc
					(start 278.203914 -58.200036)
					(mid 278.750014 -57.653936)
					(end 279.296114 -58.200036)
				)
				(xy 280.375614 -58.200036) (xy 280.375614 -58.202322) (xy 281.076146 -57.852056)
				(arc
					(start 281.074876 -57.84977)
					(mid 281.367273 -57.583021)
					(end 281.47645 -57.202578)
				)
				(arc
					(start 281.29611 -57.202578)
					(mid 280.75001 -57.746144)
					(end 280.20391 -57.202578)
				)
				(arc
					(start 280.20391 -57.200038)
					(mid 280.75001 -56.653938)
					(end 281.29611 -57.200038)
				)
			)
		)
	)
	(zone
		(layers "F.Cu" "In2.Cu" "In4.Cu" "In7.Cu" "In9.Cu")
		(hatch none 0.5)
		(connect_pads
			(clearance 0)
		)
		(min_thickness 0.25)
		(keepout
			(tracks not_allowed)
			(vias allowed)
			(pads allowed)
			(copperpour not_allowed)
			(footprints allowed)
		)
		(placement
			(enabled no)
			(sheetname "")
		)
		(fill yes
			(thermal_gap 0.5)
			(thermal_bridge_width 0.5)
			(island_removal_mode 0)
		)
		(polygon
			(pts
				(arc
					(start 238.77651 -169.499788)
					(mid 238.431982 -168.881841)
					(end 237.725204 -168.850056)
				)
				(xy 237.723934 -168.84777) (xy 235.724192 -169.847768) (xy 235.724192 -169.848022)
				(arc
					(start 235.725208 -169.850054)
					(mid 235.400342 -170.824652)
					(end 236.37494 -171.149518)
				)
				(xy 236.37621 -171.151804) (xy 237.675166 -170.502326)
				(arc
					(start 236.596174 -170.502326)
					(mid 236.050074 -171.045892)
					(end 235.503974 -170.502326)
				)
				(arc
					(start 235.503974 -170.499786)
					(mid 236.050074 -169.953686)
					(end 236.596174 -170.499786)
				)
				(xy 237.675674 -170.499786) (xy 237.675674 -170.502072) (xy 238.376206 -170.151806)
				(arc
					(start 238.374936 -170.14952)
					(mid 238.667333 -169.882771)
					(end 238.77651 -169.502328)
				)
				(arc
					(start 238.59617 -169.502328)
					(mid 238.05007 -170.045894)
					(end 237.50397 -169.502328)
				)
				(arc
					(start 237.50397 -169.499788)
					(mid 238.05007 -168.953688)
					(end 238.59617 -169.499788)
				)
			)
		)
	)
	(zone
		(layers "F.Cu" "In2.Cu" "In4.Cu" "In7.Cu" "In9.Cu")
		(hatch none 0.5)
		(connect_pads
			(clearance 0)
		)
		(min_thickness 0.25)
		(keepout
			(tracks not_allowed)
			(vias allowed)
			(pads allowed)
			(copperpour not_allowed)
			(footprints allowed)
		)
		(placement
			(enabled no)
			(sheetname "")
		)
		(fill yes
			(thermal_gap 0.5)
			(thermal_bridge_width 0.5)
			(island_removal_mode 0)
		)
		(polygon
			(pts
				(arc
					(start 221.348808 -407.000202)
					(mid 220.800168 -406.451562)
					(end 220.251528 -407.000202)
				)
				(arc
					(start 220.251528 -408.399996)
					(mid 220.798898 -408.948635)
					(end 221.348808 -408.402536)
				)
				(arc
					(start 221.193868 -408.402536)
					(mid 220.800168 -408.793704)
					(end 220.406468 -408.402536)
				)
				(arc
					(start 220.406468 -408.399996)
					(mid 220.800168 -408.006296)
					(end 221.193868 -408.399996)
				)
				(xy 221.348808 -408.399996) (xy 221.348808 -407.002742)
				(arc
					(start 221.193868 -407.002742)
					(mid 220.800168 -407.39391)
					(end 220.406468 -407.002742)
				)
				(arc
					(start 220.406468 -407.000202)
					(mid 220.800168 -406.606502)
					(end 221.193868 -407.000202)
				)
			)
		)
	)
	(zone
		(layers "F.Cu" "In2.Cu" "In4.Cu" "In7.Cu" "In9.Cu")
		(hatch none 0.5)
		(connect_pads
			(clearance 0)
		)
		(min_thickness 0.25)
		(keepout
			(tracks not_allowed)
			(vias allowed)
			(pads allowed)
			(copperpour not_allowed)
			(footprints allowed)
		)
		(placement
			(enabled no)
			(sheetname "")
		)
		(fill yes
			(thermal_gap 0.5)
			(thermal_bridge_width 0.5)
			(island_removal_mode 0)
		)
		(polygon
			(pts
				(arc
					(start 281.47645 -77.199998)
					(mid 281.131922 -76.582051)
					(end 280.425144 -76.550266)
				)
				(xy 280.423874 -76.54798) (xy 278.424132 -77.547978) (xy 278.424132 -77.548232)
				(arc
					(start 278.425148 -77.550264)
					(mid 278.100282 -78.524862)
					(end 279.07488 -78.849728)
				)
				(xy 279.07615 -78.852014) (xy 280.375106 -78.202536)
				(arc
					(start 279.296114 -78.202536)
					(mid 278.750014 -78.746102)
					(end 278.203914 -78.202536)
				)
				(arc
					(start 278.203914 -78.199996)
					(mid 278.750014 -77.653896)
					(end 279.296114 -78.199996)
				)
				(xy 280.375614 -78.199996) (xy 280.375614 -78.202282) (xy 281.076146 -77.852016)
				(arc
					(start 281.074876 -77.84973)
					(mid 281.367273 -77.582981)
					(end 281.47645 -77.202538)
				)
				(arc
					(start 281.29611 -77.202538)
					(mid 280.75001 -77.746104)
					(end 280.20391 -77.202538)
				)
				(arc
					(start 280.20391 -77.199998)
					(mid 280.75001 -76.653898)
					(end 281.29611 -77.199998)
				)
			)
		)
	)
	(zone
		(layers "F.Cu" "In2.Cu" "In4.Cu" "In7.Cu" "In9.Cu")
		(hatch none 0.5)
		(connect_pads
			(clearance 0)
		)
		(min_thickness 0.25)
		(keepout
			(tracks not_allowed)
			(vias allowed)
			(pads allowed)
			(copperpour not_allowed)
			(footprints allowed)
		)
		(placement
			(enabled no)
			(sheetname "")
		)
		(fill yes
			(thermal_gap 0.5)
			(thermal_bridge_width 0.5)
			(island_removal_mode 0)
		)
		(polygon
			(pts
				(arc
					(start 285.436564 -315.756544)
					(mid 284.887924 -316.305184)
					(end 285.436564 -316.853824)
				)
				(arc
					(start 286.836612 -316.853824)
					(mid 287.22366 -316.694028)
					(end 287.385252 -316.307724)
				)
				(arc
					(start 287.230312 -316.307724)
					(mid 286.836612 -316.698892)
					(end 286.442912 -316.307724)
				)
				(arc
					(start 285.830264 -316.307724)
					(mid 285.436564 -316.698892)
					(end 285.042864 -316.307724)
				)
				(arc
					(start 285.042864 -316.305184)
					(mid 285.436564 -315.911484)
					(end 285.830264 -316.305184)
				)
				(arc
					(start 286.442912 -316.305184)
					(mid 286.836612 -315.911484)
					(end 287.230312 -316.305184)
				)
				(arc
					(start 287.385252 -316.305184)
					(mid 287.224559 -315.917237)
					(end 286.836612 -315.756544)
				)
				(xy 285.436818 -315.756544)
			)
		)
	)
	(zone
		(layers "F.Cu" "In2.Cu" "In4.Cu" "In7.Cu" "In9.Cu")
		(hatch none 0.5)
		(connect_pads
			(clearance 0)
		)
		(min_thickness 0.25)
		(keepout
			(tracks not_allowed)
			(vias allowed)
			(pads allowed)
			(copperpour not_allowed)
			(footprints allowed)
		)
		(placement
			(enabled no)
			(sheetname "")
		)
		(fill yes
			(thermal_gap 0.5)
			(thermal_bridge_width 0.5)
			(island_removal_mode 0)
		)
		(polygon
			(pts
				(arc
					(start 281.47645 -173.49978)
					(mid 281.131922 -172.881833)
					(end 280.425144 -172.850048)
				)
				(xy 280.423874 -172.847762) (xy 278.424132 -173.84776) (xy 278.424132 -173.848014)
				(arc
					(start 278.425148 -173.850046)
					(mid 278.100282 -174.824644)
					(end 279.07488 -175.14951)
				)
				(xy 279.07615 -175.151796) (xy 280.375106 -174.502318)
				(arc
					(start 279.296114 -174.502318)
					(mid 278.750014 -175.045884)
					(end 278.203914 -174.502318)
				)
				(arc
					(start 278.203914 -174.499778)
					(mid 278.750014 -173.953678)
					(end 279.296114 -174.499778)
				)
				(xy 280.375614 -174.499778) (xy 280.375614 -174.502064) (xy 281.076146 -174.151798)
				(arc
					(start 281.074876 -174.149512)
					(mid 281.367273 -173.882763)
					(end 281.47645 -173.50232)
				)
				(arc
					(start 281.29611 -173.50232)
					(mid 280.75001 -174.045886)
					(end 280.20391 -173.50232)
				)
				(arc
					(start 280.20391 -173.49978)
					(mid 280.75001 -172.95368)
					(end 281.29611 -173.49978)
				)
			)
		)
	)
	(zone
		(layers "F.Cu" "In2.Cu" "In4.Cu" "In7.Cu" "In9.Cu")
		(hatch none 0.5)
		(connect_pads
			(clearance 0)
		)
		(min_thickness 0.25)
		(keepout
			(tracks not_allowed)
			(vias allowed)
			(pads allowed)
			(copperpour not_allowed)
			(footprints allowed)
		)
		(placement
			(enabled no)
			(sheetname "")
		)
		(fill yes
			(thermal_gap 0.5)
			(thermal_bridge_width 0.5)
			(island_removal_mode 0)
		)
		(polygon
			(pts
				(arc
					(start 281.47645 -61.20003)
					(mid 281.131922 -60.582083)
					(end 280.425144 -60.550298)
				)
				(xy 280.423874 -60.548012) (xy 278.424132 -61.54801) (xy 278.424132 -61.548264)
				(arc
					(start 278.425148 -61.550296)
					(mid 278.100282 -62.524894)
					(end 279.07488 -62.84976)
				)
				(xy 279.07615 -62.852046) (xy 280.375106 -62.202568)
				(arc
					(start 279.296114 -62.202568)
					(mid 278.750014 -62.746134)
					(end 278.203914 -62.202568)
				)
				(arc
					(start 278.203914 -62.200028)
					(mid 278.750014 -61.653928)
					(end 279.296114 -62.200028)
				)
				(xy 280.375614 -62.200028) (xy 280.375614 -62.202314) (xy 281.076146 -61.852048)
				(arc
					(start 281.074876 -61.849762)
					(mid 281.367273 -61.583013)
					(end 281.47645 -61.20257)
				)
				(arc
					(start 281.29611 -61.20257)
					(mid 280.75001 -61.746136)
					(end 280.20391 -61.20257)
				)
				(arc
					(start 280.20391 -61.20003)
					(mid 280.75001 -60.65393)
					(end 281.29611 -61.20003)
				)
			)
		)
	)
	(zone
		(layers "F.Cu" "In2.Cu" "In4.Cu" "In7.Cu" "In9.Cu")
		(hatch none 0.5)
		(connect_pads
			(clearance 0)
		)
		(min_thickness 0.25)
		(keepout
			(tracks not_allowed)
			(vias allowed)
			(pads allowed)
			(copperpour not_allowed)
			(footprints allowed)
		)
		(placement
			(enabled no)
			(sheetname "")
		)
		(fill yes
			(thermal_gap 0.5)
			(thermal_bridge_width 0.5)
			(island_removal_mode 0)
		)
		(polygon
			(pts
				(arc
					(start 238.77651 -69.200014)
					(mid 238.431982 -68.582067)
					(end 237.725204 -68.550282)
				)
				(xy 237.723934 -68.547996) (xy 235.724192 -69.547994) (xy 235.724192 -69.548248)
				(arc
					(start 235.725208 -69.55028)
					(mid 235.400342 -70.524878)
					(end 236.37494 -70.849744)
				)
				(xy 236.37621 -70.85203) (xy 237.675166 -70.202552)
				(arc
					(start 236.596174 -70.202552)
					(mid 236.050074 -70.746118)
					(end 235.503974 -70.202552)
				)
				(arc
					(start 235.503974 -70.200012)
					(mid 236.050074 -69.653912)
					(end 236.596174 -70.200012)
				)
				(xy 237.675674 -70.200012) (xy 237.675674 -70.202298) (xy 238.376206 -69.852032)
				(arc
					(start 238.374936 -69.849746)
					(mid 238.667333 -69.582997)
					(end 238.77651 -69.202554)
				)
				(arc
					(start 238.59617 -69.202554)
					(mid 238.05007 -69.74612)
					(end 237.50397 -69.202554)
				)
				(arc
					(start 237.50397 -69.200014)
					(mid 238.05007 -68.653914)
					(end 238.59617 -69.200014)
				)
			)
		)
	)
	(zone
		(layers "F.Cu" "In2.Cu" "In4.Cu" "In7.Cu" "In9.Cu")
		(hatch none 0.5)
		(connect_pads
			(clearance 0)
		)
		(min_thickness 0.25)
		(keepout
			(tracks not_allowed)
			(vias allowed)
			(pads allowed)
			(copperpour not_allowed)
			(footprints allowed)
		)
		(placement
			(enabled no)
			(sheetname "")
		)
		(fill yes
			(thermal_gap 0.5)
			(thermal_bridge_width 0.5)
			(island_removal_mode 0)
		)
		(polygon
			(pts
				(arc
					(start 238.77651 -37.200078)
					(mid 238.431982 -36.582131)
					(end 237.725204 -36.550346)
				)
				(xy 237.723934 -36.54806) (xy 235.724192 -37.548058) (xy 235.724192 -37.548312)
				(arc
					(start 235.725208 -37.550344)
					(mid 235.400342 -38.524942)
					(end 236.37494 -38.849808)
				)
				(xy 236.37621 -38.852094) (xy 237.675166 -38.202616)
				(arc
					(start 236.596174 -38.202616)
					(mid 236.050074 -38.746182)
					(end 235.503974 -38.202616)
				)
				(arc
					(start 235.503974 -38.200076)
					(mid 236.050074 -37.653976)
					(end 236.596174 -38.200076)
				)
				(xy 237.675674 -38.200076) (xy 237.675674 -38.202362) (xy 238.376206 -37.852096)
				(arc
					(start 238.374936 -37.84981)
					(mid 238.667333 -37.583061)
					(end 238.77651 -37.202618)
				)
				(arc
					(start 238.59617 -37.202618)
					(mid 238.05007 -37.746184)
					(end 237.50397 -37.202618)
				)
				(arc
					(start 237.50397 -37.200078)
					(mid 238.05007 -36.653978)
					(end 238.59617 -37.200078)
				)
			)
		)
	)
	(zone
		(layers "F.Cu" "In2.Cu" "In4.Cu" "In7.Cu" "In9.Cu")
		(hatch none 0.5)
		(connect_pads
			(clearance 0)
		)
		(min_thickness 0.25)
		(keepout
			(tracks not_allowed)
			(vias allowed)
			(pads allowed)
			(copperpour not_allowed)
			(footprints allowed)
		)
		(placement
			(enabled no)
			(sheetname "")
		)
		(fill yes
			(thermal_gap 0.5)
			(thermal_bridge_width 0.5)
			(island_removal_mode 0)
		)
		(polygon
			(pts
				(arc
					(start 281.47391 -153.49982)
					(mid 281.130538 -152.884004)
					(end 280.42616 -152.852374)
				)
				(xy 278.426418 -153.852118)
				(arc
					(start 278.426418 -153.852372)
					(mid 278.102619 -154.823516)
					(end 279.073864 -155.147264)
				)
				(xy 280.363676 -154.502358)
				(arc
					(start 279.296114 -154.502358)
					(mid 278.750014 -155.045924)
					(end 278.203914 -154.502358)
				)
				(arc
					(start 278.203914 -154.499818)
					(mid 278.750014 -153.953718)
					(end 279.296114 -154.499818)
				)
				(xy 280.368756 -154.499818)
				(arc
					(start 281.07386 -154.147266)
					(mid 281.365177 -153.881441)
					(end 281.47391 -153.50236)
				)
				(arc
					(start 281.29611 -153.50236)
					(mid 280.75001 -154.045926)
					(end 280.20391 -153.50236)
				)
				(arc
					(start 280.20391 -153.49982)
					(mid 280.75001 -152.95372)
					(end 281.29611 -153.49982)
				)
			)
		)
	)
	(zone
		(layers "F.Cu" "In2.Cu" "In4.Cu" "In7.Cu" "In9.Cu")
		(hatch none 0.5)
		(connect_pads
			(clearance 0)
		)
		(min_thickness 0.25)
		(keepout
			(tracks not_allowed)
			(vias allowed)
			(pads allowed)
			(copperpour not_allowed)
			(footprints allowed)
		)
		(placement
			(enabled no)
			(sheetname "")
		)
		(fill yes
			(thermal_gap 0.5)
			(thermal_bridge_width 0.5)
			(island_removal_mode 0)
		)
		(polygon
			(pts
				(arc
					(start 281.47391 -129.499868)
					(mid 281.130538 -128.884052)
					(end 280.42616 -128.852422)
				)
				(xy 278.426418 -129.852166)
				(arc
					(start 278.426418 -129.85242)
					(mid 278.102619 -130.823564)
					(end 279.073864 -131.147312)
				)
				(xy 280.363676 -130.502406)
				(arc
					(start 279.296114 -130.502406)
					(mid 278.750014 -131.045972)
					(end 278.203914 -130.502406)
				)
				(arc
					(start 278.203914 -130.499866)
					(mid 278.750014 -129.953766)
					(end 279.296114 -130.499866)
				)
				(xy 280.368756 -130.499866)
				(arc
					(start 281.07386 -130.147314)
					(mid 281.365177 -129.881489)
					(end 281.47391 -129.502408)
				)
				(arc
					(start 281.29611 -129.502408)
					(mid 280.75001 -130.045974)
					(end 280.20391 -129.502408)
				)
				(arc
					(start 280.20391 -129.499868)
					(mid 280.75001 -128.953768)
					(end 281.29611 -129.499868)
				)
			)
		)
	)
	(zone
		(layers "F.Cu" "In2.Cu" "In4.Cu" "In7.Cu" "In9.Cu")
		(hatch none 0.5)
		(connect_pads
			(clearance 0)
		)
		(min_thickness 0.25)
		(keepout
			(tracks not_allowed)
			(vias allowed)
			(pads allowed)
			(copperpour not_allowed)
			(footprints allowed)
		)
		(placement
			(enabled no)
			(sheetname "")
		)
		(fill yes
			(thermal_gap 0.5)
			(thermal_bridge_width 0.5)
			(island_removal_mode 0)
		)
		(polygon
			(pts
				(arc
					(start 285.436564 -319.356486)
					(mid 284.887924 -319.905126)
					(end 285.436564 -320.453766)
				)
				(arc
					(start 286.836612 -320.453766)
					(mid 287.22366 -320.29397)
					(end 287.385252 -319.907666)
				)
				(arc
					(start 287.230312 -319.907666)
					(mid 286.836612 -320.298834)
					(end 286.442912 -319.907666)
				)
				(arc
					(start 285.830264 -319.907666)
					(mid 285.436564 -320.298834)
					(end 285.042864 -319.907666)
				)
				(arc
					(start 285.042864 -319.905126)
					(mid 285.436564 -319.511426)
					(end 285.830264 -319.905126)
				)
				(arc
					(start 286.442912 -319.905126)
					(mid 286.836612 -319.511426)
					(end 287.230312 -319.905126)
				)
				(arc
					(start 287.385252 -319.905126)
					(mid 287.224559 -319.517179)
					(end 286.836612 -319.356486)
				)
				(xy 285.436818 -319.356486)
			)
		)
	)
	(zone
		(layers "F.Cu" "In2.Cu" "In4.Cu" "In7.Cu" "In9.Cu")
		(hatch none 0.5)
		(connect_pads
			(clearance 0)
		)
		(min_thickness 0.25)
		(keepout
			(tracks not_allowed)
			(vias allowed)
			(pads allowed)
			(copperpour not_allowed)
			(footprints allowed)
		)
		(placement
			(enabled no)
			(sheetname "")
		)
		(fill yes
			(thermal_gap 0.5)
			(thermal_bridge_width 0.5)
			(island_removal_mode 0)
		)
		(polygon
			(pts
				(arc
					(start 278.23668 -312.156602)
					(mid 277.68804 -312.705242)
					(end 278.23668 -313.253882)
				)
				(arc
					(start 279.636728 -313.253882)
					(mid 280.023776 -313.094086)
					(end 280.185368 -312.707782)
				)
				(arc
					(start 280.030428 -312.707782)
					(mid 279.636728 -313.09895)
					(end 279.243028 -312.707782)
				)
				(arc
					(start 278.63038 -312.707782)
					(mid 278.23668 -313.09895)
					(end 277.84298 -312.707782)
				)
				(arc
					(start 277.84298 -312.705242)
					(mid 278.23668 -312.311542)
					(end 278.63038 -312.705242)
				)
				(arc
					(start 279.243028 -312.705242)
					(mid 279.636728 -312.311542)
					(end 280.030428 -312.705242)
				)
				(arc
					(start 280.185368 -312.705242)
					(mid 280.024675 -312.317295)
					(end 279.636728 -312.156602)
				)
				(xy 278.236934 -312.156602)
			)
		)
	)
	(zone
		(layers "F.Cu" "In2.Cu" "In4.Cu" "In7.Cu" "In9.Cu")
		(hatch none 0.5)
		(connect_pads
			(clearance 0)
		)
		(min_thickness 0.25)
		(keepout
			(tracks not_allowed)
			(vias allowed)
			(pads allowed)
			(copperpour not_allowed)
			(footprints allowed)
		)
		(placement
			(enabled no)
			(sheetname "")
		)
		(fill yes
			(thermal_gap 0.5)
			(thermal_bridge_width 0.5)
			(island_removal_mode 0)
		)
		(polygon
			(pts
				(arc
					(start 285.436564 -344.556588)
					(mid 284.887924 -345.105228)
					(end 285.436564 -345.653868)
				)
				(arc
					(start 286.836612 -345.653868)
					(mid 287.22366 -345.494072)
					(end 287.385252 -345.107768)
				)
				(arc
					(start 287.230312 -345.107768)
					(mid 286.836612 -345.498936)
					(end 286.442912 -345.107768)
				)
				(arc
					(start 285.830264 -345.107768)
					(mid 285.436564 -345.498936)
					(end 285.042864 -345.107768)
				)
				(arc
					(start 285.042864 -345.105228)
					(mid 285.436564 -344.711528)
					(end 285.830264 -345.105228)
				)
				(arc
					(start 286.442912 -345.105228)
					(mid 286.836612 -344.711528)
					(end 287.230312 -345.105228)
				)
				(arc
					(start 287.385252 -345.105228)
					(mid 287.224559 -344.717281)
					(end 286.836612 -344.556588)
				)
				(xy 285.436818 -344.556588)
			)
		)
	)
	(zone
		(layers "F.Cu" "In2.Cu" "In4.Cu" "In7.Cu" "In9.Cu")
		(hatch none 0.5)
		(connect_pads
			(clearance 0)
		)
		(min_thickness 0.25)
		(keepout
			(tracks not_allowed)
			(vias allowed)
			(pads allowed)
			(copperpour not_allowed)
			(footprints allowed)
		)
		(placement
			(enabled no)
			(sheetname "")
		)
		(fill yes
			(thermal_gap 0.5)
			(thermal_bridge_width 0.5)
			(island_removal_mode 0)
		)
		(polygon
			(pts
				(arc
					(start 285.436564 -297.75658)
					(mid 284.887924 -298.30522)
					(end 285.436564 -298.85386)
				)
				(arc
					(start 286.836612 -298.85386)
					(mid 287.22366 -298.694064)
					(end 287.385252 -298.30776)
				)
				(arc
					(start 287.230312 -298.30776)
					(mid 286.836612 -298.698928)
					(end 286.442912 -298.30776)
				)
				(arc
					(start 285.830264 -298.30776)
					(mid 285.436564 -298.698928)
					(end 285.042864 -298.30776)
				)
				(arc
					(start 285.042864 -298.30522)
					(mid 285.436564 -297.91152)
					(end 285.830264 -298.30522)
				)
				(arc
					(start 286.442912 -298.30522)
					(mid 286.836612 -297.91152)
					(end 287.230312 -298.30522)
				)
				(arc
					(start 287.385252 -298.30522)
					(mid 287.224559 -297.917273)
					(end 286.836612 -297.75658)
				)
				(xy 285.436818 -297.75658)
			)
		)
	)
	(zone
		(layers "F.Cu" "In2.Cu" "In4.Cu" "In7.Cu" "In9.Cu")
		(hatch none 0.5)
		(connect_pads
			(clearance 0)
		)
		(min_thickness 0.25)
		(keepout
			(tracks not_allowed)
			(vias allowed)
			(pads allowed)
			(copperpour not_allowed)
			(footprints allowed)
		)
		(placement
			(enabled no)
			(sheetname "")
		)
		(fill yes
			(thermal_gap 0.5)
			(thermal_bridge_width 0.5)
			(island_removal_mode 0)
		)
		(polygon
			(pts
				(arc
					(start 285.436564 -301.356522)
					(mid 284.887924 -301.905162)
					(end 285.436564 -302.453802)
				)
				(arc
					(start 286.836612 -302.453802)
					(mid 287.22366 -302.294006)
					(end 287.385252 -301.907702)
				)
				(arc
					(start 287.230312 -301.907702)
					(mid 286.836612 -302.29887)
					(end 286.442912 -301.907702)
				)
				(arc
					(start 285.830264 -301.907702)
					(mid 285.436564 -302.29887)
					(end 285.042864 -301.907702)
				)
				(arc
					(start 285.042864 -301.905162)
					(mid 285.436564 -301.511462)
					(end 285.830264 -301.905162)
				)
				(arc
					(start 286.442912 -301.905162)
					(mid 286.836612 -301.511462)
					(end 287.230312 -301.905162)
				)
				(arc
					(start 287.385252 -301.905162)
					(mid 287.224559 -301.517215)
					(end 286.836612 -301.356522)
				)
				(xy 285.436818 -301.356522)
			)
		)
	)
	(zone
		(layers "F.Cu" "In2.Cu" "In4.Cu" "In7.Cu" "In9.Cu")
		(hatch none 0.5)
		(connect_pads
			(clearance 0)
		)
		(min_thickness 0.25)
		(keepout
			(tracks not_allowed)
			(vias allowed)
			(pads allowed)
			(copperpour not_allowed)
			(footprints allowed)
		)
		(placement
			(enabled no)
			(sheetname "")
		)
		(fill yes
			(thermal_gap 0.5)
			(thermal_bridge_width 0.5)
			(island_removal_mode 0)
		)
		(polygon
			(pts
				(arc
					(start 279.236678 -335.556606)
					(mid 278.688038 -336.105246)
					(end 279.236678 -336.653886)
				)
				(arc
					(start 280.636726 -336.653886)
					(mid 281.023774 -336.49409)
					(end 281.185366 -336.107786)
				)
				(arc
					(start 281.030426 -336.107786)
					(mid 280.636726 -336.498954)
					(end 280.243026 -336.107786)
				)
				(arc
					(start 279.630378 -336.107786)
					(mid 279.236678 -336.498954)
					(end 278.842978 -336.107786)
				)
				(arc
					(start 278.842978 -336.105246)
					(mid 279.236678 -335.711546)
					(end 279.630378 -336.105246)
				)
				(arc
					(start 280.243026 -336.105246)
					(mid 280.636726 -335.711546)
					(end 281.030426 -336.105246)
				)
				(arc
					(start 281.185366 -336.105246)
					(mid 281.024673 -335.717299)
					(end 280.636726 -335.556606)
				)
				(xy 279.236932 -335.556606)
			)
		)
	)
	(zone
		(layers "F.Cu" "In2.Cu" "In4.Cu" "In7.Cu" "In9.Cu")
		(hatch none 0.5)
		(connect_pads
			(clearance 0)
		)
		(min_thickness 0.25)
		(keepout
			(tracks not_allowed)
			(vias allowed)
			(pads allowed)
			(copperpour not_allowed)
			(footprints allowed)
		)
		(placement
			(enabled no)
			(sheetname "")
		)
		(fill yes
			(thermal_gap 0.5)
			(thermal_bridge_width 0.5)
			(island_removal_mode 0)
		)
		(polygon
			(pts
				(arc
					(start 278.23668 -330.156566)
					(mid 277.68804 -330.705206)
					(end 278.23668 -331.253846)
				)
				(arc
					(start 279.636728 -331.253846)
					(mid 280.023776 -331.09405)
					(end 280.185368 -330.707746)
				)
				(arc
					(start 280.030428 -330.707746)
					(mid 279.636728 -331.098914)
					(end 279.243028 -330.707746)
				)
				(arc
					(start 278.63038 -330.707746)
					(mid 278.23668 -331.098914)
					(end 277.84298 -330.707746)
				)
				(arc
					(start 277.84298 -330.705206)
					(mid 278.23668 -330.311506)
					(end 278.63038 -330.705206)
				)
				(arc
					(start 279.243028 -330.705206)
					(mid 279.636728 -330.311506)
					(end 280.030428 -330.705206)
				)
				(arc
					(start 280.185368 -330.705206)
					(mid 280.024675 -330.317259)
					(end 279.636728 -330.156566)
				)
				(xy 278.236934 -330.156566)
			)
		)
	)
	(zone
		(layers "F.Cu" "In2.Cu" "In4.Cu" "In7.Cu" "In9.Cu")
		(hatch none 0.5)
		(connect_pads
			(clearance 0)
		)
		(min_thickness 0.25)
		(keepout
			(tracks not_allowed)
			(vias allowed)
			(pads allowed)
			(copperpour not_allowed)
			(footprints allowed)
		)
		(placement
			(enabled no)
			(sheetname "")
		)
		(fill yes
			(thermal_gap 0.5)
			(thermal_bridge_width 0.5)
			(island_removal_mode 0)
		)
		(polygon
			(pts
				(arc
					(start 281.47645 -177.499772)
					(mid 281.131922 -176.881825)
					(end 280.425144 -176.85004)
				)
				(xy 280.423874 -176.847754) (xy 278.424132 -177.847752) (xy 278.424132 -177.848006)
				(arc
					(start 278.425148 -177.850038)
					(mid 278.100282 -178.824636)
					(end 279.07488 -179.149502)
				)
				(xy 279.07615 -179.151788) (xy 280.375106 -178.50231)
				(arc
					(start 279.296114 -178.50231)
					(mid 278.750014 -179.045876)
					(end 278.203914 -178.50231)
				)
				(arc
					(start 278.203914 -178.49977)
					(mid 278.750014 -177.95367)
					(end 279.296114 -178.49977)
				)
				(xy 280.375614 -178.49977) (xy 280.375614 -178.502056) (xy 281.076146 -178.15179)
				(arc
					(start 281.074876 -178.149504)
					(mid 281.367273 -177.882755)
					(end 281.47645 -177.502312)
				)
				(arc
					(start 281.29611 -177.502312)
					(mid 280.75001 -178.045878)
					(end 280.20391 -177.502312)
				)
				(arc
					(start 280.20391 -177.499772)
					(mid 280.75001 -176.953672)
					(end 281.29611 -177.499772)
				)
			)
		)
	)
	(zone
		(layers "F.Cu" "In2.Cu" "In4.Cu" "In7.Cu" "In9.Cu")
		(hatch none 0.5)
		(connect_pads
			(clearance 0)
		)
		(min_thickness 0.25)
		(keepout
			(tracks not_allowed)
			(vias allowed)
			(pads allowed)
			(copperpour not_allowed)
			(footprints allowed)
		)
		(placement
			(enabled no)
			(sheetname "")
		)
		(fill yes
			(thermal_gap 0.5)
			(thermal_bridge_width 0.5)
			(island_removal_mode 0)
		)
		(polygon
			(pts
				(arc
					(start 279.236678 -331.95641)
					(mid 278.688038 -332.50505)
					(end 279.236678 -333.05369)
				)
				(arc
					(start 280.636726 -333.05369)
					(mid 281.023774 -332.893894)
					(end 281.185366 -332.50759)
				)
				(arc
					(start 281.030426 -332.50759)
					(mid 280.636726 -332.898758)
					(end 280.243026 -332.50759)
				)
				(arc
					(start 279.630378 -332.50759)
					(mid 279.236678 -332.898758)
					(end 278.842978 -332.50759)
				)
				(arc
					(start 278.842978 -332.50505)
					(mid 279.236678 -332.11135)
					(end 279.630378 -332.50505)
				)
				(arc
					(start 280.243026 -332.50505)
					(mid 280.636726 -332.11135)
					(end 281.030426 -332.50505)
				)
				(arc
					(start 281.185366 -332.50505)
					(mid 281.024673 -332.117103)
					(end 280.636726 -331.95641)
				)
				(xy 279.236932 -331.95641)
			)
		)
	)
	(zone
		(layers "F.Cu" "In2.Cu" "In4.Cu" "In7.Cu" "In9.Cu")
		(hatch none 0.5)
		(connect_pads
			(clearance 0)
		)
		(min_thickness 0.25)
		(keepout
			(tracks not_allowed)
			(vias allowed)
			(pads allowed)
			(copperpour not_allowed)
			(footprints allowed)
		)
		(placement
			(enabled no)
			(sheetname "")
		)
		(fill yes
			(thermal_gap 0.5)
			(thermal_bridge_width 0.5)
			(island_removal_mode 0)
		)
		(polygon
			(pts
				(arc
					(start 238.77651 -61.20003)
					(mid 238.431982 -60.582083)
					(end 237.725204 -60.550298)
				)
				(xy 237.723934 -60.548012) (xy 235.724192 -61.54801) (xy 235.724192 -61.548264)
				(arc
					(start 235.725208 -61.550296)
					(mid 235.400342 -62.524894)
					(end 236.37494 -62.84976)
				)
				(xy 236.37621 -62.852046) (xy 237.675166 -62.202568)
				(arc
					(start 236.596174 -62.202568)
					(mid 236.050074 -62.746134)
					(end 235.503974 -62.202568)
				)
				(arc
					(start 235.503974 -62.200028)
					(mid 236.050074 -61.653928)
					(end 236.596174 -62.200028)
				)
				(xy 237.675674 -62.200028) (xy 237.675674 -62.202314) (xy 238.376206 -61.852048)
				(arc
					(start 238.374936 -61.849762)
					(mid 238.667333 -61.583013)
					(end 238.77651 -61.20257)
				)
				(arc
					(start 238.59617 -61.20257)
					(mid 238.05007 -61.746136)
					(end 237.50397 -61.20257)
				)
				(arc
					(start 237.50397 -61.20003)
					(mid 238.05007 -60.65393)
					(end 238.59617 -61.20003)
				)
			)
		)
	)
	(zone
		(layers "F.Cu" "In2.Cu" "In4.Cu" "In7.Cu" "In9.Cu")
		(hatch none 0.5)
		(connect_pads
			(clearance 0)
		)
		(min_thickness 0.25)
		(keepout
			(tracks not_allowed)
			(vias allowed)
			(pads allowed)
			(copperpour not_allowed)
			(footprints allowed)
		)
		(placement
			(enabled no)
			(sheetname "")
		)
		(fill yes
			(thermal_gap 0.5)
			(thermal_bridge_width 0.5)
			(island_removal_mode 0)
		)
		(polygon
			(pts
				(arc
					(start 279.236678 -357.156512)
					(mid 278.688038 -357.705152)
					(end 279.236678 -358.253792)
				)
				(arc
					(start 280.636726 -358.253792)
					(mid 281.023774 -358.093996)
					(end 281.185366 -357.707692)
				)
				(arc
					(start 281.030426 -357.707692)
					(mid 280.636726 -358.09886)
					(end 280.243026 -357.707692)
				)
				(arc
					(start 279.630378 -357.707692)
					(mid 279.236678 -358.09886)
					(end 278.842978 -357.707692)
				)
				(arc
					(start 278.842978 -357.705152)
					(mid 279.236678 -357.311452)
					(end 279.630378 -357.705152)
				)
				(arc
					(start 280.243026 -357.705152)
					(mid 280.636726 -357.311452)
					(end 281.030426 -357.705152)
				)
				(arc
					(start 281.185366 -357.705152)
					(mid 281.024673 -357.317205)
					(end 280.636726 -357.156512)
				)
				(xy 279.236932 -357.156512)
			)
		)
	)
	(zone
		(layers "F.Cu" "In2.Cu" "In4.Cu" "In7.Cu" "In9.Cu")
		(hatch none 0.5)
		(connect_pads
			(clearance 0)
		)
		(min_thickness 0.25)
		(keepout
			(tracks not_allowed)
			(vias allowed)
			(pads allowed)
			(copperpour not_allowed)
			(footprints allowed)
		)
		(placement
			(enabled no)
			(sheetname "")
		)
		(fill yes
			(thermal_gap 0.5)
			(thermal_bridge_width 0.5)
			(island_removal_mode 0)
		)
		(polygon
			(pts
				(arc
					(start 238.77651 -165.499796)
					(mid 238.431982 -164.881849)
					(end 237.725204 -164.850064)
				)
				(xy 237.723934 -164.847778) (xy 235.724192 -165.847776) (xy 235.724192 -165.84803)
				(arc
					(start 235.725208 -165.850062)
					(mid 235.400342 -166.82466)
					(end 236.37494 -167.149526)
				)
				(xy 236.37621 -167.151812) (xy 237.675166 -166.502334)
				(arc
					(start 236.596174 -166.502334)
					(mid 236.050074 -167.0459)
					(end 235.503974 -166.502334)
				)
				(arc
					(start 235.503974 -166.499794)
					(mid 236.050074 -165.953694)
					(end 236.596174 -166.499794)
				)
				(xy 237.675674 -166.499794) (xy 237.675674 -166.50208) (xy 238.376206 -166.151814)
				(arc
					(start 238.374936 -166.149528)
					(mid 238.667333 -165.882779)
					(end 238.77651 -165.502336)
				)
				(arc
					(start 238.59617 -165.502336)
					(mid 238.05007 -166.045902)
					(end 237.50397 -165.502336)
				)
				(arc
					(start 237.50397 -165.499796)
					(mid 238.05007 -164.953696)
					(end 238.59617 -165.499796)
				)
			)
		)
	)
	(zone
		(layers "F.Cu" "In2.Cu" "In4.Cu" "In7.Cu" "In9.Cu")
		(hatch none 0.5)
		(connect_pads
			(clearance 0)
		)
		(min_thickness 0.25)
		(keepout
			(tracks not_allowed)
			(vias allowed)
			(pads allowed)
			(copperpour not_allowed)
			(footprints allowed)
		)
		(placement
			(enabled no)
			(sheetname "")
		)
		(fill yes
			(thermal_gap 0.5)
			(thermal_bridge_width 0.5)
			(island_removal_mode 0)
		)
		(polygon
			(pts
				(arc
					(start 281.47645 -73.200006)
					(mid 281.131922 -72.582059)
					(end 280.425144 -72.550274)
				)
				(xy 280.423874 -72.547988) (xy 278.424132 -73.547986) (xy 278.424132 -73.54824)
				(arc
					(start 278.425148 -73.550272)
					(mid 278.100282 -74.52487)
					(end 279.07488 -74.849736)
				)
				(xy 279.07615 -74.852022) (xy 280.375106 -74.202544)
				(arc
					(start 279.296114 -74.202544)
					(mid 278.750014 -74.74611)
					(end 278.203914 -74.202544)
				)
				(arc
					(start 278.203914 -74.200004)
					(mid 278.750014 -73.653904)
					(end 279.296114 -74.200004)
				)
				(xy 280.375614 -74.200004) (xy 280.375614 -74.20229) (xy 281.076146 -73.852024)
				(arc
					(start 281.074876 -73.849738)
					(mid 281.367273 -73.582989)
					(end 281.47645 -73.202546)
				)
				(arc
					(start 281.29611 -73.202546)
					(mid 280.75001 -73.746112)
					(end 280.20391 -73.202546)
				)
				(arc
					(start 280.20391 -73.200006)
					(mid 280.75001 -72.653906)
					(end 281.29611 -73.200006)
				)
			)
		)
	)
	(zone
		(layers "F.Cu" "In2.Cu" "In4.Cu" "In7.Cu" "In9.Cu")
		(hatch none 0.5)
		(connect_pads
			(clearance 0)
		)
		(min_thickness 0.25)
		(keepout
			(tracks not_allowed)
			(vias allowed)
			(pads allowed)
			(copperpour not_allowed)
			(footprints allowed)
		)
		(placement
			(enabled no)
			(sheetname "")
		)
		(fill yes
			(thermal_gap 0.5)
			(thermal_bridge_width 0.5)
			(island_removal_mode 0)
		)
		(polygon
			(pts
				(arc
					(start 238.77651 -41.20007)
					(mid 238.431982 -40.582123)
					(end 237.725204 -40.550338)
				)
				(xy 237.723934 -40.548052) (xy 235.724192 -41.54805) (xy 235.724192 -41.548304)
				(arc
					(start 235.725208 -41.550336)
					(mid 235.400342 -42.524934)
					(end 236.37494 -42.8498)
				)
				(xy 236.37621 -42.852086) (xy 237.675166 -42.202608)
				(arc
					(start 236.596174 -42.202608)
					(mid 236.050074 -42.746174)
					(end 235.503974 -42.202608)
				)
				(arc
					(start 235.503974 -42.200068)
					(mid 236.050074 -41.653968)
					(end 236.596174 -42.200068)
				)
				(xy 237.675674 -42.200068) (xy 237.675674 -42.202354) (xy 238.376206 -41.852088)
				(arc
					(start 238.374936 -41.849802)
					(mid 238.667333 -41.583053)
					(end 238.77651 -41.20261)
				)
				(arc
					(start 238.59617 -41.20261)
					(mid 238.05007 -41.746176)
					(end 237.50397 -41.20261)
				)
				(arc
					(start 237.50397 -41.20007)
					(mid 238.05007 -40.65397)
					(end 238.59617 -41.20007)
				)
			)
		)
	)
	(zone
		(layers "F.Cu" "In2.Cu" "In4.Cu" "In7.Cu" "In9.Cu")
		(hatch none 0.5)
		(connect_pads
			(clearance 0)
		)
		(min_thickness 0.25)
		(keepout
			(tracks not_allowed)
			(vias allowed)
			(pads allowed)
			(copperpour not_allowed)
			(footprints allowed)
		)
		(placement
			(enabled no)
			(sheetname "")
		)
		(fill yes
			(thermal_gap 0.5)
			(thermal_bridge_width 0.5)
			(island_removal_mode 0)
		)
		(polygon
			(pts
				(arc
					(start 281.47645 -45.200062)
					(mid 281.131922 -44.582115)
					(end 280.425144 -44.55033)
				)
				(xy 280.423874 -44.548044) (xy 278.424132 -45.548042) (xy 278.424132 -45.548296)
				(arc
					(start 278.425148 -45.550328)
					(mid 278.100282 -46.524926)
					(end 279.07488 -46.849792)
				)
				(xy 279.07615 -46.852078) (xy 280.375106 -46.2026)
				(arc
					(start 279.296114 -46.2026)
					(mid 278.750014 -46.746166)
					(end 278.203914 -46.2026)
				)
				(arc
					(start 278.203914 -46.20006)
					(mid 278.750014 -45.65396)
					(end 279.296114 -46.20006)
				)
				(xy 280.375614 -46.20006) (xy 280.375614 -46.202346) (xy 281.076146 -45.85208)
				(arc
					(start 281.074876 -45.849794)
					(mid 281.367273 -45.583045)
					(end 281.47645 -45.202602)
				)
				(arc
					(start 281.29611 -45.202602)
					(mid 280.75001 -45.746168)
					(end 280.20391 -45.202602)
				)
				(arc
					(start 280.20391 -45.200062)
					(mid 280.75001 -44.653962)
					(end 281.29611 -45.200062)
				)
			)
		)
	)
	(zone
		(layers "F.Cu" "In2.Cu" "In4.Cu" "In7.Cu" "In9.Cu")
		(hatch none 0.5)
		(connect_pads
			(clearance 0)
		)
		(min_thickness 0.25)
		(keepout
			(tracks not_allowed)
			(vias allowed)
			(pads allowed)
			(copperpour not_allowed)
			(footprints allowed)
		)
		(placement
			(enabled no)
			(sheetname "")
		)
		(fill yes
			(thermal_gap 0.5)
			(thermal_bridge_width 0.5)
			(island_removal_mode 0)
		)
		(polygon
			(pts
				(arc
					(start 286.436562 -317.556388)
					(mid 285.887922 -318.105028)
					(end 286.436562 -318.653668)
				)
				(arc
					(start 287.83661 -318.653668)
					(mid 288.223658 -318.493872)
					(end 288.38525 -318.107568)
				)
				(arc
					(start 288.23031 -318.107568)
					(mid 287.83661 -318.498736)
					(end 287.44291 -318.107568)
				)
				(arc
					(start 286.830262 -318.107568)
					(mid 286.436562 -318.498736)
					(end 286.042862 -318.107568)
				)
				(arc
					(start 286.042862 -318.105028)
					(mid 286.436562 -317.711328)
					(end 286.830262 -318.105028)
				)
				(arc
					(start 287.44291 -318.105028)
					(mid 287.83661 -317.711328)
					(end 288.23031 -318.105028)
				)
				(arc
					(start 288.38525 -318.105028)
					(mid 288.224557 -317.717081)
					(end 287.83661 -317.556388)
				)
				(xy 286.436816 -317.556388)
			)
		)
	)
	(zone
		(layers "F.Cu" "In2.Cu" "In4.Cu" "In7.Cu" "In9.Cu")
		(hatch none 0.5)
		(connect_pads
			(clearance 0)
		)
		(min_thickness 0.25)
		(keepout
			(tracks not_allowed)
			(vias allowed)
			(pads allowed)
			(copperpour not_allowed)
			(footprints allowed)
		)
		(placement
			(enabled no)
			(sheetname "")
		)
		(fill yes
			(thermal_gap 0.5)
			(thermal_bridge_width 0.5)
			(island_removal_mode 0)
		)
		(polygon
			(pts
				(arc
					(start 285.436564 -337.35645)
					(mid 284.887924 -337.90509)
					(end 285.436564 -338.45373)
				)
				(arc
					(start 286.836612 -338.45373)
					(mid 287.22366 -338.293934)
					(end 287.385252 -337.90763)
				)
				(arc
					(start 287.230312 -337.90763)
					(mid 286.836612 -338.298798)
					(end 286.442912 -337.90763)
				)
				(arc
					(start 285.830264 -337.90763)
					(mid 285.436564 -338.298798)
					(end 285.042864 -337.90763)
				)
				(arc
					(start 285.042864 -337.90509)
					(mid 285.436564 -337.51139)
					(end 285.830264 -337.90509)
				)
				(arc
					(start 286.442912 -337.90509)
					(mid 286.836612 -337.51139)
					(end 287.230312 -337.90509)
				)
				(arc
					(start 287.385252 -337.90509)
					(mid 287.224559 -337.517143)
					(end 286.836612 -337.35645)
				)
				(xy 285.436818 -337.35645)
			)
		)
	)
	(zone
		(layers "F.Cu" "In2.Cu" "In4.Cu" "In7.Cu" "In9.Cu")
		(hatch none 0.5)
		(connect_pads
			(clearance 0)
		)
		(min_thickness 0.25)
		(keepout
			(tracks not_allowed)
			(vias allowed)
			(pads allowed)
			(copperpour not_allowed)
			(footprints allowed)
		)
		(placement
			(enabled no)
			(sheetname "")
		)
		(fill yes
			(thermal_gap 0.5)
			(thermal_bridge_width 0.5)
			(island_removal_mode 0)
		)
		(polygon
			(pts
				(arc
					(start 281.47645 -49.200054)
					(mid 281.131922 -48.582107)
					(end 280.425144 -48.550322)
				)
				(xy 280.423874 -48.548036) (xy 278.424132 -49.548034) (xy 278.424132 -49.548288)
				(arc
					(start 278.425148 -49.55032)
					(mid 278.100282 -50.524918)
					(end 279.07488 -50.849784)
				)
				(xy 279.07615 -50.85207) (xy 280.375106 -50.202592)
				(arc
					(start 279.296114 -50.202592)
					(mid 278.750014 -50.746158)
					(end 278.203914 -50.202592)
				)
				(arc
					(start 278.203914 -50.200052)
					(mid 278.750014 -49.653952)
					(end 279.296114 -50.200052)
				)
				(xy 280.375614 -50.200052) (xy 280.375614 -50.202338) (xy 281.076146 -49.852072)
				(arc
					(start 281.074876 -49.849786)
					(mid 281.367273 -49.583037)
					(end 281.47645 -49.202594)
				)
				(arc
					(start 281.29611 -49.202594)
					(mid 280.75001 -49.74616)
					(end 280.20391 -49.202594)
				)
				(arc
					(start 280.20391 -49.200054)
					(mid 280.75001 -48.653954)
					(end 281.29611 -49.200054)
				)
			)
		)
	)
	(zone
		(layers "F.Cu" "In2.Cu" "In4.Cu" "In7.Cu" "In9.Cu")
		(hatch none 0.5)
		(connect_pads
			(clearance 0)
		)
		(min_thickness 0.25)
		(keepout
			(tracks not_allowed)
			(vias allowed)
			(pads allowed)
			(copperpour not_allowed)
			(footprints allowed)
		)
		(placement
			(enabled no)
			(sheetname "")
		)
		(fill yes
			(thermal_gap 0.5)
			(thermal_bridge_width 0.5)
			(island_removal_mode 0)
		)
		(polygon
			(pts
				(arc
					(start 238.77651 -177.499772)
					(mid 238.431982 -176.881825)
					(end 237.725204 -176.85004)
				)
				(xy 237.723934 -176.847754) (xy 235.724192 -177.847752) (xy 235.724192 -177.848006)
				(arc
					(start 235.725208 -177.850038)
					(mid 235.400342 -178.824636)
					(end 236.37494 -179.149502)
				)
				(xy 236.37621 -179.151788) (xy 237.675166 -178.50231)
				(arc
					(start 236.596174 -178.50231)
					(mid 236.050074 -179.045876)
					(end 235.503974 -178.50231)
				)
				(arc
					(start 235.503974 -178.49977)
					(mid 236.050074 -177.95367)
					(end 236.596174 -178.49977)
				)
				(xy 237.675674 -178.49977) (xy 237.675674 -178.502056) (xy 238.376206 -178.15179)
				(arc
					(start 238.374936 -178.149504)
					(mid 238.667333 -177.882755)
					(end 238.77651 -177.502312)
				)
				(arc
					(start 238.59617 -177.502312)
					(mid 238.05007 -178.045878)
					(end 237.50397 -177.502312)
				)
				(arc
					(start 237.50397 -177.499772)
					(mid 238.05007 -176.953672)
					(end 238.59617 -177.499772)
				)
			)
		)
	)
	(zone
		(layers "F.Cu" "In2.Cu" "In4.Cu" "In7.Cu" "In9.Cu")
		(hatch none 0.5)
		(connect_pads
			(clearance 0)
		)
		(min_thickness 0.25)
		(keepout
			(tracks not_allowed)
			(vias allowed)
			(pads allowed)
			(copperpour not_allowed)
			(footprints allowed)
		)
		(placement
			(enabled no)
			(sheetname "")
		)
		(fill yes
			(thermal_gap 0.5)
			(thermal_bridge_width 0.5)
			(island_removal_mode 0)
		)
		(polygon
			(pts
				(arc
					(start 281.47645 -53.200046)
					(mid 281.131922 -52.582099)
					(end 280.425144 -52.550314)
				)
				(xy 280.423874 -52.548028) (xy 278.424132 -53.548026) (xy 278.424132 -53.54828)
				(arc
					(start 278.425148 -53.550312)
					(mid 278.100282 -54.52491)
					(end 279.07488 -54.849776)
				)
				(xy 279.07615 -54.852062) (xy 280.375106 -54.202584)
				(arc
					(start 279.296114 -54.202584)
					(mid 278.750014 -54.74615)
					(end 278.203914 -54.202584)
				)
				(arc
					(start 278.203914 -54.200044)
					(mid 278.750014 -53.653944)
					(end 279.296114 -54.200044)
				)
				(xy 280.375614 -54.200044) (xy 280.375614 -54.20233) (xy 281.076146 -53.852064)
				(arc
					(start 281.074876 -53.849778)
					(mid 281.367273 -53.583029)
					(end 281.47645 -53.202586)
				)
				(arc
					(start 281.29611 -53.202586)
					(mid 280.75001 -53.746152)
					(end 280.20391 -53.202586)
				)
				(arc
					(start 280.20391 -53.200046)
					(mid 280.75001 -52.653946)
					(end 281.29611 -53.200046)
				)
			)
		)
	)
	(zone
		(layers "F.Cu" "In2.Cu" "In4.Cu" "In7.Cu" "In9.Cu")
		(hatch none 0.5)
		(connect_pads
			(clearance 0)
		)
		(min_thickness 0.25)
		(keepout
			(tracks not_allowed)
			(vias allowed)
			(pads allowed)
			(copperpour not_allowed)
			(footprints allowed)
		)
		(placement
			(enabled no)
			(sheetname "")
		)
		(fill yes
			(thermal_gap 0.5)
			(thermal_bridge_width 0.5)
			(island_removal_mode 0)
		)
		(polygon
			(pts
				(arc
					(start 281.47391 -121.499884)
					(mid 281.130538 -120.884068)
					(end 280.42616 -120.852438)
				)
				(xy 278.426418 -121.852182)
				(arc
					(start 278.426418 -121.852436)
					(mid 278.102619 -122.82358)
					(end 279.073864 -123.147328)
				)
				(xy 280.363676 -122.502422)
				(arc
					(start 279.296114 -122.502422)
					(mid 278.750014 -123.045988)
					(end 278.203914 -122.502422)
				)
				(arc
					(start 278.203914 -122.499882)
					(mid 278.750014 -121.953782)
					(end 279.296114 -122.499882)
				)
				(xy 280.368756 -122.499882)
				(arc
					(start 281.07386 -122.14733)
					(mid 281.365177 -121.881505)
					(end 281.47391 -121.502424)
				)
				(arc
					(start 281.29611 -121.502424)
					(mid 280.75001 -122.04599)
					(end 280.20391 -121.502424)
				)
				(arc
					(start 280.20391 -121.499884)
					(mid 280.75001 -120.953784)
					(end 281.29611 -121.499884)
				)
			)
		)
	)
	(zone
		(layers "F.Cu" "In2.Cu" "In4.Cu" "In7.Cu" "In9.Cu")
		(hatch none 0.5)
		(connect_pads
			(clearance 0)
		)
		(min_thickness 0.25)
		(keepout
			(tracks not_allowed)
			(vias allowed)
			(pads allowed)
			(copperpour not_allowed)
			(footprints allowed)
		)
		(placement
			(enabled no)
			(sheetname "")
		)
		(fill yes
			(thermal_gap 0.5)
			(thermal_bridge_width 0.5)
			(island_removal_mode 0)
		)
		(polygon
			(pts
				(arc
					(start 279.236678 -313.956446)
					(mid 278.688038 -314.505086)
					(end 279.236678 -315.053726)
				)
				(arc
					(start 280.636726 -315.053726)
					(mid 281.023774 -314.89393)
					(end 281.185366 -314.507626)
				)
				(arc
					(start 281.030426 -314.507626)
					(mid 280.636726 -314.898794)
					(end 280.243026 -314.507626)
				)
				(arc
					(start 279.630378 -314.507626)
					(mid 279.236678 -314.898794)
					(end 278.842978 -314.507626)
				)
				(arc
					(start 278.842978 -314.505086)
					(mid 279.236678 -314.111386)
					(end 279.630378 -314.505086)
				)
				(arc
					(start 280.243026 -314.505086)
					(mid 280.636726 -314.111386)
					(end 281.030426 -314.505086)
				)
				(arc
					(start 281.185366 -314.505086)
					(mid 281.024673 -314.117139)
					(end 280.636726 -313.956446)
				)
				(xy 279.236932 -313.956446)
			)
		)
	)
	(zone
		(layers "F.Cu" "In2.Cu" "In4.Cu" "In7.Cu" "In9.Cu")
		(hatch none 0.5)
		(connect_pads
			(clearance 0)
		)
		(min_thickness 0.25)
		(keepout
			(tracks not_allowed)
			(vias allowed)
			(pads allowed)
			(copperpour not_allowed)
			(footprints allowed)
		)
		(placement
			(enabled no)
			(sheetname "")
		)
		(fill yes
			(thermal_gap 0.5)
			(thermal_bridge_width 0.5)
			(island_removal_mode 0)
		)
		(polygon
			(pts
				(arc
					(start 278.23668 -333.756508)
					(mid 277.68804 -334.305148)
					(end 278.23668 -334.853788)
				)
				(arc
					(start 279.636728 -334.853788)
					(mid 280.023776 -334.693992)
					(end 280.185368 -334.307688)
				)
				(arc
					(start 280.030428 -334.307688)
					(mid 279.636728 -334.698856)
					(end 279.243028 -334.307688)
				)
				(arc
					(start 278.63038 -334.307688)
					(mid 278.23668 -334.698856)
					(end 277.84298 -334.307688)
				)
				(arc
					(start 277.84298 -334.305148)
					(mid 278.23668 -333.911448)
					(end 278.63038 -334.305148)
				)
				(arc
					(start 279.243028 -334.305148)
					(mid 279.636728 -333.911448)
					(end 280.030428 -334.305148)
				)
				(arc
					(start 280.185368 -334.305148)
					(mid 280.024675 -333.917201)
					(end 279.636728 -333.756508)
				)
				(xy 278.236934 -333.756508)
			)
		)
	)
	(zone
		(layers "F.Cu" "In2.Cu" "In4.Cu" "In7.Cu" "In9.Cu")
		(hatch none 0.5)
		(connect_pads
			(clearance 0)
		)
		(min_thickness 0.25)
		(keepout
			(tracks not_allowed)
			(vias allowed)
			(pads allowed)
			(copperpour not_allowed)
			(footprints allowed)
		)
		(placement
			(enabled no)
			(sheetname "")
		)
		(fill yes
			(thermal_gap 0.5)
			(thermal_bridge_width 0.5)
			(island_removal_mode 0)
		)
		(polygon
			(pts
				(arc
					(start 217.748612 -407.000202)
					(mid 217.199972 -406.451562)
					(end 216.651332 -407.000202)
				)
				(arc
					(start 216.651332 -408.399996)
					(mid 217.198702 -408.948635)
					(end 217.748612 -408.402536)
				)
				(arc
					(start 217.593672 -408.402536)
					(mid 217.199972 -408.793704)
					(end 216.806272 -408.402536)
				)
				(arc
					(start 216.806272 -408.399996)
					(mid 217.199972 -408.006296)
					(end 217.593672 -408.399996)
				)
				(xy 217.748612 -408.399996) (xy 217.748612 -407.002742)
				(arc
					(start 217.593672 -407.002742)
					(mid 217.199972 -407.39391)
					(end 216.806272 -407.002742)
				)
				(arc
					(start 216.806272 -407.000202)
					(mid 217.199972 -406.606502)
					(end 217.593672 -407.000202)
				)
			)
		)
	)
	(zone
		(layers "F.Cu" "In2.Cu" "In4.Cu" "In7.Cu" "In9.Cu")
		(hatch none 0.5)
		(connect_pads
			(clearance 0)
		)
		(min_thickness 0.25)
		(keepout
			(tracks not_allowed)
			(vias allowed)
			(pads allowed)
			(copperpour not_allowed)
			(footprints allowed)
		)
		(placement
			(enabled no)
			(sheetname "")
		)
		(fill yes
			(thermal_gap 0.5)
			(thermal_bridge_width 0.5)
			(island_removal_mode 0)
		)
		(polygon
			(pts
				(arc
					(start 281.47391 -149.499828)
					(mid 281.130538 -148.884012)
					(end 280.42616 -148.852382)
				)
				(xy 278.426418 -149.852126)
				(arc
					(start 278.426418 -149.85238)
					(mid 278.102619 -150.823524)
					(end 279.073864 -151.147272)
				)
				(xy 280.363676 -150.502366)
				(arc
					(start 279.296114 -150.502366)
					(mid 278.750014 -151.045932)
					(end 278.203914 -150.502366)
				)
				(arc
					(start 278.203914 -150.499826)
					(mid 278.750014 -149.953726)
					(end 279.296114 -150.499826)
				)
				(xy 280.368756 -150.499826)
				(arc
					(start 281.07386 -150.147274)
					(mid 281.365177 -149.881449)
					(end 281.47391 -149.502368)
				)
				(arc
					(start 281.29611 -149.502368)
					(mid 280.75001 -150.045934)
					(end 280.20391 -149.502368)
				)
				(arc
					(start 280.20391 -149.499828)
					(mid 280.75001 -148.953728)
					(end 281.29611 -149.499828)
				)
			)
		)
	)
	(zone
		(layers "F.Cu" "In2.Cu" "In4.Cu" "In7.Cu" "In9.Cu")
		(hatch none 0.5)
		(connect_pads
			(clearance 0)
		)
		(min_thickness 0.25)
		(keepout
			(tracks not_allowed)
			(vias allowed)
			(pads allowed)
			(copperpour not_allowed)
			(footprints allowed)
		)
		(placement
			(enabled no)
			(sheetname "")
		)
		(fill yes
			(thermal_gap 0.5)
			(thermal_bridge_width 0.5)
			(island_removal_mode 0)
		)
		(polygon
			(pts
				(arc
					(start 281.47391 -117.499892)
					(mid 281.130538 -116.884076)
					(end 280.42616 -116.852446)
				)
				(xy 278.426418 -117.85219)
				(arc
					(start 278.426418 -117.852444)
					(mid 278.102619 -118.823588)
					(end 279.073864 -119.147336)
				)
				(xy 280.363676 -118.50243)
				(arc
					(start 279.296114 -118.50243)
					(mid 278.750014 -119.045996)
					(end 278.203914 -118.50243)
				)
				(arc
					(start 278.203914 -118.49989)
					(mid 278.750014 -117.95379)
					(end 279.296114 -118.49989)
				)
				(xy 280.368756 -118.49989)
				(arc
					(start 281.07386 -118.147338)
					(mid 281.365177 -117.881513)
					(end 281.47391 -117.502432)
				)
				(arc
					(start 281.29611 -117.502432)
					(mid 280.75001 -118.045998)
					(end 280.20391 -117.502432)
				)
				(arc
					(start 280.20391 -117.499892)
					(mid 280.75001 -116.953792)
					(end 281.29611 -117.499892)
				)
			)
		)
	)
	(zone
		(layers "F.Cu" "In2.Cu" "In4.Cu" "In7.Cu" "In9.Cu")
		(hatch none 0.5)
		(connect_pads
			(clearance 0)
		)
		(min_thickness 0.25)
		(keepout
			(tracks not_allowed)
			(vias allowed)
			(pads allowed)
			(copperpour not_allowed)
			(footprints allowed)
		)
		(placement
			(enabled no)
			(sheetname "")
		)
		(fill yes
			(thermal_gap 0.5)
			(thermal_bridge_width 0.5)
			(island_removal_mode 0)
		)
		(polygon
			(pts
				(arc
					(start 238.77651 -57.200038)
					(mid 238.431982 -56.582091)
					(end 237.725204 -56.550306)
				)
				(xy 237.723934 -56.54802) (xy 235.724192 -57.548018) (xy 235.724192 -57.548272)
				(arc
					(start 235.725208 -57.550304)
					(mid 235.400342 -58.524902)
					(end 236.37494 -58.849768)
				)
				(xy 236.37621 -58.852054) (xy 237.675166 -58.202576)
				(arc
					(start 236.596174 -58.202576)
					(mid 236.050074 -58.746142)
					(end 235.503974 -58.202576)
				)
				(arc
					(start 235.503974 -58.200036)
					(mid 236.050074 -57.653936)
					(end 236.596174 -58.200036)
				)
				(xy 237.675674 -58.200036) (xy 237.675674 -58.202322) (xy 238.376206 -57.852056)
				(arc
					(start 238.374936 -57.84977)
					(mid 238.667333 -57.583021)
					(end 238.77651 -57.202578)
				)
				(arc
					(start 238.59617 -57.202578)
					(mid 238.05007 -57.746144)
					(end 237.50397 -57.202578)
				)
				(arc
					(start 237.50397 -57.200038)
					(mid 238.05007 -56.653938)
					(end 238.59617 -57.200038)
				)
			)
		)
	)
	(zone
		(layers "F.Cu" "In2.Cu" "In4.Cu" "In7.Cu" "In9.Cu")
		(hatch none 0.5)
		(connect_pads
			(clearance 0)
		)
		(min_thickness 0.25)
		(keepout
			(tracks not_allowed)
			(vias allowed)
			(pads allowed)
			(copperpour not_allowed)
			(footprints allowed)
		)
		(placement
			(enabled no)
			(sheetname "")
		)
		(fill yes
			(thermal_gap 0.5)
			(thermal_bridge_width 0.5)
			(island_removal_mode 0)
		)
		(polygon
			(pts
				(arc
					(start 279.236678 -328.356468)
					(mid 278.688038 -328.905108)
					(end 279.236678 -329.453748)
				)
				(arc
					(start 280.636726 -329.453748)
					(mid 281.023774 -329.293952)
					(end 281.185366 -328.907648)
				)
				(arc
					(start 281.030426 -328.907648)
					(mid 280.636726 -329.298816)
					(end 280.243026 -328.907648)
				)
				(arc
					(start 279.630378 -328.907648)
					(mid 279.236678 -329.298816)
					(end 278.842978 -328.907648)
				)
				(arc
					(start 278.842978 -328.905108)
					(mid 279.236678 -328.511408)
					(end 279.630378 -328.905108)
				)
				(arc
					(start 280.243026 -328.905108)
					(mid 280.636726 -328.511408)
					(end 281.030426 -328.905108)
				)
				(arc
					(start 281.185366 -328.905108)
					(mid 281.024673 -328.517161)
					(end 280.636726 -328.356468)
				)
				(xy 279.236932 -328.356468)
			)
		)
	)
	(zone
		(layers "F.Cu" "In2.Cu" "In4.Cu" "In7.Cu" "In9.Cu")
		(hatch none 0.5)
		(connect_pads
			(clearance 0)
		)
		(min_thickness 0.25)
		(keepout
			(tracks not_allowed)
			(vias allowed)
			(pads allowed)
			(copperpour not_allowed)
			(footprints allowed)
		)
		(placement
			(enabled no)
			(sheetname "")
		)
		(fill yes
			(thermal_gap 0.5)
			(thermal_bridge_width 0.5)
			(island_removal_mode 0)
		)
		(polygon
			(pts
				(arc
					(start 223.148652 -405.99995)
					(mid 222.600012 -405.45131)
					(end 222.051372 -405.99995)
				)
				(arc
					(start 222.051372 -407.399998)
					(mid 222.598742 -407.948637)
					(end 223.148652 -407.402538)
				)
				(arc
					(start 222.993712 -407.402538)
					(mid 222.600012 -407.793706)
					(end 222.206312 -407.402538)
				)
				(arc
					(start 222.206312 -407.399998)
					(mid 222.600012 -407.006298)
					(end 222.993712 -407.399998)
				)
				(xy 223.148652 -407.399998) (xy 223.148652 -406.00249)
				(arc
					(start 222.993712 -406.00249)
					(mid 222.600012 -406.393658)
					(end 222.206312 -406.00249)
				)
				(arc
					(start 222.206312 -405.99995)
					(mid 222.600012 -405.60625)
					(end 222.993712 -405.99995)
				)
			)
		)
	)
	(zone
		(layers "F.Cu" "In2.Cu" "In4.Cu" "In7.Cu" "In9.Cu")
		(hatch none 0.5)
		(connect_pads
			(clearance 0)
		)
		(min_thickness 0.25)
		(keepout
			(tracks not_allowed)
			(vias allowed)
			(pads allowed)
			(copperpour not_allowed)
			(footprints allowed)
		)
		(placement
			(enabled no)
			(sheetname "")
		)
		(fill yes
			(thermal_gap 0.5)
			(thermal_bridge_width 0.5)
			(island_removal_mode 0)
		)
		(polygon
			(pts
				(arc
					(start 278.23668 -304.956464)
					(mid 277.68804 -305.505104)
					(end 278.23668 -306.053744)
				)
				(arc
					(start 279.636728 -306.053744)
					(mid 280.023776 -305.893948)
					(end 280.185368 -305.507644)
				)
				(arc
					(start 280.030428 -305.507644)
					(mid 279.636728 -305.898812)
					(end 279.243028 -305.507644)
				)
				(arc
					(start 278.63038 -305.507644)
					(mid 278.23668 -305.898812)
					(end 277.84298 -305.507644)
				)
				(arc
					(start 277.84298 -305.505104)
					(mid 278.23668 -305.111404)
					(end 278.63038 -305.505104)
				)
				(arc
					(start 279.243028 -305.505104)
					(mid 279.636728 -305.111404)
					(end 280.030428 -305.505104)
				)
				(arc
					(start 280.185368 -305.505104)
					(mid 280.024675 -305.117157)
					(end 279.636728 -304.956464)
				)
				(xy 278.236934 -304.956464)
			)
		)
	)
	(zone
		(layers "F.Cu" "In2.Cu" "In4.Cu" "In7.Cu" "In9.Cu")
		(hatch none 0.5)
		(connect_pads
			(clearance 0)
		)
		(min_thickness 0.25)
		(keepout
			(tracks not_allowed)
			(vias allowed)
			(pads allowed)
			(copperpour not_allowed)
			(footprints allowed)
		)
		(placement
			(enabled no)
			(sheetname "")
		)
		(fill yes
			(thermal_gap 0.5)
			(thermal_bridge_width 0.5)
			(island_removal_mode 0)
		)
		(polygon
			(pts
				(arc
					(start 281.47645 -81.19999)
					(mid 281.131922 -80.582043)
					(end 280.425144 -80.550258)
				)
				(xy 280.423874 -80.547972) (xy 278.424132 -81.54797) (xy 278.424132 -81.548224)
				(arc
					(start 278.425148 -81.550256)
					(mid 278.100282 -82.524854)
					(end 279.07488 -82.84972)
				)
				(xy 279.07615 -82.852006) (xy 280.375106 -82.202528)
				(arc
					(start 279.296114 -82.202528)
					(mid 278.750014 -82.746094)
					(end 278.203914 -82.202528)
				)
				(arc
					(start 278.203914 -82.199988)
					(mid 278.750014 -81.653888)
					(end 279.296114 -82.199988)
				)
				(xy 280.375614 -82.199988) (xy 280.375614 -82.202274) (xy 281.076146 -81.852008)
				(arc
					(start 281.074876 -81.849722)
					(mid 281.367273 -81.582973)
					(end 281.47645 -81.20253)
				)
				(arc
					(start 281.29611 -81.20253)
					(mid 280.75001 -81.746096)
					(end 280.20391 -81.20253)
				)
				(arc
					(start 280.20391 -81.19999)
					(mid 280.75001 -80.65389)
					(end 281.29611 -81.19999)
				)
			)
		)
	)
	(zone
		(layers "F.Cu" "In2.Cu" "In4.Cu" "In7.Cu" "In9.Cu")
		(hatch none 0.5)
		(connect_pads
			(clearance 0)
		)
		(min_thickness 0.25)
		(keepout
			(tracks not_allowed)
			(vias allowed)
			(pads allowed)
			(copperpour not_allowed)
			(footprints allowed)
		)
		(placement
			(enabled no)
			(sheetname "")
		)
		(fill yes
			(thermal_gap 0.5)
			(thermal_bridge_width 0.5)
			(island_removal_mode 0)
		)
		(polygon
			(pts
				(arc
					(start 285.436564 -322.956428)
					(mid 284.887924 -323.505068)
					(end 285.436564 -324.053708)
				)
				(arc
					(start 286.836612 -324.053708)
					(mid 287.22366 -323.893912)
					(end 287.385252 -323.507608)
				)
				(arc
					(start 287.230312 -323.507608)
					(mid 286.836612 -323.898776)
					(end 286.442912 -323.507608)
				)
				(arc
					(start 285.830264 -323.507608)
					(mid 285.436564 -323.898776)
					(end 285.042864 -323.507608)
				)
				(arc
					(start 285.042864 -323.505068)
					(mid 285.436564 -323.111368)
					(end 285.830264 -323.505068)
				)
				(arc
					(start 286.442912 -323.505068)
					(mid 286.836612 -323.111368)
					(end 287.230312 -323.505068)
				)
				(arc
					(start 287.385252 -323.505068)
					(mid 287.224559 -323.117121)
					(end 286.836612 -322.956428)
				)
				(xy 285.436818 -322.956428)
			)
		)
	)
	(zone
		(layers "F.Cu" "In2.Cu" "In4.Cu" "In7.Cu" "In9.Cu")
		(hatch none 0.5)
		(connect_pads
			(clearance 0)
		)
		(min_thickness 0.25)
		(keepout
			(tracks not_allowed)
			(vias allowed)
			(pads allowed)
			(copperpour not_allowed)
			(footprints allowed)
		)
		(placement
			(enabled no)
			(sheetname "")
		)
		(fill yes
			(thermal_gap 0.5)
			(thermal_bridge_width 0.5)
			(island_removal_mode 0)
		)
		(polygon
			(pts
				(arc
					(start 210.548728 -407.000202)
					(mid 210.000088 -406.451562)
					(end 209.451448 -407.000202)
				)
				(arc
					(start 209.451448 -408.399996)
					(mid 209.998818 -408.948635)
					(end 210.548728 -408.402536)
				)
				(arc
					(start 210.393788 -408.402536)
					(mid 210.000088 -408.793704)
					(end 209.606388 -408.402536)
				)
				(arc
					(start 209.606388 -408.399996)
					(mid 210.000088 -408.006296)
					(end 210.393788 -408.399996)
				)
				(xy 210.548728 -408.399996) (xy 210.548728 -407.002742)
				(arc
					(start 210.393788 -407.002742)
					(mid 210.000088 -407.39391)
					(end 209.606388 -407.002742)
				)
				(arc
					(start 209.606388 -407.000202)
					(mid 210.000088 -406.606502)
					(end 210.393788 -407.000202)
				)
			)
		)
	)
	(zone
		(layers "F.Cu" "In2.Cu" "In4.Cu" "In7.Cu" "In9.Cu")
		(hatch none 0.5)
		(connect_pads
			(clearance 0)
		)
		(min_thickness 0.25)
		(keepout
			(tracks not_allowed)
			(vias allowed)
			(pads allowed)
			(copperpour not_allowed)
			(footprints allowed)
		)
		(placement
			(enabled no)
			(sheetname "")
		)
		(fill yes
			(thermal_gap 0.5)
			(thermal_bridge_width 0.5)
			(island_removal_mode 0)
		)
		(polygon
			(pts
				(arc
					(start 214.14867 -407.000202)
					(mid 213.60003 -406.451562)
					(end 213.05139 -407.000202)
				)
				(arc
					(start 213.05139 -408.399996)
					(mid 213.59876 -408.948635)
					(end 214.14867 -408.402536)
				)
				(arc
					(start 213.99373 -408.402536)
					(mid 213.60003 -408.793704)
					(end 213.20633 -408.402536)
				)
				(arc
					(start 213.20633 -408.399996)
					(mid 213.60003 -408.006296)
					(end 213.99373 -408.399996)
				)
				(xy 214.14867 -408.399996) (xy 214.14867 -407.002742)
				(arc
					(start 213.99373 -407.002742)
					(mid 213.60003 -407.39391)
					(end 213.20633 -407.002742)
				)
				(arc
					(start 213.20633 -407.000202)
					(mid 213.60003 -406.606502)
					(end 213.99373 -407.000202)
				)
			)
		)
	)
	(zone
		(layers "F.Cu" "In2.Cu" "In4.Cu" "In7.Cu" "In9.Cu")
		(hatch none 0.5)
		(connect_pads
			(clearance 0)
		)
		(min_thickness 0.25)
		(keepout
			(tracks not_allowed)
			(vias allowed)
			(pads allowed)
			(copperpour not_allowed)
			(footprints allowed)
		)
		(placement
			(enabled no)
			(sheetname "")
		)
		(fill yes
			(thermal_gap 0.5)
			(thermal_bridge_width 0.5)
			(island_removal_mode 0)
		)
		(polygon
			(pts
				(arc
					(start 238.77651 -45.200062)
					(mid 238.431982 -44.582115)
					(end 237.725204 -44.55033)
				)
				(xy 237.723934 -44.548044) (xy 235.724192 -45.548042) (xy 235.724192 -45.548296)
				(arc
					(start 235.725208 -45.550328)
					(mid 235.400342 -46.524926)
					(end 236.37494 -46.849792)
				)
				(xy 236.37621 -46.852078) (xy 237.675166 -46.2026)
				(arc
					(start 236.596174 -46.2026)
					(mid 236.050074 -46.746166)
					(end 235.503974 -46.2026)
				)
				(arc
					(start 235.503974 -46.20006)
					(mid 236.050074 -45.65396)
					(end 236.596174 -46.20006)
				)
				(xy 237.675674 -46.20006) (xy 237.675674 -46.202346) (xy 238.376206 -45.85208)
				(arc
					(start 238.374936 -45.849794)
					(mid 238.667333 -45.583045)
					(end 238.77651 -45.202602)
				)
				(arc
					(start 238.59617 -45.202602)
					(mid 238.05007 -45.746168)
					(end 237.50397 -45.202602)
				)
				(arc
					(start 237.50397 -45.200062)
					(mid 238.05007 -44.653962)
					(end 238.59617 -45.200062)
				)
			)
		)
	)
	(zone
		(layers "F.Cu" "In2.Cu" "In4.Cu" "In7.Cu" "In9.Cu")
		(hatch none 0.5)
		(connect_pads
			(clearance 0)
		)
		(min_thickness 0.25)
		(keepout
			(tracks not_allowed)
			(vias allowed)
			(pads allowed)
			(copperpour not_allowed)
			(footprints allowed)
		)
		(placement
			(enabled no)
			(sheetname "")
		)
		(fill yes
			(thermal_gap 0.5)
			(thermal_bridge_width 0.5)
			(island_removal_mode 0)
		)
		(polygon
			(pts
				(arc
					(start 212.348826 -405.99995)
					(mid 211.800186 -405.45131)
					(end 211.251546 -405.99995)
				)
				(arc
					(start 211.251546 -407.399998)
					(mid 211.798916 -407.948637)
					(end 212.348826 -407.402538)
				)
				(arc
					(start 212.193886 -407.402538)
					(mid 211.800186 -407.793706)
					(end 211.406486 -407.402538)
				)
				(arc
					(start 211.406486 -407.399998)
					(mid 211.800186 -407.006298)
					(end 212.193886 -407.399998)
				)
				(xy 212.348826 -407.399998) (xy 212.348826 -406.00249)
				(arc
					(start 212.193886 -406.00249)
					(mid 211.800186 -406.393658)
					(end 211.406486 -406.00249)
				)
				(arc
					(start 211.406486 -405.99995)
					(mid 211.800186 -405.60625)
					(end 212.193886 -405.99995)
				)
			)
		)
	)
	(zone
		(layers "F.Cu" "In2.Cu" "In4.Cu" "In7.Cu" "In9.Cu")
		(hatch none 0.5)
		(connect_pads
			(clearance 0)
		)
		(min_thickness 0.25)
		(keepout
			(tracks not_allowed)
			(vias allowed)
			(pads allowed)
			(copperpour not_allowed)
			(footprints allowed)
		)
		(placement
			(enabled no)
			(sheetname "")
		)
		(fill yes
			(thermal_gap 0.5)
			(thermal_bridge_width 0.5)
			(island_removal_mode 0)
		)
		(polygon
			(pts
				(arc
					(start 285.436564 -340.956392)
					(mid 284.887924 -341.505032)
					(end 285.436564 -342.053672)
				)
				(arc
					(start 286.836612 -342.053672)
					(mid 287.22366 -341.893876)
					(end 287.385252 -341.507572)
				)
				(arc
					(start 287.230312 -341.507572)
					(mid 286.836612 -341.89874)
					(end 286.442912 -341.507572)
				)
				(arc
					(start 285.830264 -341.507572)
					(mid 285.436564 -341.89874)
					(end 285.042864 -341.507572)
				)
				(arc
					(start 285.042864 -341.505032)
					(mid 285.436564 -341.111332)
					(end 285.830264 -341.505032)
				)
				(arc
					(start 286.442912 -341.505032)
					(mid 286.836612 -341.111332)
					(end 287.230312 -341.505032)
				)
				(arc
					(start 287.385252 -341.505032)
					(mid 287.224559 -341.117085)
					(end 286.836612 -340.956392)
				)
				(xy 285.436818 -340.956392)
			)
		)
	)
	(zone
		(layers "F.Cu" "In2.Cu" "In4.Cu" "In7.Cu" "In9.Cu")
		(hatch none 0.5)
		(connect_pads
			(clearance 0)
		)
		(min_thickness 0.25)
		(keepout
			(tracks not_allowed)
			(vias allowed)
			(pads allowed)
			(copperpour not_allowed)
			(footprints allowed)
		)
		(placement
			(enabled no)
			(sheetname "")
		)
		(fill yes
			(thermal_gap 0.5)
			(thermal_bridge_width 0.5)
			(island_removal_mode 0)
		)
		(polygon
			(pts
				(arc
					(start 219.54871 -405.99995)
					(mid 219.00007 -405.45131)
					(end 218.45143 -405.99995)
				)
				(arc
					(start 218.45143 -407.399998)
					(mid 218.9988 -407.948637)
					(end 219.54871 -407.402538)
				)
				(arc
					(start 219.39377 -407.402538)
					(mid 219.00007 -407.793706)
					(end 218.60637 -407.402538)
				)
				(arc
					(start 218.60637 -407.399998)
					(mid 219.00007 -407.006298)
					(end 219.39377 -407.399998)
				)
				(xy 219.54871 -407.399998) (xy 219.54871 -406.00249)
				(arc
					(start 219.39377 -406.00249)
					(mid 219.00007 -406.393658)
					(end 218.60637 -406.00249)
				)
				(arc
					(start 218.60637 -405.99995)
					(mid 219.00007 -405.60625)
					(end 219.39377 -405.99995)
				)
			)
		)
	)
	(zone
		(layers "F.Cu" "In2.Cu" "In4.Cu" "In7.Cu" "In9.Cu")
		(hatch none 0.5)
		(connect_pads
			(clearance 0)
		)
		(min_thickness 0.25)
		(keepout
			(tracks not_allowed)
			(vias allowed)
			(pads allowed)
			(copperpour not_allowed)
			(footprints allowed)
		)
		(placement
			(enabled no)
			(sheetname "")
		)
		(fill yes
			(thermal_gap 0.5)
			(thermal_bridge_width 0.5)
			(island_removal_mode 0)
		)
		(polygon
			(pts
				(arc
					(start 278.23668 -308.556406)
					(mid 277.68804 -309.105046)
					(end 278.23668 -309.653686)
				)
				(arc
					(start 279.636728 -309.653686)
					(mid 280.023776 -309.49389)
					(end 280.185368 -309.107586)
				)
				(arc
					(start 280.030428 -309.107586)
					(mid 279.636728 -309.498754)
					(end 279.243028 -309.107586)
				)
				(arc
					(start 278.63038 -309.107586)
					(mid 278.23668 -309.498754)
					(end 277.84298 -309.107586)
				)
				(arc
					(start 277.84298 -309.105046)
					(mid 278.23668 -308.711346)
					(end 278.63038 -309.105046)
				)
				(arc
					(start 279.243028 -309.105046)
					(mid 279.636728 -308.711346)
					(end 280.030428 -309.105046)
				)
				(arc
					(start 280.185368 -309.105046)
					(mid 280.024675 -308.717099)
					(end 279.636728 -308.556406)
				)
				(xy 278.236934 -308.556406)
			)
		)
	)
	(zone
		(layers "F.Cu" "In2.Cu" "In4.Cu" "In7.Cu" "In9.Cu")
		(hatch none 0.5)
		(connect_pads
			(clearance 0)
		)
		(min_thickness 0.25)
		(keepout
			(tracks not_allowed)
			(vias allowed)
			(pads allowed)
			(copperpour not_allowed)
			(footprints allowed)
		)
		(placement
			(enabled no)
			(sheetname "")
		)
		(fill yes
			(thermal_gap 0.5)
			(thermal_bridge_width 0.5)
			(island_removal_mode 0)
		)
		(polygon
			(pts
				(arc
					(start 286.436562 -324.756526)
					(mid 285.887922 -325.305166)
					(end 286.436562 -325.853806)
				)
				(arc
					(start 287.83661 -325.853806)
					(mid 288.223658 -325.69401)
					(end 288.38525 -325.307706)
				)
				(arc
					(start 288.23031 -325.307706)
					(mid 287.83661 -325.698874)
					(end 287.44291 -325.307706)
				)
				(arc
					(start 286.830262 -325.307706)
					(mid 286.436562 -325.698874)
					(end 286.042862 -325.307706)
				)
				(arc
					(start 286.042862 -325.305166)
					(mid 286.436562 -324.911466)
					(end 286.830262 -325.305166)
				)
				(arc
					(start 287.44291 -325.305166)
					(mid 287.83661 -324.911466)
					(end 288.23031 -325.305166)
				)
				(arc
					(start 288.38525 -325.305166)
					(mid 288.224557 -324.917219)
					(end 287.83661 -324.756526)
				)
				(xy 286.436816 -324.756526)
			)
		)
	)
	(zone
		(layers "F.Cu" "In2.Cu" "In4.Cu" "In7.Cu" "In9.Cu")
		(hatch none 0.5)
		(connect_pads
			(clearance 0)
		)
		(min_thickness 0.25)
		(keepout
			(tracks not_allowed)
			(vias allowed)
			(pads allowed)
			(copperpour not_allowed)
			(footprints allowed)
		)
		(placement
			(enabled no)
			(sheetname "")
		)
		(fill yes
			(thermal_gap 0.5)
			(thermal_bridge_width 0.5)
			(island_removal_mode 0)
		)
		(polygon
			(pts
				(arc
					(start 286.436562 -339.156548)
					(mid 285.887922 -339.705188)
					(end 286.436562 -340.253828)
				)
				(arc
					(start 287.83661 -340.253828)
					(mid 288.223658 -340.094032)
					(end 288.38525 -339.707728)
				)
				(arc
					(start 288.23031 -339.707728)
					(mid 287.83661 -340.098896)
					(end 287.44291 -339.707728)
				)
				(arc
					(start 286.830262 -339.707728)
					(mid 286.436562 -340.098896)
					(end 286.042862 -339.707728)
				)
				(arc
					(start 286.042862 -339.705188)
					(mid 286.436562 -339.311488)
					(end 286.830262 -339.705188)
				)
				(arc
					(start 287.44291 -339.705188)
					(mid 287.83661 -339.311488)
					(end 288.23031 -339.705188)
				)
				(arc
					(start 288.38525 -339.705188)
					(mid 288.224557 -339.317241)
					(end 287.83661 -339.156548)
				)
				(xy 286.436816 -339.156548)
			)
		)
	)
	(zone
		(layers "F.Cu" "In2.Cu" "In4.Cu" "In7.Cu" "In9.Cu")
		(hatch none 0.5)
		(connect_pads
			(clearance 0)
		)
		(min_thickness 0.25)
		(keepout
			(tracks not_allowed)
			(vias allowed)
			(pads allowed)
			(copperpour not_allowed)
			(footprints allowed)
		)
		(placement
			(enabled no)
			(sheetname "")
		)
		(fill yes
			(thermal_gap 0.5)
			(thermal_bridge_width 0.5)
			(island_removal_mode 0)
		)
		(polygon
			(pts
				(arc
					(start 278.23668 -351.756472)
					(mid 277.68804 -352.305112)
					(end 278.23668 -352.853752)
				)
				(arc
					(start 279.636728 -352.853752)
					(mid 280.023776 -352.693956)
					(end 280.185368 -352.307652)
				)
				(arc
					(start 280.030428 -352.307652)
					(mid 279.636728 -352.69882)
					(end 279.243028 -352.307652)
				)
				(arc
					(start 278.63038 -352.307652)
					(mid 278.23668 -352.69882)
					(end 277.84298 -352.307652)
				)
				(arc
					(start 277.84298 -352.305112)
					(mid 278.23668 -351.911412)
					(end 278.63038 -352.305112)
				)
				(arc
					(start 279.243028 -352.305112)
					(mid 279.636728 -351.911412)
					(end 280.030428 -352.305112)
				)
				(arc
					(start 280.185368 -352.305112)
					(mid 280.024675 -351.917165)
					(end 279.636728 -351.756472)
				)
				(xy 278.236934 -351.756472)
			)
		)
	)
	(zone
		(layers "F.Cu" "In2.Cu" "In4.Cu" "In7.Cu" "In9.Cu")
		(hatch none 0.5)
		(connect_pads
			(clearance 0)
		)
		(min_thickness 0.25)
		(keepout
			(tracks not_allowed)
			(vias allowed)
			(pads allowed)
			(copperpour not_allowed)
			(footprints allowed)
		)
		(placement
			(enabled no)
			(sheetname "")
		)
		(fill yes
			(thermal_gap 0.5)
			(thermal_bridge_width 0.5)
			(island_removal_mode 0)
		)
		(polygon
			(pts
				(arc
					(start 281.47391 -125.499876)
					(mid 281.130538 -124.88406)
					(end 280.42616 -124.85243)
				)
				(xy 278.426418 -125.852174)
				(arc
					(start 278.426418 -125.852428)
					(mid 278.102619 -126.823572)
					(end 279.073864 -127.14732)
				)
				(xy 280.363676 -126.502414)
				(arc
					(start 279.296114 -126.502414)
					(mid 278.750014 -127.04598)
					(end 278.203914 -126.502414)
				)
				(arc
					(start 278.203914 -126.499874)
					(mid 278.750014 -125.953774)
					(end 279.296114 -126.499874)
				)
				(xy 280.368756 -126.499874)
				(arc
					(start 281.07386 -126.147322)
					(mid 281.365177 -125.881497)
					(end 281.47391 -125.502416)
				)
				(arc
					(start 281.29611 -125.502416)
					(mid 280.75001 -126.045982)
					(end 280.20391 -125.502416)
				)
				(arc
					(start 280.20391 -125.499876)
					(mid 280.75001 -124.953776)
					(end 281.29611 -125.499876)
				)
			)
		)
	)
	(zone
		(layers "F.Cu" "In2.Cu" "In4.Cu" "In7.Cu" "In9.Cu")
		(hatch none 0.5)
		(connect_pads
			(clearance 0)
		)
		(min_thickness 0.25)
		(keepout
			(tracks not_allowed)
			(vias allowed)
			(pads allowed)
			(copperpour not_allowed)
			(footprints allowed)
		)
		(placement
			(enabled no)
			(sheetname "")
		)
		(fill yes
			(thermal_gap 0.5)
			(thermal_bridge_width 0.5)
			(island_removal_mode 0)
		)
		(polygon
			(pts
				(arc
					(start 278.23668 -355.356414)
					(mid 277.68804 -355.905054)
					(end 278.23668 -356.453694)
				)
				(arc
					(start 279.636728 -356.453694)
					(mid 280.023776 -356.293898)
					(end 280.185368 -355.907594)
				)
				(arc
					(start 280.030428 -355.907594)
					(mid 279.636728 -356.298762)
					(end 279.243028 -355.907594)
				)
				(arc
					(start 278.63038 -355.907594)
					(mid 278.23668 -356.298762)
					(end 277.84298 -355.907594)
				)
				(arc
					(start 277.84298 -355.905054)
					(mid 278.23668 -355.511354)
					(end 278.63038 -355.905054)
				)
				(arc
					(start 279.243028 -355.905054)
					(mid 279.636728 -355.511354)
					(end 280.030428 -355.905054)
				)
				(arc
					(start 280.185368 -355.905054)
					(mid 280.024675 -355.517107)
					(end 279.636728 -355.356414)
				)
				(xy 278.236934 -355.356414)
			)
		)
	)
	(zone
		(layers "F.Cu" "In2.Cu" "In4.Cu" "In7.Cu" "In9.Cu")
		(hatch none 0.5)
		(connect_pads
			(clearance 0)
		)
		(min_thickness 0.25)
		(keepout
			(tracks not_allowed)
			(vias allowed)
			(pads allowed)
			(copperpour not_allowed)
			(footprints allowed)
		)
		(placement
			(enabled no)
			(sheetname "")
		)
		(fill yes
			(thermal_gap 0.5)
			(thermal_bridge_width 0.5)
			(island_removal_mode 0)
		)
		(polygon
			(pts
				(arc
					(start 281.47645 -41.20007)
					(mid 281.131922 -40.582123)
					(end 280.425144 -40.550338)
				)
				(xy 280.423874 -40.548052) (xy 278.424132 -41.54805) (xy 278.424132 -41.548304)
				(arc
					(start 278.425148 -41.550336)
					(mid 278.100282 -42.524934)
					(end 279.07488 -42.8498)
				)
				(xy 279.07615 -42.852086) (xy 280.375106 -42.202608)
				(arc
					(start 279.296114 -42.202608)
					(mid 278.750014 -42.746174)
					(end 278.203914 -42.202608)
				)
				(arc
					(start 278.203914 -42.200068)
					(mid 278.750014 -41.653968)
					(end 279.296114 -42.200068)
				)
				(xy 280.375614 -42.200068) (xy 280.375614 -42.202354) (xy 281.076146 -41.852088)
				(arc
					(start 281.074876 -41.849802)
					(mid 281.367273 -41.583053)
					(end 281.47645 -41.20261)
				)
				(arc
					(start 281.29611 -41.20261)
					(mid 280.75001 -41.746176)
					(end 280.20391 -41.20261)
				)
				(arc
					(start 280.20391 -41.20007)
					(mid 280.75001 -40.65397)
					(end 281.29611 -41.20007)
				)
			)
		)
	)
	(zone
		(layers "F.Cu" "In2.Cu" "In4.Cu" "In7.Cu" "In9.Cu")
		(hatch none 0.5)
		(connect_pads
			(clearance 0)
		)
		(min_thickness 0.25)
		(keepout
			(tracks not_allowed)
			(vias allowed)
			(pads allowed)
			(copperpour not_allowed)
			(footprints allowed)
		)
		(placement
			(enabled no)
			(sheetname "")
		)
		(fill yes
			(thermal_gap 0.5)
			(thermal_bridge_width 0.5)
			(island_removal_mode 0)
		)
		(polygon
			(pts
				(arc
					(start 281.47645 -37.200078)
					(mid 281.131922 -36.582131)
					(end 280.425144 -36.550346)
				)
				(xy 280.423874 -36.54806) (xy 278.424132 -37.548058) (xy 278.424132 -37.548312)
				(arc
					(start 278.425148 -37.550344)
					(mid 278.100282 -38.524942)
					(end 279.07488 -38.849808)
				)
				(xy 279.07615 -38.852094) (xy 280.375106 -38.202616)
				(arc
					(start 279.296114 -38.202616)
					(mid 278.750014 -38.746182)
					(end 278.203914 -38.202616)
				)
				(arc
					(start 278.203914 -38.200076)
					(mid 278.750014 -37.653976)
					(end 279.296114 -38.200076)
				)
				(xy 280.375614 -38.200076) (xy 280.375614 -38.202362) (xy 281.076146 -37.852096)
				(arc
					(start 281.074876 -37.84981)
					(mid 281.367273 -37.583061)
					(end 281.47645 -37.202618)
				)
				(arc
					(start 281.29611 -37.202618)
					(mid 280.75001 -37.746184)
					(end 280.20391 -37.202618)
				)
				(arc
					(start 280.20391 -37.200078)
					(mid 280.75001 -36.653978)
					(end 281.29611 -37.200078)
				)
			)
		)
	)
	(zone
		(layers "F.Cu" "In2.Cu" "In4.Cu" "In7.Cu" "In9.Cu")
		(hatch none 0.5)
		(connect_pads
			(clearance 0)
		)
		(min_thickness 0.25)
		(keepout
			(tracks not_allowed)
			(vias allowed)
			(pads allowed)
			(copperpour not_allowed)
			(footprints allowed)
		)
		(placement
			(enabled no)
			(sheetname "")
		)
		(fill yes
			(thermal_gap 0.5)
			(thermal_bridge_width 0.5)
			(island_removal_mode 0)
		)
		(polygon
			(pts
				(arc
					(start 238.77651 -77.199998)
					(mid 238.431982 -76.582051)
					(end 237.725204 -76.550266)
				)
				(xy 237.723934 -76.54798) (xy 235.724192 -77.547978) (xy 235.724192 -77.548232)
				(arc
					(start 235.725208 -77.550264)
					(mid 235.400342 -78.524862)
					(end 236.37494 -78.849728)
				)
				(xy 236.37621 -78.852014) (xy 237.675166 -78.202536)
				(arc
					(start 236.596174 -78.202536)
					(mid 236.050074 -78.746102)
					(end 235.503974 -78.202536)
				)
				(arc
					(start 235.503974 -78.199996)
					(mid 236.050074 -77.653896)
					(end 236.596174 -78.199996)
				)
				(xy 237.675674 -78.199996) (xy 237.675674 -78.202282) (xy 238.376206 -77.852016)
				(arc
					(start 238.374936 -77.84973)
					(mid 238.667333 -77.582981)
					(end 238.77651 -77.202538)
				)
				(arc
					(start 238.59617 -77.202538)
					(mid 238.05007 -77.746104)
					(end 237.50397 -77.202538)
				)
				(arc
					(start 237.50397 -77.199998)
					(mid 238.05007 -76.653898)
					(end 238.59617 -77.199998)
				)
			)
		)
	)
	(zone
		(layers "F.Cu" "In2.Cu" "In4.Cu" "In7.Cu" "In9.Cu")
		(hatch none 0.5)
		(connect_pads
			(clearance 0)
		)
		(min_thickness 0.25)
		(keepout
			(tracks not_allowed)
			(vias allowed)
			(pads allowed)
			(copperpour not_allowed)
			(footprints allowed)
		)
		(placement
			(enabled no)
			(sheetname "")
		)
		(fill yes
			(thermal_gap 0.5)
			(thermal_bridge_width 0.5)
			(island_removal_mode 0)
		)
		(polygon
			(pts
				(arc
					(start 286.436562 -303.15662)
					(mid 285.887922 -303.70526)
					(end 286.436562 -304.2539)
				)
				(arc
					(start 287.83661 -304.2539)
					(mid 288.223658 -304.094104)
					(end 288.38525 -303.7078)
				)
				(arc
					(start 288.23031 -303.7078)
					(mid 287.83661 -304.098968)
					(end 287.44291 -303.7078)
				)
				(arc
					(start 286.830262 -303.7078)
					(mid 286.436562 -304.098968)
					(end 286.042862 -303.7078)
				)
				(arc
					(start 286.042862 -303.70526)
					(mid 286.436562 -303.31156)
					(end 286.830262 -303.70526)
				)
				(arc
					(start 287.44291 -303.70526)
					(mid 287.83661 -303.31156)
					(end 288.23031 -303.70526)
				)
				(arc
					(start 288.38525 -303.70526)
					(mid 288.224557 -303.317313)
					(end 287.83661 -303.15662)
				)
				(xy 286.436816 -303.15662)
			)
		)
	)
	(zone
		(layers "F.Cu" "In2.Cu" "In4.Cu" "In7.Cu" "In9.Cu")
		(hatch none 0.5)
		(connect_pads
			(clearance 0)
		)
		(min_thickness 0.25)
		(keepout
			(tracks not_allowed)
			(vias allowed)
			(pads allowed)
			(copperpour not_allowed)
			(footprints allowed)
		)
		(placement
			(enabled no)
			(sheetname "")
		)
		(fill yes
			(thermal_gap 0.5)
			(thermal_bridge_width 0.5)
			(island_removal_mode 0)
		)
		(polygon
			(pts
				(arc
					(start 215.948768 -405.99995)
					(mid 215.400128 -405.45131)
					(end 214.851488 -405.99995)
				)
				(arc
					(start 214.851488 -407.399998)
					(mid 215.398858 -407.948637)
					(end 215.948768 -407.402538)
				)
				(arc
					(start 215.793828 -407.402538)
					(mid 215.400128 -407.793706)
					(end 215.006428 -407.402538)
				)
				(arc
					(start 215.006428 -407.399998)
					(mid 215.400128 -407.006298)
					(end 215.793828 -407.399998)
				)
				(xy 215.948768 -407.399998) (xy 215.948768 -406.00249)
				(arc
					(start 215.793828 -406.00249)
					(mid 215.400128 -406.393658)
					(end 215.006428 -406.00249)
				)
				(arc
					(start 215.006428 -405.99995)
					(mid 215.400128 -405.60625)
					(end 215.793828 -405.99995)
				)
			)
		)
	)
	(zone
		(layers "F.Cu" "In2.Cu" "In4.Cu" "In7.Cu" "In9.Cu")
		(hatch none 0.5)
		(connect_pads
			(clearance 0)
		)
		(min_thickness 0.25)
		(keepout
			(tracks not_allowed)
			(vias allowed)
			(pads allowed)
			(copperpour not_allowed)
			(footprints allowed)
		)
		(placement
			(enabled no)
			(sheetname "")
		)
		(fill yes
			(thermal_gap 0.5)
			(thermal_bridge_width 0.5)
			(island_removal_mode 0)
		)
		(polygon
			(pts
				(arc
					(start 238.77651 -173.49978)
					(mid 238.431982 -172.881833)
					(end 237.725204 -172.850048)
				)
				(xy 237.723934 -172.847762) (xy 235.724192 -173.84776) (xy 235.724192 -173.848014)
				(arc
					(start 235.725208 -173.850046)
					(mid 235.400342 -174.824644)
					(end 236.37494 -175.14951)
				)
				(xy 236.37621 -175.151796) (xy 237.675166 -174.502318)
				(arc
					(start 236.596174 -174.502318)
					(mid 236.050074 -175.045884)
					(end 235.503974 -174.502318)
				)
				(arc
					(start 235.503974 -174.499778)
					(mid 236.050074 -173.953678)
					(end 236.596174 -174.499778)
				)
				(xy 237.675674 -174.499778) (xy 237.675674 -174.502064) (xy 238.376206 -174.151798)
				(arc
					(start 238.374936 -174.149512)
					(mid 238.667333 -173.882763)
					(end 238.77651 -173.50232)
				)
				(arc
					(start 238.59617 -173.50232)
					(mid 238.05007 -174.045886)
					(end 237.50397 -173.50232)
				)
				(arc
					(start 237.50397 -173.49978)
					(mid 238.05007 -172.95368)
					(end 238.59617 -173.49978)
				)
			)
		)
	)
	(zone
		(layers "F.Cu" "In2.Cu" "In4.Cu" "In7.Cu" "In9.Cu")
		(hatch none 0.5)
		(connect_pads
			(clearance 0)
		)
		(min_thickness 0.25)
		(keepout
			(tracks not_allowed)
			(vias allowed)
			(pads allowed)
			(copperpour not_allowed)
			(footprints allowed)
		)
		(placement
			(enabled no)
			(sheetname "")
		)
		(fill yes
			(thermal_gap 0.5)
			(thermal_bridge_width 0.5)
			(island_removal_mode 0)
		)
		(polygon
			(pts
				(arc
					(start 279.236678 -310.356504)
					(mid 278.688038 -310.905144)
					(end 279.236678 -311.453784)
				)
				(arc
					(start 280.636726 -311.453784)
					(mid 281.023774 -311.293988)
					(end 281.185366 -310.907684)
				)
				(arc
					(start 281.030426 -310.907684)
					(mid 280.636726 -311.298852)
					(end 280.243026 -310.907684)
				)
				(arc
					(start 279.630378 -310.907684)
					(mid 279.236678 -311.298852)
					(end 278.842978 -310.907684)
				)
				(arc
					(start 278.842978 -310.905144)
					(mid 279.236678 -310.511444)
					(end 279.630378 -310.905144)
				)
				(arc
					(start 280.243026 -310.905144)
					(mid 280.636726 -310.511444)
					(end 281.030426 -310.905144)
				)
				(arc
					(start 281.185366 -310.905144)
					(mid 281.024673 -310.517197)
					(end 280.636726 -310.356504)
				)
				(xy 279.236932 -310.356504)
			)
		)
	)
	(zone
		(layers "F.Cu" "In2.Cu" "In4.Cu" "In7.Cu" "In9.Cu")
		(hatch none 0.5)
		(connect_pads
			(clearance 0)
		)
		(min_thickness 0.25)
		(keepout
			(tracks not_allowed)
			(vias allowed)
			(pads allowed)
			(copperpour not_allowed)
			(footprints allowed)
		)
		(placement
			(enabled no)
			(sheetname "")
		)
		(fill yes
			(thermal_gap 0.5)
			(thermal_bridge_width 0.5)
			(island_removal_mode 0)
		)
		(polygon
			(pts
				(arc
					(start 238.77651 -81.19999)
					(mid 238.431982 -80.582043)
					(end 237.725204 -80.550258)
				)
				(xy 237.723934 -80.547972) (xy 235.724192 -81.54797) (xy 235.724192 -81.548224)
				(arc
					(start 235.725208 -81.550256)
					(mid 235.400342 -82.524854)
					(end 236.37494 -82.84972)
				)
				(xy 236.37621 -82.852006) (xy 237.675166 -82.202528)
				(arc
					(start 236.596174 -82.202528)
					(mid 236.050074 -82.746094)
					(end 235.503974 -82.202528)
				)
				(arc
					(start 235.503974 -82.199988)
					(mid 236.050074 -81.653888)
					(end 236.596174 -82.199988)
				)
				(xy 237.675674 -82.199988) (xy 237.675674 -82.202274) (xy 238.376206 -81.852008)
				(arc
					(start 238.374936 -81.849722)
					(mid 238.667333 -81.582973)
					(end 238.77651 -81.20253)
				)
				(arc
					(start 238.59617 -81.20253)
					(mid 238.05007 -81.746096)
					(end 237.50397 -81.20253)
				)
				(arc
					(start 237.50397 -81.19999)
					(mid 238.05007 -80.65389)
					(end 238.59617 -81.19999)
				)
			)
		)
	)
	(zone
		(layers "F.Cu" "In2.Cu" "In4.Cu" "In7.Cu" "In9.Cu")
		(hatch none 0.5)
		(connect_pads
			(clearance 0)
		)
		(min_thickness 0.25)
		(keepout
			(tracks not_allowed)
			(vias allowed)
			(pads allowed)
			(copperpour not_allowed)
			(footprints allowed)
		)
		(placement
			(enabled no)
			(sheetname "")
		)
		(fill yes
			(thermal_gap 0.5)
			(thermal_bridge_width 0.5)
			(island_removal_mode 0)
		)
		(polygon
			(pts
				(arc
					(start 238.77651 -53.200046)
					(mid 238.431982 -52.582099)
					(end 237.725204 -52.550314)
				)
				(xy 237.723934 -52.548028) (xy 235.724192 -53.548026) (xy 235.724192 -53.54828)
				(arc
					(start 235.725208 -53.550312)
					(mid 235.400342 -54.52491)
					(end 236.37494 -54.849776)
				)
				(xy 236.37621 -54.852062) (xy 237.675166 -54.202584)
				(arc
					(start 236.596174 -54.202584)
					(mid 236.050074 -54.74615)
					(end 235.503974 -54.202584)
				)
				(arc
					(start 235.503974 -54.200044)
					(mid 236.050074 -53.653944)
					(end 236.596174 -54.200044)
				)
				(xy 237.675674 -54.200044) (xy 237.675674 -54.20233) (xy 238.376206 -53.852064)
				(arc
					(start 238.374936 -53.849778)
					(mid 238.667333 -53.583029)
					(end 238.77651 -53.202586)
				)
				(arc
					(start 238.59617 -53.202586)
					(mid 238.05007 -53.746152)
					(end 237.50397 -53.202586)
				)
				(arc
					(start 237.50397 -53.200046)
					(mid 238.05007 -52.653946)
					(end 238.59617 -53.200046)
				)
			)
		)
	)
	(zone
		(layers "F.Cu" "In2.Cu" "In4.Cu" "In7.Cu" "In9.Cu")
		(hatch none 0.5)
		(connect_pads
			(clearance 0)
		)
		(min_thickness 0.25)
		(keepout
			(tracks not_allowed)
			(vias allowed)
			(pads allowed)
			(copperpour not_allowed)
			(footprints allowed)
		)
		(placement
			(enabled no)
			(sheetname "")
		)
		(fill yes
			(thermal_gap 0.5)
			(thermal_bridge_width 0.5)
			(island_removal_mode 0)
		)
		(polygon
			(pts
				(arc
					(start 279.236678 -306.756562)
					(mid 278.688038 -307.305202)
					(end 279.236678 -307.853842)
				)
				(arc
					(start 280.636726 -307.853842)
					(mid 281.023774 -307.694046)
					(end 281.185366 -307.307742)
				)
				(arc
					(start 281.030426 -307.307742)
					(mid 280.636726 -307.69891)
					(end 280.243026 -307.307742)
				)
				(arc
					(start 279.630378 -307.307742)
					(mid 279.236678 -307.69891)
					(end 278.842978 -307.307742)
				)
				(arc
					(start 278.842978 -307.305202)
					(mid 279.236678 -306.911502)
					(end 279.630378 -307.305202)
				)
				(arc
					(start 280.243026 -307.305202)
					(mid 280.636726 -306.911502)
					(end 281.030426 -307.305202)
				)
				(arc
					(start 281.185366 -307.305202)
					(mid 281.024673 -306.917255)
					(end 280.636726 -306.756562)
				)
				(xy 279.236932 -306.756562)
			)
		)
	)
	(zone
		(layers "F.Cu" "In2.Cu" "In4.Cu" "In7.Cu" "In9.Cu")
		(hatch none 0.5)
		(connect_pads
			(clearance 0)
		)
		(min_thickness 0.25)
		(keepout
			(tracks not_allowed)
			(vias allowed)
			(pads allowed)
			(copperpour not_allowed)
			(footprints allowed)
		)
		(placement
			(enabled no)
			(sheetname "")
		)
		(fill yes
			(thermal_gap 0.5)
			(thermal_bridge_width 0.5)
			(island_removal_mode 0)
		)
		(polygon
			(pts
				(arc
					(start 279.236678 -353.55657)
					(mid 278.688038 -354.10521)
					(end 279.236678 -354.65385)
				)
				(arc
					(start 280.636726 -354.65385)
					(mid 281.023774 -354.494054)
					(end 281.185366 -354.10775)
				)
				(arc
					(start 281.030426 -354.10775)
					(mid 280.636726 -354.498918)
					(end 280.243026 -354.10775)
				)
				(arc
					(start 279.630378 -354.10775)
					(mid 279.236678 -354.498918)
					(end 278.842978 -354.10775)
				)
				(arc
					(start 278.842978 -354.10521)
					(mid 279.236678 -353.71151)
					(end 279.630378 -354.10521)
				)
				(arc
					(start 280.243026 -354.10521)
					(mid 280.636726 -353.71151)
					(end 281.030426 -354.10521)
				)
				(arc
					(start 281.185366 -354.10521)
					(mid 281.024673 -353.717263)
					(end 280.636726 -353.55657)
				)
				(xy 279.236932 -353.55657)
			)
		)
	)
	(zone
		(layers "F.Cu" "In2.Cu" "In4.Cu" "In7.Cu" "In9.Cu")
		(hatch none 0.5)
		(connect_pads
			(clearance 0)
		)
		(min_thickness 0.25)
		(keepout
			(tracks not_allowed)
			(vias allowed)
			(pads allowed)
			(copperpour not_allowed)
			(footprints allowed)
		)
		(placement
			(enabled no)
			(sheetname "")
		)
		(fill yes
			(thermal_gap 0.5)
			(thermal_bridge_width 0.5)
			(island_removal_mode 0)
		)
		(polygon
			(pts
				(arc
					(start 281.47645 -69.200014)
					(mid 281.131922 -68.582067)
					(end 280.425144 -68.550282)
				)
				(xy 280.423874 -68.547996) (xy 278.424132 -69.547994) (xy 278.424132 -69.548248)
				(arc
					(start 278.425148 -69.55028)
					(mid 278.100282 -70.524878)
					(end 279.07488 -70.849744)
				)
				(xy 279.07615 -70.85203) (xy 280.375106 -70.202552)
				(arc
					(start 279.296114 -70.202552)
					(mid 278.750014 -70.746118)
					(end 278.203914 -70.202552)
				)
				(arc
					(start 278.203914 -70.200012)
					(mid 278.750014 -69.653912)
					(end 279.296114 -70.200012)
				)
				(xy 280.375614 -70.200012) (xy 280.375614 -70.202298) (xy 281.076146 -69.852032)
				(arc
					(start 281.074876 -69.849746)
					(mid 281.367273 -69.582997)
					(end 281.47645 -69.202554)
				)
				(arc
					(start 281.29611 -69.202554)
					(mid 280.75001 -69.74612)
					(end 280.20391 -69.202554)
				)
				(arc
					(start 280.20391 -69.200014)
					(mid 280.75001 -68.653914)
					(end 281.29611 -69.200014)
				)
			)
		)
	)
	(zone
		(layer "B.Cu")
		(hatch none 0.5)
		(connect_pads
			(clearance 0)
		)
		(min_thickness 0.25)
		(keepout
			(tracks allowed)
			(vias allowed)
			(pads allowed)
			(copperpour allowed)
			(footprints not_allowed)
		)
		(placement
			(enabled no)
			(sheetname "")
		)
		(fill
			(thermal_gap 0.5)
			(thermal_bridge_width 0.5)
			(island_removal_mode 0)
		)
		(polygon
			(pts
				(arc
					(start 375.350024 -220.199966)
					(mid 371.599968 -216.44991)
					(end 367.849912 -220.199966)
				)
				(arc
					(start 367.849912 -220.199966)
					(mid 371.599968 -223.950022)
					(end 375.350024 -220.199966)
				)
			)
		)
	)
	(zone
		(layer "B.Cu")
		(hatch none 0.5)
		(connect_pads
			(clearance 0)
		)
		(min_thickness 0.25)
		(keepout
			(tracks not_allowed)
			(vias allowed)
			(pads allowed)
			(copperpour not_allowed)
			(footprints allowed)
		)
		(placement
			(enabled no)
			(sheetname "")
		)
		(fill
			(thermal_gap 0.5)
			(thermal_bridge_width 0.5)
			(island_removal_mode 0)
		)
		(polygon
			(pts
				(xy 279.047448 -173.770798) (xy 278.58085 -173.769528) (xy 278.424132 -173.84776) (xy 278.424132 -173.848014)
				(arc
					(start 278.425148 -173.850046)
					(mid 278.100282 -174.824644)
					(end 279.07488 -175.14951)
				)
				(xy 279.07615 -175.151796) (xy 281.076146 -174.151798)
				(arc
					(start 281.074876 -174.149512)
					(mid 281.399742 -173.174914)
					(end 280.425144 -172.850048)
				)
				(xy 280.423874 -172.847762)
				(arc
					(start 279.406858 -173.35627)
					(mid 279.435725 -173.369907)
					(end 279.464008 -173.384718)
				)
				(arc
					(start 279.464262 -173.384718)
					(mid 279.540831 -173.432776)
					(end 279.611328 -173.489366)
				)
				(xy 279.612598 -173.489366) (xy 279.640284 -173.517052) (xy 279.640538 -173.517306) (xy 279.775158 -173.651926)
				(arc
					(start 279.845516 -173.722284)
					(mid 279.884556 -173.75077)
					(end 279.930352 -173.766226)
				)
				(arc
					(start 279.948894 -173.769274)
					(mid 279.998664 -173.769115)
					(end 280.045922 -173.753526)
				)
				(arc
					(start 280.22804 -173.660308)
					(mid 281.236003 -173.250717)
					(end 280.314908 -173.829726)
				)
				(xy 280.13279 -173.923198) (xy 280.097738 -173.941232)
				(arc
					(start 280.094182 -173.939962)
					(mid 280.028424 -173.957176)
					(end 279.960578 -173.961298)
				)
				(xy 279.95753 -173.963584) (xy 279.903428 -173.954694) (xy 279.898856 -173.953932) (xy 279.864058 -173.948344)
				(arc
					(start 279.86228 -173.945804)
					(mid 279.799382 -173.921136)
					(end 279.742392 -173.884844)
				)
				(xy 279.738836 -173.884844) (xy 279.679146 -173.825154) (xy 279.505918 -173.651926)
				(arc
					(start 279.505664 -173.651672)
					(mid 279.442649 -173.59705)
					(end 279.372568 -173.55185)
				)
				(arc
					(start 279.372568 -173.55185)
					(mid 279.266851 -173.506647)
					(end 279.154382 -173.482762)
				)
				(xy 278.95931 -173.580044) (xy 279.087326 -173.580552) (xy 279.127712 -173.580552)
				(arc
					(start 279.12949 -173.58233)
					(mid 279.229597 -173.60149)
					(end 279.323546 -173.641004)
				)
				(arc
					(start 279.323546 -173.641004)
					(mid 279.364913 -173.666584)
					(end 279.403556 -173.696122)
				)
				(xy 279.405842 -173.696122) (xy 279.433528 -173.723554) (xy 279.433782 -173.724062) (xy 279.534874 -173.825154)
				(xy 279.562814 -173.853094)
				(arc
					(start 279.562814 -173.85792)
					(mid 279.605174 -173.951287)
					(end 279.608788 -174.053754)
				)
				(arc
					(start 279.608788 -174.054008)
					(mid 279.572867 -174.150046)
					(end 279.503124 -174.225204)
				)
				(xy 279.5016 -174.23003)
				(arc
					(start 279.273508 -174.344076)
					(mid 278.262231 -174.744823)
					(end 279.188164 -174.173896)
				)
				(arc
					(start 279.38095 -174.077376)
					(mid 279.407376 -174.055104)
					(end 279.420828 -174.023274)
				)
				(arc
					(start 279.420828 -174.023274)
					(mid 279.418215 -173.989023)
					(end 279.400254 -173.959774)
				)
				(xy 279.299162 -173.858682)
				(arc
					(start 279.298654 -173.858428)
					(mid 279.266896 -173.830923)
					(end 279.231598 -173.808136)
				)
				(arc
					(start 279.231598 -173.808136)
					(mid 279.163286 -173.780847)
					(end 279.090374 -173.771052)
				)
				(xy 279.086818 -173.771052) (xy 279.047702 -173.771052)
			)
		)
	)
	(zone
		(layer "B.Cu")
		(hatch none 0.5)
		(connect_pads
			(clearance 0)
		)
		(min_thickness 0.25)
		(keepout
			(tracks not_allowed)
			(vias allowed)
			(pads allowed)
			(copperpour not_allowed)
			(footprints allowed)
		)
		(placement
			(enabled no)
			(sheetname "")
		)
		(fill
			(thermal_gap 0.5)
			(thermal_bridge_width 0.5)
			(island_removal_mode 0)
		)
		(polygon
			(pts
				(arc
					(start 279.236678 -306.756562)
					(mid 278.688038 -307.305202)
					(end 279.236678 -307.853842)
				)
				(xy 279.642824 -307.853842) (xy 279.644094 -307.852572)
				(arc
					(start 279.661874 -307.83276)
					(mid 279.700941 -307.762182)
					(end 279.714452 -307.682646)
				)
				(arc
					(start 279.714452 -307.432202)
					(mid 279.699573 -307.396281)
					(end 279.663652 -307.381402)
				)
				(arc
					(start 279.623012 -307.381402)
					(mid 278.842901 -307.305202)
					(end 279.623012 -307.229002)
				)
				(xy 279.695148 -307.229002)
				(arc
					(start 279.698196 -307.23205)
					(mid 279.807273 -307.288581)
					(end 279.863804 -307.397658)
				)
				(xy 279.866852 -307.400706) (xy 279.866852 -307.714142)
				(arc
					(start 279.865582 -307.715666)
					(mid 279.852889 -307.786507)
					(end 279.827482 -307.853842)
				)
				(arc
					(start 279.978358 -307.853842)
					(mid 279.999443 -307.769652)
					(end 280.006552 -307.683154)
				)
				(xy 280.006552 -307.400706)
				(arc
					(start 280.0096 -307.397658)
					(mid 280.066131 -307.288581)
					(end 280.175208 -307.23205)
				)
				(xy 280.178256 -307.229002)
				(arc
					(start 280.250392 -307.229002)
					(mid 281.030503 -307.305202)
					(end 280.250392 -307.381402)
				)
				(arc
					(start 280.209752 -307.381402)
					(mid 280.173831 -307.396281)
					(end 280.158952 -307.432202)
				)
				(xy 280.158952 -307.683154) (xy 280.158952 -307.71465)
				(arc
					(start 280.15819 -307.715412)
					(mid 280.151333 -307.785163)
					(end 280.137362 -307.853842)
				)
				(arc
					(start 280.636726 -307.853842)
					(mid 281.185366 -307.305202)
					(end 280.636726 -306.756562)
				)
				(xy 279.236932 -306.756562)
			)
		)
	)
	(zone
		(layer "B.Cu")
		(hatch none 0.5)
		(connect_pads
			(clearance 0)
		)
		(min_thickness 0.25)
		(keepout
			(tracks allowed)
			(vias allowed)
			(pads allowed)
			(copperpour allowed)
			(footprints not_allowed)
		)
		(placement
			(enabled no)
			(sheetname "")
		)
		(fill
			(thermal_gap 0.5)
			(thermal_bridge_width 0.5)
			(island_removal_mode 0)
		)
		(polygon
			(pts
				(arc
					(start 284.299914 -414.219898)
					(mid 280.550112 -410.470096)
					(end 276.800056 -414.219898)
				)
				(arc
					(start 276.800056 -414.219898)
					(mid 280.550112 -417.969954)
					(end 284.299914 -414.219898)
				)
			)
		)
	)
	(zone
		(layer "B.Cu")
		(hatch none 0.5)
		(connect_pads
			(clearance 0)
		)
		(min_thickness 0.25)
		(keepout
			(tracks not_allowed)
			(vias allowed)
			(pads allowed)
			(copperpour not_allowed)
			(footprints allowed)
		)
		(placement
			(enabled no)
			(sheetname "")
		)
		(fill
			(thermal_gap 0.5)
			(thermal_bridge_width 0.5)
			(island_removal_mode 0)
		)
		(polygon
			(pts
				(xy 204.387196 -420.437056) (xy 204.387196 -419.514274) (xy 230.200962 -419.514274) (xy 230.98506 -420.298372)
				(xy 233.172254 -420.298372) (xy 233.956352 -419.514274) (xy 272.003266 -419.514274) (xy 272.003266 -420.437056)
			)
		)
	)
	(zone
		(layer "B.Cu")
		(hatch none 0.5)
		(connect_pads
			(clearance 0)
		)
		(min_thickness 0.25)
		(keepout
			(tracks allowed)
			(vias allowed)
			(pads allowed)
			(copperpour allowed)
			(footprints not_allowed)
		)
		(placement
			(enabled no)
			(sheetname "")
		)
		(fill
			(thermal_gap 0.5)
			(thermal_bridge_width 0.5)
			(island_removal_mode 0)
		)
		(polygon
			(pts
				(arc
					(start 458.924914 -9.19988)
					(mid 463.674968 -13.949934)
					(end 468.425022 -9.19988)
				)
				(arc
					(start 468.425022 -9.19988)
					(mid 463.674968 -4.449826)
					(end 458.924914 -9.19988)
				)
			)
		)
	)
	(zone
		(layer "B.Cu")
		(hatch none 0.5)
		(connect_pads
			(clearance 0)
		)
		(min_thickness 0.25)
		(keepout
			(tracks not_allowed)
			(vias allowed)
			(pads allowed)
			(copperpour not_allowed)
			(footprints allowed)
		)
		(placement
			(enabled no)
			(sheetname "")
		)
		(fill
			(thermal_gap 0.5)
			(thermal_bridge_width 0.5)
			(island_removal_mode 0)
		)
		(polygon
			(pts
				(arc
					(start 419.770052 -47.178722)
					(mid 419.389179 -46.797468)
					(end 419.008052 -47.178468)
				)
				(xy 419.008052 -47.527718)
				(arc
					(start 419.212268 -47.527718)
					(mid 419.280924 -47.500643)
					(end 419.312598 -47.433992)
				)
				(arc
					(start 419.312598 -47.433992)
					(mid 419.389174 -46.911751)
					(end 419.465252 -47.433992)
				)
				(xy 419.465252 -47.45863)
				(arc
					(start 419.462966 -47.460916)
					(mid 419.39114 -47.606006)
					(end 419.24605 -47.677832)
				)
				(xy 419.243764 -47.680118) (xy 419.008052 -47.680118) (xy 419.008052 -47.819818) (xy 419.243764 -47.819818)
				(arc
					(start 419.24605 -47.822104)
					(mid 419.39114 -47.89393)
					(end 419.462966 -48.03902)
				)
				(xy 419.465252 -48.041306)
				(arc
					(start 419.465252 -48.065944)
					(mid 419.389174 -48.588112)
					(end 419.312598 -48.065944)
				)
				(arc
					(start 419.312598 -48.065944)
					(mid 419.28091 -47.999308)
					(end 419.212268 -47.972218)
				)
				(xy 419.008052 -47.972218)
				(arc
					(start 419.008052 -48.321468)
					(mid 419.389052 -48.702468)
					(end 419.770052 -48.321468)
				)
			)
		)
	)
	(zone
		(layer "B.Cu")
		(hatch none 0.5)
		(connect_pads
			(clearance 0)
		)
		(min_thickness 0.25)
		(keepout
			(tracks not_allowed)
			(vias allowed)
			(pads allowed)
			(copperpour not_allowed)
			(footprints allowed)
		)
		(placement
			(enabled no)
			(sheetname "")
		)
		(fill
			(thermal_gap 0.5)
			(thermal_bridge_width 0.5)
			(island_removal_mode 0)
		)
		(polygon
			(pts
				(arc
					(start 271.970754 -332.12151)
					(mid 271.58696 -332.504923)
					(end 271.9705 -332.88859)
				)
				(arc
					(start 273.1135 -332.88859)
					(mid 273.49704 -332.50505)
					(end 273.1135 -332.12151)
				)
				(arc
					(start 272.768568 -332.12151)
					(mid 272.765366 -332.14835)
					(end 272.76425 -332.175358)
				)
				(arc
					(start 272.76425 -332.323948)
					(mid 272.791127 -332.394066)
					(end 272.857976 -332.428342)
				)
				(arc
					(start 272.857976 -332.428342)
					(mid 273.380217 -332.504796)
					(end 272.857976 -332.58125)
				)
				(xy 272.837656 -332.58125)
				(arc
					(start 272.83537 -332.578964)
					(mid 272.687253 -332.505847)
					(end 272.614136 -332.35773)
				)
				(xy 272.61185 -332.355444) (xy 272.61185 -332.143862) (xy 272.612866 -332.142846) (xy 272.614644 -332.12151)
				(arc
					(start 272.474436 -332.12151)
					(mid 272.472724 -332.14841)
					(end 272.47215 -332.175358)
				)
				(xy 272.47215 -332.355444)
				(arc
					(start 272.469864 -332.35773)
					(mid 272.396747 -332.505847)
					(end 272.24863 -332.578964)
				)
				(xy 272.246344 -332.58125)
				(arc
					(start 272.226024 -332.58125)
					(mid 271.703783 -332.504796)
					(end 272.226024 -332.428342)
				)
				(arc
					(start 272.226024 -332.428342)
					(mid 272.292939 -332.394125)
					(end 272.31975 -332.323948)
				)
				(xy 272.31975 -332.143862) (xy 272.320512 -332.1431) (xy 272.321528 -332.12151)
			)
		)
	)
	(zone
		(net "P3V3_STBY_SNB")
		(layer "B.Cu")
		(hatch none 0.5)
		(connect_pads
			(clearance 0.5)
		)
		(min_thickness 0.25)
		(fill yes
			(thermal_gap 0.5)
			(thermal_bridge_width 0.5)
			(island_removal_mode 0)
		)
		(polygon
			(pts
				(xy 177.389282 -232.204006) (xy 177.135282 -232.458006) (xy 177.135282 -234.744006) (xy 177.389282 -234.998006)
				(xy 179.040282 -234.998006) (xy 179.421282 -234.617006) (xy 179.421282 -232.585006) (xy 179.040282 -232.204006)
			)
		)
		(polygon
			(pts
				(xy 179.192682 -232.737406) (xy 178.989482 -232.737406) (xy 178.989482 -232.940606) (xy 179.192682 -232.940606)
			)
		)
		(polygon
			(pts
				(xy 178.583082 -232.737406) (xy 178.379882 -232.737406) (xy 178.379882 -232.940606) (xy 178.583082 -232.940606)
			)
		)
	)
	(zone
		(layer "B.Cu")
		(hatch none 0.5)
		(connect_pads
			(clearance 0)
		)
		(min_thickness 0.25)
		(keepout
			(tracks not_allowed)
			(vias allowed)
			(pads allowed)
			(copperpour not_allowed)
			(footprints allowed)
		)
		(placement
			(enabled no)
			(sheetname "")
		)
		(fill
			(thermal_gap 0.5)
			(thermal_bridge_width 0.5)
			(island_removal_mode 0)
		)
		(polygon
			(pts
				(arc
					(start 278.23668 -330.156566)
					(mid 277.68804 -330.705206)
					(end 278.23668 -331.253846)
				)
				(xy 278.642826 -331.253846) (xy 278.644096 -331.252576)
				(arc
					(start 278.661876 -331.232764)
					(mid 278.700943 -331.162186)
					(end 278.714454 -331.08265)
				)
				(arc
					(start 278.714454 -330.832206)
					(mid 278.699575 -330.796285)
					(end 278.663654 -330.781406)
				)
				(arc
					(start 278.623014 -330.781406)
					(mid 277.842903 -330.705206)
					(end 278.623014 -330.629006)
				)
				(xy 278.69515 -330.629006)
				(arc
					(start 278.698198 -330.632054)
					(mid 278.807275 -330.688585)
					(end 278.863806 -330.797662)
				)
				(xy 278.866854 -330.80071) (xy 278.866854 -331.114146)
				(arc
					(start 278.865584 -331.11567)
					(mid 278.852891 -331.186511)
					(end 278.827484 -331.253846)
				)
				(arc
					(start 278.97836 -331.253846)
					(mid 278.999445 -331.169656)
					(end 279.006554 -331.083158)
				)
				(xy 279.006554 -330.80071)
				(arc
					(start 279.009602 -330.797662)
					(mid 279.066133 -330.688585)
					(end 279.17521 -330.632054)
				)
				(xy 279.178258 -330.629006)
				(arc
					(start 279.250394 -330.629006)
					(mid 280.030505 -330.705206)
					(end 279.250394 -330.781406)
				)
				(arc
					(start 279.209754 -330.781406)
					(mid 279.173833 -330.796285)
					(end 279.158954 -330.832206)
				)
				(xy 279.158954 -331.083158) (xy 279.158954 -331.114654)
				(arc
					(start 279.158192 -331.115416)
					(mid 279.151335 -331.185167)
					(end 279.137364 -331.253846)
				)
				(arc
					(start 279.636728 -331.253846)
					(mid 280.185368 -330.705206)
					(end 279.636728 -330.156566)
				)
				(xy 278.236934 -330.156566)
			)
		)
	)
	(zone
		(net "GND")
		(layer "B.Cu")
		(hatch none 0.5)
		(connect_pads
			(clearance 0.5)
		)
		(min_thickness 0.25)
		(fill yes
			(thermal_gap 0.5)
			(thermal_bridge_width 0.5)
			(island_removal_mode 0)
		)
		(polygon
			(pts
				(arc
					(start 95.497396 -168.401492)
					(mid 98.443968 -167.251412)
					(end 99.674426 -164.337492)
				)
				(arc
					(start 99.674426 -161.162492)
					(mid 99.626767 -160.541811)
					(end 99.484942 -159.935672)
				)
				(arc
					(start 104.12476 -159.935672)
					(mid 104.775398 -162.90622)
					(end 107.296458 -164.606732)
				)
				(arc
					(start 107.296458 -164.606732)
					(mid 107.005286 -165.641921)
					(end 106.993944 -166.717218)
				)
				(arc
					(start 106.993944 -166.717218)
					(mid 103.246492 -170.963991)
					(end 107.333796 -174.884842)
				)
				(arc
					(start 109.222286 -174.884842)
					(mid 109.323739 -175.550978)
					(end 109.533182 -176.191418)
				)
				(arc
					(start 109.492542 -176.292002)
					(mid 106.744928 -175.61988)
					(end 104.218232 -176.891442)
				)
				(arc
					(start 104.218232 -176.891442)
					(mid 103.74259 -176.653441)
					(end 103.240078 -176.4792)
				)
				(arc
					(start 103.240078 -176.4792)
					(mid 102.329076 -172.444304)
					(end 98.363532 -171.267628)
				)
			)
		)
	)
	(zone
		(layer "B.Cu")
		(hatch none 0.5)
		(connect_pads
			(clearance 0)
		)
		(min_thickness 0.25)
		(keepout
			(tracks allowed)
			(vias allowed)
			(pads allowed)
			(copperpour allowed)
			(footprints allowed)
		)
		(placement
			(enabled no)
			(sheetname "")
		)
		(fill
			(thermal_gap 0.5)
			(thermal_bridge_width 0.5)
			(island_removal_mode 0)
		)
		(polygon
			(pts
				(xy 480.37242 -228.22916) (xy 482.157786 -228.22916) (xy 482.157786 -226.734878) (xy 480.37242 -226.734878)
			)
		)
	)
	(zone
		(net "MB0_P12V_R")
		(layer "B.Cu")
		(hatch none 0.5)
		(connect_pads
			(clearance 0.5)
		)
		(min_thickness 0.25)
		(fill yes
			(thermal_gap 0.5)
			(thermal_bridge_width 0.5)
			(island_removal_mode 0)
		)
		(polygon
			(pts
				(xy 166.436802 -147.66417) (xy 165.928802 -148.17217) (xy 165.928802 -155.79217) (xy 166.436802 -156.30017)
				(xy 173.929802 -156.30017) (xy 174.183802 -156.04617) (xy 174.183802 -149.82317) (xy 174.056802 -149.69617)
				(xy 173.167802 -149.69617) (xy 172.913802 -149.44217) (xy 172.913802 -147.91817) (xy 172.659802 -147.66417)
			)
		)
	)
	(zone
		(net "AGND_P3V3_STBY")
		(layer "B.Cu")
		(hatch none 0.5)
		(connect_pads
			(clearance 0.5)
		)
		(min_thickness 0.25)
		(fill yes
			(thermal_gap 0.5)
			(thermal_bridge_width 0.5)
			(island_removal_mode 0)
		)
		(polygon
			(pts
				(xy 183.663082 -217.776806) (xy 183.536082 -217.903806) (xy 183.536082 -218.727528) (xy 183.495442 -218.768168)
				(xy 183.495442 -220.490034) (xy 183.039766 -220.94571) (xy 183.039766 -222.91929) (xy 184.729882 -224.609406)
				(xy 184.958482 -224.609406) (xy 185.060082 -224.507806) (xy 185.060082 -223.633538) (xy 183.916828 -222.490284)
				(xy 183.916828 -221.102682) (xy 184.348882 -220.670628) (xy 184.348882 -217.903806) (xy 184.221882 -217.776806)
			)
		)
	)
	(zone
		(net "GND")
		(layer "B.Cu")
		(hatch none 0.5)
		(connect_pads
			(clearance 0.5)
		)
		(min_thickness 0.25)
		(fill yes
			(thermal_gap 0.5)
			(thermal_bridge_width 0.5)
			(island_removal_mode 0)
		)
		(polygon
			(pts
				(xy 51.578002 -252.40615) (xy 51.324002 -252.66015) (xy 51.324002 -254.43815) (xy 51.705002 -254.81915)
				(xy 56.912002 -254.81915) (xy 57.166002 -254.56515) (xy 57.166002 -252.53315) (xy 57.039002 -252.40615)
			)
		)
	)
	(zone
		(net "P5V_A_2")
		(layer "B.Cu")
		(hatch none 0.5)
		(connect_pads
			(clearance 0.5)
		)
		(min_thickness 0.25)
		(fill yes
			(thermal_gap 0.5)
			(thermal_bridge_width 0.5)
			(island_removal_mode 0)
		)
		(polygon
			(pts
				(xy 58.468006 -139.37615) (xy 57.978802 -139.865354) (xy 57.978802 -146.48815) (xy 58.867802 -147.37715)
				(xy 73.98004 -147.37715) (xy 74.061828 -147.295362) (xy 74.061828 -146.947128) (xy 74.156062 -146.852894)
				(xy 75.394058 -146.852894) (xy 76.139802 -146.10715) (xy 76.139802 -140.77315) (xy 74.742802 -139.37615)
			)
		)
	)
	(zone
		(layer "B.Cu")
		(hatch none 0.5)
		(connect_pads
			(clearance 0)
		)
		(min_thickness 0.25)
		(keepout
			(tracks allowed)
			(vias allowed)
			(pads allowed)
			(copperpour allowed)
			(footprints not_allowed)
		)
		(placement
			(enabled no)
			(sheetname "")
		)
		(fill
			(thermal_gap 0.5)
			(thermal_bridge_width 0.5)
			(island_removal_mode 0)
		)
		(polygon
			(pts
				(arc
					(start 409.150058 -289.999928)
					(mid 404.400004 -285.249874)
					(end 399.64995 -289.999928)
				)
				(arc
					(start 399.64995 -289.999928)
					(mid 404.400004 -294.749982)
					(end 409.150058 -289.999928)
				)
			)
		)
	)
	(zone
		(net "GND")
		(layer "B.Cu")
		(hatch none 0.5)
		(connect_pads
			(clearance 0.5)
		)
		(min_thickness 0.25)
		(fill yes
			(thermal_gap 0.5)
			(thermal_bridge_width 0.5)
			(island_removal_mode 0)
		)
		(polygon
			(pts
				(xy 363.835188 -211.7344)
				(arc
					(start 376.57405 -203.772516)
					(mid 374.202794 -202.114302)
					(end 373.509032 -199.305164)
				)
				(arc
					(start 373.509032 -199.305164)
					(mid 372.285917 -199.030511)
					(end 371.202204 -198.400416)
				)
				(xy 363.1438 -211.039456) (xy 363.1438 -211.455) (xy 363.4232 -211.7344)
			)
		)
	)
	(zone
		(layer "B.Cu")
		(hatch none 0.5)
		(connect_pads
			(clearance 0)
		)
		(min_thickness 0.25)
		(keepout
			(tracks not_allowed)
			(vias allowed)
			(pads allowed)
			(copperpour not_allowed)
			(footprints allowed)
		)
		(placement
			(enabled no)
			(sheetname "")
		)
		(fill
			(thermal_gap 0.5)
			(thermal_bridge_width 0.5)
			(island_removal_mode 0)
		)
		(polygon
			(pts
				(arc
					(start 377.298712 -20.950428)
					(mid 376.750199 -20.401534)
					(end 376.201432 -20.950174)
				)
				(arc
					(start 376.201432 -22.350222)
					(mid 376.750072 -22.898862)
					(end 377.298712 -22.350222)
				)
				(xy 377.298712 -21.891498) (xy 377.295918 -21.891498)
				(arc
					(start 376.916442 -21.891498)
					(mid 376.866153 -21.912329)
					(end 376.845322 -21.962618)
				)
				(arc
					(start 376.845322 -21.968206)
					(mid 376.750072 -22.743934)
					(end 376.654822 -21.968206)
				)
				(xy 376.654822 -21.923248)
				(arc
					(start 376.658378 -21.919692)
					(mid 376.731456 -21.777632)
					(end 376.873516 -21.704554)
				)
				(xy 376.877072 -21.700998) (xy 377.298712 -21.700998) (xy 377.298712 -21.599398) (xy 377.295918 -21.599398)
				(xy 376.877072 -21.599398)
				(arc
					(start 376.873516 -21.595842)
					(mid 376.731456 -21.522764)
					(end 376.658378 -21.380704)
				)
				(xy 376.654822 -21.377148)
				(arc
					(start 376.654822 -21.33219)
					(mid 376.750072 -20.556462)
					(end 376.845322 -21.33219)
				)
				(arc
					(start 376.845322 -21.337778)
					(mid 376.866153 -21.388067)
					(end 376.916442 -21.408898)
				)
				(xy 377.298712 -21.408898)
			)
		)
	)
	(zone
		(layer "B.Cu")
		(hatch none 0.5)
		(connect_pads
			(clearance 0)
		)
		(min_thickness 0.25)
		(keepout
			(tracks allowed)
			(vias allowed)
			(pads allowed)
			(copperpour allowed)
			(footprints not_allowed)
		)
		(placement
			(enabled no)
			(sheetname "")
		)
		(fill
			(thermal_gap 0.5)
			(thermal_bridge_width 0.5)
			(island_removal_mode 0)
		)
		(polygon
			(pts
				(arc
					(start 456.574906 -13.200126)
					(mid 457.67498 -14.3002)
					(end 458.775054 -13.200126)
				)
				(arc
					(start 458.775054 -13.200126)
					(mid 457.67498 -12.100052)
					(end 456.574906 -13.200126)
				)
			)
		)
	)
	(zone
		(layer "B.Cu")
		(hatch none 0.5)
		(connect_pads
			(clearance 0)
		)
		(min_thickness 0.25)
		(keepout
			(tracks not_allowed)
			(vias allowed)
			(pads allowed)
			(copperpour not_allowed)
			(footprints allowed)
		)
		(placement
			(enabled no)
			(sheetname "")
		)
		(fill
			(thermal_gap 0.5)
			(thermal_bridge_width 0.5)
			(island_removal_mode 0)
		)
		(polygon
			(pts
				(arc
					(start 238.374936 -45.849794)
					(mid 238.699802 -44.875196)
					(end 237.725204 -44.55033)
				)
				(xy 237.723934 -44.548044)
				(arc
					(start 236.706918 -45.056552)
					(mid 236.735785 -45.070189)
					(end 236.764068 -45.085)
				)
				(arc
					(start 236.764322 -45.085)
					(mid 236.840891 -45.133058)
					(end 236.911388 -45.189648)
				)
				(xy 236.912658 -45.189648) (xy 236.940344 -45.217334) (xy 236.940598 -45.217588)
				(arc
					(start 237.145576 -45.422566)
					(mid 237.184616 -45.451052)
					(end 237.230412 -45.466508)
				)
				(arc
					(start 237.248954 -45.469556)
					(mid 237.298724 -45.469397)
					(end 237.345982 -45.453808)
				)
				(arc
					(start 237.5281 -45.36059)
					(mid 238.536063 -44.950999)
					(end 237.614968 -45.530008)
				)
				(xy 237.43285 -45.62348) (xy 237.397798 -45.641514)
				(arc
					(start 237.394242 -45.640244)
					(mid 237.328484 -45.657458)
					(end 237.260638 -45.66158)
				)
				(xy 237.25759 -45.663866) (xy 237.203488 -45.654976) (xy 237.198916 -45.654214) (xy 237.164118 -45.648626)
				(arc
					(start 237.16234 -45.646086)
					(mid 237.099442 -45.621418)
					(end 237.042452 -45.585126)
				)
				(xy 237.038896 -45.585126) (xy 237.010956 -45.557186)
				(arc
					(start 236.805724 -45.351954)
					(mid 236.742709 -45.297332)
					(end 236.672628 -45.252132)
				)
				(arc
					(start 236.672628 -45.252132)
					(mid 236.566911 -45.206929)
					(end 236.454442 -45.183044)
				)
				(xy 236.258608 -45.280834) (xy 236.427772 -45.280834)
				(arc
					(start 236.42955 -45.282612)
					(mid 236.529657 -45.301772)
					(end 236.623606 -45.341286)
				)
				(arc
					(start 236.623606 -45.341286)
					(mid 236.664973 -45.366866)
					(end 236.703616 -45.396404)
				)
				(xy 236.705902 -45.396404) (xy 236.733588 -45.423836) (xy 236.733842 -45.424344) (xy 236.862874 -45.553376)
				(arc
					(start 236.862874 -45.558202)
					(mid 236.905234 -45.651569)
					(end 236.908848 -45.754036)
				)
				(arc
					(start 236.908848 -45.75429)
					(mid 236.872927 -45.850328)
					(end 236.803184 -45.925486)
				)
				(xy 236.80166 -45.930312)
				(arc
					(start 236.573568 -46.044358)
					(mid 235.562291 -46.445105)
					(end 236.488224 -45.874178)
				)
				(arc
					(start 236.68101 -45.777658)
					(mid 236.707436 -45.755386)
					(end 236.720888 -45.723556)
				)
				(arc
					(start 236.720888 -45.723556)
					(mid 236.718275 -45.689305)
					(end 236.700314 -45.660056)
				)
				(arc
					(start 236.598714 -45.55871)
					(mid 236.566956 -45.531205)
					(end 236.531658 -45.508418)
				)
				(arc
					(start 236.531658 -45.508418)
					(mid 236.462363 -45.480872)
					(end 236.388402 -45.471334)
				)
				(xy 235.877608 -45.471334) (xy 235.724192 -45.548042) (xy 235.724192 -45.548296)
				(arc
					(start 235.725208 -45.550328)
					(mid 235.400342 -46.524926)
					(end 236.37494 -46.849792)
				)
				(xy 236.37621 -46.852078) (xy 238.376206 -45.85208)
			)
		)
	)
	(zone
		(layer "B.Cu")
		(hatch none 0.5)
		(connect_pads
			(clearance 0)
		)
		(min_thickness 0.25)
		(keepout
			(tracks not_allowed)
			(vias allowed)
			(pads allowed)
			(copperpour not_allowed)
			(footprints allowed)
		)
		(placement
			(enabled no)
			(sheetname "")
		)
		(fill
			(thermal_gap 0.5)
			(thermal_bridge_width 0.5)
			(island_removal_mode 0)
		)
		(polygon
			(pts
				(arc
					(start 362.89869 -20.950428)
					(mid 362.350177 -20.401534)
					(end 361.80141 -20.950174)
				)
				(arc
					(start 361.80141 -21.42871)
					(mid 361.866913 -21.416437)
					(end 361.933236 -21.409914)
				)
				(xy 361.934506 -21.408898)
				(arc
					(start 362.18368 -21.408898)
					(mid 362.233969 -21.388067)
					(end 362.2548 -21.337778)
				)
				(arc
					(start 362.2548 -21.33219)
					(mid 362.35005 -20.556462)
					(end 362.4453 -21.33219)
				)
				(xy 362.4453 -21.377148)
				(arc
					(start 362.441744 -21.380704)
					(mid 362.368666 -21.522764)
					(end 362.226606 -21.595842)
				)
				(xy 362.22305 -21.599398)
				(arc
					(start 361.973876 -21.599398)
					(mid 361.886634 -21.606021)
					(end 361.80141 -21.625814)
				)
				(arc
					(start 361.80141 -21.73351)
					(mid 361.865965 -21.713421)
					(end 361.932728 -21.702776)
				)
				(xy 361.934506 -21.700998) (xy 362.22305 -21.700998)
				(arc
					(start 362.226606 -21.704554)
					(mid 362.368666 -21.777632)
					(end 362.441744 -21.919692)
				)
				(xy 362.4453 -21.923248)
				(arc
					(start 362.4453 -21.968206)
					(mid 362.35005 -22.743934)
					(end 362.2548 -21.968206)
				)
				(arc
					(start 362.2548 -21.962618)
					(mid 362.233969 -21.912329)
					(end 362.18368 -21.891498)
				)
				(arc
					(start 361.973876 -21.891498)
					(mid 361.882801 -21.906584)
					(end 361.80141 -21.950172)
				)
				(arc
					(start 361.80141 -22.350222)
					(mid 362.35005 -22.898862)
					(end 362.89869 -22.350222)
				)
			)
		)
	)
	(zone
		(layer "B.Cu")
		(hatch none 0.5)
		(connect_pads
			(clearance 0)
		)
		(min_thickness 0.25)
		(keepout
			(tracks allowed)
			(vias allowed)
			(pads allowed)
			(copperpour allowed)
			(footprints allowed)
		)
		(placement
			(enabled no)
			(sheetname "")
		)
		(fill
			(thermal_gap 0.5)
			(thermal_bridge_width 0.5)
			(island_removal_mode 0)
		)
		(polygon
			(pts
				(xy 46.772576 -145.374614) (xy 44.621704 -145.374614) (xy 44.621704 -139.954) (xy 46.772576 -139.954)
			)
		)
	)
	(zone
		(net "GND")
		(layer "B.Cu")
		(hatch none 0.5)
		(connect_pads
			(clearance 0.5)
		)
		(min_thickness 0.25)
		(fill yes
			(thermal_gap 0.5)
			(thermal_bridge_width 0.5)
			(island_removal_mode 0)
		)
		(polygon
			(pts
				(xy 464.150202 -255.55575) (xy 463.27441 -256.431542) (xy 463.27441 -258.969002) (xy 463.772758 -259.46735)
				(xy 467.54288 -259.46735) (xy 468.001604 -259.008626) (xy 468.001604 -256.587752) (xy 466.969602 -255.55575)
			)
		)
	)
	(zone
		(net "P5V_A_LL_R")
		(layer "B.Cu")
		(hatch none 0.5)
		(connect_pads
			(clearance 0.5)
		)
		(min_thickness 0.25)
		(fill yes
			(thermal_gap 0.5)
			(thermal_bridge_width 0.5)
			(island_removal_mode 0)
		)
		(polygon
			(pts
				(xy 38.166802 -253.09195) (xy 37.989002 -253.26975) (xy 37.989002 -254.811276) (xy 38.203124 -255.025398)
				(xy 38.841172 -255.025398) (xy 38.97249 -255.156716) (xy 38.97249 -256.183638) (xy 39.259002 -256.47015)
				(xy 39.99484 -256.47015) (xy 40.24884 -256.21615) (xy 40.24884 -253.268988) (xy 40.071802 -253.09195)
			)
		)
		(polygon
			(pts
				(xy 39.739824 -254.914654) (xy 39.536624 -254.914654) (xy 39.536624 -255.117854) (xy 39.739824 -255.117854)
			)
		)
		(polygon
			(pts
				(xy 39.739824 -254.305054) (xy 39.536624 -254.305054) (xy 39.536624 -254.508254) (xy 39.739824 -254.508254)
			)
		)
		(polygon
			(pts
				(xy 39.532814 -253.934976) (xy 39.329614 -253.934976) (xy 39.329614 -254.138176) (xy 39.532814 -254.138176)
			)
		)
		(polygon
			(pts
				(xy 38.871144 -253.510796) (xy 38.667944 -253.510796) (xy 38.667944 -253.713996) (xy 38.871144 -253.713996)
			)
		)
		(polygon
			(pts
				(xy 38.312344 -253.510796) (xy 38.109144 -253.510796) (xy 38.109144 -253.713996) (xy 38.312344 -253.713996)
			)
		)
	)
	(zone
		(layer "B.Cu")
		(hatch none 0.5)
		(connect_pads
			(clearance 0)
		)
		(min_thickness 0.25)
		(keepout
			(tracks allowed)
			(vias allowed)
			(pads allowed)
			(copperpour allowed)
			(footprints not_allowed)
		)
		(placement
			(enabled no)
			(sheetname "")
		)
		(fill
			(thermal_gap 0.5)
			(thermal_bridge_width 0.5)
			(island_removal_mode 0)
		)
		(polygon
			(pts
				(arc
					(start 350.750124 -164.200078)
					(mid 347.000068 -160.450022)
					(end 343.250012 -164.200078)
				)
				(arc
					(start 343.250012 -164.200078)
					(mid 347.000068 -167.950134)
					(end 350.750124 -164.200078)
				)
			)
		)
	)
	(zone
		(net "GND")
		(layer "B.Cu")
		(hatch none 0.5)
		(connect_pads
			(clearance 0.5)
		)
		(min_thickness 0.25)
		(fill yes
			(thermal_gap 0.5)
			(thermal_bridge_width 0.5)
			(island_removal_mode 0)
		)
		(polygon
			(pts
				(xy 17.542002 -247.07215) (xy 17.288002 -247.32615) (xy 17.288002 -249.10415) (xy 19.828002 -251.64415)
				(xy 22.876002 -251.64415) (xy 23.003002 -251.51715) (xy 23.003002 -250.12015) (xy 23.511002 -249.611896)
				(xy 23.511002 -248.46915) (xy 24.019002 -247.96115) (xy 24.019002 -247.32615) (xy 23.892002 -247.19915)
				(xy 23.130002 -247.19915) (xy 23.003002 -247.07215)
			)
		)
		(polygon
			(pts
				(xy 22.731222 -249.55373) (xy 22.528022 -249.55373) (xy 22.528022 -249.75693) (xy 22.731222 -249.75693)
			)
		)
		(polygon
			(pts
				(xy 22.731222 -248.69013) (xy 22.528022 -248.69013) (xy 22.528022 -248.89333) (xy 22.731222 -248.89333)
			)
		)
		(polygon
			(pts
				(xy 23.4442 -247.7516) (xy 23.241 -247.7516) (xy 23.241 -247.9548) (xy 23.4442 -247.9548)
			)
		)
	)
	(zone
		(layer "B.Cu")
		(hatch none 0.5)
		(connect_pads
			(clearance 0)
		)
		(min_thickness 0.25)
		(keepout
			(tracks not_allowed)
			(vias allowed)
			(pads allowed)
			(copperpour not_allowed)
			(footprints allowed)
		)
		(placement
			(enabled no)
			(sheetname "")
		)
		(fill
			(thermal_gap 0.5)
			(thermal_bridge_width 0.5)
			(island_removal_mode 0)
		)
		(polygon
			(pts
				(arc
					(start 279.236678 -335.556606)
					(mid 278.688038 -336.105246)
					(end 279.236678 -336.653886)
				)
				(xy 279.642824 -336.653886) (xy 279.644094 -336.652616)
				(arc
					(start 279.661874 -336.632804)
					(mid 279.700941 -336.562226)
					(end 279.714452 -336.48269)
				)
				(arc
					(start 279.714452 -336.232246)
					(mid 279.699573 -336.196325)
					(end 279.663652 -336.181446)
				)
				(arc
					(start 279.623012 -336.181446)
					(mid 278.842901 -336.105246)
					(end 279.623012 -336.029046)
				)
				(xy 279.695148 -336.029046)
				(arc
					(start 279.698196 -336.032094)
					(mid 279.807273 -336.088625)
					(end 279.863804 -336.197702)
				)
				(xy 279.866852 -336.20075) (xy 279.866852 -336.514186)
				(arc
					(start 279.865582 -336.51571)
					(mid 279.852889 -336.586551)
					(end 279.827482 -336.653886)
				)
				(arc
					(start 279.978358 -336.653886)
					(mid 279.999443 -336.569696)
					(end 280.006552 -336.483198)
				)
				(xy 280.006552 -336.20075)
				(arc
					(start 280.0096 -336.197702)
					(mid 280.066131 -336.088625)
					(end 280.175208 -336.032094)
				)
				(xy 280.178256 -336.029046)
				(arc
					(start 280.250392 -336.029046)
					(mid 281.030503 -336.105246)
					(end 280.250392 -336.181446)
				)
				(arc
					(start 280.209752 -336.181446)
					(mid 280.173831 -336.196325)
					(end 280.158952 -336.232246)
				)
				(xy 280.158952 -336.483198) (xy 280.158952 -336.514694)
				(arc
					(start 280.15819 -336.515456)
					(mid 280.151333 -336.585207)
					(end 280.137362 -336.653886)
				)
				(arc
					(start 280.636726 -336.653886)
					(mid 281.185366 -336.105246)
					(end 280.636726 -335.556606)
				)
				(xy 279.236932 -335.556606)
			)
		)
	)
	(zone
		(layer "B.Cu")
		(hatch none 0.5)
		(connect_pads
			(clearance 0)
		)
		(min_thickness 0.25)
		(keepout
			(tracks allowed)
			(vias allowed)
			(pads allowed)
			(copperpour allowed)
			(footprints not_allowed)
		)
		(placement
			(enabled no)
			(sheetname "")
		)
		(fill
			(thermal_gap 0.5)
			(thermal_bridge_width 0.5)
			(island_removal_mode 0)
		)
		(polygon
			(pts
				(arc
					(start 11.75004 -224.199958)
					(mid 7.999984 -220.449902)
					(end 4.249928 -224.199958)
				)
				(arc
					(start 4.249928 -224.199958)
					(mid 7.999984 -227.950014)
					(end 11.75004 -224.199958)
				)
			)
		)
	)
	(zone
		(layer "B.Cu")
		(hatch none 0.5)
		(connect_pads
			(clearance 0)
		)
		(min_thickness 0.25)
		(keepout
			(tracks allowed)
			(vias allowed)
			(pads allowed)
			(copperpour allowed)
			(footprints allowed)
		)
		(placement
			(enabled no)
			(sheetname "")
		)
		(fill
			(thermal_gap 0.5)
			(thermal_bridge_width 0.5)
			(island_removal_mode 0)
		)
		(polygon
			(pts
				(xy 433.470558 -253.485142) (xy 433.470558 -251.33427) (xy 441.635896 -251.33427) (xy 441.635896 -253.485142)
			)
		)
	)
	(zone
		(layer "B.Cu")
		(hatch none 0.5)
		(connect_pads
			(clearance 0)
		)
		(min_thickness 0.25)
		(keepout
			(tracks allowed)
			(vias allowed)
			(pads allowed)
			(copperpour allowed)
			(footprints allowed)
		)
		(placement
			(enabled no)
			(sheetname "")
		)
		(fill
			(thermal_gap 0.5)
			(thermal_bridge_width 0.5)
			(island_removal_mode 0)
		)
		(polygon
			(pts
				(xy 216.394792 -118.265702) (xy 216.394792 -121.271538) (xy 218.392502 -121.271538) (xy 218.392502 -118.265702)
			)
		)
	)
	(zone
		(layer "B.Cu")
		(hatch none 0.5)
		(connect_pads
			(clearance 0)
		)
		(min_thickness 0.25)
		(keepout
			(tracks not_allowed)
			(vias allowed)
			(pads allowed)
			(copperpour not_allowed)
			(footprints allowed)
		)
		(placement
			(enabled no)
			(sheetname "")
		)
		(fill
			(thermal_gap 0.5)
			(thermal_bridge_width 0.5)
			(island_removal_mode 0)
		)
		(polygon
			(pts
				(arc
					(start 7.599934 -120.499886)
					(mid 3.850132 -116.750084)
					(end 0.100076 -120.499886)
				)
				(arc
					(start 0.100076 -120.499886)
					(mid 3.850132 -124.249942)
					(end 7.599934 -120.499886)
				)
			)
		)
	)
	(zone
		(layer "B.Cu")
		(hatch none 0.5)
		(connect_pads
			(clearance 0)
		)
		(min_thickness 0.25)
		(keepout
			(tracks not_allowed)
			(vias allowed)
			(pads allowed)
			(copperpour not_allowed)
			(footprints allowed)
		)
		(placement
			(enabled no)
			(sheetname "")
		)
		(fill
			(thermal_gap 0.5)
			(thermal_bridge_width 0.5)
			(island_removal_mode 0)
		)
		(polygon
			(pts
				(arc
					(start 281.074876 -81.849722)
					(mid 281.399742 -80.875124)
					(end 280.425144 -80.550258)
				)
				(xy 280.423874 -80.547972) (xy 278.424132 -81.54797) (xy 278.424132 -81.548224)
				(arc
					(start 278.425148 -81.550256)
					(mid 278.100282 -82.524854)
					(end 279.07488 -82.84972)
				)
				(xy 279.07615 -82.852006)
				(arc
					(start 280.086562 -82.3468)
					(mid 279.982979 -82.285348)
					(end 279.888696 -82.210402)
				)
				(xy 279.887426 -82.210402)
				(arc
					(start 279.654508 -81.977484)
					(mid 279.615468 -81.948998)
					(end 279.569672 -81.933542)
				)
				(xy 279.566116 -81.933034)
				(arc
					(start 279.55113 -81.930494)
					(mid 279.50136 -81.930653)
					(end 279.454102 -81.946242)
				)
				(arc
					(start 279.271984 -82.03946)
					(mid 278.264021 -82.449051)
					(end 279.185116 -81.870042)
				)
				(xy 279.367234 -81.77657) (xy 279.402286 -81.758536)
				(arc
					(start 279.405842 -81.759806)
					(mid 279.4716 -81.742592)
					(end 279.539446 -81.73847)
				)
				(xy 279.542494 -81.736184) (xy 279.58161 -81.742534) (xy 279.596596 -81.745074) (xy 279.601168 -81.745836)
				(xy 279.635966 -81.751424)
				(arc
					(start 279.637744 -81.753964)
					(mid 279.700642 -81.778632)
					(end 279.757632 -81.814924)
				)
				(xy 279.761188 -81.814924) (xy 279.879298 -81.933034)
				(arc
					(start 279.994106 -82.047842)
					(mid 280.143896 -82.161495)
					(end 280.318718 -82.230722)
				)
				(xy 280.481786 -82.149188) (xy 280.445464 -82.149188)
				(arc
					(start 280.44394 -82.147664)
					(mid 280.258325 -82.104028)
					(end 280.096214 -82.003646)
				)
				(xy 280.094182 -82.003646) (xy 280.066242 -81.975706) (xy 279.93721 -81.846674)
				(arc
					(start 279.93721 -81.841848)
					(mid 279.89485 -81.748481)
					(end 279.891236 -81.646014)
				)
				(arc
					(start 279.891236 -81.64576)
					(mid 279.927157 -81.549722)
					(end 279.9969 -81.474564)
				)
				(xy 279.998424 -81.469738)
				(arc
					(start 280.226516 -81.355692)
					(mid 281.237793 -80.954945)
					(end 280.31186 -81.525872)
				)
				(arc
					(start 280.119074 -81.622392)
					(mid 280.092648 -81.644664)
					(end 280.079196 -81.676494)
				)
				(arc
					(start 280.079196 -81.676494)
					(mid 280.081809 -81.710745)
					(end 280.09977 -81.739994)
				)
				(arc
					(start 280.200862 -81.841086)
					(mid 280.331149 -81.928141)
					(end 280.484834 -81.958688)
				)
				(xy 280.862786 -81.958688) (xy 281.076146 -81.852008)
			)
		)
	)
	(zone
		(layer "B.Cu")
		(hatch none 0.5)
		(connect_pads
			(clearance 0)
		)
		(min_thickness 0.25)
		(keepout
			(tracks allowed)
			(vias allowed)
			(pads allowed)
			(copperpour allowed)
			(footprints not_allowed)
		)
		(placement
			(enabled no)
			(sheetname "")
		)
		(fill
			(thermal_gap 0.5)
			(thermal_bridge_width 0.5)
			(island_removal_mode 0)
		)
		(polygon
			(pts
				(arc
					(start 307.200046 -393.199874)
					(mid 300.20006 -386.199888)
					(end 293.200074 -393.199874)
				)
				(arc
					(start 293.200074 -399.200116)
					(mid 300.20006 -406.200102)
					(end 307.200046 -399.200116)
				)
			)
		)
	)
	(zone
		(layer "B.Cu")
		(hatch none 0.5)
		(connect_pads
			(clearance 0)
		)
		(min_thickness 0.25)
		(keepout
			(tracks allowed)
			(vias allowed)
			(pads allowed)
			(copperpour allowed)
			(footprints allowed)
		)
		(placement
			(enabled no)
			(sheetname "")
		)
		(fill
			(thermal_gap 0.5)
			(thermal_bridge_width 0.5)
			(island_removal_mode 0)
		)
		(polygon
			(pts
				(xy 446.847976 -253.070614) (xy 444.697104 -253.070614) (xy 444.697104 -247.65) (xy 446.847976 -247.65)
			)
		)
	)
	(zone
		(layer "B.Cu")
		(hatch none 0.5)
		(connect_pads
			(clearance 0)
		)
		(min_thickness 0.25)
		(keepout
			(tracks not_allowed)
			(vias allowed)
			(pads allowed)
			(copperpour not_allowed)
			(footprints allowed)
		)
		(placement
			(enabled no)
			(sheetname "")
		)
		(fill
			(thermal_gap 0.5)
			(thermal_bridge_width 0.5)
			(island_removal_mode 0)
		)
		(polygon
			(pts
				(arc
					(start 328.425048 -9.19988)
					(mid 323.674994 -4.449826)
					(end 318.92494 -9.19988)
				)
				(arc
					(start 318.92494 -9.19988)
					(mid 323.674994 -13.949934)
					(end 328.425048 -9.19988)
				)
			)
		)
	)
	(zone
		(net "GND")
		(layer "B.Cu")
		(hatch none 0.5)
		(connect_pads
			(clearance 0.5)
		)
		(min_thickness 0.25)
		(fill yes
			(thermal_gap 0.5)
			(thermal_bridge_width 0.5)
			(island_removal_mode 0)
		)
		(polygon
			(pts
				(arc
					(start 415.676334 -183.896)
					(mid 413.990573 -186.120794)
					(end 411.270196 -186.746134)
				)
				(arc
					(start 399.331688 -198.575168)
					(mid 403.117115 -202.513937)
					(end 404.496016 -207.79994)
				)
				(arc
					(start 404.496016 -213.79434)
					(mid 403.510998 -218.30514)
					(end 400.735292 -221.99473)
				)
				(arc
					(start 400.735292 -221.99473)
					(mid 401.641476 -222.611787)
					(end 402.35124 -223.447356)
				)
				(arc
					(start 402.35124 -223.447356)
					(mid 404.67303 -224.043756)
					(end 406.261824 -225.838766)
				)
				(arc
					(start 412.637224 -224.568766)
					(mid 413.448778 -223.240279)
					(end 414.697926 -222.311214)
				)
				(arc
					(start 414.697926 -222.311214)
					(mid 415.199208 -221.704516)
					(end 415.807398 -221.205044)
				)
				(arc
					(start 415.807398 -221.205044)
					(mid 411.351389 -208.580298)
					(end 419.535864 -197.98538)
				)
				(arc
					(start 419.535864 -197.98538)
					(mid 418.636243 -196.987118)
					(end 418.108638 -195.751196)
				)
				(arc
					(start 418.108638 -195.751196)
					(mid 415.724024 -192.04938)
					(end 417.656264 -188.092588)
				)
				(arc
					(start 417.656264 -188.092588)
					(mid 416.592058 -186.692507)
					(end 416.214052 -184.974992)
				)
				(xy 416.214052 -183.896)
			)
		)
	)
	(zone
		(layer "B.Cu")
		(hatch none 0.5)
		(connect_pads
			(clearance 0)
		)
		(min_thickness 0.25)
		(keepout
			(tracks allowed)
			(vias allowed)
			(pads allowed)
			(copperpour allowed)
			(footprints not_allowed)
		)
		(placement
			(enabled no)
			(sheetname "")
		)
		(fill
			(thermal_gap 0.5)
			(thermal_bridge_width 0.5)
			(island_removal_mode 0)
		)
		(polygon
			(pts
				(xy 251.84989 38.800024) (xy 251.84989 -99.199954) (xy 281.850084 -99.199954) (xy 281.850084 -135.359902)
				(arc
					(start 293.802054 -135.359902)
					(mid 300.20006 -131.199881)
					(end 306.598066 -135.359902)
				)
				(xy 392.34999 -135.359902) (xy 392.34999 -149.200108) (xy 476.25 -149.200108) (xy 476.25 0)
				(arc
					(start 396.999968 0)
					(mid 396.292863 -0.292893)
					(end 395.99997 -0.999998)
				)
				(arc
					(start 395.99997 -13.999972)
					(mid 395.707077 -14.707077)
					(end 394.999972 -14.99997)
				)
				(arc
					(start 349.000064 -14.99997)
					(mid 348.292959 -14.707077)
					(end 348.000066 -13.999972)
				)
				(arc
					(start 348.000066 -0.999998)
					(mid 347.707173 -0.292893)
					(end 347.000068 0)
				)
				(arc
					(start 300.999906 0)
					(mid 300.292801 0.292893)
					(end 299.999908 0.999998)
				)
				(arc
					(start 299.999908 37.800026)
					(mid 299.707015 38.507131)
					(end 298.99991 38.800024)
				)
			)
		)
	)
	(zone
		(net "GND")
		(layer "B.Cu")
		(hatch none 0.5)
		(connect_pads
			(clearance 0.5)
		)
		(min_thickness 0.25)
		(fill yes
			(thermal_gap 0.5)
			(thermal_bridge_width 0.5)
			(island_removal_mode 0)
		)
		(polygon
			(pts
				(arc
					(start 368.67973 -105.911396)
					(mid 373.91051 -105.703335)
					(end 374.65254 -100.521262)
				)
				(xy 382.853692 -95.20682)
				(arc
					(start 382.853692 -98.794316)
					(mid 384.007886 -103.657164)
					(end 387.22427 -107.48264)
				)
				(arc
					(start 364.327948 -107.48264)
					(mid 364.33822 -107.342313)
					(end 364.343696 -107.201716)
				)
				(arc
					(start 365.291878 -106.58729)
					(mid 367.060656 -106.624554)
					(end 368.67973 -105.911396)
				)
			)
		)
	)
	(zone
		(layer "B.Cu")
		(hatch none 0.5)
		(connect_pads
			(clearance 0)
		)
		(min_thickness 0.25)
		(keepout
			(tracks not_allowed)
			(vias allowed)
			(pads allowed)
			(copperpour not_allowed)
			(footprints allowed)
		)
		(placement
			(enabled no)
			(sheetname "")
		)
		(fill
			(thermal_gap 0.5)
			(thermal_bridge_width 0.5)
			(island_removal_mode 0)
		)
		(polygon
			(pts
				(arc
					(start 238.374936 -65.849754)
					(mid 238.699802 -64.875156)
					(end 237.725204 -64.55029)
				)
				(xy 237.723934 -64.548004) (xy 235.723938 -65.548002)
				(arc
					(start 235.725208 -65.550288)
					(mid 235.400342 -66.524886)
					(end 236.37494 -66.849752)
				)
				(xy 236.37621 -66.852038) (xy 236.864906 -66.60769)
				(arc
					(start 237.11662 -66.355976)
					(mid 237.131673 -66.333354)
					(end 237.13694 -66.3067)
				)
				(arc
					(start 237.13694 -66.188844)
					(mid 237.131657 -66.162197)
					(end 237.11662 -66.139568)
				)
				(arc
					(start 236.954568 -65.977516)
					(mid 236.915528 -65.94903)
					(end 236.869732 -65.933574)
				)
				(arc
					(start 236.85119 -65.930526)
					(mid 236.80142 -65.930685)
					(end 236.754162 -65.946274)
				)
				(arc
					(start 236.572044 -66.039492)
					(mid 235.564081 -66.449083)
					(end 236.485176 -65.870074)
				)
				(xy 236.667294 -65.776602) (xy 236.702346 -65.758568)
				(arc
					(start 236.705902 -65.759838)
					(mid 236.77166 -65.742624)
					(end 236.839506 -65.738502)
				)
				(xy 236.842554 -65.736216) (xy 236.896656 -65.745106) (xy 236.901228 -65.745868) (xy 236.936026 -65.751456)
				(arc
					(start 236.937804 -65.753996)
					(mid 237.000702 -65.778664)
					(end 237.057692 -65.814956)
				)
				(xy 237.061248 -65.814956) (xy 237.27918 -66.032888)
				(arc
					(start 237.27918 -66.037968)
					(mid 237.307656 -66.089405)
					(end 237.323884 -66.145918)
				)
				(xy 237.32744 -66.149474) (xy 237.32744 -66.34607)
				(arc
					(start 237.323884 -66.349626)
					(mid 237.320596 -66.365879)
					(end 237.316264 -66.381884)
				)
				(xy 237.42904 -66.325496)
				(arc
					(start 237.42904 -66.104516)
					(mid 237.416892 -66.043916)
					(end 237.382558 -65.992502)
				)
				(xy 237.237016 -65.846706)
				(arc
					(start 237.237016 -65.841626)
					(mid 237.226537 -65.825849)
					(end 237.217204 -65.809368)
				)
				(arc
					(start 237.217204 -65.80886)
					(mid 237.191186 -65.729527)
					(end 237.191296 -65.646046)
				)
				(arc
					(start 237.191296 -65.645792)
					(mid 237.227217 -65.549754)
					(end 237.29696 -65.474596)
				)
				(xy 237.298484 -65.46977)
				(arc
					(start 237.526576 -65.355724)
					(mid 238.537853 -64.954977)
					(end 237.61192 -65.525904)
				)
				(arc
					(start 237.419134 -65.622424)
					(mid 237.392708 -65.644696)
					(end 237.379256 -65.676526)
				)
				(arc
					(start 237.379256 -65.676526)
					(mid 237.379224 -65.699694)
					(end 237.386368 -65.721738)
				)
				(arc
					(start 237.386368 -65.721738)
					(mid 237.392303 -65.731125)
					(end 237.399576 -65.739518)
				)
				(xy 237.39983 -65.740026) (xy 237.42777 -65.767966) (xy 237.42777 -65.76822) (xy 237.50651 -65.846706)
				(xy 237.517178 -65.857628) (xy 237.517432 -65.857628) (xy 237.545118 -65.885568)
				(arc
					(start 237.545118 -65.889124)
					(mid 237.592944 -65.97094)
					(end 237.617 -66.062606)
				)
				(xy 237.61954 -66.065146) (xy 237.61954 -66.230246) (xy 238.375952 -65.85204) (xy 238.375952 -65.851786)
			)
		)
	)
	(zone
		(net "P12V_B")
		(layer "B.Cu")
		(hatch none 0.5)
		(connect_pads
			(clearance 0.5)
		)
		(min_thickness 0.25)
		(fill yes
			(thermal_gap 0.5)
			(thermal_bridge_width 0.5)
			(island_removal_mode 0)
		)
		(polygon
			(pts
				(xy 347.726 -146.685) (xy 347.472 -146.939) (xy 347.472 -152.654) (xy 348.107 -153.289) (xy 353.020376 -153.289)
				(xy 353.632008 -152.677368) (xy 353.632008 -148.791422) (xy 352.933 -148.092414) (xy 352.933 -146.812)
				(xy 352.806 -146.685)
			)
		)
	)
	(zone
		(net "P3V3_STBY_VBST")
		(layer "B.Cu")
		(hatch none 0.5)
		(connect_pads
			(clearance 0.5)
		)
		(min_thickness 0.25)
		(fill yes
			(thermal_gap 0.5)
			(thermal_bridge_width 0.5)
			(island_removal_mode 0)
		)
		(polygon
			(pts
				(xy 186.330082 -226.743006) (xy 186.253882 -226.819206) (xy 186.253882 -227.657406) (xy 186.279282 -227.682806)
				(xy 186.279282 -227.759006) (xy 186.660282 -228.140006) (xy 186.660282 -229.791006) (xy 186.914282 -230.045006)
				(xy 187.676282 -230.045006) (xy 187.803282 -229.918006) (xy 187.803282 -228.140006) (xy 186.406282 -226.743006)
			)
		)
		(polygon
			(pts
				(xy 187.345828 -229.260908) (xy 187.142628 -229.260908) (xy 187.142628 -229.464108) (xy 187.345828 -229.464108)
			)
		)
	)
	(zone
		(layer "B.Cu")
		(hatch none 0.5)
		(connect_pads
			(clearance 0)
		)
		(min_thickness 0.25)
		(keepout
			(tracks not_allowed)
			(vias allowed)
			(pads allowed)
			(copperpour not_allowed)
			(footprints allowed)
		)
		(placement
			(enabled no)
			(sheetname "")
		)
		(fill
			(thermal_gap 0.5)
			(thermal_bridge_width 0.5)
			(island_removal_mode 0)
		)
		(polygon
			(pts
				(arc
					(start 285.436564 -337.35645)
					(mid 284.887924 -337.90509)
					(end 285.436564 -338.45373)
				)
				(arc
					(start 285.935928 -338.45373)
					(mid 285.921943 -338.384796)
					(end 285.9151 -338.314792)
				)
				(xy 285.914338 -338.31403)
				(arc
					(start 285.914338 -338.03209)
					(mid 285.899459 -337.996169)
					(end 285.863538 -337.98129)
				)
				(arc
					(start 285.822898 -337.98129)
					(mid 285.042787 -337.90509)
					(end 285.822898 -337.82889)
				)
				(xy 285.895034 -337.82889)
				(arc
					(start 285.898082 -337.831938)
					(mid 286.007159 -337.888469)
					(end 286.06369 -337.997546)
				)
				(xy 286.066738 -338.000594)
				(arc
					(start 286.066738 -338.282788)
					(mid 286.073833 -338.369414)
					(end 286.094932 -338.45373)
				)
				(arc
					(start 286.245808 -338.45373)
					(mid 286.220397 -338.386396)
					(end 286.207708 -338.315554)
				)
				(xy 286.206438 -338.31403) (xy 286.206438 -338.000594)
				(arc
					(start 286.209486 -337.997546)
					(mid 286.266017 -337.888469)
					(end 286.375094 -337.831938)
				)
				(xy 286.378142 -337.82889)
				(arc
					(start 286.450278 -337.82889)
					(mid 287.230389 -337.90509)
					(end 286.450278 -337.98129)
				)
				(arc
					(start 286.409638 -337.98129)
					(mid 286.373717 -337.996169)
					(end 286.358838 -338.03209)
				)
				(arc
					(start 286.358838 -338.282534)
					(mid 286.377129 -338.374487)
					(end 286.429196 -338.45246)
				)
				(xy 286.430466 -338.45373)
				(arc
					(start 286.836612 -338.45373)
					(mid 287.385252 -337.90509)
					(end 286.836612 -337.35645)
				)
				(xy 285.436818 -337.35645)
			)
		)
	)
	(zone
		(net "GND")
		(layer "B.Cu")
		(hatch none 0.5)
		(connect_pads
			(clearance 0.5)
		)
		(min_thickness 0.25)
		(fill yes
			(thermal_gap 0.5)
			(thermal_bridge_width 0.5)
			(island_removal_mode 0)
		)
		(polygon
			(pts
				(arc
					(start 209.177128 -300.42231)
					(mid 209.712206 -301.0368)
					(end 210.114896 -301.745142)
				)
				(arc
					(start 223.937576 -256.19075)
					(mid 223.590186 -254.405689)
					(end 224.05086 -252.646434)
				)
				(arc
					(start 224.05086 -252.646434)
					(mid 223.444527 -251.053795)
					(end 223.539812 -249.352308)
				)
				(arc
					(start 223.539812 -249.352308)
					(mid 223.616725 -247.363231)
					(end 224.623376 -245.64594)
				)
				(arc
					(start 224.623376 -245.64594)
					(mid 225.286812 -244.301399)
					(end 226.3902 -243.28628)
				)
				(arc
					(start 226.3902 -241.33556)
					(mid 226.007068 -240.976104)
					(end 225.673158 -240.570512)
				)
				(arc
					(start 225.673158 -240.570512)
					(mid 223.763763 -238.482143)
					(end 223.666812 -235.654088)
				)
				(arc
					(start 223.666812 -235.654088)
					(mid 223.712618 -234.972416)
					(end 223.871282 -234.307888)
				)
				(arc
					(start 223.871282 -234.307888)
					(mid 223.604833 -233.033098)
					(end 223.752664 -231.739186)
				)
				(arc
					(start 223.752664 -231.739186)
					(mid 220.265249 -229.052464)
					(end 221.235778 -224.758504)
				)
				(xy 216.49817 -224.758504)
				(arc
					(start 200.827894 -240.42878)
					(mid 201.491756 -246.248396)
					(end 195.657216 -246.764302)
				)
				(arc
					(start 195.657216 -246.764302)
					(mid 194.915483 -246.370529)
					(end 194.269106 -245.834408)
				)
				(xy 192.583308 -245.834408)
				(arc
					(start 192.583308 -264.172446)
					(mid 197.003263 -268.2494)
					(end 192.583308 -272.326354)
				)
				(xy 192.583308 -272.574258)
				(arc
					(start 192.43167 -272.72615)
					(mid 193.819963 -274.200931)
					(end 194.324478 -276.162516)
				)
				(arc
					(start 194.324478 -279.337516)
					(mid 193.084622 -282.260543)
					(end 190.121286 -283.400754)
				)
				(arc
					(start 192.257426 -285.536894)
					(mid 195.307997 -287.102067)
					(end 196.09562 -290.439094)
				)
				(arc
					(start 196.09562 -290.439094)
					(mid 196.137942 -290.77599)
					(end 196.152008 -291.115242)
				)
				(arc
					(start 196.152008 -292.088316)
					(mid 195.964372 -293.847991)
					(end 195.050918 -295.363646)
				)
				(arc
					(start 195.050918 -295.363646)
					(mid 195.200618 -296.096935)
					(end 195.21424 -296.845228)
				)
				(arc
					(start 195.21424 -296.845228)
					(mid 196.232602 -296.150761)
					(end 197.411594 -295.791128)
				)
				(arc
					(start 197.411594 -295.791128)
					(mid 198.608203 -294.110149)
					(end 200.473056 -293.226998)
				)
				(arc
					(start 200.473056 -293.226998)
					(mid 200.838787 -292.812064)
					(end 201.257154 -292.450266)
				)
				(arc
					(start 201.257154 -292.450266)
					(mid 204.306472 -285.400182)
					(end 206.533242 -292.75151)
				)
				(arc
					(start 206.533242 -292.75151)
					(mid 207.807278 -295.684294)
					(end 206.581756 -298.637706)
				)
				(arc
					(start 206.581756 -298.637706)
					(mid 208.058107 -299.270189)
					(end 209.177128 -300.42231)
				)
			)
		)
		(polygon
			(pts
				(arc
					(start 203.240132 -260.39191)
					(mid 201.206443 -254.180238)
					(end 195.743068 -257.76809)
				)
				(arc
					(start 195.743068 -257.76809)
					(mid 197.776757 -263.979762)
					(end 203.240132 -260.39191)
				)
			)
		)
	)
	(zone
		(layer "B.Cu")
		(hatch none 0.5)
		(connect_pads
			(clearance 0)
		)
		(min_thickness 0.25)
		(keepout
			(tracks not_allowed)
			(vias allowed)
			(pads allowed)
			(copperpour not_allowed)
			(footprints allowed)
		)
		(placement
			(enabled no)
			(sheetname "")
		)
		(fill
			(thermal_gap 0.5)
			(thermal_bridge_width 0.5)
			(island_removal_mode 0)
		)
		(polygon
			(pts
				(arc
					(start 281.074876 -57.84977)
					(mid 281.399742 -56.875172)
					(end 280.425144 -56.550306)
				)
				(xy 280.423874 -56.54802) (xy 278.424132 -57.548018) (xy 278.424132 -57.548272)
				(arc
					(start 278.425148 -57.550304)
					(mid 278.100282 -58.524902)
					(end 279.07488 -58.849768)
				)
				(xy 279.07615 -58.852054)
				(arc
					(start 280.086562 -58.346848)
					(mid 279.982979 -58.285396)
					(end 279.888696 -58.21045)
				)
				(xy 279.887426 -58.21045)
				(arc
					(start 279.654508 -57.977532)
					(mid 279.615468 -57.949046)
					(end 279.569672 -57.93359)
				)
				(xy 279.566116 -57.933082)
				(arc
					(start 279.55113 -57.930542)
					(mid 279.50136 -57.930701)
					(end 279.454102 -57.94629)
				)
				(arc
					(start 279.271984 -58.039508)
					(mid 278.264021 -58.449099)
					(end 279.185116 -57.87009)
				)
				(xy 279.367234 -57.776618) (xy 279.402286 -57.758584)
				(arc
					(start 279.405842 -57.759854)
					(mid 279.4716 -57.74264)
					(end 279.539446 -57.738518)
				)
				(xy 279.542494 -57.736232) (xy 279.58161 -57.742582) (xy 279.596596 -57.745122) (xy 279.601168 -57.745884)
				(xy 279.635966 -57.751472)
				(arc
					(start 279.637744 -57.754012)
					(mid 279.700642 -57.77868)
					(end 279.757632 -57.814972)
				)
				(xy 279.761188 -57.814972) (xy 279.879298 -57.933082)
				(arc
					(start 279.994106 -58.04789)
					(mid 280.143896 -58.161543)
					(end 280.318718 -58.23077)
				)
				(xy 280.481786 -58.149236) (xy 280.445464 -58.149236)
				(arc
					(start 280.44394 -58.147712)
					(mid 280.258325 -58.104076)
					(end 280.096214 -58.003694)
				)
				(xy 280.094182 -58.003694) (xy 280.066242 -57.975754) (xy 279.93721 -57.846722)
				(arc
					(start 279.93721 -57.841896)
					(mid 279.89485 -57.748529)
					(end 279.891236 -57.646062)
				)
				(arc
					(start 279.891236 -57.645808)
					(mid 279.927157 -57.54977)
					(end 279.9969 -57.474612)
				)
				(xy 279.998424 -57.469786)
				(arc
					(start 280.226516 -57.35574)
					(mid 281.237793 -56.954993)
					(end 280.31186 -57.52592)
				)
				(arc
					(start 280.119074 -57.62244)
					(mid 280.092648 -57.644712)
					(end 280.079196 -57.676542)
				)
				(arc
					(start 280.079196 -57.676542)
					(mid 280.081809 -57.710793)
					(end 280.09977 -57.740042)
				)
				(arc
					(start 280.200862 -57.841134)
					(mid 280.331149 -57.928189)
					(end 280.484834 -57.958736)
				)
				(xy 280.862786 -57.958736) (xy 281.076146 -57.852056)
			)
		)
	)
	(zone
		(layer "B.Cu")
		(hatch none 0.5)
		(connect_pads
			(clearance 0)
		)
		(min_thickness 0.25)
		(keepout
			(tracks allowed)
			(vias allowed)
			(pads allowed)
			(copperpour allowed)
			(footprints allowed)
		)
		(placement
			(enabled no)
			(sheetname "")
		)
		(fill
			(thermal_gap 0.5)
			(thermal_bridge_width 0.5)
			(island_removal_mode 0)
		)
		(polygon
			(pts
				(xy 186.5884 -224.6122) (xy 186.5884 -223.1644) (xy 185.1152 -223.1644) (xy 185.1152 -224.6122)
			)
		)
	)
	(zone
		(layer "B.Cu")
		(hatch none 0.5)
		(connect_pads
			(clearance 0)
		)
		(min_thickness 0.25)
		(keepout
			(tracks not_allowed)
			(vias allowed)
			(pads allowed)
			(copperpour not_allowed)
			(footprints allowed)
		)
		(placement
			(enabled no)
			(sheetname "")
		)
		(fill
			(thermal_gap 0.5)
			(thermal_bridge_width 0.5)
			(island_removal_mode 0)
		)
		(polygon
			(pts
				(arc
					(start 350.750124 -164.200078)
					(mid 347.000068 -160.450022)
					(end 343.250012 -164.200078)
				)
				(arc
					(start 343.250012 -164.200078)
					(mid 347.000068 -167.950134)
					(end 350.750124 -164.200078)
				)
			)
		)
	)
	(zone
		(layer "B.Cu")
		(hatch none 0.5)
		(connect_pads
			(clearance 0)
		)
		(min_thickness 0.25)
		(keepout
			(tracks not_allowed)
			(vias allowed)
			(pads allowed)
			(copperpour not_allowed)
			(footprints allowed)
		)
		(placement
			(enabled no)
			(sheetname "")
		)
		(fill
			(thermal_gap 0.5)
			(thermal_bridge_width 0.5)
			(island_removal_mode 0)
		)
		(polygon
			(pts
				(arc
					(start 281.07386 -126.147322)
					(mid 281.397456 -125.176026)
					(end 280.42616 -124.85243)
				)
				(arc
					(start 279.487122 -125.321822)
					(mid 279.638469 -125.405632)
					(end 279.768554 -125.519688)
				)
				(xy 279.781762 -125.524006) (xy 279.832308 -125.624082) (xy 279.849834 -125.659388) (xy 279.867614 -125.69444)
				(xy 279.867614 -125.694694)
				(arc
					(start 279.892506 -125.744478)
					(mid 279.932791 -125.779474)
					(end 279.985978 -125.77572)
				)
				(arc
					(start 280.226516 -125.655324)
					(mid 281.23834 -125.25545)
					(end 280.31186 -125.825758)
				)
				(xy 280.071322 -125.9459) (xy 280.036016 -125.96368)
				(arc
					(start 280.03119 -125.962156)
					(mid 279.872501 -125.960143)
					(end 279.744424 -125.866398)
				)
				(xy 279.739598 -125.864874) (xy 279.722072 -125.829822) (xy 279.722072 -125.829568) (xy 279.679654 -125.744732)
				(arc
					(start 279.634696 -125.655578)
					(mid 279.450574 -125.514757)
					(end 279.227534 -125.451616)
				)
				(xy 279.028906 -125.55093) (xy 279.213056 -125.55093)
				(arc
					(start 279.214834 -125.552454)
					(mid 279.379517 -125.593664)
					(end 279.52192 -125.686058)
				)
				(xy 279.539192 -125.691646) (xy 279.623774 -125.860556) (xy 279.640792 -125.877574) (xy 279.640792 -125.894338)
				(xy 279.648412 -125.909578)
				(arc
					(start 279.646634 -125.914404)
					(mid 279.644931 -126.073138)
					(end 279.551384 -126.201424)
				)
				(xy 279.54986 -126.20625) (xy 279.514554 -126.223776)
				(arc
					(start 279.273508 -126.344426)
					(mid 278.261684 -126.7443)
					(end 279.188164 -126.173992)
				)
				(arc
					(start 279.42921 -126.053596)
					(mid 279.462054 -126.018921)
					(end 279.46477 -125.9713)
				)
				(xy 279.450292 -125.956568) (xy 279.450292 -125.93955)
				(arc
					(start 279.393904 -125.827028)
					(mid 279.291818 -125.763593)
					(end 279.173686 -125.74143)
				)
				(xy 278.647906 -125.74143) (xy 278.426418 -125.852174)
				(arc
					(start 278.426418 -125.852428)
					(mid 278.102619 -126.823572)
					(end 279.073864 -127.14732)
				)
			)
		)
	)
	(zone
		(layer "B.Cu")
		(hatch none 0.5)
		(connect_pads
			(clearance 0)
		)
		(min_thickness 0.25)
		(keepout
			(tracks not_allowed)
			(vias allowed)
			(pads allowed)
			(copperpour not_allowed)
			(footprints allowed)
		)
		(placement
			(enabled no)
			(sheetname "")
		)
		(fill
			(thermal_gap 0.5)
			(thermal_bridge_width 0.5)
			(island_removal_mode 0)
		)
		(polygon
			(pts
				(arc
					(start 286.436562 -324.756526)
					(mid 285.887922 -325.305166)
					(end 286.436562 -325.853806)
				)
				(arc
					(start 286.935926 -325.853806)
					(mid 286.921941 -325.784872)
					(end 286.915098 -325.714868)
				)
				(xy 286.914336 -325.714106)
				(arc
					(start 286.914336 -325.432166)
					(mid 286.899457 -325.396245)
					(end 286.863536 -325.381366)
				)
				(arc
					(start 286.822896 -325.381366)
					(mid 286.042785 -325.305166)
					(end 286.822896 -325.228966)
				)
				(xy 286.895032 -325.228966)
				(arc
					(start 286.89808 -325.232014)
					(mid 287.007157 -325.288545)
					(end 287.063688 -325.397622)
				)
				(xy 287.066736 -325.40067)
				(arc
					(start 287.066736 -325.682864)
					(mid 287.073831 -325.76949)
					(end 287.09493 -325.853806)
				)
				(arc
					(start 287.245806 -325.853806)
					(mid 287.220395 -325.786472)
					(end 287.207706 -325.71563)
				)
				(xy 287.206436 -325.714106) (xy 287.206436 -325.40067)
				(arc
					(start 287.209484 -325.397622)
					(mid 287.266015 -325.288545)
					(end 287.375092 -325.232014)
				)
				(xy 287.37814 -325.228966)
				(arc
					(start 287.450276 -325.228966)
					(mid 288.230387 -325.305166)
					(end 287.450276 -325.381366)
				)
				(arc
					(start 287.409636 -325.381366)
					(mid 287.373715 -325.396245)
					(end 287.358836 -325.432166)
				)
				(arc
					(start 287.358836 -325.68261)
					(mid 287.377127 -325.774563)
					(end 287.429194 -325.852536)
				)
				(xy 287.430464 -325.853806)
				(arc
					(start 287.83661 -325.853806)
					(mid 288.38525 -325.305166)
					(end 287.83661 -324.756526)
				)
				(xy 286.436816 -324.756526)
			)
		)
	)
	(zone
		(net "GND")
		(layer "B.Cu")
		(hatch none 0.5)
		(connect_pads
			(clearance 0.5)
		)
		(min_thickness 0.25)
		(fill yes
			(thermal_gap 0.5)
			(thermal_bridge_width 0.5)
			(island_removal_mode 0)
		)
		(polygon
			(pts
				(xy 44.857416 -140.985494) (xy 44.6786 -141.16431) (xy 44.6786 -146.86915) (xy 44.946824 -147.137374)
				(xy 44.946824 -147.984972) (xy 45.431202 -148.46935) (xy 46.285404 -148.46935) (xy 46.294802 -148.478748)
				(xy 47.9806 -146.79295) (xy 47.9806 -141.167104) (xy 47.79899 -140.985494)
			)
		)
	)
	(zone
		(layer "B.Cu")
		(hatch none 0.5)
		(connect_pads
			(clearance 0)
		)
		(min_thickness 0.25)
		(keepout
			(tracks not_allowed)
			(vias allowed)
			(pads allowed)
			(copperpour not_allowed)
			(footprints allowed)
		)
		(placement
			(enabled no)
			(sheetname "")
		)
		(fill
			(thermal_gap 0.5)
			(thermal_bridge_width 0.5)
			(island_removal_mode 0)
		)
		(polygon
			(pts
				(arc
					(start 271.970754 -357.323898)
					(mid 271.5895 -357.704771)
					(end 271.9705 -358.085898)
				)
				(arc
					(start 273.1135 -358.085898)
					(mid 273.4945 -357.704898)
					(end 273.1135 -357.323898)
				)
				(arc
					(start 272.76806 -357.323898)
					(mid 272.765209 -357.349482)
					(end 272.76425 -357.375206)
				)
				(arc
					(start 272.76425 -357.523796)
					(mid 272.791127 -357.593914)
					(end 272.857976 -357.62819)
				)
				(arc
					(start 272.857976 -357.62819)
					(mid 273.380217 -357.704644)
					(end 272.857976 -357.781098)
				)
				(xy 272.837656 -357.781098)
				(arc
					(start 272.83537 -357.778812)
					(mid 272.687253 -357.705695)
					(end 272.614136 -357.557578)
				)
				(xy 272.61185 -357.555292) (xy 272.61185 -357.34371) (xy 272.612866 -357.342694) (xy 272.61439 -357.323898)
				(arc
					(start 272.474182 -357.323898)
					(mid 272.472648 -357.349532)
					(end 272.47215 -357.375206)
				)
				(xy 272.47215 -357.555292)
				(arc
					(start 272.469864 -357.557578)
					(mid 272.396747 -357.705695)
					(end 272.24863 -357.778812)
				)
				(xy 272.246344 -357.781098)
				(arc
					(start 272.226024 -357.781098)
					(mid 271.703783 -357.704644)
					(end 272.226024 -357.62819)
				)
				(arc
					(start 272.226024 -357.62819)
					(mid 272.292939 -357.593973)
					(end 272.31975 -357.523796)
				)
				(xy 272.31975 -357.34371) (xy 272.320512 -357.342948) (xy 272.321528 -357.323898)
			)
		)
	)
	(zone
		(layer "B.Cu")
		(hatch none 0.5)
		(connect_pads
			(clearance 0)
		)
		(min_thickness 0.25)
		(keepout
			(tracks not_allowed)
			(vias allowed)
			(pads allowed)
			(copperpour not_allowed)
			(footprints allowed)
		)
		(placement
			(enabled no)
			(sheetname "")
		)
		(fill
			(thermal_gap 0.5)
			(thermal_bridge_width 0.5)
			(island_removal_mode 0)
		)
		(polygon
			(pts
				(arc
					(start 482.870002 -162.178746)
					(mid 482.489129 -161.797492)
					(end 482.108002 -162.178492)
				)
				(xy 482.108002 -162.527742)
				(arc
					(start 482.312218 -162.527742)
					(mid 482.380874 -162.500667)
					(end 482.412548 -162.434016)
				)
				(arc
					(start 482.412548 -162.434016)
					(mid 482.489124 -161.911775)
					(end 482.565202 -162.434016)
				)
				(xy 482.565202 -162.458654)
				(arc
					(start 482.562916 -162.46094)
					(mid 482.49109 -162.60603)
					(end 482.346 -162.677856)
				)
				(xy 482.343714 -162.680142) (xy 482.108002 -162.680142) (xy 482.108002 -162.819842) (xy 482.343714 -162.819842)
				(arc
					(start 482.346 -162.822128)
					(mid 482.49109 -162.893954)
					(end 482.562916 -163.039044)
				)
				(xy 482.565202 -163.04133)
				(arc
					(start 482.565202 -163.065968)
					(mid 482.489124 -163.588136)
					(end 482.412548 -163.065968)
				)
				(arc
					(start 482.412548 -163.065968)
					(mid 482.38086 -162.999332)
					(end 482.312218 -162.972242)
				)
				(xy 482.108002 -162.972242)
				(arc
					(start 482.108002 -163.321492)
					(mid 482.489002 -163.702492)
					(end 482.870002 -163.321492)
				)
			)
		)
	)
	(zone
		(net "P12V_A")
		(layer "B.Cu")
		(hatch none 0.5)
		(connect_pads
			(clearance 0.5)
		)
		(min_thickness 0.25)
		(fill yes
			(thermal_gap 0.5)
			(thermal_bridge_width 0.5)
			(island_removal_mode 0)
		)
		(polygon
			(pts
				(xy 429.580294 -252.183138) (xy 429.326294 -252.437138) (xy 429.326294 -255.358138) (xy 429.580294 -255.612138)
				(xy 433.118514 -255.612138) (xy 433.483004 -255.247648) (xy 433.483004 -252.451362) (xy 433.21478 -252.183138)
			)
		)
		(polygon
			(pts
				(xy 433.034694 -254.494538) (xy 432.831494 -254.494538) (xy 432.831494 -254.697738) (xy 433.034694 -254.697738)
			)
		)
		(polygon
			(pts
				(xy 432.171094 -254.494538) (xy 431.967894 -254.494538) (xy 431.967894 -254.697738) (xy 432.171094 -254.697738)
			)
		)
		(polygon
			(pts
				(xy 432.011582 -253.533402) (xy 431.808382 -253.533402) (xy 431.808382 -253.736602) (xy 432.011582 -253.736602)
			)
		)
		(polygon
			(pts
				(xy 432.011582 -252.390402) (xy 431.808382 -252.390402) (xy 431.808382 -252.593602) (xy 432.011582 -252.593602)
			)
		)
	)
	(zone
		(layer "B.Cu")
		(hatch none 0.5)
		(connect_pads
			(clearance 0)
		)
		(min_thickness 0.25)
		(keepout
			(tracks not_allowed)
			(vias allowed)
			(pads allowed)
			(copperpour not_allowed)
			(footprints allowed)
		)
		(placement
			(enabled no)
			(sheetname "")
		)
		(fill
			(thermal_gap 0.5)
			(thermal_bridge_width 0.5)
			(island_removal_mode 0)
		)
		(polygon
			(pts
				(arc
					(start 356.670102 -277.17877)
					(mid 356.289229 -276.797516)
					(end 355.908102 -277.178516)
				)
				(xy 355.908102 -277.527766)
				(arc
					(start 356.112318 -277.527766)
					(mid 356.180974 -277.500691)
					(end 356.212648 -277.43404)
				)
				(arc
					(start 356.212648 -277.43404)
					(mid 356.289224 -276.911799)
					(end 356.365302 -277.43404)
				)
				(xy 356.365302 -277.458678)
				(arc
					(start 356.363016 -277.460964)
					(mid 356.29119 -277.606054)
					(end 356.1461 -277.67788)
				)
				(xy 356.143814 -277.680166) (xy 355.908102 -277.680166) (xy 355.908102 -277.819866) (xy 356.143814 -277.819866)
				(arc
					(start 356.1461 -277.822152)
					(mid 356.29119 -277.893978)
					(end 356.363016 -278.039068)
				)
				(xy 356.365302 -278.041354)
				(arc
					(start 356.365302 -278.065992)
					(mid 356.289224 -278.58816)
					(end 356.212648 -278.065992)
				)
				(arc
					(start 356.212648 -278.065992)
					(mid 356.18096 -277.999356)
					(end 356.112318 -277.972266)
				)
				(xy 355.908102 -277.972266)
				(arc
					(start 355.908102 -278.321516)
					(mid 356.289102 -278.702516)
					(end 356.670102 -278.321516)
				)
			)
		)
	)
	(zone
		(layer "B.Cu")
		(hatch none 0.5)
		(connect_pads
			(clearance 0)
		)
		(min_thickness 0.25)
		(keepout
			(tracks not_allowed)
			(vias allowed)
			(pads allowed)
			(copperpour not_allowed)
			(footprints allowed)
		)
		(placement
			(enabled no)
			(sheetname "")
		)
		(fill
			(thermal_gap 0.5)
			(thermal_bridge_width 0.5)
			(island_removal_mode 0)
		)
		(polygon
			(pts
				(arc
					(start 111.849916 -289.999928)
					(mid 107.100116 -285.250128)
					(end 102.350062 -289.999928)
				)
				(arc
					(start 102.350062 -289.999928)
					(mid 107.100116 -294.749982)
					(end 111.849916 -289.999928)
				)
			)
		)
	)
	(zone
		(net "GND")
		(layer "B.Cu")
		(hatch none 0.5)
		(connect_pads
			(clearance 0.5)
		)
		(min_thickness 0.25)
		(fill yes
			(thermal_gap 0.5)
			(thermal_bridge_width 0.5)
			(island_removal_mode 0)
		)
		(polygon
			(pts
				(xy 439.264806 -150.697184)
				(arc
					(start 435.83479 -154.127454)
					(mid 436.216236 -154.527984)
					(end 436.540148 -154.976322)
				)
				(arc
					(start 436.540148 -154.976322)
					(mid 441.087495 -153.483283)
					(end 443.904624 -157.352492)
				)
				(arc
					(start 443.904624 -160.527492)
					(mid 443.482672 -162.331004)
					(end 442.304424 -163.76015)
				)
				(arc
					(start 442.304424 -164.337492)
					(mid 440.91787 -167.395531)
					(end 437.703976 -168.36771)
				)
				(arc
					(start 437.703976 -169.777918)
					(mid 437.052778 -171.992403)
					(end 435.30647 -173.501812)
				)
				(arc
					(start 435.30647 -173.501812)
					(mid 433.802657 -175.069854)
					(end 431.708052 -175.646842)
				)
				(arc
					(start 429.168052 -175.646842)
					(mid 426.794411 -174.88775)
					(end 425.301664 -172.892212)
				)
				(xy 425.204636 -172.93971)
				(arc
					(start 424.2816 -173.854364)
					(mid 424.367213 -174.330908)
					(end 424.3959 -174.81423)
				)
				(arc
					(start 424.3959 -177.354992)
					(mid 424.335323 -178.05639)
					(end 424.155362 -178.737006)
				)
				(arc
					(start 424.155362 -178.737006)
					(mid 425.296062 -178.519128)
					(end 426.45203 -178.63058)
				)
				(arc
					(start 426.45203 -178.63058)
					(mid 432.142888 -180.560687)
					(end 429.768 -186.080654)
				)
				(arc
					(start 429.768 -187.355734)
					(mid 432.158889 -191.938838)
					(end 428.152052 -195.204842)
				)
				(arc
					(start 426.151548 -195.204842)
					(mid 425.978163 -196.032642)
					(end 425.638214 -196.807074)
				)
				(arc
					(start 425.638214 -196.807074)
					(mid 433.039201 -199.216851)
					(end 438.009538 -205.2066)
				)
				(xy 442.81344 -205.2066) (xy 447.583306 -198.771764)
				(arc
					(start 450.093588 -196.835014)
					(mid 449.83716 -196.308713)
					(end 449.658486 -195.751196)
				)
				(arc
					(start 449.658486 -195.751196)
					(mid 447.273872 -192.04938)
					(end 449.206112 -188.092588)
				)
				(arc
					(start 449.206112 -188.092588)
					(mid 448.734605 -187.620522)
					(end 448.346068 -187.078112)
				)
				(arc
					(start 448.346068 -187.078112)
					(mid 445.716004 -185.754191)
					(end 444.65621 -183.007)
				)
				(arc
					(start 444.65621 -181.991)
					(mid 445.542156 -179.448693)
					(end 447.816224 -178.007518)
				)
				(arc
					(start 447.816224 -178.007518)
					(mid 447.777014 -177.682683)
					(end 447.7639 -177.355754)
				)
				(arc
					(start 447.7639 -174.814992)
					(mid 447.834229 -174.059694)
					(end 448.042792 -173.330362)
				)
				(arc
					(start 448.042792 -173.330362)
					(mid 446.993318 -171.935457)
					(end 446.6209 -170.230038)
				)
				(arc
					(start 446.6209 -165.429946)
					(mid 446.993459 -163.724187)
					(end 448.0433 -162.329114)
				)
				(arc
					(start 448.0433 -162.329114)
					(mid 447.771097 -160.613683)
					(end 448.235324 -158.939992)
				)
				(arc
					(start 448.235324 -158.939992)
					(mid 447.787709 -157.469018)
					(end 447.914776 -155.936696)
				)
				(arc
					(start 447.914776 -155.936696)
					(mid 447.569525 -153.11354)
					(end 449.069714 -150.697184)
				)
			)
		)
	)
	(zone
		(net "GND")
		(layer "B.Cu")
		(hatch none 0.5)
		(connect_pads
			(clearance 0.5)
		)
		(min_thickness 0.25)
		(fill yes
			(thermal_gap 0.5)
			(thermal_bridge_width 0.5)
			(island_removal_mode 0)
		)
		(polygon
			(pts
				(xy 348.694248 -214.7316) (xy 360.807 -195.72351)
				(arc
					(start 360.807 -195.16598)
					(mid 360.497078 -195.110759)
					(end 360.19232 -195.031868)
				)
				(arc
					(start 360.19232 -195.031868)
					(mid 359.683726 -195.449699)
					(end 359.119424 -195.788534)
				)
				(arc
					(start 359.119424 -195.788534)
					(mid 355.771688 -198.828324)
					(end 351.66935 -196.9262)
				)
				(arc
					(start 351.187512 -196.9262)
					(mid 351.042486 -197.020347)
					(end 350.893634 -197.108318)
				)
				(xy 347.161612 -213.938612) (xy 347.9546 -214.7316)
			)
		)
	)
	(zone
		(layer "B.Cu")
		(hatch none 0.5)
		(connect_pads
			(clearance 0)
		)
		(min_thickness 0.25)
		(keepout
			(tracks allowed)
			(vias allowed)
			(pads allowed)
			(copperpour allowed)
			(footprints allowed)
		)
		(placement
			(enabled no)
			(sheetname "")
		)
		(fill
			(thermal_gap 0.5)
			(thermal_bridge_width 0.5)
			(island_removal_mode 0)
		)
		(polygon
			(pts
				(xy 16.880586 -248.194576) (xy 16.880586 -246.043704) (xy 25.045924 -246.043704) (xy 25.045924 -248.194576)
			)
		)
	)
	(zone
		(net "GND")
		(layer "B.Cu")
		(hatch none 0.5)
		(connect_pads
			(clearance 0.5)
		)
		(min_thickness 0.25)
		(fill yes
			(thermal_gap 0.5)
			(thermal_bridge_width 0.5)
			(island_removal_mode 0)
		)
		(polygon
			(pts
				(xy 301.5234 -180.8988) (xy 301.0662 -181.356) (xy 301.0662 -186.2328) (xy 301.7266 -186.8932) (xy 303.8094 -186.8932)
				(xy 304.4698 -186.2328) (xy 304.4698 -181.3052) (xy 304.0634 -180.8988)
			)
		)
	)
	(zone
		(layer "B.Cu")
		(hatch none 0.5)
		(connect_pads
			(clearance 0)
		)
		(min_thickness 0.25)
		(keepout
			(tracks allowed)
			(vias allowed)
			(pads allowed)
			(copperpour allowed)
			(footprints not_allowed)
		)
		(placement
			(enabled no)
			(sheetname "")
		)
		(fill
			(thermal_gap 0.5)
			(thermal_bridge_width 0.5)
			(island_removal_mode 0)
		)
		(polygon
			(pts
				(arc
					(start 127.355092 -20.550124)
					(mid 126.150116 -19.345148)
					(end 124.944886 -20.550124)
				)
				(arc
					(start 124.944886 -20.550124)
					(mid 126.150116 -21.755354)
					(end 127.355092 -20.550124)
				)
			)
		)
	)
	(zone
		(net "GND")
		(layer "B.Cu")
		(hatch none 0.5)
		(connect_pads
			(clearance 0.5)
		)
		(min_thickness 0.25)
		(fill yes
			(thermal_gap 0.5)
			(thermal_bridge_width 0.5)
			(island_removal_mode 0)
		)
		(polygon
			(pts
				(xy 434.131974 -252.362716) (xy 433.877974 -252.616716) (xy 433.877974 -254.394716) (xy 436.417974 -256.934716)
				(xy 439.465974 -256.934716) (xy 439.592974 -256.807716) (xy 439.592974 -255.410716) (xy 440.100974 -254.902462)
				(xy 440.100974 -253.759716) (xy 440.608974 -253.251716) (xy 440.608974 -252.616716) (xy 440.481974 -252.489716)
				(xy 439.719974 -252.489716) (xy 439.592974 -252.362716)
			)
		)
		(polygon
			(pts
				(xy 439.321194 -254.844296) (xy 439.117994 -254.844296) (xy 439.117994 -255.047496) (xy 439.321194 -255.047496)
			)
		)
		(polygon
			(pts
				(xy 439.321194 -253.980696) (xy 439.117994 -253.980696) (xy 439.117994 -254.183896) (xy 439.321194 -254.183896)
			)
		)
		(polygon
			(pts
				(xy 440.034172 -253.042166) (xy 439.830972 -253.042166) (xy 439.830972 -253.245366) (xy 440.034172 -253.245366)
			)
		)
	)
	(zone
		(layer "B.Cu")
		(hatch none 0.5)
		(connect_pads
			(clearance 0)
		)
		(min_thickness 0.25)
		(keepout
			(tracks not_allowed)
			(vias allowed)
			(pads allowed)
			(copperpour not_allowed)
			(footprints allowed)
		)
		(placement
			(enabled no)
			(sheetname "")
		)
		(fill
			(thermal_gap 0.5)
			(thermal_bridge_width 0.5)
			(island_removal_mode 0)
		)
		(polygon
			(pts
				(arc
					(start 281.07386 -150.147274)
					(mid 281.397456 -149.175978)
					(end 280.42616 -148.852382)
				)
				(arc
					(start 279.487122 -149.321774)
					(mid 279.638469 -149.405584)
					(end 279.768554 -149.51964)
				)
				(xy 279.781762 -149.523958) (xy 279.832308 -149.624034) (xy 279.849834 -149.65934) (xy 279.867614 -149.694392)
				(xy 279.867614 -149.694646)
				(arc
					(start 279.892506 -149.74443)
					(mid 279.932791 -149.779426)
					(end 279.985978 -149.775672)
				)
				(arc
					(start 280.226516 -149.655276)
					(mid 281.23834 -149.255402)
					(end 280.31186 -149.82571)
				)
				(xy 280.071322 -149.945852) (xy 280.036016 -149.963632)
				(arc
					(start 280.03119 -149.962108)
					(mid 279.872501 -149.960095)
					(end 279.744424 -149.86635)
				)
				(xy 279.739598 -149.864826) (xy 279.722072 -149.829774) (xy 279.722072 -149.82952) (xy 279.679654 -149.744684)
				(arc
					(start 279.634696 -149.65553)
					(mid 279.450574 -149.514709)
					(end 279.227534 -149.451568)
				)
				(xy 279.028906 -149.550882) (xy 279.213056 -149.550882)
				(arc
					(start 279.214834 -149.552406)
					(mid 279.379517 -149.593616)
					(end 279.52192 -149.68601)
				)
				(xy 279.539192 -149.691598) (xy 279.623774 -149.860508) (xy 279.640792 -149.877526) (xy 279.640792 -149.89429)
				(xy 279.648412 -149.90953)
				(arc
					(start 279.646634 -149.914356)
					(mid 279.644931 -150.07309)
					(end 279.551384 -150.201376)
				)
				(xy 279.54986 -150.206202) (xy 279.514554 -150.223728)
				(arc
					(start 279.273508 -150.344378)
					(mid 278.261684 -150.744252)
					(end 279.188164 -150.173944)
				)
				(arc
					(start 279.42921 -150.053548)
					(mid 279.462054 -150.018873)
					(end 279.46477 -149.971252)
				)
				(xy 279.450292 -149.95652) (xy 279.450292 -149.939502)
				(arc
					(start 279.393904 -149.82698)
					(mid 279.291818 -149.763545)
					(end 279.173686 -149.741382)
				)
				(xy 278.647906 -149.741382) (xy 278.426418 -149.852126)
				(arc
					(start 278.426418 -149.85238)
					(mid 278.102619 -150.823524)
					(end 279.073864 -151.147272)
				)
			)
		)
	)
	(zone
		(layer "B.Cu")
		(hatch none 0.5)
		(connect_pads
			(clearance 0)
		)
		(min_thickness 0.25)
		(keepout
			(tracks allowed)
			(vias allowed)
			(pads allowed)
			(copperpour allowed)
			(footprints not_allowed)
		)
		(placement
			(enabled no)
			(sheetname "")
		)
		(fill
			(thermal_gap 0.5)
			(thermal_bridge_width 0.5)
			(island_removal_mode 0)
		)
		(polygon
			(pts
				(xy 491.450122 -300.999906) (xy 289.999928 -300.999906) (xy 289.999928 -258.99999) (xy 491.450122 -258.99999)
			)
		)
	)
	(zone
		(layer "B.Cu")
		(hatch none 0.5)
		(connect_pads
			(clearance 0)
		)
		(min_thickness 0.25)
		(keepout
			(tracks not_allowed)
			(vias allowed)
			(pads allowed)
			(copperpour not_allowed)
			(footprints allowed)
		)
		(placement
			(enabled no)
			(sheetname "")
		)
		(fill
			(thermal_gap 0.5)
			(thermal_bridge_width 0.5)
			(island_removal_mode 0)
		)
		(polygon
			(pts
				(arc
					(start 279.372568 -169.551858)
					(mid 279.266851 -169.506655)
					(end 279.154382 -169.48277)
				)
				(xy 278.95931 -169.580052) (xy 279.087326 -169.58056) (xy 279.127712 -169.58056)
				(arc
					(start 279.12949 -169.582338)
					(mid 279.229597 -169.601498)
					(end 279.323546 -169.641012)
				)
				(arc
					(start 279.323546 -169.641012)
					(mid 279.364913 -169.666592)
					(end 279.403556 -169.69613)
				)
				(xy 279.405842 -169.69613) (xy 279.433528 -169.723562) (xy 279.433782 -169.72407) (xy 279.534874 -169.825162)
				(xy 279.562814 -169.853102)
				(arc
					(start 279.562814 -169.857928)
					(mid 279.605174 -169.951295)
					(end 279.608788 -170.053762)
				)
				(arc
					(start 279.608788 -170.054016)
					(mid 279.572867 -170.150054)
					(end 279.503124 -170.225212)
				)
				(xy 279.5016 -170.230038)
				(arc
					(start 279.273508 -170.344084)
					(mid 278.262231 -170.744831)
					(end 279.188164 -170.173904)
				)
				(arc
					(start 279.38095 -170.077384)
					(mid 279.407376 -170.055112)
					(end 279.420828 -170.023282)
				)
				(arc
					(start 279.420828 -170.023282)
					(mid 279.418215 -169.989031)
					(end 279.400254 -169.959782)
				)
				(xy 279.299162 -169.85869)
				(arc
					(start 279.298654 -169.858436)
					(mid 279.266896 -169.830931)
					(end 279.231598 -169.808144)
				)
				(arc
					(start 279.231598 -169.808144)
					(mid 279.163286 -169.780855)
					(end 279.090374 -169.77106)
				)
				(xy 279.086818 -169.77106) (xy 279.047702 -169.77106) (xy 279.047448 -169.770806) (xy 278.58085 -169.769536)
				(xy 278.424132 -169.847768) (xy 278.424132 -169.848022)
				(arc
					(start 278.425148 -169.850054)
					(mid 278.100282 -170.824652)
					(end 279.07488 -171.149518)
				)
				(xy 279.07615 -171.151804) (xy 281.076146 -170.151806)
				(arc
					(start 281.074876 -170.14952)
					(mid 281.399742 -169.174922)
					(end 280.425144 -168.850056)
				)
				(xy 280.423874 -168.84777)
				(arc
					(start 279.406858 -169.356278)
					(mid 279.435725 -169.369915)
					(end 279.464008 -169.384726)
				)
				(arc
					(start 279.464262 -169.384726)
					(mid 279.540831 -169.432784)
					(end 279.611328 -169.489374)
				)
				(xy 279.612598 -169.489374) (xy 279.640284 -169.51706) (xy 279.640538 -169.517314) (xy 279.775158 -169.651934)
				(arc
					(start 279.845516 -169.722292)
					(mid 279.884556 -169.750778)
					(end 279.930352 -169.766234)
				)
				(arc
					(start 279.948894 -169.769282)
					(mid 279.998664 -169.769123)
					(end 280.045922 -169.753534)
				)
				(arc
					(start 280.22804 -169.660316)
					(mid 281.236003 -169.250725)
					(end 280.314908 -169.829734)
				)
				(xy 280.13279 -169.923206) (xy 280.097738 -169.94124)
				(arc
					(start 280.094182 -169.93997)
					(mid 280.028424 -169.957184)
					(end 279.960578 -169.961306)
				)
				(xy 279.95753 -169.963592) (xy 279.903428 -169.954702) (xy 279.898856 -169.95394) (xy 279.864058 -169.948352)
				(arc
					(start 279.86228 -169.945812)
					(mid 279.799382 -169.921144)
					(end 279.742392 -169.884852)
				)
				(xy 279.738836 -169.884852) (xy 279.679146 -169.825162) (xy 279.505918 -169.651934)
				(arc
					(start 279.505664 -169.65168)
					(mid 279.442649 -169.597058)
					(end 279.372568 -169.551858)
				)
			)
		)
	)
	(zone
		(layer "B.Cu")
		(hatch none 0.5)
		(connect_pads
			(clearance 0)
		)
		(min_thickness 0.25)
		(keepout
			(tracks not_allowed)
			(vias allowed)
			(pads allowed)
			(copperpour not_allowed)
			(footprints allowed)
		)
		(placement
			(enabled no)
			(sheetname "")
		)
		(fill
			(thermal_gap 0.5)
			(thermal_bridge_width 0.5)
			(island_removal_mode 0)
		)
		(polygon
			(pts
				(arc
					(start 238.374936 -53.849778)
					(mid 238.699802 -52.87518)
					(end 237.725204 -52.550314)
				)
				(xy 237.723934 -52.548028) (xy 235.724192 -53.548026) (xy 235.724192 -53.54828)
				(arc
					(start 235.725208 -53.550312)
					(mid 235.333 -54.316209)
					(end 235.94695 -54.919118)
				)
				(arc
					(start 236.153198 -54.919118)
					(mid 236.266861 -54.893373)
					(end 236.37494 -54.849776)
				)
				(xy 236.37621 -54.852062) (xy 236.864652 -54.607714)
				(arc
					(start 237.11662 -54.356)
					(mid 237.131673 -54.333378)
					(end 237.13694 -54.306724)
				)
				(arc
					(start 237.13694 -54.188868)
					(mid 237.131657 -54.162221)
					(end 237.11662 -54.139592)
				)
				(arc
					(start 236.954568 -53.97754)
					(mid 236.915528 -53.949054)
					(end 236.869732 -53.933598)
				)
				(arc
					(start 236.85119 -53.93055)
					(mid 236.80142 -53.930709)
					(end 236.754162 -53.946298)
				)
				(arc
					(start 236.572044 -54.039516)
					(mid 235.564081 -54.449107)
					(end 236.485176 -53.870098)
				)
				(xy 236.667294 -53.776626) (xy 236.702346 -53.758592)
				(arc
					(start 236.705902 -53.759862)
					(mid 236.77166 -53.742648)
					(end 236.839506 -53.738526)
				)
				(xy 236.842554 -53.73624) (xy 236.896656 -53.74513) (xy 236.901228 -53.745892) (xy 236.936026 -53.75148)
				(arc
					(start 236.937804 -53.75402)
					(mid 237.000702 -53.778688)
					(end 237.057692 -53.81498)
				)
				(xy 237.061248 -53.81498) (xy 237.27918 -54.032912)
				(arc
					(start 237.27918 -54.037992)
					(mid 237.307656 -54.089429)
					(end 237.323884 -54.145942)
				)
				(xy 237.32744 -54.149498) (xy 237.32744 -54.346094)
				(arc
					(start 237.323884 -54.34965)
					(mid 237.320596 -54.365903)
					(end 237.316264 -54.381908)
				)
				(xy 237.42904 -54.32552)
				(arc
					(start 237.42904 -54.10454)
					(mid 237.416892 -54.04394)
					(end 237.382558 -53.992526)
				)
				(xy 237.237016 -53.84673)
				(arc
					(start 237.237016 -53.84165)
					(mid 237.226537 -53.825873)
					(end 237.217204 -53.809392)
				)
				(arc
					(start 237.217204 -53.808884)
					(mid 237.191186 -53.729551)
					(end 237.191296 -53.64607)
				)
				(arc
					(start 237.191296 -53.645816)
					(mid 237.227217 -53.549778)
					(end 237.29696 -53.47462)
				)
				(xy 237.298484 -53.469794)
				(arc
					(start 237.526576 -53.355748)
					(mid 238.537853 -52.955001)
					(end 237.61192 -53.525928)
				)
				(arc
					(start 237.419134 -53.622448)
					(mid 237.392708 -53.64472)
					(end 237.379256 -53.67655)
				)
				(arc
					(start 237.379256 -53.67655)
					(mid 237.379224 -53.699718)
					(end 237.386368 -53.721762)
				)
				(arc
					(start 237.386368 -53.721762)
					(mid 237.392303 -53.731149)
					(end 237.399576 -53.739542)
				)
				(xy 237.39983 -53.74005) (xy 237.42777 -53.76799) (xy 237.42777 -53.768244) (xy 237.50651 -53.84673)
				(xy 237.517178 -53.857652) (xy 237.517432 -53.857652) (xy 237.545118 -53.885592)
				(arc
					(start 237.545118 -53.889148)
					(mid 237.592944 -53.970964)
					(end 237.617 -54.06263)
				)
				(xy 237.61954 -54.06517) (xy 237.61954 -54.23027) (xy 238.376206 -53.852064)
			)
		)
	)
	(zone
		(layer "B.Cu")
		(hatch none 0.5)
		(connect_pads
			(clearance 0)
		)
		(min_thickness 0.25)
		(keepout
			(tracks not_allowed)
			(vias allowed)
			(pads allowed)
			(copperpour not_allowed)
			(footprints allowed)
		)
		(placement
			(enabled no)
			(sheetname "")
		)
		(fill
			(thermal_gap 0.5)
			(thermal_bridge_width 0.5)
			(island_removal_mode 0)
		)
		(polygon
			(pts
				(arc
					(start 217.748612 -407.000456)
					(mid 217.200099 -406.451562)
					(end 216.651332 -407.000202)
				)
				(xy 216.651332 -407.458672)
				(arc
					(start 217.0176 -407.458672)
					(mid 217.032444 -407.457322)
					(end 217.04681 -407.453338)
				)
				(arc
					(start 217.04681 -407.453338)
					(mid 217.085196 -407.425502)
					(end 217.10396 -407.381964)
				)
				(arc
					(start 217.10396 -407.381964)
					(mid 217.200372 -406.606552)
					(end 217.295222 -407.382218)
				)
				(xy 217.295222 -407.408888)
				(arc
					(start 217.29192 -407.41219)
					(mid 217.232594 -407.546015)
					(end 217.113866 -407.631646)
				)
				(arc
					(start 217.113866 -407.631646)
					(mid 217.087554 -407.640099)
					(end 217.060526 -407.64587)
				)
				(xy 217.05697 -407.649172) (xy 216.651332 -407.649172) (xy 216.651332 -407.750772) (xy 217.054684 -407.750772)
				(arc
					(start 217.057986 -407.754074)
					(mid 217.213218 -407.832776)
					(end 217.29192 -407.988008)
				)
				(xy 217.295222 -407.99131)
				(arc
					(start 217.295222 -408.01798)
					(mid 217.200372 -408.793707)
					(end 217.10396 -408.018234)
				)
				(arc
					(start 217.10396 -408.018234)
					(mid 217.074046 -407.963126)
					(end 217.015314 -407.941272)
				)
				(xy 216.651332 -407.941272)
				(arc
					(start 216.651332 -408.399996)
					(mid 217.199972 -408.948636)
					(end 217.748612 -408.399996)
				)
			)
		)
	)
	(zone
		(layer "B.Cu")
		(hatch none 0.5)
		(connect_pads
			(clearance 0)
		)
		(min_thickness 0.25)
		(keepout
			(tracks not_allowed)
			(vias allowed)
			(pads allowed)
			(copperpour not_allowed)
			(footprints allowed)
		)
		(placement
			(enabled no)
			(sheetname "")
		)
		(fill
			(thermal_gap 0.5)
			(thermal_bridge_width 0.5)
			(island_removal_mode 0)
		)
		(polygon
			(pts
				(arc
					(start 166.325042 -322.799964)
					(mid 159.325056 -315.799978)
					(end 152.32507 -322.799964)
				)
				(arc
					(start 152.32507 -328.799952)
					(mid 159.325056 -335.799938)
					(end 166.325042 -328.799952)
				)
			)
		)
	)
	(zone
		(layer "B.Cu")
		(hatch none 0.5)
		(connect_pads
			(clearance 0)
		)
		(min_thickness 0.25)
		(keepout
			(tracks not_allowed)
			(vias allowed)
			(pads allowed)
			(copperpour not_allowed)
			(footprints allowed)
		)
		(placement
			(enabled no)
			(sheetname "")
		)
		(fill
			(thermal_gap 0.5)
			(thermal_bridge_width 0.5)
			(island_removal_mode 0)
		)
		(polygon
			(pts
				(arc
					(start 236.531658 -169.808144)
					(mid 236.462854 -169.780726)
					(end 236.389418 -169.77106)
				)
				(xy 235.88091 -169.769536) (xy 235.724192 -169.847768) (xy 235.724192 -169.848022)
				(arc
					(start 235.725208 -169.850054)
					(mid 235.400342 -170.824652)
					(end 236.37494 -171.149518)
				)
				(xy 236.37621 -171.151804) (xy 238.376206 -170.151806)
				(arc
					(start 238.374936 -170.14952)
					(mid 238.699802 -169.174922)
					(end 237.725204 -168.850056)
				)
				(xy 237.723934 -168.84777)
				(arc
					(start 236.706918 -169.356278)
					(mid 236.735785 -169.369915)
					(end 236.764068 -169.384726)
				)
				(arc
					(start 236.764322 -169.384726)
					(mid 236.840891 -169.432784)
					(end 236.911388 -169.489374)
				)
				(xy 236.912658 -169.489374) (xy 236.940344 -169.51706) (xy 236.940598 -169.517314)
				(arc
					(start 237.145576 -169.722292)
					(mid 237.184616 -169.750778)
					(end 237.230412 -169.766234)
				)
				(arc
					(start 237.248954 -169.769282)
					(mid 237.298724 -169.769123)
					(end 237.345982 -169.753534)
				)
				(arc
					(start 237.5281 -169.660316)
					(mid 238.536063 -169.250725)
					(end 237.614968 -169.829734)
				)
				(xy 237.43285 -169.923206) (xy 237.397798 -169.94124)
				(arc
					(start 237.394242 -169.93997)
					(mid 237.328484 -169.957184)
					(end 237.260638 -169.961306)
				)
				(xy 237.25759 -169.963592) (xy 237.203488 -169.954702) (xy 237.198916 -169.95394) (xy 237.164118 -169.948352)
				(arc
					(start 237.16234 -169.945812)
					(mid 237.099442 -169.921144)
					(end 237.042452 -169.884852)
				)
				(xy 237.038896 -169.884852)
				(arc
					(start 236.805724 -169.65168)
					(mid 236.742709 -169.597058)
					(end 236.672628 -169.551858)
				)
				(arc
					(start 236.672628 -169.551858)
					(mid 236.566911 -169.506655)
					(end 236.454442 -169.48277)
				)
				(xy 236.25937 -169.580052) (xy 236.388656 -169.58056) (xy 236.39018 -169.58056) (xy 236.42828 -169.580814)
				(arc
					(start 236.429804 -169.582338)
					(mid 236.529784 -169.601514)
					(end 236.623606 -169.641012)
				)
				(arc
					(start 236.623606 -169.641012)
					(mid 236.664973 -169.666592)
					(end 236.703616 -169.69613)
				)
				(xy 236.705902 -169.69613) (xy 236.733588 -169.723562) (xy 236.733842 -169.72407) (xy 236.862874 -169.853102)
				(arc
					(start 236.862874 -169.857928)
					(mid 236.905234 -169.951295)
					(end 236.908848 -170.053762)
				)
				(arc
					(start 236.908848 -170.054016)
					(mid 236.872927 -170.150054)
					(end 236.803184 -170.225212)
				)
				(xy 236.80166 -170.230038) (xy 236.766354 -170.247564)
				(arc
					(start 236.573568 -170.344084)
					(mid 235.562291 -170.744831)
					(end 236.488224 -170.173904)
				)
				(arc
					(start 236.68101 -170.077384)
					(mid 236.707436 -170.055112)
					(end 236.720888 -170.023282)
				)
				(arc
					(start 236.720888 -170.023282)
					(mid 236.718275 -169.989031)
					(end 236.700314 -169.959782)
				)
				(arc
					(start 236.598714 -169.858436)
					(mid 236.566956 -169.830931)
					(end 236.531658 -169.808144)
				)
			)
		)
	)
	(zone
		(layer "B.Cu")
		(hatch none 0.5)
		(connect_pads
			(clearance 0)
		)
		(min_thickness 0.25)
		(keepout
			(tracks allowed)
			(vias allowed)
			(pads allowed)
			(copperpour allowed)
			(footprints not_allowed)
		)
		(placement
			(enabled no)
			(sheetname "")
		)
		(fill
			(thermal_gap 0.5)
			(thermal_bridge_width 0.5)
			(island_removal_mode 0)
		)
		(polygon
			(pts
				(arc
					(start 386.675122 -213.799928)
					(mid 390.84931 -220.204198)
					(end 398.393666 -218.970606)
				)
				(arc
					(start 398.393666 -218.970606)
					(mid 425.175135 -238.800094)
					(end 451.956424 -218.970606)
				)
				(arc
					(start 451.956424 -218.970606)
					(mid 459.500806 -220.204256)
					(end 463.674968 -213.799928)
				)
				(arc
					(start 463.674968 -207.79994)
					(mid 459.500701 -201.395636)
					(end 451.956424 -202.629516)
				)
				(arc
					(start 451.956424 -202.629516)
					(mid 425.175135 -182.800091)
					(end 398.393666 -202.629516)
				)
				(arc
					(start 398.393666 -202.629516)
					(mid 390.849438 -201.395749)
					(end 386.675122 -207.79994)
				)
			)
		)
	)
	(zone
		(layer "B.Cu")
		(hatch none 0.5)
		(connect_pads
			(clearance 0)
		)
		(min_thickness 0.25)
		(keepout
			(tracks not_allowed)
			(vias allowed)
			(pads allowed)
			(copperpour not_allowed)
			(footprints allowed)
		)
		(placement
			(enabled no)
			(sheetname "")
		)
		(fill
			(thermal_gap 0.5)
			(thermal_bridge_width 0.5)
			(island_removal_mode 0)
		)
		(polygon
			(pts
				(arc
					(start 48.749966 -269.999968)
					(mid 44.000166 -265.250168)
					(end 39.250112 -269.999968)
				)
				(arc
					(start 39.250112 -269.999968)
					(mid 44.000166 -274.750022)
					(end 48.749966 -269.999968)
				)
			)
		)
	)
	(zone
		(layer "B.Cu")
		(hatch none 0.5)
		(connect_pads
			(clearance 0)
		)
		(min_thickness 0.25)
		(keepout
			(tracks allowed)
			(vias allowed)
			(pads allowed)
			(copperpour allowed)
			(footprints allowed)
		)
		(placement
			(enabled no)
			(sheetname "")
		)
		(fill
			(thermal_gap 0.5)
			(thermal_bridge_width 0.5)
			(island_removal_mode 0)
		)
		(polygon
			(pts
				(xy 474.823028 -244.38483) (xy 472.672156 -244.38483) (xy 472.672156 -236.219492) (xy 474.823028 -236.219492)
			)
		)
	)
	(zone
		(layer "B.Cu")
		(hatch none 0.5)
		(connect_pads
			(clearance 0)
		)
		(min_thickness 0.25)
		(keepout
			(tracks not_allowed)
			(vias allowed)
			(pads allowed)
			(copperpour not_allowed)
			(footprints allowed)
		)
		(placement
			(enabled no)
			(sheetname "")
		)
		(fill
			(thermal_gap 0.5)
			(thermal_bridge_width 0.5)
			(island_removal_mode 0)
		)
		(polygon
			(pts
				(xy 279.047448 -177.77079) (xy 278.58085 -177.76952) (xy 278.424132 -177.847752) (xy 278.424132 -177.848006)
				(arc
					(start 278.425148 -177.850038)
					(mid 278.100282 -178.824636)
					(end 279.07488 -179.149502)
				)
				(xy 279.07615 -179.151788) (xy 281.076146 -178.15179)
				(arc
					(start 281.074876 -178.149504)
					(mid 281.399742 -177.174906)
					(end 280.425144 -176.85004)
				)
				(xy 280.423874 -176.847754)
				(arc
					(start 279.406858 -177.356262)
					(mid 279.435725 -177.369899)
					(end 279.464008 -177.38471)
				)
				(arc
					(start 279.464262 -177.38471)
					(mid 279.540831 -177.432768)
					(end 279.611328 -177.489358)
				)
				(xy 279.612598 -177.489358) (xy 279.640284 -177.517044) (xy 279.640538 -177.517298) (xy 279.775158 -177.651918)
				(arc
					(start 279.845516 -177.722276)
					(mid 279.884556 -177.750762)
					(end 279.930352 -177.766218)
				)
				(arc
					(start 279.948894 -177.769266)
					(mid 279.998664 -177.769107)
					(end 280.045922 -177.753518)
				)
				(arc
					(start 280.22804 -177.6603)
					(mid 281.236003 -177.250709)
					(end 280.314908 -177.829718)
				)
				(xy 280.13279 -177.92319) (xy 280.097738 -177.941224)
				(arc
					(start 280.094182 -177.939954)
					(mid 280.028424 -177.957168)
					(end 279.960578 -177.96129)
				)
				(xy 279.95753 -177.963576) (xy 279.903428 -177.954686) (xy 279.898856 -177.953924) (xy 279.864058 -177.948336)
				(arc
					(start 279.86228 -177.945796)
					(mid 279.799382 -177.921128)
					(end 279.742392 -177.884836)
				)
				(xy 279.738836 -177.884836) (xy 279.679146 -177.825146) (xy 279.505918 -177.651918)
				(arc
					(start 279.505664 -177.651664)
					(mid 279.442649 -177.597042)
					(end 279.372568 -177.551842)
				)
				(arc
					(start 279.372568 -177.551842)
					(mid 279.266851 -177.506639)
					(end 279.154382 -177.482754)
				)
				(xy 278.95931 -177.580036) (xy 279.087326 -177.580544) (xy 279.127712 -177.580544)
				(arc
					(start 279.12949 -177.582322)
					(mid 279.229597 -177.601482)
					(end 279.323546 -177.640996)
				)
				(arc
					(start 279.323546 -177.640996)
					(mid 279.364913 -177.666576)
					(end 279.403556 -177.696114)
				)
				(xy 279.405842 -177.696114) (xy 279.433528 -177.723546) (xy 279.433782 -177.724054) (xy 279.534874 -177.825146)
				(xy 279.562814 -177.853086)
				(arc
					(start 279.562814 -177.857912)
					(mid 279.605174 -177.951279)
					(end 279.608788 -178.053746)
				)
				(arc
					(start 279.608788 -178.054)
					(mid 279.572867 -178.150038)
					(end 279.503124 -178.225196)
				)
				(xy 279.5016 -178.230022)
				(arc
					(start 279.273508 -178.344068)
					(mid 278.262231 -178.744815)
					(end 279.188164 -178.173888)
				)
				(arc
					(start 279.38095 -178.077368)
					(mid 279.407376 -178.055096)
					(end 279.420828 -178.023266)
				)
				(arc
					(start 279.420828 -178.023266)
					(mid 279.418215 -177.989015)
					(end 279.400254 -177.959766)
				)
				(xy 279.299162 -177.858674)
				(arc
					(start 279.298654 -177.85842)
					(mid 279.266896 -177.830915)
					(end 279.231598 -177.808128)
				)
				(arc
					(start 279.231598 -177.808128)
					(mid 279.163286 -177.780839)
					(end 279.090374 -177.771044)
				)
				(xy 279.086818 -177.771044) (xy 279.047702 -177.771044)
			)
		)
	)
	(zone
		(layer "B.Cu")
		(hatch none 0.5)
		(connect_pads
			(clearance 0)
		)
		(min_thickness 0.25)
		(keepout
			(tracks not_allowed)
			(vias allowed)
			(pads allowed)
			(copperpour not_allowed)
			(footprints allowed)
		)
		(placement
			(enabled no)
			(sheetname "")
		)
		(fill
			(thermal_gap 0.5)
			(thermal_bridge_width 0.5)
			(island_removal_mode 0)
		)
		(polygon
			(pts
				(arc
					(start 286.436562 -342.75649)
					(mid 285.887922 -343.30513)
					(end 286.436562 -343.85377)
				)
				(arc
					(start 286.935926 -343.85377)
					(mid 286.921941 -343.784836)
					(end 286.915098 -343.714832)
				)
				(xy 286.914336 -343.71407)
				(arc
					(start 286.914336 -343.43213)
					(mid 286.899457 -343.396209)
					(end 286.863536 -343.38133)
				)
				(arc
					(start 286.822896 -343.38133)
					(mid 286.042785 -343.30513)
					(end 286.822896 -343.22893)
				)
				(xy 286.895032 -343.22893)
				(arc
					(start 286.89808 -343.231978)
					(mid 287.007157 -343.288509)
					(end 287.063688 -343.397586)
				)
				(xy 287.066736 -343.400634)
				(arc
					(start 287.066736 -343.682828)
					(mid 287.073831 -343.769454)
					(end 287.09493 -343.85377)
				)
				(arc
					(start 287.245806 -343.85377)
					(mid 287.220395 -343.786436)
					(end 287.207706 -343.715594)
				)
				(xy 287.206436 -343.71407) (xy 287.206436 -343.400634)
				(arc
					(start 287.209484 -343.397586)
					(mid 287.266015 -343.288509)
					(end 287.375092 -343.231978)
				)
				(xy 287.37814 -343.22893)
				(arc
					(start 287.450276 -343.22893)
					(mid 288.230387 -343.30513)
					(end 287.450276 -343.38133)
				)
				(arc
					(start 287.409636 -343.38133)
					(mid 287.373715 -343.396209)
					(end 287.358836 -343.43213)
				)
				(arc
					(start 287.358836 -343.682574)
					(mid 287.377127 -343.774527)
					(end 287.429194 -343.8525)
				)
				(xy 287.430464 -343.85377)
				(arc
					(start 287.83661 -343.85377)
					(mid 288.38525 -343.30513)
					(end 287.83661 -342.75649)
				)
				(xy 286.436816 -342.75649)
			)
		)
	)
	(zone
		(net "P12V_A_VIN_U22")
		(layer "B.Cu")
		(hatch none 0.5)
		(connect_pads
			(clearance 0.5)
		)
		(min_thickness 0.25)
		(fill yes
			(thermal_gap 0.5)
			(thermal_bridge_width 0.5)
			(island_removal_mode 0)
		)
		(polygon
			(pts
				(xy 432.077876 -247.349264) (xy 431.31359 -248.11355) (xy 431.31359 -251.436632) (xy 431.687224 -251.810266)
				(xy 439.517028 -251.810266) (xy 439.970926 -252.264164) (xy 441.032646 -252.264164) (xy 441.39866 -251.89815)
				(xy 444.592202 -251.89815) (xy 444.592202 -248.85015) (xy 443.091316 -247.349264)
			)
		)
		(polygon
			(pts
				(xy 440.643772 -251.518166) (xy 440.440572 -251.518166) (xy 440.440572 -251.721366) (xy 440.643772 -251.721366)
			)
		)
		(polygon
			(pts
				(xy 440.034172 -251.518166) (xy 439.830972 -251.518166) (xy 439.830972 -251.721366) (xy 440.034172 -251.721366)
			)
		)
		(polygon
			(pts
				(xy 433.408582 -250.460002) (xy 433.205382 -250.460002) (xy 433.205382 -250.663202) (xy 433.408582 -250.663202)
			)
		)
		(polygon
			(pts
				(xy 432.011582 -250.460002) (xy 431.808382 -250.460002) (xy 431.808382 -250.663202) (xy 432.011582 -250.663202)
			)
		)
	)
	(zone
		(layer "B.Cu")
		(hatch none 0.5)
		(connect_pads
			(clearance 0)
		)
		(min_thickness 0.25)
		(keepout
			(tracks not_allowed)
			(vias allowed)
			(pads allowed)
			(copperpour not_allowed)
			(footprints allowed)
		)
		(placement
			(enabled no)
			(sheetname "")
		)
		(fill
			(thermal_gap 0.5)
			(thermal_bridge_width 0.5)
			(island_removal_mode 0)
		)
		(polygon
			(pts
				(arc
					(start 278.23668 -348.15653)
					(mid 277.68804 -348.70517)
					(end 278.23668 -349.25381)
				)
				(xy 278.642826 -349.25381) (xy 278.644096 -349.25254)
				(arc
					(start 278.661876 -349.232728)
					(mid 278.700943 -349.16215)
					(end 278.714454 -349.082614)
				)
				(arc
					(start 278.714454 -348.83217)
					(mid 278.699575 -348.796249)
					(end 278.663654 -348.78137)
				)
				(arc
					(start 278.623014 -348.78137)
					(mid 277.842903 -348.70517)
					(end 278.623014 -348.62897)
				)
				(xy 278.69515 -348.62897)
				(arc
					(start 278.698198 -348.632018)
					(mid 278.807275 -348.688549)
					(end 278.863806 -348.797626)
				)
				(xy 278.866854 -348.800674) (xy 278.866854 -349.11411)
				(arc
					(start 278.865584 -349.115634)
					(mid 278.852891 -349.186475)
					(end 278.827484 -349.25381)
				)
				(arc
					(start 278.97836 -349.25381)
					(mid 278.999445 -349.16962)
					(end 279.006554 -349.083122)
				)
				(xy 279.006554 -348.800674)
				(arc
					(start 279.009602 -348.797626)
					(mid 279.066133 -348.688549)
					(end 279.17521 -348.632018)
				)
				(xy 279.178258 -348.62897)
				(arc
					(start 279.250394 -348.62897)
					(mid 280.030505 -348.70517)
					(end 279.250394 -348.78137)
				)
				(arc
					(start 279.209754 -348.78137)
					(mid 279.173833 -348.796249)
					(end 279.158954 -348.83217)
				)
				(xy 279.158954 -349.083122) (xy 279.158954 -349.114618)
				(arc
					(start 279.158192 -349.11538)
					(mid 279.151335 -349.185131)
					(end 279.137364 -349.25381)
				)
				(arc
					(start 279.636728 -349.25381)
					(mid 280.185368 -348.70517)
					(end 279.636728 -348.15653)
				)
				(xy 278.236934 -348.15653)
			)
		)
	)
	(zone
		(layer "B.Cu")
		(hatch none 0.5)
		(connect_pads
			(clearance 0)
		)
		(min_thickness 0.25)
		(keepout
			(tracks allowed)
			(vias allowed)
			(pads allowed)
			(copperpour allowed)
			(footprints not_allowed)
		)
		(placement
			(enabled no)
			(sheetname "")
		)
		(fill
			(thermal_gap 0.5)
			(thermal_bridge_width 0.5)
			(island_removal_mode 0)
		)
		(polygon
			(pts
				(xy 491.450122 -209.199988)
				(arc
					(start 491.450122 -0.999998)
					(mid 491.157229 -0.292893)
					(end 490.450124 0)
				)
				(xy 476.25 0) (xy 476.25 -209.199988)
			)
		)
	)
	(zone
		(layer "B.Cu")
		(hatch none 0.5)
		(connect_pads
			(clearance 0)
		)
		(min_thickness 0.25)
		(keepout
			(tracks allowed)
			(vias allowed)
			(pads allowed)
			(copperpour allowed)
			(footprints not_allowed)
		)
		(placement
			(enabled no)
			(sheetname "")
		)
		(fill
			(thermal_gap 0.5)
			(thermal_bridge_width 0.5)
			(island_removal_mode 0)
		)
		(polygon
			(pts
				(arc
					(start 4.249928 -224.199958)
					(mid 7.999984 -227.950014)
					(end 11.75004 -224.199958)
				)
				(arc
					(start 11.75004 -224.199958)
					(mid 7.999984 -220.449902)
					(end 4.249928 -224.199958)
				)
			)
		)
	)
	(zone
		(net "GND")
		(layer "B.Cu")
		(hatch none 0.5)
		(connect_pads
			(clearance 0.5)
		)
		(min_thickness 0.25)
		(fill yes
			(thermal_gap 0.5)
			(thermal_bridge_width 0.5)
			(island_removal_mode 0)
		)
		(polygon
			(pts
				(xy 444.932816 -248.681494) (xy 444.754 -248.86031) (xy 444.754 -254.56515) (xy 445.022224 -254.833374)
				(xy 445.022224 -255.680972) (xy 445.506602 -256.16535) (xy 446.360804 -256.16535) (xy 446.370202 -256.174748)
				(xy 448.056 -254.48895) (xy 448.056 -248.863104) (xy 447.87439 -248.681494)
			)
		)
	)
	(zone
		(net "GND")
		(layer "B.Cu")
		(hatch none 0.5)
		(connect_pads
			(clearance 0.5)
		)
		(min_thickness 0.25)
		(fill yes
			(thermal_gap 0.5)
			(thermal_bridge_width 0.5)
			(island_removal_mode 0)
		)
		(polygon
			(pts
				(xy 468.253318 -236.214666) (xy 468.062564 -236.40542) (xy 468.062564 -241.976148) (xy 468.213948 -242.127532)
				(xy 470.016078 -242.127532) (xy 470.05875 -242.08486) (xy 470.05875 -236.333538) (xy 469.939878 -236.214666)
			)
		)
	)
	(zone
		(layer "B.Cu")
		(hatch none 0.5)
		(connect_pads
			(clearance 0)
		)
		(min_thickness 0.25)
		(keepout
			(tracks not_allowed)
			(vias allowed)
			(pads allowed)
			(copperpour not_allowed)
			(footprints allowed)
		)
		(placement
			(enabled no)
			(sheetname "")
		)
		(fill
			(thermal_gap 0.5)
			(thermal_bridge_width 0.5)
			(island_removal_mode 0)
		)
		(polygon
			(pts
				(arc
					(start 337.674966 -322.799964)
					(mid 330.67498 -315.799978)
					(end 323.674994 -322.799964)
				)
				(arc
					(start 323.674994 -328.799952)
					(mid 330.67498 -335.799938)
					(end 337.674966 -328.799952)
				)
			)
		)
	)
	(zone
		(layer "B.Cu")
		(hatch none 0.5)
		(connect_pads
			(clearance 0)
		)
		(min_thickness 0.25)
		(keepout
			(tracks not_allowed)
			(vias allowed)
			(pads allowed)
			(copperpour not_allowed)
			(footprints allowed)
		)
		(placement
			(enabled no)
			(sheetname "")
		)
		(fill
			(thermal_gap 0.5)
			(thermal_bridge_width 0.5)
			(island_removal_mode 0)
		)
		(polygon
			(pts
				(arc
					(start 281.074876 -77.84973)
					(mid 281.399742 -76.875132)
					(end 280.425144 -76.550266)
				)
				(xy 280.423874 -76.54798) (xy 278.424132 -77.547978) (xy 278.424132 -77.548232)
				(arc
					(start 278.425148 -77.550264)
					(mid 278.100282 -78.524862)
					(end 279.07488 -78.849728)
				)
				(xy 279.07615 -78.852014)
				(arc
					(start 280.086562 -78.346808)
					(mid 279.982979 -78.285356)
					(end 279.888696 -78.21041)
				)
				(xy 279.887426 -78.21041)
				(arc
					(start 279.654508 -77.977492)
					(mid 279.615468 -77.949006)
					(end 279.569672 -77.93355)
				)
				(xy 279.566116 -77.933042)
				(arc
					(start 279.55113 -77.930502)
					(mid 279.50136 -77.930661)
					(end 279.454102 -77.94625)
				)
				(arc
					(start 279.271984 -78.039468)
					(mid 278.264021 -78.449059)
					(end 279.185116 -77.87005)
				)
				(xy 279.367234 -77.776578) (xy 279.402286 -77.758544)
				(arc
					(start 279.405842 -77.759814)
					(mid 279.4716 -77.7426)
					(end 279.539446 -77.738478)
				)
				(xy 279.542494 -77.736192) (xy 279.58161 -77.742542) (xy 279.596596 -77.745082) (xy 279.601168 -77.745844)
				(xy 279.635966 -77.751432)
				(arc
					(start 279.637744 -77.753972)
					(mid 279.700642 -77.77864)
					(end 279.757632 -77.814932)
				)
				(xy 279.761188 -77.814932) (xy 279.879298 -77.933042)
				(arc
					(start 279.994106 -78.04785)
					(mid 280.143896 -78.161503)
					(end 280.318718 -78.23073)
				)
				(xy 280.481786 -78.149196) (xy 280.445464 -78.149196)
				(arc
					(start 280.44394 -78.147672)
					(mid 280.258325 -78.104036)
					(end 280.096214 -78.003654)
				)
				(xy 280.094182 -78.003654) (xy 280.066242 -77.975714) (xy 279.93721 -77.846682)
				(arc
					(start 279.93721 -77.841856)
					(mid 279.89485 -77.748489)
					(end 279.891236 -77.646022)
				)
				(arc
					(start 279.891236 -77.645768)
					(mid 279.927157 -77.54973)
					(end 279.9969 -77.474572)
				)
				(xy 279.998424 -77.469746)
				(arc
					(start 280.226516 -77.3557)
					(mid 281.237793 -76.954953)
					(end 280.31186 -77.52588)
				)
				(arc
					(start 280.119074 -77.6224)
					(mid 280.092648 -77.644672)
					(end 280.079196 -77.676502)
				)
				(arc
					(start 280.079196 -77.676502)
					(mid 280.081809 -77.710753)
					(end 280.09977 -77.740002)
				)
				(arc
					(start 280.200862 -77.841094)
					(mid 280.331149 -77.928149)
					(end 280.484834 -77.958696)
				)
				(xy 280.862786 -77.958696) (xy 281.076146 -77.852016)
			)
		)
	)
	(zone
		(layer "B.Cu")
		(hatch none 0.5)
		(connect_pads
			(clearance 0)
		)
		(min_thickness 0.25)
		(keepout
			(tracks not_allowed)
			(vias allowed)
			(pads allowed)
			(copperpour not_allowed)
			(footprints allowed)
		)
		(placement
			(enabled no)
			(sheetname "")
		)
		(fill
			(thermal_gap 0.5)
			(thermal_bridge_width 0.5)
			(island_removal_mode 0)
		)
		(polygon
			(pts
				(arc
					(start 271.970754 -353.723956)
					(mid 271.5895 -354.104829)
					(end 271.9705 -354.485956)
				)
				(arc
					(start 273.1135 -354.485956)
					(mid 273.4945 -354.104956)
					(end 273.1135 -353.723956)
				)
				(arc
					(start 272.76806 -353.723956)
					(mid 272.765209 -353.74954)
					(end 272.76425 -353.775264)
				)
				(arc
					(start 272.76425 -353.923854)
					(mid 272.791127 -353.993972)
					(end 272.857976 -354.028248)
				)
				(arc
					(start 272.857976 -354.028248)
					(mid 273.380217 -354.104702)
					(end 272.857976 -354.181156)
				)
				(xy 272.837656 -354.181156)
				(arc
					(start 272.83537 -354.17887)
					(mid 272.687253 -354.105753)
					(end 272.614136 -353.957636)
				)
				(xy 272.61185 -353.95535) (xy 272.61185 -353.743768) (xy 272.612866 -353.742752) (xy 272.61439 -353.723956)
				(arc
					(start 272.474182 -353.723956)
					(mid 272.472648 -353.74959)
					(end 272.47215 -353.775264)
				)
				(xy 272.47215 -353.95535)
				(arc
					(start 272.469864 -353.957636)
					(mid 272.396747 -354.105753)
					(end 272.24863 -354.17887)
				)
				(xy 272.246344 -354.181156)
				(arc
					(start 272.226024 -354.181156)
					(mid 271.703783 -354.104702)
					(end 272.226024 -354.028248)
				)
				(arc
					(start 272.226024 -354.028248)
					(mid 272.292939 -353.994031)
					(end 272.31975 -353.923854)
				)
				(xy 272.31975 -353.743768) (xy 272.320512 -353.743006) (xy 272.321528 -353.723956)
			)
		)
	)
	(zone
		(layer "B.Cu")
		(hatch none 0.5)
		(connect_pads
			(clearance 0)
		)
		(min_thickness 0.25)
		(keepout
			(tracks not_allowed)
			(vias allowed)
			(pads allowed)
			(copperpour not_allowed)
			(footprints allowed)
		)
		(placement
			(enabled no)
			(sheetname "")
		)
		(fill
			(thermal_gap 0.5)
			(thermal_bridge_width 0.5)
			(island_removal_mode 0)
		)
		(polygon
			(pts
				(arc
					(start 221.348808 -407.000456)
					(mid 220.800295 -406.451562)
					(end 220.251528 -407.000202)
				)
				(xy 220.251528 -407.458672)
				(arc
					(start 220.617796 -407.458672)
					(mid 220.63264 -407.457322)
					(end 220.647006 -407.453338)
				)
				(arc
					(start 220.647006 -407.453338)
					(mid 220.685392 -407.425502)
					(end 220.704156 -407.381964)
				)
				(arc
					(start 220.704156 -407.381964)
					(mid 220.800568 -406.606552)
					(end 220.895418 -407.382218)
				)
				(xy 220.895418 -407.408888)
				(arc
					(start 220.892116 -407.41219)
					(mid 220.83279 -407.546015)
					(end 220.714062 -407.631646)
				)
				(arc
					(start 220.714062 -407.631646)
					(mid 220.68775 -407.640099)
					(end 220.660722 -407.64587)
				)
				(xy 220.657166 -407.649172) (xy 220.251528 -407.649172) (xy 220.251528 -407.750772) (xy 220.65488 -407.750772)
				(arc
					(start 220.658182 -407.754074)
					(mid 220.813414 -407.832776)
					(end 220.892116 -407.988008)
				)
				(xy 220.895418 -407.99131)
				(arc
					(start 220.895418 -408.01798)
					(mid 220.800568 -408.793707)
					(end 220.704156 -408.018234)
				)
				(arc
					(start 220.704156 -408.018234)
					(mid 220.674242 -407.963126)
					(end 220.61551 -407.941272)
				)
				(xy 220.251528 -407.941272)
				(arc
					(start 220.251528 -408.399996)
					(mid 220.800168 -408.948636)
					(end 221.348808 -408.399996)
				)
			)
		)
	)
	(zone
		(net "MB1_P12V_B_R")
		(layer "B.Cu")
		(hatch none 0.5)
		(connect_pads
			(clearance 0.5)
		)
		(min_thickness 0.25)
		(fill yes
			(thermal_gap 0.5)
			(thermal_bridge_width 0.5)
			(island_removal_mode 0)
		)
		(polygon
			(pts
				(xy 345.3384 -138.6586) (xy 344.932 -139.065) (xy 344.932 -144.399) (xy 345.3892 -144.8562) (xy 350.2152 -144.8562)
				(xy 350.52 -145.161) (xy 350.52 -145.923) (xy 350.774 -146.177) (xy 352.806 -146.177) (xy 352.933 -146.05)
				(xy 352.933 -145.034) (xy 353.06 -144.907) (xy 354.711 -144.907) (xy 355.092 -144.526) (xy 355.092 -138.938)
				(xy 354.8126 -138.6586)
			)
		)
	)
	(zone
		(net "GND")
		(layer "B.Cu")
		(hatch none 0.5)
		(connect_pads
			(clearance 0.5)
		)
		(min_thickness 0.25)
		(fill yes
			(thermal_gap 0.5)
			(thermal_bridge_width 0.5)
			(island_removal_mode 0)
		)
		(polygon
			(pts
				(arc
					(start 339.878162 -254.965962)
					(mid 341.37746 -253.95594)
					(end 343.165684 -253.690882)
				)
				(arc
					(start 348.025212 -250.47448)
					(mid 347.299862 -249.952388)
					(end 346.705174 -249.285252)
				)
				(arc
					(start 346.705174 -249.285252)
					(mid 344.937631 -250.295425)
					(end 342.902032 -250.32843)
				)
				(arc
					(start 342.902032 -250.32843)
					(mid 342.168232 -250.317837)
					(end 341.448136 -250.176284)
				)
				(arc
					(start 341.448136 -250.176284)
					(mid 341.213324 -250.24329)
					(end 340.974934 -250.296172)
				)
				(xy 339.0392 -253.220982) (xy 339.0392 -254.127)
			)
		)
	)
	(zone
		(net "P12V_A_VIN_U21")
		(layer "B.Cu")
		(hatch none 0.5)
		(connect_pads
			(clearance 0.5)
		)
		(min_thickness 0.25)
		(fill yes
			(thermal_gap 0.5)
			(thermal_bridge_width 0.5)
			(island_removal_mode 0)
		)
		(polygon
			(pts
				(xy 34.483802 -138.36015) (xy 34.102802 -138.74115) (xy 34.102802 -141.66215) (xy 34.356802 -141.91615)
				(xy 39.944802 -141.91615) (xy 40.325802 -142.29715) (xy 41.087802 -142.29715) (xy 41.341802 -142.55115)
				(xy 41.341802 -143.56715) (xy 41.595802 -143.82115) (xy 42.230802 -143.82115) (xy 42.611802 -144.20215)
				(xy 44.516802 -144.20215) (xy 44.516802 -141.15415) (xy 41.722802 -138.36015)
			)
		)
		(polygon
			(pts
				(xy 40.9956 -141.5796) (xy 40.7924 -141.5796) (xy 40.7924 -141.7828) (xy 40.9956 -141.7828)
			)
		)
		(polygon
			(pts
				(xy 40.386 -141.5796) (xy 40.1828 -141.5796) (xy 40.1828 -141.7828) (xy 40.386 -141.7828)
			)
		)
		(polygon
			(pts
				(xy 35.5473 -139.8905) (xy 35.3441 -139.8905) (xy 35.3441 -140.0937) (xy 35.5473 -140.0937)
			)
		)
		(polygon
			(pts
				(xy 35.5473 -138.4935) (xy 35.3441 -138.4935) (xy 35.3441 -138.6967) (xy 35.5473 -138.6967)
			)
		)
	)
	(zone
		(layer "B.Cu")
		(hatch none 0.5)
		(connect_pads
			(clearance 0)
		)
		(min_thickness 0.25)
		(keepout
			(tracks not_allowed)
			(vias allowed)
			(pads allowed)
			(copperpour not_allowed)
			(footprints allowed)
		)
		(placement
			(enabled no)
			(sheetname "")
		)
		(fill
			(thermal_gap 0.5)
			(thermal_bridge_width 0.5)
			(island_removal_mode 0)
		)
		(polygon
			(pts
				(arc
					(start 278.23668 -355.356414)
					(mid 277.68804 -355.905054)
					(end 278.23668 -356.453694)
				)
				(xy 278.642826 -356.453694) (xy 278.644096 -356.452424)
				(arc
					(start 278.661876 -356.432612)
					(mid 278.700943 -356.362034)
					(end 278.714454 -356.282498)
				)
				(arc
					(start 278.714454 -356.032054)
					(mid 278.699575 -355.996133)
					(end 278.663654 -355.981254)
				)
				(arc
					(start 278.623014 -355.981254)
					(mid 277.842903 -355.905054)
					(end 278.623014 -355.828854)
				)
				(xy 278.69515 -355.828854)
				(arc
					(start 278.698198 -355.831902)
					(mid 278.807275 -355.888433)
					(end 278.863806 -355.99751)
				)
				(xy 278.866854 -356.000558) (xy 278.866854 -356.313994)
				(arc
					(start 278.865584 -356.315518)
					(mid 278.852891 -356.386359)
					(end 278.827484 -356.453694)
				)
				(arc
					(start 278.97836 -356.453694)
					(mid 278.999445 -356.369504)
					(end 279.006554 -356.283006)
				)
				(xy 279.006554 -356.000558)
				(arc
					(start 279.009602 -355.99751)
					(mid 279.066133 -355.888433)
					(end 279.17521 -355.831902)
				)
				(xy 279.178258 -355.828854)
				(arc
					(start 279.250394 -355.828854)
					(mid 280.030505 -355.905054)
					(end 279.250394 -355.981254)
				)
				(arc
					(start 279.209754 -355.981254)
					(mid 279.173833 -355.996133)
					(end 279.158954 -356.032054)
				)
				(xy 279.158954 -356.283006) (xy 279.158954 -356.314502)
				(arc
					(start 279.158192 -356.315264)
					(mid 279.151335 -356.385015)
					(end 279.137364 -356.453694)
				)
				(arc
					(start 279.636728 -356.453694)
					(mid 280.185368 -355.905054)
					(end 279.636728 -355.356414)
				)
				(xy 278.236934 -355.356414)
			)
		)
	)
	(zone
		(layer "B.Cu")
		(hatch none 0.5)
		(connect_pads
			(clearance 0)
		)
		(min_thickness 0.25)
		(keepout
			(tracks not_allowed)
			(vias allowed)
			(pads allowed)
			(copperpour not_allowed)
			(footprints allowed)
		)
		(placement
			(enabled no)
			(sheetname "")
		)
		(fill
			(thermal_gap 0.5)
			(thermal_bridge_width 0.5)
			(island_removal_mode 0)
		)
		(polygon
			(pts
				(arc
					(start 166.325042 -92.799916)
					(mid 159.325056 -85.79993)
					(end 152.32507 -92.799916)
				)
				(arc
					(start 152.32507 -98.799904)
					(mid 159.325056 -105.79989)
					(end 166.325042 -98.799904)
				)
			)
		)
	)
	(zone
		(layer "B.Cu")
		(hatch none 0.5)
		(connect_pads
			(clearance 0)
		)
		(min_thickness 0.25)
		(keepout
			(tracks not_allowed)
			(vias allowed)
			(pads allowed)
			(copperpour not_allowed)
			(footprints allowed)
		)
		(placement
			(enabled no)
			(sheetname "")
		)
		(fill
			(thermal_gap 0.5)
			(thermal_bridge_width 0.5)
			(island_removal_mode 0)
		)
		(polygon
			(pts
				(arc
					(start 285.436564 -319.356486)
					(mid 284.887924 -319.905126)
					(end 285.436564 -320.453766)
				)
				(arc
					(start 285.935928 -320.453766)
					(mid 285.921943 -320.384832)
					(end 285.9151 -320.314828)
				)
				(xy 285.914338 -320.314066)
				(arc
					(start 285.914338 -320.032126)
					(mid 285.899459 -319.996205)
					(end 285.863538 -319.981326)
				)
				(arc
					(start 285.822898 -319.981326)
					(mid 285.042787 -319.905126)
					(end 285.822898 -319.828926)
				)
				(xy 285.895034 -319.828926)
				(arc
					(start 285.898082 -319.831974)
					(mid 286.007159 -319.888505)
					(end 286.06369 -319.997582)
				)
				(xy 286.066738 -320.00063)
				(arc
					(start 286.066738 -320.282824)
					(mid 286.073833 -320.36945)
					(end 286.094932 -320.453766)
				)
				(arc
					(start 286.245808 -320.453766)
					(mid 286.220397 -320.386432)
					(end 286.207708 -320.31559)
				)
				(xy 286.206438 -320.314066) (xy 286.206438 -320.00063)
				(arc
					(start 286.209486 -319.997582)
					(mid 286.266017 -319.888505)
					(end 286.375094 -319.831974)
				)
				(xy 286.378142 -319.828926)
				(arc
					(start 286.450278 -319.828926)
					(mid 287.230389 -319.905126)
					(end 286.450278 -319.981326)
				)
				(arc
					(start 286.409638 -319.981326)
					(mid 286.373717 -319.996205)
					(end 286.358838 -320.032126)
				)
				(arc
					(start 286.358838 -320.28257)
					(mid 286.377129 -320.374523)
					(end 286.429196 -320.452496)
				)
				(xy 286.430466 -320.453766)
				(arc
					(start 286.836612 -320.453766)
					(mid 287.385252 -319.905126)
					(end 286.836612 -319.356486)
				)
				(xy 285.436818 -319.356486)
			)
		)
	)
	(zone
		(layer "B.Cu")
		(hatch none 0.5)
		(connect_pads
			(clearance 0)
		)
		(min_thickness 0.25)
		(keepout
			(tracks allowed)
			(vias allowed)
			(pads allowed)
			(copperpour allowed)
			(footprints not_allowed)
		)
		(placement
			(enabled no)
			(sheetname "")
		)
		(fill
			(thermal_gap 0.5)
			(thermal_bridge_width 0.5)
			(island_removal_mode 0)
		)
		(polygon
			(pts
				(arc
					(start 337.674966 -207.79994)
					(mid 330.67498 -200.799954)
					(end 323.674994 -207.79994)
				)
				(arc
					(start 323.674994 -213.799928)
					(mid 330.67498 -220.799914)
					(end 337.674966 -213.799928)
				)
			)
		)
	)
	(zone
		(layer "B.Cu")
		(hatch none 0.5)
		(connect_pads
			(clearance 0)
		)
		(min_thickness 0.25)
		(keepout
			(tracks not_allowed)
			(vias allowed)
			(pads allowed)
			(copperpour not_allowed)
			(footprints allowed)
		)
		(placement
			(enabled no)
			(sheetname "")
		)
		(fill
			(thermal_gap 0.5)
			(thermal_bridge_width 0.5)
			(island_removal_mode 0)
		)
		(polygon
			(pts
				(arc
					(start 487.19994 -204.199998)
					(mid 483.450138 -200.450196)
					(end 479.700082 -204.199998)
				)
				(arc
					(start 479.700082 -204.199998)
					(mid 483.450138 -207.950054)
					(end 487.19994 -204.199998)
				)
			)
		)
	)
	(zone
		(layer "B.Cu")
		(hatch none 0.5)
		(connect_pads
			(clearance 0)
		)
		(min_thickness 0.25)
		(keepout
			(tracks not_allowed)
			(vias allowed)
			(pads allowed)
			(copperpour not_allowed)
			(footprints allowed)
		)
		(placement
			(enabled no)
			(sheetname "")
		)
		(fill
			(thermal_gap 0.5)
			(thermal_bridge_width 0.5)
			(island_removal_mode 0)
		)
		(polygon
			(pts
				(arc
					(start 141.824964 -210.799934)
					(mid 127.824992 -196.799962)
					(end 113.82502 -210.799934)
				)
				(arc
					(start 113.82502 -210.799934)
					(mid 127.824992 -224.799906)
					(end 141.824964 -210.799934)
				)
			)
		)
	)
	(zone
		(layer "B.Cu")
		(hatch none 0.5)
		(connect_pads
			(clearance 0)
		)
		(min_thickness 0.25)
		(keepout
			(tracks not_allowed)
			(vias allowed)
			(pads allowed)
			(copperpour not_allowed)
			(footprints allowed)
		)
		(placement
			(enabled no)
			(sheetname "")
		)
		(fill
			(thermal_gap 0.5)
			(thermal_bridge_width 0.5)
			(island_removal_mode 0)
		)
		(polygon
			(pts
				(arc
					(start 286.436562 -321.156584)
					(mid 285.887922 -321.705224)
					(end 286.436562 -322.253864)
				)
				(arc
					(start 286.935926 -322.253864)
					(mid 286.921941 -322.18493)
					(end 286.915098 -322.114926)
				)
				(xy 286.914336 -322.114164)
				(arc
					(start 286.914336 -321.832224)
					(mid 286.899457 -321.796303)
					(end 286.863536 -321.781424)
				)
				(arc
					(start 286.822896 -321.781424)
					(mid 286.042785 -321.705224)
					(end 286.822896 -321.629024)
				)
				(xy 286.895032 -321.629024)
				(arc
					(start 286.89808 -321.632072)
					(mid 287.007157 -321.688603)
					(end 287.063688 -321.79768)
				)
				(xy 287.066736 -321.800728)
				(arc
					(start 287.066736 -322.082922)
					(mid 287.073831 -322.169548)
					(end 287.09493 -322.253864)
				)
				(arc
					(start 287.245806 -322.253864)
					(mid 287.220395 -322.18653)
					(end 287.207706 -322.115688)
				)
				(xy 287.206436 -322.114164) (xy 287.206436 -321.800728)
				(arc
					(start 287.209484 -321.79768)
					(mid 287.266015 -321.688603)
					(end 287.375092 -321.632072)
				)
				(xy 287.37814 -321.629024)
				(arc
					(start 287.450276 -321.629024)
					(mid 288.230387 -321.705224)
					(end 287.450276 -321.781424)
				)
				(arc
					(start 287.409636 -321.781424)
					(mid 287.373715 -321.796303)
					(end 287.358836 -321.832224)
				)
				(arc
					(start 287.358836 -322.082668)
					(mid 287.377127 -322.174621)
					(end 287.429194 -322.252594)
				)
				(xy 287.430464 -322.253864)
				(arc
					(start 287.83661 -322.253864)
					(mid 288.38525 -321.705224)
					(end 287.83661 -321.156584)
				)
				(xy 286.436816 -321.156584)
			)
		)
	)
	(zone
		(layer "B.Cu")
		(hatch none 0.5)
		(connect_pads
			(clearance 0)
		)
		(min_thickness 0.25)
		(keepout
			(tracks allowed)
			(vias allowed)
			(pads allowed)
			(copperpour allowed)
			(footprints not_allowed)
		)
		(placement
			(enabled no)
			(sheetname "")
		)
		(fill
			(thermal_gap 0.5)
			(thermal_bridge_width 0.5)
			(island_removal_mode 0)
		)
		(polygon
			(pts
				(arc
					(start 163.949888 -164.200078)
					(mid 167.699944 -167.950134)
					(end 171.45 -164.200078)
				)
				(arc
					(start 171.45 -164.200078)
					(mid 167.699944 -160.450022)
					(end 163.949888 -164.200078)
				)
			)
		)
	)
	(zone
		(layer "B.Cu")
		(hatch none 0.5)
		(connect_pads
			(clearance 0)
		)
		(min_thickness 0.25)
		(keepout
			(tracks allowed)
			(vias allowed)
			(pads allowed)
			(copperpour allowed)
			(footprints not_allowed)
		)
		(placement
			(enabled no)
			(sheetname "")
		)
		(fill
			(thermal_gap 0.5)
			(thermal_bridge_width 0.5)
			(island_removal_mode 0)
		)
		(polygon
			(pts
				(arc
					(start 337.674966 -322.799964)
					(mid 330.67498 -315.799978)
					(end 323.674994 -322.799964)
				)
				(arc
					(start 323.674994 -328.799952)
					(mid 330.67498 -335.799938)
					(end 337.674966 -328.799952)
				)
			)
		)
	)
	(zone
		(net "GND")
		(layer "B.Cu")
		(hatch none 0.5)
		(connect_pads
			(clearance 0.5)
		)
		(min_thickness 0.25)
		(fill yes
			(thermal_gap 0.5)
			(thermal_bridge_width 0.5)
			(island_removal_mode 0)
		)
		(polygon
			(pts
				(arc
					(start 63.990474 -258.810252)
					(mid 61.429619 -259.19855)
					(end 59.14898 -257.970782)
				)
				(xy 58.490358 -258.629404) (xy 54.788308 -258.629404) (xy 54.788308 -260.488176) (xy 53.632862 -261.643622)
				(xy 53.632862 -262.052562) (xy 53.223922 -262.052562) (xy 52.07508 -263.201404)
				(arc
					(start 49.222914 -263.201404)
					(mid 51.988551 -266.888397)
					(end 52.445412 -271.474692)
				)
				(arc
					(start 53.537358 -271.474692)
					(mid 54.637348 -270.954622)
					(end 55.841646 -270.781018)
				)
				(arc
					(start 55.841646 -270.781018)
					(mid 55.676838 -267.717957)
					(end 57.603644 -265.331194)
				)
				(arc
					(start 57.603644 -265.331194)
					(mid 62.969319 -262.169321)
					(end 65.236344 -267.97)
				)
				(arc
					(start 65.339468 -267.97)
					(mid 66.632945 -266.621833)
					(end 68.391024 -265.989562)
				)
				(arc
					(start 68.391024 -265.989562)
					(mid 67.638197 -264.677651)
					(end 67.413632 -263.181846)
				)
				(arc
					(start 67.413632 -263.181846)
					(mid 67.46118 -261.372577)
					(end 68.284852 -259.760974)
				)
				(arc
					(start 68.284852 -259.760974)
					(mid 68.071133 -259.503218)
					(end 67.879214 -259.228844)
				)
				(arc
					(start 67.879214 -259.228844)
					(mid 65.881582 -259.514448)
					(end 63.990474 -258.810252)
				)
			)
		)
	)
	(zone
		(layer "B.Cu")
		(hatch none 0.5)
		(connect_pads
			(clearance 0)
		)
		(min_thickness 0.25)
		(keepout
			(tracks not_allowed)
			(vias allowed)
			(pads allowed)
			(copperpour not_allowed)
			(footprints allowed)
		)
		(placement
			(enabled no)
			(sheetname "")
		)
		(fill
			(thermal_gap 0.5)
			(thermal_bridge_width 0.5)
			(island_removal_mode 0)
		)
		(polygon
			(pts
				(arc
					(start 281.074876 -61.849762)
					(mid 281.399742 -60.875164)
					(end 280.425144 -60.550298)
				)
				(xy 280.423874 -60.548012) (xy 278.424132 -61.54801) (xy 278.424132 -61.548264)
				(arc
					(start 278.425148 -61.550296)
					(mid 278.100282 -62.524894)
					(end 279.07488 -62.84976)
				)
				(xy 279.07615 -62.852046)
				(arc
					(start 280.086562 -62.34684)
					(mid 279.982979 -62.285388)
					(end 279.888696 -62.210442)
				)
				(xy 279.887426 -62.210442)
				(arc
					(start 279.654508 -61.977524)
					(mid 279.615468 -61.949038)
					(end 279.569672 -61.933582)
				)
				(xy 279.566116 -61.933074)
				(arc
					(start 279.55113 -61.930534)
					(mid 279.50136 -61.930693)
					(end 279.454102 -61.946282)
				)
				(arc
					(start 279.271984 -62.0395)
					(mid 278.264021 -62.449091)
					(end 279.185116 -61.870082)
				)
				(xy 279.367234 -61.77661) (xy 279.402286 -61.758576)
				(arc
					(start 279.405842 -61.759846)
					(mid 279.4716 -61.742632)
					(end 279.539446 -61.73851)
				)
				(xy 279.542494 -61.736224) (xy 279.58161 -61.742574) (xy 279.596596 -61.745114) (xy 279.601168 -61.745876)
				(xy 279.635966 -61.751464)
				(arc
					(start 279.637744 -61.754004)
					(mid 279.700642 -61.778672)
					(end 279.757632 -61.814964)
				)
				(xy 279.761188 -61.814964) (xy 279.879298 -61.933074)
				(arc
					(start 279.994106 -62.047882)
					(mid 280.143896 -62.161535)
					(end 280.318718 -62.230762)
				)
				(xy 280.481786 -62.149228) (xy 280.445464 -62.149228)
				(arc
					(start 280.44394 -62.147704)
					(mid 280.258325 -62.104068)
					(end 280.096214 -62.003686)
				)
				(xy 280.094182 -62.003686) (xy 280.066242 -61.975746) (xy 279.93721 -61.846714)
				(arc
					(start 279.93721 -61.841888)
					(mid 279.89485 -61.748521)
					(end 279.891236 -61.646054)
				)
				(arc
					(start 279.891236 -61.6458)
					(mid 279.927157 -61.549762)
					(end 279.9969 -61.474604)
				)
				(xy 279.998424 -61.469778)
				(arc
					(start 280.226516 -61.355732)
					(mid 281.237793 -60.954985)
					(end 280.31186 -61.525912)
				)
				(arc
					(start 280.119074 -61.622432)
					(mid 280.092648 -61.644704)
					(end 280.079196 -61.676534)
				)
				(arc
					(start 280.079196 -61.676534)
					(mid 280.081809 -61.710785)
					(end 280.09977 -61.740034)
				)
				(arc
					(start 280.200862 -61.841126)
					(mid 280.331149 -61.928181)
					(end 280.484834 -61.958728)
				)
				(xy 280.862786 -61.958728) (xy 281.076146 -61.852048)
			)
		)
	)
	(zone
		(net "GND")
		(layer "B.Cu")
		(hatch none 0.5)
		(connect_pads
			(clearance 0.5)
		)
		(min_thickness 0.25)
		(fill yes
			(thermal_gap 0.5)
			(thermal_bridge_width 0.5)
			(island_removal_mode 0)
		)
		(polygon
			(pts
				(xy 468.595202 -252.76175) (xy 468.341202 -253.01575) (xy 468.341202 -254.79375) (xy 468.722202 -255.17475)
				(xy 473.929202 -255.17475) (xy 474.183202 -254.92075) (xy 474.183202 -252.88875) (xy 474.056202 -252.76175)
			)
		)
	)
	(zone
		(layer "B.Cu")
		(hatch none 0.5)
		(connect_pads
			(clearance 0)
		)
		(min_thickness 0.25)
		(keepout
			(tracks not_allowed)
			(vias allowed)
			(pads allowed)
			(copperpour not_allowed)
			(footprints allowed)
		)
		(placement
			(enabled no)
			(sheetname "")
		)
		(fill
			(thermal_gap 0.5)
			(thermal_bridge_width 0.5)
			(island_removal_mode 0)
		)
		(polygon
			(pts
				(arc
					(start 279.236678 -331.95641)
					(mid 278.688038 -332.50505)
					(end 279.236678 -333.05369)
				)
				(xy 279.642824 -333.05369) (xy 279.644094 -333.05242)
				(arc
					(start 279.661874 -333.032608)
					(mid 279.700941 -332.96203)
					(end 279.714452 -332.882494)
				)
				(arc
					(start 279.714452 -332.63205)
					(mid 279.699573 -332.596129)
					(end 279.663652 -332.58125)
				)
				(arc
					(start 279.623012 -332.58125)
					(mid 278.842901 -332.50505)
					(end 279.623012 -332.42885)
				)
				(xy 279.695148 -332.42885)
				(arc
					(start 279.698196 -332.431898)
					(mid 279.807273 -332.488429)
					(end 279.863804 -332.597506)
				)
				(xy 279.866852 -332.600554) (xy 279.866852 -332.91399)
				(arc
					(start 279.865582 -332.915514)
					(mid 279.852889 -332.986355)
					(end 279.827482 -333.05369)
				)
				(arc
					(start 279.978358 -333.05369)
					(mid 279.999443 -332.9695)
					(end 280.006552 -332.883002)
				)
				(xy 280.006552 -332.600554)
				(arc
					(start 280.0096 -332.597506)
					(mid 280.066131 -332.488429)
					(end 280.175208 -332.431898)
				)
				(xy 280.178256 -332.42885)
				(arc
					(start 280.250392 -332.42885)
					(mid 281.030503 -332.50505)
					(end 280.250392 -332.58125)
				)
				(arc
					(start 280.209752 -332.58125)
					(mid 280.173831 -332.596129)
					(end 280.158952 -332.63205)
				)
				(xy 280.158952 -332.883002) (xy 280.158952 -332.914498)
				(arc
					(start 280.15819 -332.91526)
					(mid 280.151333 -332.985011)
					(end 280.137362 -333.05369)
				)
				(arc
					(start 280.636726 -333.05369)
					(mid 281.185366 -332.50505)
					(end 280.636726 -331.95641)
				)
				(xy 279.236932 -331.95641)
			)
		)
	)
	(zone
		(layer "B.Cu")
		(hatch none 0.5)
		(connect_pads
			(clearance 0)
		)
		(min_thickness 0.25)
		(keepout
			(tracks not_allowed)
			(vias allowed)
			(pads allowed)
			(copperpour not_allowed)
			(footprints allowed)
		)
		(placement
			(enabled no)
			(sheetname "")
		)
		(fill
			(thermal_gap 0.5)
			(thermal_bridge_width 0.5)
			(island_removal_mode 0)
		)
		(polygon
			(pts
				(arc
					(start 133.09854 -21.950426)
					(mid 132.550027 -21.401532)
					(end 132.00126 -21.950172)
				)
				(arc
					(start 132.00126 -23.35022)
					(mid 132.5499 -23.89886)
					(end 133.09854 -23.35022)
				)
				(arc
					(start 133.09854 -22.895052)
					(mid 133.082639 -22.892373)
					(end 133.066536 -22.891496)
				)
				(arc
					(start 132.71627 -22.891496)
					(mid 132.665981 -22.912327)
					(end 132.64515 -22.962616)
				)
				(arc
					(start 132.64515 -22.968204)
					(mid 132.5499 -23.743932)
					(end 132.45465 -22.968204)
				)
				(xy 132.45465 -22.923246)
				(arc
					(start 132.458206 -22.91969)
					(mid 132.531284 -22.77763)
					(end 132.673344 -22.704552)
				)
				(xy 132.6769 -22.700996) (xy 133.09854 -22.700996) (xy 133.09854 -22.600666) (xy 133.066536 -22.599396)
				(xy 132.6769 -22.599396)
				(arc
					(start 132.673344 -22.59584)
					(mid 132.531284 -22.522762)
					(end 132.458206 -22.380702)
				)
				(xy 132.45465 -22.377146)
				(arc
					(start 132.45465 -22.332188)
					(mid 132.5499 -21.55646)
					(end 132.64515 -22.332188)
				)
				(arc
					(start 132.64515 -22.337776)
					(mid 132.665981 -22.388065)
					(end 132.71627 -22.408896)
				)
				(xy 133.09854 -22.408896)
			)
		)
	)
	(zone
		(layer "B.Cu")
		(hatch none 0.5)
		(connect_pads
			(clearance 0)
		)
		(min_thickness 0.25)
		(keepout
			(tracks not_allowed)
			(vias allowed)
			(pads allowed)
			(copperpour not_allowed)
			(footprints allowed)
		)
		(placement
			(enabled no)
			(sheetname "")
		)
		(fill
			(thermal_gap 0.5)
			(thermal_bridge_width 0.5)
			(island_removal_mode 0)
		)
		(polygon
			(pts
				(arc
					(start 380.898654 -20.950428)
					(mid 380.350141 -20.401534)
					(end 379.801374 -20.950174)
				)
				(arc
					(start 379.801374 -22.350222)
					(mid 380.350014 -22.898862)
					(end 380.898654 -22.350222)
				)
				(xy 380.898654 -21.891752) (xy 380.893066 -21.891498)
				(arc
					(start 380.516384 -21.891498)
					(mid 380.466095 -21.912329)
					(end 380.445264 -21.962618)
				)
				(arc
					(start 380.445264 -21.968206)
					(mid 380.350014 -22.743934)
					(end 380.254764 -21.968206)
				)
				(xy 380.254764 -21.923248)
				(arc
					(start 380.25832 -21.919692)
					(mid 380.331398 -21.777632)
					(end 380.473458 -21.704554)
				)
				(xy 380.477014 -21.700998) (xy 380.898654 -21.700998) (xy 380.898654 -21.599398) (xy 380.893066 -21.599398)
				(xy 380.477014 -21.599398)
				(arc
					(start 380.473458 -21.595842)
					(mid 380.331398 -21.522764)
					(end 380.25832 -21.380704)
				)
				(xy 380.254764 -21.377148)
				(arc
					(start 380.254764 -21.33219)
					(mid 380.350014 -20.556462)
					(end 380.445264 -21.33219)
				)
				(arc
					(start 380.445264 -21.337778)
					(mid 380.466095 -21.388067)
					(end 380.516384 -21.408898)
				)
				(xy 380.898654 -21.408898)
			)
		)
	)
	(zone
		(layer "B.Cu")
		(hatch none 0.5)
		(connect_pads
			(clearance 0)
		)
		(min_thickness 0.25)
		(keepout
			(tracks not_allowed)
			(vias allowed)
			(pads allowed)
			(copperpour not_allowed)
			(footprints allowed)
		)
		(placement
			(enabled no)
			(sheetname "")
		)
		(fill
			(thermal_gap 0.5)
			(thermal_bridge_width 0.5)
			(island_removal_mode 0)
		)
		(polygon
			(pts
				(arc
					(start 468.425022 -9.19988)
					(mid 463.674968 -4.449826)
					(end 458.924914 -9.19988)
				)
				(arc
					(start 458.924914 -9.19988)
					(mid 463.674968 -13.949934)
					(end 468.425022 -9.19988)
				)
			)
		)
	)
	(zone
		(layer "B.Cu")
		(hatch none 0.5)
		(connect_pads
			(clearance 0)
		)
		(min_thickness 0.25)
		(keepout
			(tracks not_allowed)
			(vias allowed)
			(pads allowed)
			(copperpour not_allowed)
			(footprints allowed)
		)
		(placement
			(enabled no)
			(sheetname "")
		)
		(fill
			(thermal_gap 0.5)
			(thermal_bridge_width 0.5)
			(island_removal_mode 0)
		)
		(polygon
			(pts
				(arc
					(start 346.050108 -269.999968)
					(mid 341.300054 -265.249914)
					(end 336.55 -269.999968)
				)
				(arc
					(start 336.55 -269.999968)
					(mid 341.300054 -274.750022)
					(end 346.050108 -269.999968)
				)
			)
		)
	)
	(zone
		(layer "B.Cu")
		(hatch none 0.5)
		(connect_pads
			(clearance 0)
		)
		(min_thickness 0.25)
		(keepout
			(tracks not_allowed)
			(vias allowed)
			(pads allowed)
			(copperpour not_allowed)
			(footprints allowed)
		)
		(placement
			(enabled no)
			(sheetname "")
		)
		(fill
			(thermal_gap 0.5)
			(thermal_bridge_width 0.5)
			(island_removal_mode 0)
		)
		(polygon
			(pts
				(xy 236.347508 -177.77079) (xy 235.88091 -177.76952) (xy 235.724192 -177.847752) (xy 235.724192 -177.848006)
				(arc
					(start 235.725208 -177.850038)
					(mid 235.400342 -178.824636)
					(end 236.37494 -179.149502)
				)
				(xy 236.37621 -179.151788) (xy 238.376206 -178.15179)
				(arc
					(start 238.374936 -178.149504)
					(mid 238.699802 -177.174906)
					(end 237.725204 -176.85004)
				)
				(xy 237.723934 -176.847754)
				(arc
					(start 236.706918 -177.356262)
					(mid 236.735785 -177.369899)
					(end 236.764068 -177.38471)
				)
				(arc
					(start 236.764322 -177.38471)
					(mid 236.840891 -177.432768)
					(end 236.911388 -177.489358)
				)
				(xy 236.912658 -177.489358) (xy 236.940344 -177.517044) (xy 236.940598 -177.517298)
				(arc
					(start 237.145576 -177.722276)
					(mid 237.184616 -177.750762)
					(end 237.230412 -177.766218)
				)
				(arc
					(start 237.248954 -177.769266)
					(mid 237.298724 -177.769107)
					(end 237.345982 -177.753518)
				)
				(arc
					(start 237.5281 -177.6603)
					(mid 238.536063 -177.250709)
					(end 237.614968 -177.829718)
				)
				(xy 237.43285 -177.92319) (xy 237.397798 -177.941224)
				(arc
					(start 237.394242 -177.939954)
					(mid 237.328484 -177.957168)
					(end 237.260638 -177.96129)
				)
				(xy 237.25759 -177.963576) (xy 237.203488 -177.954686) (xy 237.198916 -177.953924) (xy 237.164118 -177.948336)
				(arc
					(start 237.16234 -177.945796)
					(mid 237.099442 -177.921128)
					(end 237.042452 -177.884836)
				)
				(xy 237.038896 -177.884836)
				(arc
					(start 236.805724 -177.651664)
					(mid 236.742709 -177.597042)
					(end 236.672628 -177.551842)
				)
				(arc
					(start 236.672628 -177.551842)
					(mid 236.566911 -177.506639)
					(end 236.454442 -177.482754)
				)
				(xy 236.25937 -177.580036) (xy 236.387386 -177.580544) (xy 236.427772 -177.580544)
				(arc
					(start 236.42955 -177.582322)
					(mid 236.529657 -177.601482)
					(end 236.623606 -177.640996)
				)
				(arc
					(start 236.623606 -177.640996)
					(mid 236.664973 -177.666576)
					(end 236.703616 -177.696114)
				)
				(xy 236.705902 -177.696114) (xy 236.733588 -177.723546) (xy 236.733842 -177.724054) (xy 236.862874 -177.853086)
				(arc
					(start 236.862874 -177.857912)
					(mid 236.905234 -177.951279)
					(end 236.908848 -178.053746)
				)
				(arc
					(start 236.908848 -178.054)
					(mid 236.872927 -178.150038)
					(end 236.803184 -178.225196)
				)
				(xy 236.80166 -178.230022) (xy 236.766354 -178.247548)
				(arc
					(start 236.573568 -178.344068)
					(mid 235.562291 -178.744815)
					(end 236.488224 -178.173888)
				)
				(arc
					(start 236.68101 -178.077368)
					(mid 236.707436 -178.055096)
					(end 236.720888 -178.023266)
				)
				(arc
					(start 236.720888 -178.023266)
					(mid 236.718275 -177.989015)
					(end 236.700314 -177.959766)
				)
				(arc
					(start 236.598714 -177.85842)
					(mid 236.566956 -177.830915)
					(end 236.531658 -177.808128)
				)
				(arc
					(start 236.531658 -177.808128)
					(mid 236.463346 -177.780839)
					(end 236.390434 -177.771044)
				)
				(xy 236.386878 -177.771044) (xy 236.347762 -177.771044)
			)
		)
	)
	(zone
		(net "AGND_P5V_C")
		(layer "B.Cu")
		(hatch none 0.5)
		(connect_pads
			(clearance 0.5)
		)
		(min_thickness 0.25)
		(fill yes
			(thermal_gap 0.5)
			(thermal_bridge_width 0.5)
			(island_removal_mode 0)
		)
		(polygon
			(pts
				(xy 445.100202 -256.580386) (xy 444.753238 -256.92735) (xy 444.744602 -256.92735) (xy 444.744602 -257.866388)
				(xy 444.820802 -257.942588) (xy 447.005202 -257.942588) (xy 447.005202 -257.94335) (xy 447.462402 -257.94335)
				(xy 447.758312 -257.64744) (xy 447.758312 -256.734056) (xy 447.604642 -256.580386)
			)
		)
		(polygon
			(pts
				(xy 447.253614 -257.001264) (xy 447.050414 -257.001264) (xy 447.050414 -257.204464) (xy 447.253614 -257.204464)
			)
		)
	)
	(zone
		(layer "B.Cu")
		(hatch none 0.5)
		(connect_pads
			(clearance 0)
		)
		(min_thickness 0.25)
		(keepout
			(tracks not_allowed)
			(vias allowed)
			(pads allowed)
			(copperpour not_allowed)
			(footprints allowed)
		)
		(placement
			(enabled no)
			(sheetname "")
		)
		(fill
			(thermal_gap 0.5)
			(thermal_bridge_width 0.5)
			(island_removal_mode 0)
		)
		(polygon
			(pts
				(arc
					(start 409.150058 -289.999928)
					(mid 404.400004 -285.249874)
					(end 399.64995 -289.999928)
				)
				(arc
					(start 399.64995 -289.999928)
					(mid 404.400004 -294.749982)
					(end 409.150058 -289.999928)
				)
			)
		)
	)
	(zone
		(layer "B.Cu")
		(hatch none 0.5)
		(connect_pads
			(clearance 0)
		)
		(min_thickness 0.25)
		(keepout
			(tracks allowed)
			(vias allowed)
			(pads allowed)
			(copperpour allowed)
			(footprints not_allowed)
		)
		(placement
			(enabled no)
			(sheetname "")
		)
		(fill
			(thermal_gap 0.5)
			(thermal_bridge_width 0.5)
			(island_removal_mode 0)
		)
		(polygon
			(pts
				(arc
					(start 367.849912 -220.199966)
					(mid 371.599968 -223.950022)
					(end 375.350024 -220.199966)
				)
				(arc
					(start 375.350024 -220.199966)
					(mid 371.599968 -216.44991)
					(end 367.849912 -220.199966)
				)
			)
		)
	)
	(zone
		(layer "B.Cu")
		(hatch none 0.5)
		(connect_pads
			(clearance 0)
		)
		(min_thickness 0.25)
		(keepout
			(tracks not_allowed)
			(vias allowed)
			(pads allowed)
			(copperpour not_allowed)
			(footprints allowed)
		)
		(placement
			(enabled no)
			(sheetname "")
		)
		(fill
			(thermal_gap 0.5)
			(thermal_bridge_width 0.5)
			(island_removal_mode 0)
		)
		(polygon
			(pts
				(arc
					(start 388.21995 -162.178746)
					(mid 387.839077 -161.797492)
					(end 387.45795 -162.178492)
				)
				(xy 387.45795 -162.527742)
				(arc
					(start 387.662166 -162.527742)
					(mid 387.730822 -162.500667)
					(end 387.762496 -162.434016)
				)
				(arc
					(start 387.762496 -162.434016)
					(mid 387.839072 -161.911775)
					(end 387.91515 -162.434016)
				)
				(xy 387.91515 -162.458654)
				(arc
					(start 387.912864 -162.46094)
					(mid 387.841038 -162.60603)
					(end 387.695948 -162.677856)
				)
				(xy 387.693662 -162.680142) (xy 387.45795 -162.680142) (xy 387.45795 -162.819842) (xy 387.693662 -162.819842)
				(arc
					(start 387.695948 -162.822128)
					(mid 387.841038 -162.893954)
					(end 387.912864 -163.039044)
				)
				(xy 387.91515 -163.04133)
				(arc
					(start 387.91515 -163.065968)
					(mid 387.839072 -163.588136)
					(end 387.762496 -163.065968)
				)
				(arc
					(start 387.762496 -163.065968)
					(mid 387.730808 -162.999332)
					(end 387.662166 -162.972242)
				)
				(xy 387.45795 -162.972242)
				(arc
					(start 387.45795 -163.321492)
					(mid 387.83895 -163.702492)
					(end 388.21995 -163.321492)
				)
			)
		)
	)
	(zone
		(layer "B.Cu")
		(hatch none 0.5)
		(connect_pads
			(clearance 0)
		)
		(min_thickness 0.25)
		(keepout
			(tracks allowed)
			(vias allowed)
			(pads allowed)
			(copperpour allowed)
			(footprints not_allowed)
		)
		(placement
			(enabled no)
			(sheetname "")
		)
		(fill
			(thermal_gap 0.5)
			(thermal_bridge_width 0.5)
			(island_removal_mode 0)
		)
		(polygon
			(pts
				(arc
					(start 0.999998 0)
					(mid 0.292893 -0.292893)
					(end 0 -0.999998)
				)
				(xy 0 -209.199988) (xy 13.850112 -209.199988) (xy 13.850112 0)
			)
		)
	)
	(zone
		(layer "B.Cu")
		(hatch none 0.5)
		(connect_pads
			(clearance 0)
		)
		(min_thickness 0.25)
		(keepout
			(tracks allowed)
			(vias allowed)
			(pads allowed)
			(copperpour allowed)
			(footprints not_allowed)
		)
		(placement
			(enabled no)
			(sheetname "")
		)
		(fill
			(thermal_gap 0.5)
			(thermal_bridge_width 0.5)
			(island_removal_mode 0)
		)
		(polygon
			(pts
				(arc
					(start 19.225006 -13.200126)
					(mid 20.32508 -14.3002)
					(end 21.4249 -13.200126)
				)
				(arc
					(start 21.4249 -13.200126)
					(mid 20.32508 -12.100306)
					(end 19.225006 -13.200126)
				)
			)
		)
	)
	(zone
		(layer "B.Cu")
		(hatch none 0.5)
		(connect_pads
			(clearance 0)
		)
		(min_thickness 0.25)
		(keepout
			(tracks allowed)
			(vias allowed)
			(pads allowed)
			(copperpour allowed)
			(footprints not_allowed)
		)
		(placement
			(enabled no)
			(sheetname "")
		)
		(fill
			(thermal_gap 0.5)
			(thermal_bridge_width 0.5)
			(island_removal_mode 0)
		)
		(polygon
			(pts
				(arc
					(start 159.22498 -13.200126)
					(mid 160.325054 -14.3002)
					(end 161.424874 -13.200126)
				)
				(arc
					(start 161.424874 -13.200126)
					(mid 160.325054 -12.100306)
					(end 159.22498 -13.200126)
				)
			)
		)
	)
	(zone
		(layer "B.Cu")
		(hatch none 0.5)
		(connect_pads
			(clearance 0)
		)
		(min_thickness 0.25)
		(keepout
			(tracks allowed)
			(vias allowed)
			(pads allowed)
			(copperpour allowed)
			(footprints not_allowed)
		)
		(placement
			(enabled no)
			(sheetname "")
		)
		(fill
			(thermal_gap 0.5)
			(thermal_bridge_width 0.5)
			(island_removal_mode 0)
		)
		(polygon
			(pts
				(arc
					(start 124.875036 -28.079954)
					(mid 126.150116 -29.355034)
					(end 127.424942 -28.079954)
				)
				(arc
					(start 127.424942 -28.079954)
					(mid 126.150116 -26.805128)
					(end 124.875036 -28.079954)
				)
			)
		)
	)
	(zone
		(layer "B.Cu")
		(hatch none 0.5)
		(connect_pads
			(clearance 0)
		)
		(min_thickness 0.25)
		(keepout
			(tracks not_allowed)
			(vias allowed)
			(pads allowed)
			(copperpour not_allowed)
			(footprints allowed)
		)
		(placement
			(enabled no)
			(sheetname "")
		)
		(fill
			(thermal_gap 0.5)
			(thermal_bridge_width 0.5)
			(island_removal_mode 0)
		)
		(polygon
			(pts
				(arc
					(start 271.970754 -312.321448)
					(mid 271.58696 -312.704861)
					(end 271.9705 -313.088528)
				)
				(arc
					(start 273.1135 -313.088528)
					(mid 273.49704 -312.704988)
					(end 273.1135 -312.321448)
				)
				(arc
					(start 272.768568 -312.321448)
					(mid 272.765366 -312.348288)
					(end 272.76425 -312.375296)
				)
				(arc
					(start 272.76425 -312.523886)
					(mid 272.791127 -312.594004)
					(end 272.857976 -312.62828)
				)
				(arc
					(start 272.857976 -312.62828)
					(mid 273.380217 -312.704734)
					(end 272.857976 -312.781188)
				)
				(xy 272.837656 -312.781188)
				(arc
					(start 272.83537 -312.778902)
					(mid 272.687253 -312.705785)
					(end 272.614136 -312.557668)
				)
				(xy 272.61185 -312.555382) (xy 272.61185 -312.3438) (xy 272.612866 -312.342784) (xy 272.614644 -312.321448)
				(arc
					(start 272.474436 -312.321448)
					(mid 272.472724 -312.348348)
					(end 272.47215 -312.375296)
				)
				(xy 272.47215 -312.555382)
				(arc
					(start 272.469864 -312.557668)
					(mid 272.396747 -312.705785)
					(end 272.24863 -312.778902)
				)
				(xy 272.246344 -312.781188)
				(arc
					(start 272.226024 -312.781188)
					(mid 271.703783 -312.704734)
					(end 272.226024 -312.62828)
				)
				(arc
					(start 272.226024 -312.62828)
					(mid 272.292939 -312.594063)
					(end 272.31975 -312.523886)
				)
				(xy 272.31975 -312.3438) (xy 272.320512 -312.343038) (xy 272.321528 -312.321448)
			)
		)
	)
	(zone
		(net "GND")
		(layer "B.Cu")
		(hatch none 0.5)
		(connect_pads
			(clearance 0.5)
		)
		(min_thickness 0.25)
		(fill yes
			(thermal_gap 0.5)
			(thermal_bridge_width 0.5)
			(island_removal_mode 0)
		)
		(polygon
			(pts
				(arc
					(start 150.13686 -155.794202)
					(mid 149.655756 -155.706456)
					(end 149.167596 -155.677108)
				)
				(xy 131.2418 -155.677108)
				(arc
					(start 128.403604 -152.838912)
					(mid 128.774866 -151.660448)
					(end 128.777238 -150.424896)
				)
				(arc
					(start 129.225802 -149.976332)
					(mid 132.524355 -150.485506)
					(end 135.104124 -148.36775)
				)
				(arc
					(start 135.104124 -148.36775)
					(mid 135.695913 -148.13422)
					(end 136.24433 -147.811744)
				)
				(arc
					(start 136.24433 -147.811744)
					(mid 137.209944 -147.534114)
					(end 138.078718 -147.029424)
				)
				(arc
					(start 138.078718 -147.029424)
					(mid 138.479828 -147.567908)
					(end 138.963654 -148.033486)
				)
				(arc
					(start 138.963654 -148.033486)
					(mid 140.73216 -150.185187)
					(end 143.468344 -150.70582)
				)
				(arc
					(start 143.468344 -150.70582)
					(mid 144.074988 -150.766981)
					(end 144.683988 -150.737316)
				)
				(arc
					(start 144.683988 -150.737316)
					(mid 145.196261 -150.762098)
					(end 145.707608 -150.722584)
				)
				(arc
					(start 145.707608 -150.722584)
					(mid 145.977144 -150.749447)
					(end 146.247866 -150.758398)
				)
				(arc
					(start 150.565866 -150.758398)
					(mid 151.280558 -150.695485)
					(end 151.97328 -150.508716)
				)
				(arc
					(start 151.97328 -150.508716)
					(mid 150.279016 -152.876923)
					(end 150.491698 -155.780994)
				)
				(arc
					(start 150.491698 -155.780994)
					(mid 150.314136 -155.783746)
					(end 150.13686 -155.794202)
				)
			)
		)
	)
	(zone
		(net "GND")
		(layer "B.Cu")
		(hatch none 0.5)
		(connect_pads
			(clearance 0.5)
		)
		(min_thickness 0.25)
		(fill yes
			(thermal_gap 0.5)
			(thermal_bridge_width 0.5)
			(island_removal_mode 0)
		)
		(polygon
			(pts
				(xy 426.90034 -151.565356) (xy 435.897782 -142.568168) (xy 454.928478 -142.568168)
				(arc
					(start 462.32191 -149.9616)
					(mid 462.820034 -150.566371)
					(end 463.192876 -151.255476)
				)
				(arc
					(start 463.192876 -151.255476)
					(mid 463.483709 -151.223894)
					(end 463.77606 -151.213312)
				)
				(arc
					(start 464.559904 -151.213312)
					(mid 467.502249 -149.885289)
					(end 470.491312 -151.1046)
				)
				(xy 473.5068 -151.1046) (xy 474.986604 -149.624796) (xy 474.986604 -148.673058) (xy 481.803964 -141.855444)
				(arc
					(start 481.803964 -128.049528)
					(mid 479.942393 -127.956163)
					(end 478.16008 -127.410718)
				)
				(arc
					(start 477.20123 -127.410718)
					(mid 476.978349 -131.361435)
					(end 473.514928 -133.275324)
				)
				(arc
					(start 473.306902 -133.275324)
					(mid 471.133542 -135.243006)
					(end 468.201756 -135.250936)
				)
				(arc
					(start 468.147908 -135.243062)
					(mid 466.191022 -135.811976)
					(end 464.202526 -135.365998)
				)
				(arc
					(start 464.202526 -135.365998)
					(mid 461.276065 -130.099624)
					(end 466.771736 -127.630428)
				)
				(arc
					(start 466.771736 -127.630428)
					(mid 467.712777 -127.24853)
					(end 468.7189 -127.110236)
				)
				(arc
					(start 468.7189 -127.110236)
					(mid 470.213894 -125.633248)
					(end 472.244928 -125.093476)
				)
				(arc
					(start 473.515436 -125.093476)
					(mid 473.957963 -125.117481)
					(end 474.395292 -125.189234)
				)
				(arc
					(start 474.395292 -123.71197)
					(mid 475.014719 -116.207361)
					(end 481.803964 -112.950244)
				)
				(arc
					(start 481.803964 -82.090006)
					(mid 481.445833 -81.447467)
					(end 481.208588 -80.751172)
				)
				(arc
					(start 481.208588 -80.751172)
					(mid 480.177196 -80.00269)
					(end 479.398076 -78.994254)
				)
				(arc
					(start 479.398076 -78.994254)
					(mid 474.585119 -77.764028)
					(end 474.509084 -72.796908)
				)
				(arc
					(start 474.509084 -72.796908)
					(mid 474.551911 -67.793093)
					(end 479.405442 -66.575432)
				)
				(arc
					(start 479.405442 -66.575432)
					(mid 479.705146 -65.689602)
					(end 480.198176 -64.894968)
				)
				(arc
					(start 480.198176 -64.894968)
					(mid 479.541362 -63.699709)
					(end 479.314002 -62.354968)
				)
				(arc
					(start 479.314002 -59.814968)
					(mid 479.384331 -59.05967)
					(end 479.592894 -58.330338)
				)
				(arc
					(start 479.592894 -58.330338)
					(mid 478.554832 -56.960099)
					(end 478.171256 -55.28437)
				)
				(arc
					(start 478.171256 -55.28437)
					(mid 477.93101 -55.30569)
					(end 477.689926 -55.312818)
				)
				(arc
					(start 475.358714 -55.312818)
					(mid 475.273752 -55.543671)
					(end 475.175072 -55.769002)
				)
				(arc
					(start 475.175072 -55.769002)
					(mid 477.506411 -57.979011)
					(end 477.52254 -61.191394)
				)
				(arc
					(start 477.52254 -61.191394)
					(mid 476.350847 -65.938158)
					(end 471.46718 -66.17081)
				)
				(arc
					(start 471.46718 -66.17081)
					(mid 469.054393 -68.527855)
					(end 465.69122 -68.270628)
				)
				(arc
					(start 463.909918 -68.270628)
					(mid 463.046678 -69.902887)
					(end 461.55356 -70.98919)
				)
				(arc
					(start 461.55356 -72.465946)
					(mid 463.680585 -77.065856)
					(end 459.7019 -80.204818)
				)
				(arc
					(start 457.701396 -80.204818)
					(mid 457.494859 -81.131897)
					(end 457.080112 -81.986374)
				)
				(arc
					(start 457.080112 -81.986374)
					(mid 464.468594 -85.292824)
					(end 467.496144 -92.799916)
				)
				(arc
					(start 467.496144 -98.794316)
					(mid 456.674982 -109.615478)
					(end 445.85382 -98.794316)
				)
				(arc
					(start 445.85382 -92.799916)
					(mid 447.377227 -87.263735)
					(end 451.518528 -83.286346)
				)
				(arc
					(start 451.518528 -83.286346)
					(mid 450.335164 -82.204639)
					(end 449.658486 -80.751172)
				)
				(arc
					(start 449.658486 -80.751172)
					(mid 447.273872 -77.049356)
					(end 449.206112 -73.092564)
				)
				(arc
					(start 449.206112 -73.092564)
					(mid 448.21664 -71.845583)
					(end 447.778124 -70.315328)
				)
				(arc
					(start 446.652142 -70.315328)
					(mid 441.153239 -70.360711)
					(end 440.579002 -64.891666)
				)
				(arc
					(start 440.579002 -64.891666)
					(mid 440.442785 -64.736256)
					(end 440.314588 -64.574166)
				)
				(xy 434.926232 -67.04838) (xy 434.926232 -67.702176)
				(arc
					(start 432.36642 -68.24599)
					(mid 431.769125 -69.551755)
					(end 430.75733 -70.570598)
				)
				(arc
					(start 430.75733 -72.959722)
					(mid 432.001727 -77.498192)
					(end 428.152052 -80.204818)
				)
				(arc
					(start 426.151548 -80.204818)
					(mid 422.360189 -83.86573)
					(end 418.108638 -80.751172)
				)
				(arc
					(start 418.108638 -80.751172)
					(mid 415.762348 -77.426457)
					(end 417.071048 -73.573386)
				)
				(arc
					(start 417.071048 -73.573386)
					(mid 416.897061 -73.418072)
					(end 416.732212 -73.253092)
				)
				(arc
					(start 400.055334 -84.06003)
					(mid 403.322205 -87.898243)
					(end 404.496016 -92.799916)
				)
				(arc
					(start 404.496016 -98.794316)
					(mid 403.296579 -103.746141)
					(end 399.964148 -107.600242)
				)
				(arc
					(start 399.964148 -107.600242)
					(mid 402.239876 -112.784836)
					(end 397.154908 -115.27536)
				)
				(arc
					(start 355.650292 -115.27536)
					(mid 355.403713 -115.34564)
					(end 355.153214 -115.400328)
				)
				(arc
					(start 348.343982 -125.2982)
					(mid 350.315421 -127.159259)
					(end 350.69018 -129.844292)
				)
				(xy 354.170234 -129.844292) (xy 354.845112 -130.518916)
				(arc
					(start 356.040436 -130.518916)
					(mid 356.206695 -130.323652)
					(end 356.38486 -130.139186)
				)
				(arc
					(start 356.38486 -130.139186)
					(mid 358.617027 -127.592421)
					(end 362.003594 -127.600964)
				)
				(arc
					(start 362.003594 -127.600964)
					(mid 363.036964 -127.005555)
					(end 364.198154 -126.733554)
				)
				(arc
					(start 364.198154 -126.733554)
					(mid 365.153191 -123.115019)
					(end 368.652552 -121.788174)
				)
				(arc
					(start 368.652552 -121.788174)
					(mid 371.165528 -120.555161)
					(end 373.88292 -121.226834)
				)
				(arc
					(start 373.88292 -121.226834)
					(mid 378.565227 -120.963504)
					(end 380.41707 -125.272038)
				)
				(arc
					(start 380.41707 -125.272038)
					(mid 381.606566 -126.020686)
					(end 382.472438 -127.127762)
				)
				(arc
					(start 382.472438 -127.127762)
					(mid 384.924487 -127.259474)
					(end 386.859272 -128.77165)
				)
				(arc
					(start 386.859272 -128.77165)
					(mid 388.392743 -131.365008)
					(end 387.734302 -134.30504)
				)
				(arc
					(start 391.872216 -134.30504)
					(mid 393.197334 -134.085873)
					(end 394.522452 -134.30504)
				)
				(arc
					(start 397.154908 -134.30504)
					(mid 398.097189 -134.122393)
					(end 399.056098 -134.164324)
				)
				(arc
					(start 399.056098 -134.164324)
					(mid 398.762177 -129.042443)
					(end 403.703536 -127.662432)
				)
				(arc
					(start 403.703536 -127.662432)
					(mid 404.61993 -127.2872)
					(end 405.599646 -127.143256)
				)
				(arc
					(start 405.599646 -127.143256)
					(mid 407.097359 -125.642804)
					(end 409.144978 -125.093476)
				)
				(arc
					(start 410.414978 -125.093476)
					(mid 414.505902 -129.1844)
					(end 410.414978 -133.275324)
				)
				(arc
					(start 410.254704 -133.275324)
					(mid 408.082007 -135.268502)
					(end 405.133556 -135.28294)
				)
				(arc
					(start 405.079708 -135.275066)
					(mid 403.34216 -135.83124)
					(end 401.535646 -135.576564)
				)
				(arc
					(start 401.535646 -135.576564)
					(mid 402.387994 -137.297458)
					(end 402.360892 -139.217654)
				)
				(arc
					(start 402.360892 -139.217654)
					(mid 400.782299 -142.548196)
					(end 397.165322 -143.256508)
				)
				(arc
					(start 396.119604 -143.256508)
					(mid 394.922502 -143.434461)
					(end 393.7254 -143.256508)
				)
				(arc
					(start 386.620258 -143.256508)
					(mid 384.966544 -144.416507)
					(end 382.959356 -144.643602)
				)
				(arc
					(start 382.959356 -144.643602)
					(mid 381.512448 -145.946021)
					(end 379.627384 -146.43227)
				)
				(arc
					(start 379.627384 -146.43227)
					(mid 378.706935 -149.74093)
					(end 375.5898 -151.182324)
				)
				(arc
					(start 375.316496 -151.182324)
					(mid 375.238809 -151.28351)
					(end 375.158 -151.382222)
				)
				(xy 375.158 -151.6634) (xy 375.745756 -152.251156)
				(arc
					(start 384.758692 -152.251156)
					(mid 385.48225 -151.155816)
					(end 386.503672 -150.33117)
				)
				(arc
					(start 386.503672 -150.33117)
					(mid 390.945295 -146.965636)
					(end 394.621258 -151.153876)
				)
				(arc
					(start 395.25067 -151.153876)
					(mid 396.743977 -151.438138)
					(end 398.028414 -152.251156)
				)
				(arc
					(start 416.308794 -152.251156)
					(mid 417.032352 -151.155816)
					(end 418.053774 -150.33117)
				)
				(arc
					(start 418.053774 -150.33117)
					(mid 422.70021 -146.99142)
					(end 426.138594 -151.565356)
				)
			)
		)
		(polygon
			(pts
				(arc
					(start 436.175404 -135.471916)
					(mid 439.612549 -135.733317)
					(end 442.02985 -133.275832)
				)
				(arc
					(start 442.02985 -133.275832)
					(mid 446.041704 -128.833532)
					(end 441.329826 -125.14199)
				)
				(arc
					(start 441.329826 -125.14199)
					(mid 438.962528 -125.477184)
					(end 437.186578 -127.077978)
				)
				(arc
					(start 437.186578 -127.077978)
					(mid 436.220815 -127.224807)
					(end 435.317392 -127.596392)
				)
				(arc
					(start 435.317392 -127.596392)
					(mid 429.819995 -130.067219)
					(end 432.747928 -135.335264)
				)
				(arc
					(start 432.747928 -135.335264)
					(mid 434.446662 -135.780104)
					(end 436.175404 -135.471916)
				)
			)
		)
	)
	(zone
		(net "GND")
		(layer "B.Cu")
		(hatch none 0.5)
		(connect_pads
			(clearance 0.5)
		)
		(min_thickness 0.25)
		(fill yes
			(thermal_gap 0.5)
			(thermal_bridge_width 0.5)
			(island_removal_mode 0)
		)
		(polygon
			(pts
				(arc
					(start 65.865248 -52.979574)
					(mid 67.513672 -51.480375)
					(end 68.124324 -49.337468)
				)
				(arc
					(start 68.124324 -46.162468)
					(mid 68.096822 -45.689879)
					(end 68.014596 -45.223684)
				)
				(arc
					(start 72.53986 -45.223684)
					(mid 73.291791 -48.026167)
					(end 75.713336 -49.624742)
				)
				(arc
					(start 75.713336 -49.624742)
					(mid 75.428418 -50.65263)
					(end 75.41895 -51.719226)
				)
				(arc
					(start 75.41895 -51.719226)
					(mid 71.697046 -55.976575)
					(end 75.783948 -59.884818)
				)
				(arc
					(start 77.672438 -59.884818)
					(mid 77.773891 -60.550954)
					(end 77.983334 -61.191394)
				)
				(arc
					(start 77.942694 -61.291978)
					(mid 74.48068 -60.766481)
					(end 71.88073 -63.112142)
				)
				(arc
					(start 71.88073 -63.112142)
					(mid 71.831908 -62.353419)
					(end 71.643494 -61.616844)
				)
				(arc
					(start 71.643494 -61.616844)
					(mid 71.04655 -57.760943)
					(end 67.488308 -56.160162)
				)
				(xy 67.488308 -54.602888)
			)
		)
	)
	(zone
		(layer "B.Cu")
		(hatch none 0.5)
		(connect_pads
			(clearance 0)
		)
		(min_thickness 0.25)
		(keepout
			(tracks allowed)
			(vias allowed)
			(pads allowed)
			(copperpour allowed)
			(footprints allowed)
		)
		(placement
			(enabled no)
			(sheetname "")
		)
		(fill
			(thermal_gap 0.5)
			(thermal_bridge_width 0.5)
			(island_removal_mode 0)
		)
		(polygon
			(pts
				(xy 221.247208 -118.265702) (xy 221.247208 -121.271538) (xy 219.249498 -121.271538) (xy 219.249498 -118.265702)
			)
		)
	)
	(zone
		(layer "B.Cu")
		(hatch none 0.5)
		(connect_pads
			(clearance 0)
		)
		(min_thickness 0.25)
		(keepout
			(tracks not_allowed)
			(vias allowed)
			(pads allowed)
			(copperpour not_allowed)
			(footprints allowed)
		)
		(placement
			(enabled no)
			(sheetname "")
		)
		(fill
			(thermal_gap 0.5)
			(thermal_bridge_width 0.5)
			(island_removal_mode 0)
		)
		(polygon
			(pts
				(arc
					(start 109.698536 -20.950428)
					(mid 109.150023 -20.401534)
					(end 108.601256 -20.950174)
				)
				(xy 108.601256 -21.408898)
				(arc
					(start 108.983526 -21.408898)
					(mid 109.033815 -21.388067)
					(end 109.054646 -21.337778)
				)
				(arc
					(start 109.054646 -21.33219)
					(mid 109.149896 -20.556462)
					(end 109.245146 -21.33219)
				)
				(xy 109.245146 -21.377148)
				(arc
					(start 109.24159 -21.380704)
					(mid 109.168512 -21.522764)
					(end 109.026452 -21.595842)
				)
				(xy 109.022896 -21.599398) (xy 108.63326 -21.599398) (xy 108.601256 -21.60016) (xy 108.601256 -21.700998)
				(xy 109.022896 -21.700998)
				(arc
					(start 109.026452 -21.704554)
					(mid 109.168512 -21.777632)
					(end 109.24159 -21.919692)
				)
				(xy 109.245146 -21.923248)
				(arc
					(start 109.245146 -21.968206)
					(mid 109.149896 -22.743934)
					(end 109.054646 -21.968206)
				)
				(arc
					(start 109.054646 -21.962618)
					(mid 109.033815 -21.912329)
					(end 108.983526 -21.891498)
				)
				(xy 108.63326 -21.891498) (xy 108.601256 -21.892768)
				(arc
					(start 108.601256 -22.350222)
					(mid 109.149896 -22.898862)
					(end 109.698536 -22.350222)
				)
			)
		)
	)
	(zone
		(layer "B.Cu")
		(hatch none 0.5)
		(connect_pads
			(clearance 0)
		)
		(min_thickness 0.25)
		(keepout
			(tracks allowed)
			(vias allowed)
			(pads allowed)
			(copperpour allowed)
			(footprints not_allowed)
		)
		(placement
			(enabled no)
			(sheetname "")
		)
		(fill
			(thermal_gap 0.5)
			(thermal_bridge_width 0.5)
			(island_removal_mode 0)
		)
		(polygon
			(pts
				(arc
					(start 400.675094 -322.799964)
					(mid 393.675108 -315.799978)
					(end 386.675122 -322.799964)
				)
				(arc
					(start 386.675122 -328.799952)
					(mid 393.675108 -335.799938)
					(end 400.675094 -328.799952)
				)
			)
		)
	)
	(zone
		(layer "B.Cu")
		(hatch none 0.5)
		(connect_pads
			(clearance 0)
		)
		(min_thickness 0.25)
		(keepout
			(tracks not_allowed)
			(vias allowed)
			(pads allowed)
			(copperpour not_allowed)
			(footprints allowed)
		)
		(placement
			(enabled no)
			(sheetname "")
		)
		(fill
			(thermal_gap 0.5)
			(thermal_bridge_width 0.5)
			(island_removal_mode 0)
		)
		(polygon
			(pts
				(arc
					(start 278.23668 -308.556406)
					(mid 277.68804 -309.105046)
					(end 278.23668 -309.653686)
				)
				(xy 278.642826 -309.653686) (xy 278.644096 -309.652416)
				(arc
					(start 278.661876 -309.632604)
					(mid 278.700943 -309.562026)
					(end 278.714454 -309.48249)
				)
				(arc
					(start 278.714454 -309.232046)
					(mid 278.699575 -309.196125)
					(end 278.663654 -309.181246)
				)
				(arc
					(start 278.623014 -309.181246)
					(mid 277.842903 -309.105046)
					(end 278.623014 -309.028846)
				)
				(xy 278.69515 -309.028846)
				(arc
					(start 278.698198 -309.031894)
					(mid 278.807275 -309.088425)
					(end 278.863806 -309.197502)
				)
				(xy 278.866854 -309.20055) (xy 278.866854 -309.513986)
				(arc
					(start 278.865584 -309.51551)
					(mid 278.852891 -309.586351)
					(end 278.827484 -309.653686)
				)
				(arc
					(start 278.97836 -309.653686)
					(mid 278.999445 -309.569496)
					(end 279.006554 -309.482998)
				)
				(xy 279.006554 -309.20055)
				(arc
					(start 279.009602 -309.197502)
					(mid 279.066133 -309.088425)
					(end 279.17521 -309.031894)
				)
				(xy 279.178258 -309.028846)
				(arc
					(start 279.250394 -309.028846)
					(mid 280.030505 -309.105046)
					(end 279.250394 -309.181246)
				)
				(arc
					(start 279.209754 -309.181246)
					(mid 279.173833 -309.196125)
					(end 279.158954 -309.232046)
				)
				(xy 279.158954 -309.482998) (xy 279.158954 -309.514494)
				(arc
					(start 279.158192 -309.515256)
					(mid 279.151335 -309.585007)
					(end 279.137364 -309.653686)
				)
				(arc
					(start 279.636728 -309.653686)
					(mid 280.185368 -309.105046)
					(end 279.636728 -308.556406)
				)
				(xy 278.236934 -308.556406)
			)
		)
	)
	(zone
		(layer "B.Cu")
		(hatch none 0.5)
		(connect_pads
			(clearance 0)
		)
		(min_thickness 0.25)
		(keepout
			(tracks allowed)
			(vias allowed)
			(pads allowed)
			(copperpour allowed)
			(footprints allowed)
		)
		(placement
			(enabled no)
			(sheetname "")
		)
		(fill
			(thermal_gap 0.5)
			(thermal_bridge_width 0.5)
			(island_removal_mode 0)
		)
		(polygon
			(pts
				(xy 448.2846 -252.095) (xy 448.2846 -254.889) (xy 451.0278 -254.889) (xy 451.0278 -252.095)
			)
		)
	)
	(zone
		(layer "B.Cu")
		(hatch none 0.5)
		(connect_pads
			(clearance 0)
		)
		(min_thickness 0.25)
		(keepout
			(tracks not_allowed)
			(vias allowed)
			(pads allowed)
			(copperpour not_allowed)
			(footprints allowed)
		)
		(placement
			(enabled no)
			(sheetname "")
		)
		(fill
			(thermal_gap 0.5)
			(thermal_bridge_width 0.5)
			(island_removal_mode 0)
		)
		(polygon
			(pts
				(arc
					(start 463.674968 -322.799964)
					(mid 456.674982 -315.799978)
					(end 449.674996 -322.799964)
				)
				(arc
					(start 449.674996 -328.799952)
					(mid 456.674982 -335.799938)
					(end 463.674968 -328.799952)
				)
			)
		)
	)
	(zone
		(layer "B.Cu")
		(hatch none 0.5)
		(connect_pads
			(clearance 0)
		)
		(min_thickness 0.25)
		(keepout
			(tracks allowed)
			(vias allowed)
			(pads allowed)
			(copperpour allowed)
			(footprints not_allowed)
		)
		(placement
			(enabled no)
			(sheetname "")
		)
		(fill
			(thermal_gap 0.5)
			(thermal_bridge_width 0.5)
			(island_removal_mode 0)
		)
		(polygon
			(pts
				(arc
					(start 89.324942 -213.799928)
					(mid 93.499178 -220.204473)
					(end 101.04374 -218.970606)
				)
				(arc
					(start 101.04374 -218.970606)
					(mid 127.825209 -238.800094)
					(end 154.606498 -218.970606)
				)
				(arc
					(start 154.606498 -218.970606)
					(mid 162.15088 -220.204256)
					(end 166.325042 -213.799928)
				)
				(arc
					(start 166.325042 -207.79994)
					(mid 162.150738 -201.395873)
					(end 154.606498 -202.629516)
				)
				(arc
					(start 154.606498 -202.629516)
					(mid 127.825209 -182.800091)
					(end 101.04374 -202.629516)
				)
				(arc
					(start 101.04374 -202.629516)
					(mid 93.499275 -201.395554)
					(end 89.324942 -207.79994)
				)
			)
		)
	)
	(zone
		(net "GND")
		(layer "B.Cu")
		(hatch none 0.5)
		(connect_pads
			(clearance 0.5)
		)
		(min_thickness 0.25)
		(fill yes
			(thermal_gap 0.5)
			(thermal_bridge_width 0.5)
			(island_removal_mode 0)
		)
		(polygon
			(pts
				(xy 63.521082 -133.979158) (xy 63.201804 -134.298436) (xy 63.201804 -137.233152) (xy 63.693802 -137.72515)
				(xy 67.249802 -137.72515) (xy 67.884802 -137.09015) (xy 67.884802 -134.66318) (xy 67.884548 -134.662672)
				(xy 67.884548 -134.295642) (xy 67.568064 -133.979158)
			)
		)
	)
	(zone
		(layer "B.Cu")
		(hatch none 0.5)
		(connect_pads
			(clearance 0)
		)
		(min_thickness 0.25)
		(keepout
			(tracks not_allowed)
			(vias allowed)
			(pads allowed)
			(copperpour not_allowed)
			(footprints allowed)
		)
		(placement
			(enabled no)
			(sheetname "")
		)
		(fill
			(thermal_gap 0.5)
			(thermal_bridge_width 0.5)
			(island_removal_mode 0)
		)
		(polygon
			(pts
				(arc
					(start 271.970754 -306.921408)
					(mid 271.58696 -307.304821)
					(end 271.9705 -307.688488)
				)
				(arc
					(start 273.1135 -307.688488)
					(mid 273.49704 -307.304948)
					(end 273.1135 -306.921408)
				)
				(arc
					(start 272.768568 -306.921408)
					(mid 272.765366 -306.948248)
					(end 272.76425 -306.975256)
				)
				(arc
					(start 272.76425 -307.123846)
					(mid 272.791127 -307.193964)
					(end 272.857976 -307.22824)
				)
				(arc
					(start 272.857976 -307.22824)
					(mid 273.380217 -307.304694)
					(end 272.857976 -307.381148)
				)
				(xy 272.837656 -307.381148)
				(arc
					(start 272.83537 -307.378862)
					(mid 272.687253 -307.305745)
					(end 272.614136 -307.157628)
				)
				(xy 272.61185 -307.155342) (xy 272.61185 -306.94376) (xy 272.612866 -306.942744) (xy 272.614644 -306.921408)
				(arc
					(start 272.474436 -306.921408)
					(mid 272.472724 -306.948308)
					(end 272.47215 -306.975256)
				)
				(xy 272.47215 -307.155342)
				(arc
					(start 272.469864 -307.157628)
					(mid 272.396747 -307.305745)
					(end 272.24863 -307.378862)
				)
				(xy 272.246344 -307.381148)
				(arc
					(start 272.226024 -307.381148)
					(mid 271.703783 -307.304694)
					(end 272.226024 -307.22824)
				)
				(arc
					(start 272.226024 -307.22824)
					(mid 272.292939 -307.194023)
					(end 272.31975 -307.123846)
				)
				(xy 272.31975 -306.94376) (xy 272.320512 -306.942998) (xy 272.321528 -306.921408)
			)
		)
	)
	(zone
		(net "P12V_A")
		(layer "B.Cu")
		(hatch none 0.5)
		(connect_pads
			(clearance 0.5)
		)
		(min_thickness 0.25)
		(fill yes
			(thermal_gap 0.5)
			(thermal_bridge_width 0.5)
			(island_removal_mode 0)
		)
		(polygon
			(pts
				(xy 30.038802 -138.10615) (xy 29.784802 -138.36015) (xy 29.784802 -141.28115) (xy 30.038802 -141.53515)
				(xy 33.340802 -141.53515) (xy 33.594802 -141.28115) (xy 33.594802 -138.36015) (xy 33.340802 -138.10615)
			)
		)
		(polygon
			(pts
				(xy 32.629602 -140.41755) (xy 32.426402 -140.41755) (xy 32.426402 -140.62075) (xy 32.629602 -140.62075)
			)
		)
		(polygon
			(pts
				(xy 32.4739 -139.8905) (xy 32.2707 -139.8905) (xy 32.2707 -140.0937) (xy 32.4739 -140.0937)
			)
		)
		(polygon
			(pts
				(xy 32.4739 -138.4935) (xy 32.2707 -138.4935) (xy 32.2707 -138.6967) (xy 32.4739 -138.6967)
			)
		)
	)
	(zone
		(layer "B.Cu")
		(hatch none 0.5)
		(connect_pads
			(clearance 0)
		)
		(min_thickness 0.25)
		(keepout
			(tracks allowed)
			(vias allowed)
			(pads allowed)
			(copperpour allowed)
			(footprints not_allowed)
		)
		(placement
			(enabled no)
			(sheetname "")
		)
		(fill
			(thermal_gap 0.5)
			(thermal_bridge_width 0.5)
			(island_removal_mode 0)
		)
		(polygon
			(pts
				(xy 200.000108 -300.999906) (xy 200.000108 -258.99999) (xy 0 -258.99999) (xy 0 -300.999906)
			)
		)
	)
	(zone
		(layer "B.Cu")
		(hatch none 0.5)
		(connect_pads
			(clearance 0)
		)
		(min_thickness 0.25)
		(keepout
			(tracks not_allowed)
			(vias allowed)
			(pads allowed)
			(copperpour not_allowed)
			(footprints allowed)
		)
		(placement
			(enabled no)
			(sheetname "")
		)
		(fill
			(thermal_gap 0.5)
			(thermal_bridge_width 0.5)
			(island_removal_mode 0)
		)
		(polygon
			(pts
				(arc
					(start 103.324914 -322.799964)
					(mid 96.324928 -315.799978)
					(end 89.324942 -322.799964)
				)
				(arc
					(start 89.324942 -328.799952)
					(mid 96.324928 -335.799938)
					(end 103.324914 -328.799952)
				)
			)
		)
	)
	(zone
		(layer "B.Cu")
		(hatch none 0.5)
		(connect_pads
			(clearance 0)
		)
		(min_thickness 0.25)
		(keepout
			(tracks not_allowed)
			(vias allowed)
			(pads allowed)
			(copperpour not_allowed)
			(footprints allowed)
		)
		(placement
			(enabled no)
			(sheetname "")
		)
		(fill
			(thermal_gap 0.5)
			(thermal_bridge_width 0.5)
			(island_removal_mode 0)
		)
		(polygon
			(pts
				(arc
					(start 482.870002 -277.17877)
					(mid 482.489129 -276.797516)
					(end 482.108002 -277.178516)
				)
				(xy 482.108002 -277.527766)
				(arc
					(start 482.312218 -277.527766)
					(mid 482.380874 -277.500691)
					(end 482.412548 -277.43404)
				)
				(arc
					(start 482.412548 -277.43404)
					(mid 482.489124 -276.911799)
					(end 482.565202 -277.43404)
				)
				(xy 482.565202 -277.458678)
				(arc
					(start 482.562916 -277.460964)
					(mid 482.49109 -277.606054)
					(end 482.346 -277.67788)
				)
				(xy 482.343714 -277.680166) (xy 482.108002 -277.680166) (xy 482.108002 -277.819866) (xy 482.343714 -277.819866)
				(arc
					(start 482.346 -277.822152)
					(mid 482.49109 -277.893978)
					(end 482.562916 -278.039068)
				)
				(xy 482.565202 -278.041354)
				(arc
					(start 482.565202 -278.065992)
					(mid 482.489124 -278.58816)
					(end 482.412548 -278.065992)
				)
				(arc
					(start 482.412548 -278.065992)
					(mid 482.38086 -277.999356)
					(end 482.312218 -277.972266)
				)
				(xy 482.108002 -277.972266)
				(arc
					(start 482.108002 -278.321516)
					(mid 482.489002 -278.702516)
					(end 482.870002 -278.321516)
				)
			)
		)
	)
	(zone
		(layer "B.Cu")
		(hatch none 0.5)
		(connect_pads
			(clearance 0)
		)
		(min_thickness 0.25)
		(keepout
			(tracks not_allowed)
			(vias allowed)
			(pads allowed)
			(copperpour not_allowed)
			(footprints allowed)
		)
		(placement
			(enabled no)
			(sheetname "")
		)
		(fill
			(thermal_gap 0.5)
			(thermal_bridge_width 0.5)
			(island_removal_mode 0)
		)
		(polygon
			(pts
				(arc
					(start 281.07386 -122.14733)
					(mid 281.397456 -121.176034)
					(end 280.42616 -120.852438)
				)
				(arc
					(start 279.487122 -121.32183)
					(mid 279.638469 -121.40564)
					(end 279.768554 -121.519696)
				)
				(xy 279.781762 -121.524014) (xy 279.832308 -121.62409) (xy 279.849834 -121.659396) (xy 279.867614 -121.694448)
				(xy 279.867614 -121.694702)
				(arc
					(start 279.892506 -121.744486)
					(mid 279.932791 -121.779482)
					(end 279.985978 -121.775728)
				)
				(arc
					(start 280.226516 -121.655332)
					(mid 281.23834 -121.255458)
					(end 280.31186 -121.825766)
				)
				(xy 280.071322 -121.945908) (xy 280.036016 -121.963688)
				(arc
					(start 280.03119 -121.962164)
					(mid 279.872501 -121.960151)
					(end 279.744424 -121.866406)
				)
				(xy 279.739598 -121.864882) (xy 279.722072 -121.82983) (xy 279.722072 -121.829576) (xy 279.679654 -121.74474)
				(arc
					(start 279.634696 -121.655586)
					(mid 279.450574 -121.514765)
					(end 279.227534 -121.451624)
				)
				(xy 279.028906 -121.550938) (xy 279.213056 -121.550938)
				(arc
					(start 279.214834 -121.552462)
					(mid 279.379517 -121.593672)
					(end 279.52192 -121.686066)
				)
				(xy 279.539192 -121.691654) (xy 279.623774 -121.860564) (xy 279.640792 -121.877582) (xy 279.640792 -121.894346)
				(xy 279.648412 -121.909586)
				(arc
					(start 279.646634 -121.914412)
					(mid 279.644931 -122.073146)
					(end 279.551384 -122.201432)
				)
				(xy 279.54986 -122.206258) (xy 279.514554 -122.223784)
				(arc
					(start 279.273508 -122.344434)
					(mid 278.261684 -122.744308)
					(end 279.188164 -122.174)
				)
				(arc
					(start 279.42921 -122.053604)
					(mid 279.462054 -122.018929)
					(end 279.46477 -121.971308)
				)
				(xy 279.450292 -121.956576) (xy 279.450292 -121.939558)
				(arc
					(start 279.393904 -121.827036)
					(mid 279.291818 -121.763601)
					(end 279.173686 -121.741438)
				)
				(xy 278.647906 -121.741438) (xy 278.426418 -121.852182)
				(arc
					(start 278.426418 -121.852436)
					(mid 278.102619 -122.82358)
					(end 279.073864 -123.147328)
				)
			)
		)
	)
	(zone
		(layer "B.Cu")
		(hatch none 0.5)
		(connect_pads
			(clearance 0)
		)
		(min_thickness 0.25)
		(keepout
			(tracks not_allowed)
			(vias allowed)
			(pads allowed)
			(copperpour not_allowed)
			(footprints allowed)
		)
		(placement
			(enabled no)
			(sheetname "")
		)
		(fill
			(thermal_gap 0.5)
			(thermal_bridge_width 0.5)
			(island_removal_mode 0)
		)
		(polygon
			(pts
				(arc
					(start 439.17489 -210.799934)
					(mid 425.174918 -196.799962)
					(end 411.174946 -210.799934)
				)
				(arc
					(start 411.174946 -210.799934)
					(mid 425.174918 -224.799906)
					(end 439.17489 -210.799934)
				)
			)
		)
	)
	(zone
		(layer "B.Cu")
		(hatch none 0.5)
		(connect_pads
			(clearance 0)
		)
		(min_thickness 0.25)
		(keepout
			(tracks not_allowed)
			(vias allowed)
			(pads allowed)
			(copperpour not_allowed)
			(footprints allowed)
		)
		(placement
			(enabled no)
			(sheetname "")
		)
		(fill
			(thermal_gap 0.5)
			(thermal_bridge_width 0.5)
			(island_removal_mode 0)
		)
		(polygon
			(pts
				(arc
					(start 286.436562 -303.15662)
					(mid 285.887922 -303.70526)
					(end 286.436562 -304.2539)
				)
				(arc
					(start 286.935926 -304.2539)
					(mid 286.921941 -304.184966)
					(end 286.915098 -304.114962)
				)
				(xy 286.914336 -304.1142)
				(arc
					(start 286.914336 -303.83226)
					(mid 286.899457 -303.796339)
					(end 286.863536 -303.78146)
				)
				(arc
					(start 286.822896 -303.78146)
					(mid 286.042785 -303.70526)
					(end 286.822896 -303.62906)
				)
				(xy 286.895032 -303.62906)
				(arc
					(start 286.89808 -303.632108)
					(mid 287.007157 -303.688639)
					(end 287.063688 -303.797716)
				)
				(xy 287.066736 -303.800764)
				(arc
					(start 287.066736 -304.082958)
					(mid 287.073831 -304.169584)
					(end 287.09493 -304.2539)
				)
				(arc
					(start 287.245806 -304.2539)
					(mid 287.220395 -304.186566)
					(end 287.207706 -304.115724)
				)
				(xy 287.206436 -304.1142) (xy 287.206436 -303.800764)
				(arc
					(start 287.209484 -303.797716)
					(mid 287.266015 -303.688639)
					(end 287.375092 -303.632108)
				)
				(xy 287.37814 -303.62906)
				(arc
					(start 287.450276 -303.62906)
					(mid 288.230387 -303.70526)
					(end 287.450276 -303.78146)
				)
				(arc
					(start 287.409636 -303.78146)
					(mid 287.373715 -303.796339)
					(end 287.358836 -303.83226)
				)
				(arc
					(start 287.358836 -304.082704)
					(mid 287.377127 -304.174657)
					(end 287.429194 -304.25263)
				)
				(xy 287.430464 -304.2539)
				(arc
					(start 287.83661 -304.2539)
					(mid 288.38525 -303.70526)
					(end 287.83661 -303.15662)
				)
				(xy 286.436816 -303.15662)
			)
		)
	)
	(zone
		(net "GND")
		(layer "B.Cu")
		(hatch none 0.5)
		(connect_pads
			(clearance 0.5)
		)
		(min_thickness 0.25)
		(fill yes
			(thermal_gap 0.5)
			(thermal_bridge_width 0.5)
			(island_removal_mode 0)
		)
		(polygon
			(pts
				(xy 190.470282 -228.267006) (xy 190.343282 -228.394006) (xy 190.343282 -229.918006) (xy 191.486282 -231.061006)
				(xy 194.915282 -231.061006) (xy 195.931282 -230.045006) (xy 195.931282 -229.283006) (xy 195.296282 -228.648006)
				(xy 191.359282 -228.648006) (xy 190.978282 -228.267006)
			)
		)
		(polygon
			(pts
				(xy 191.152272 -228.777292) (xy 190.949072 -228.777292) (xy 190.949072 -228.980492) (xy 191.152272 -228.980492)
			)
		)
	)
	(zone
		(layer "B.Cu")
		(hatch none 0.5)
		(connect_pads
			(clearance 0)
		)
		(min_thickness 0.25)
		(keepout
			(tracks not_allowed)
			(vias allowed)
			(pads allowed)
			(copperpour not_allowed)
			(footprints allowed)
		)
		(placement
			(enabled no)
			(sheetname "")
		)
		(fill
			(thermal_gap 0.5)
			(thermal_bridge_width 0.5)
			(island_removal_mode 0)
		)
		(polygon
			(pts
				(arc
					(start 279.236678 -313.956446)
					(mid 278.688038 -314.505086)
					(end 279.236678 -315.053726)
				)
				(xy 279.642824 -315.053726) (xy 279.644094 -315.052456)
				(arc
					(start 279.661874 -315.032644)
					(mid 279.700941 -314.962066)
					(end 279.714452 -314.88253)
				)
				(arc
					(start 279.714452 -314.632086)
					(mid 279.699573 -314.596165)
					(end 279.663652 -314.581286)
				)
				(arc
					(start 279.623012 -314.581286)
					(mid 278.842901 -314.505086)
					(end 279.623012 -314.428886)
				)
				(xy 279.695148 -314.428886)
				(arc
					(start 279.698196 -314.431934)
					(mid 279.807273 -314.488465)
					(end 279.863804 -314.597542)
				)
				(xy 279.866852 -314.60059) (xy 279.866852 -314.914026)
				(arc
					(start 279.865582 -314.91555)
					(mid 279.852889 -314.986391)
					(end 279.827482 -315.053726)
				)
				(arc
					(start 279.978358 -315.053726)
					(mid 279.999443 -314.969536)
					(end 280.006552 -314.883038)
				)
				(xy 280.006552 -314.60059)
				(arc
					(start 280.0096 -314.597542)
					(mid 280.066131 -314.488465)
					(end 280.175208 -314.431934)
				)
				(xy 280.178256 -314.428886)
				(arc
					(start 280.250392 -314.428886)
					(mid 281.030503 -314.505086)
					(end 280.250392 -314.581286)
				)
				(arc
					(start 280.209752 -314.581286)
					(mid 280.173831 -314.596165)
					(end 280.158952 -314.632086)
				)
				(xy 280.158952 -314.883038) (xy 280.158952 -314.914534)
				(arc
					(start 280.15819 -314.915296)
					(mid 280.151333 -314.985047)
					(end 280.137362 -315.053726)
				)
				(arc
					(start 280.636726 -315.053726)
					(mid 281.185366 -314.505086)
					(end 280.636726 -313.956446)
				)
				(xy 279.236932 -313.956446)
			)
		)
	)
	(zone
		(layer "B.Cu")
		(hatch none 0.5)
		(connect_pads
			(clearance 0)
		)
		(min_thickness 0.25)
		(keepout
			(tracks not_allowed)
			(vias allowed)
			(pads allowed)
			(copperpour not_allowed)
			(footprints allowed)
		)
		(placement
			(enabled no)
			(sheetname "")
		)
		(fill
			(thermal_gap 0.5)
			(thermal_bridge_width 0.5)
			(island_removal_mode 0)
		)
		(polygon
			(pts
				(arc
					(start 286.436562 -346.356432)
					(mid 285.887922 -346.905072)
					(end 286.436562 -347.453712)
				)
				(arc
					(start 286.935926 -347.453712)
					(mid 286.921941 -347.384778)
					(end 286.915098 -347.314774)
				)
				(xy 286.914336 -347.314012)
				(arc
					(start 286.914336 -347.032072)
					(mid 286.899457 -346.996151)
					(end 286.863536 -346.981272)
				)
				(arc
					(start 286.822896 -346.981272)
					(mid 286.042785 -346.905072)
					(end 286.822896 -346.828872)
				)
				(xy 286.895032 -346.828872)
				(arc
					(start 286.89808 -346.83192)
					(mid 287.007157 -346.888451)
					(end 287.063688 -346.997528)
				)
				(xy 287.066736 -347.000576)
				(arc
					(start 287.066736 -347.28277)
					(mid 287.073831 -347.369396)
					(end 287.09493 -347.453712)
				)
				(arc
					(start 287.245806 -347.453712)
					(mid 287.220395 -347.386378)
					(end 287.207706 -347.315536)
				)
				(xy 287.206436 -347.314012) (xy 287.206436 -347.000576)
				(arc
					(start 287.209484 -346.997528)
					(mid 287.266015 -346.888451)
					(end 287.375092 -346.83192)
				)
				(xy 287.37814 -346.828872)
				(arc
					(start 287.450276 -346.828872)
					(mid 288.230387 -346.905072)
					(end 287.450276 -346.981272)
				)
				(arc
					(start 287.409636 -346.981272)
					(mid 287.373715 -346.996151)
					(end 287.358836 -347.032072)
				)
				(arc
					(start 287.358836 -347.282516)
					(mid 287.377127 -347.374469)
					(end 287.429194 -347.452442)
				)
				(xy 287.430464 -347.453712)
				(arc
					(start 287.83661 -347.453712)
					(mid 288.38525 -346.905072)
					(end 287.83661 -346.356432)
				)
				(xy 286.436816 -346.356432)
			)
		)
	)
	(zone
		(net "GND")
		(layer "B.Cu")
		(hatch none 0.5)
		(connect_pads
			(clearance 0.5)
		)
		(min_thickness 0.25)
		(fill yes
			(thermal_gap 0.5)
			(thermal_bridge_width 0.5)
			(island_removal_mode 0)
		)
		(polygon
			(pts
				(xy 465.873338 -209.535776) (xy 465.563966 -209.845148) (xy 465.563966 -214.956136) (xy 466.083142 -215.475312)
				(xy 468.797386 -215.475312) (xy 470.278968 -213.99373) (xy 470.278968 -211.158836) (xy 468.655908 -209.535776)
			)
		)
	)
	(zone
		(net "GND")
		(layer "B.Cu")
		(hatch none 0.5)
		(connect_pads
			(clearance 0.5)
		)
		(min_thickness 0.25)
		(fill yes
			(thermal_gap 0.5)
			(thermal_bridge_width 0.5)
			(island_removal_mode 0)
		)
		(polygon
			(pts
				(xy 27.915616 -245.633494) (xy 27.7368 -245.81231) (xy 27.7368 -251.51715) (xy 28.005024 -251.785374)
				(xy 28.005024 -252.632972) (xy 28.489402 -253.11735) (xy 29.343604 -253.11735) (xy 29.353002 -253.126748)
				(xy 31.0388 -251.44095) (xy 31.0388 -245.815104) (xy 30.85719 -245.633494)
			)
		)
	)
	(zone
		(layer "B.Cu")
		(hatch none 0.5)
		(connect_pads
			(clearance 0)
		)
		(min_thickness 0.25)
		(keepout
			(tracks allowed)
			(vias allowed)
			(pads allowed)
			(copperpour allowed)
			(footprints not_allowed)
		)
		(placement
			(enabled no)
			(sheetname "")
		)
		(fill
			(thermal_gap 0.5)
			(thermal_bridge_width 0.5)
			(island_removal_mode 0)
		)
		(polygon
			(pts
				(arc
					(start 398.393666 -202.629516)
					(mid 400.079385 -204.974254)
					(end 400.675094 -207.79994)
				)
				(arc
					(start 400.675094 -213.799928)
					(mid 400.079378 -216.625726)
					(end 398.393666 -218.970606)
				)
				(arc
					(start 398.393666 -218.970606)
					(mid 425.175135 -238.800094)
					(end 451.956424 -218.970606)
				)
				(arc
					(start 451.956424 -218.970606)
					(mid 450.270654 -216.625752)
					(end 449.674996 -213.799928)
				)
				(arc
					(start 449.674996 -207.79994)
					(mid 450.270764 -204.97428)
					(end 451.956424 -202.629516)
				)
				(arc
					(start 451.956424 -202.629516)
					(mid 425.175135 -182.800091)
					(end 398.393666 -202.629516)
				)
			)
		)
	)
	(zone
		(layer "B.Cu")
		(hatch none 0.5)
		(connect_pads
			(clearance 0)
		)
		(min_thickness 0.25)
		(keepout
			(tracks not_allowed)
			(vias allowed)
			(pads allowed)
			(copperpour not_allowed)
			(footprints allowed)
		)
		(placement
			(enabled no)
			(sheetname "")
		)
		(fill
			(thermal_gap 0.5)
			(thermal_bridge_width 0.5)
			(island_removal_mode 0)
		)
		(polygon
			(pts
				(arc
					(start 40.32504 -322.799964)
					(mid 33.325054 -315.799978)
					(end 26.325068 -322.799964)
				)
				(arc
					(start 26.325068 -328.799952)
					(mid 33.325054 -335.799938)
					(end 40.32504 -328.799952)
				)
			)
		)
	)
	(zone
		(layer "B.Cu")
		(hatch none 0.5)
		(connect_pads
			(clearance 0)
		)
		(min_thickness 0.25)
		(keepout
			(tracks allowed)
			(vias allowed)
			(pads allowed)
			(copperpour allowed)
			(footprints not_allowed)
		)
		(placement
			(enabled no)
			(sheetname "")
		)
		(fill
			(thermal_gap 0.5)
			(thermal_bridge_width 0.5)
			(island_removal_mode 0)
		)
		(polygon
			(pts
				(arc
					(start 7.599934 -5.500116)
					(mid 3.850132 -1.750314)
					(end 0.100076 -5.500116)
				)
				(arc
					(start 0.100076 -5.500116)
					(mid 3.850132 -9.250172)
					(end 7.599934 -5.500116)
				)
			)
		)
	)
	(zone
		(net "GND")
		(layer "B.Cu")
		(hatch none 0.5)
		(connect_pads
			(clearance 0.5)
		)
		(min_thickness 0.25)
		(fill yes
			(thermal_gap 0.5)
			(thermal_bridge_width 0.5)
			(island_removal_mode 0)
		)
		(polygon
			(pts
				(arc
					(start 267.25118 -269.669514)
					(mid 265.755407 -267.70002)
					(end 263.398 -266.952476)
				)
				(arc
					(start 262.255 -266.952476)
					(mid 258.495294 -269.430864)
					(end 259.291074 -273.863054)
				)
				(arc
					(start 259.188204 -273.866864)
					(mid 256.871536 -274.037533)
					(end 255.021334 -275.442172)
				)
				(arc
					(start 255.021334 -273.205702)
					(mid 254.453006 -269.744931)
					(end 252.807724 -266.647676)
				)
				(arc
					(start 252.807724 -266.647676)
					(mid 253.699719 -266.621926)
					(end 254.564896 -266.403328)
				)
				(arc
					(start 254.564896 -266.403328)
					(mid 255.516943 -266.633045)
					(end 256.496312 -266.629896)
				)
				(arc
					(start 256.496312 -266.629896)
					(mid 256.833721 -266.672176)
					(end 257.173476 -266.686284)
				)
				(arc
					(start 258.367276 -266.686284)
					(mid 261.253793 -265.49427)
					(end 262.4582 -262.612886)
				)
				(arc
					(start 262.4582 -262.612886)
					(mid 262.73931 -262.208456)
					(end 262.969756 -261.773162)
				)
				(arc
					(start 262.969756 -261.773162)
					(mid 264.583054 -263.131919)
					(end 266.658852 -263.506204)
				)
				(arc
					(start 266.658852 -263.506204)
					(mid 269.206165 -263.212169)
					(end 271.077944 -261.459472)
				)
				(arc
					(start 271.077944 -261.459472)
					(mid 271.522189 -261.386097)
					(end 271.955768 -261.264654)
				)
				(arc
					(start 272.99285 -261.264654)
					(mid 273.132816 -263.146298)
					(end 274.08378 -264.77595)
				)
				(arc
					(start 274.08378 -264.77595)
					(mid 274.632177 -266.003642)
					(end 275.540978 -266.99464)
				)
				(arc
					(start 275.540978 -266.99464)
					(mid 275.248747 -266.963033)
					(end 274.955 -266.952476)
				)
				(arc
					(start 271.526 -266.952476)
					(mid 269.181022 -267.691276)
					(end 267.68298 -269.640812)
				)
				(arc
					(start 267.68298 -269.640812)
					(mid 267.466701 -269.649454)
					(end 267.25118 -269.669514)
				)
			)
		)
	)
	(zone
		(layer "B.Cu")
		(hatch none 0.5)
		(connect_pads
			(clearance 0)
		)
		(min_thickness 0.25)
		(keepout
			(tracks not_allowed)
			(vias allowed)
			(pads allowed)
			(copperpour not_allowed)
			(footprints allowed)
		)
		(placement
			(enabled no)
			(sheetname "")
		)
		(fill
			(thermal_gap 0.5)
			(thermal_bridge_width 0.5)
			(island_removal_mode 0)
		)
		(polygon
			(pts
				(arc
					(start 161.574988 -9.19988)
					(mid 166.325042 -13.949934)
					(end 171.075096 -9.19988)
				)
				(arc
					(start 171.075096 -9.19988)
					(mid 166.325042 -4.449826)
					(end 161.574988 -9.19988)
				)
			)
		)
	)
	(zone
		(layer "B.Cu")
		(hatch none 0.5)
		(connect_pads
			(clearance 0)
		)
		(min_thickness 0.25)
		(keepout
			(tracks allowed)
			(vias allowed)
			(pads allowed)
			(copperpour allowed)
			(footprints not_allowed)
		)
		(placement
			(enabled no)
			(sheetname "")
		)
		(fill
			(thermal_gap 0.5)
			(thermal_bridge_width 0.5)
			(island_removal_mode 0)
		)
		(polygon
			(pts
				(arc
					(start 101.04374 -202.629516)
					(mid 102.729314 -204.974287)
					(end 103.324914 -207.79994)
				)
				(arc
					(start 103.324914 -213.799928)
					(mid 102.729321 -216.625699)
					(end 101.04374 -218.970606)
				)
				(arc
					(start 101.04374 -218.970606)
					(mid 127.825209 -238.800094)
					(end 154.606498 -218.970606)
				)
				(arc
					(start 154.606498 -218.970606)
					(mid 152.920728 -216.625752)
					(end 152.32507 -213.799928)
				)
				(arc
					(start 152.32507 -207.79994)
					(mid 152.920838 -204.97428)
					(end 154.606498 -202.629516)
				)
				(arc
					(start 154.606498 -202.629516)
					(mid 127.825209 -182.800091)
					(end 101.04374 -202.629516)
				)
			)
		)
	)
	(zone
		(net "GND")
		(layer "B.Cu")
		(hatch none 0.5)
		(connect_pads
			(clearance 0.5)
		)
		(min_thickness 0.25)
		(fill yes
			(thermal_gap 0.5)
			(thermal_bridge_width 0.5)
			(island_removal_mode 0)
		)
		(polygon
			(pts
				(arc
					(start 379.067822 -195.942458)
					(mid 379.710915 -194.416623)
					(end 379.700536 -192.760854)
				)
				(arc
					(start 379.700536 -192.760854)
					(mid 382.20886 -192.462304)
					(end 384.070352 -190.754762)
				)
				(arc
					(start 384.070352 -190.754762)
					(mid 384.234552 -190.577939)
					(end 384.388106 -190.391796)
				)
				(arc
					(start 384.388106 -190.391796)
					(mid 384.494047 -193.468069)
					(end 386.558536 -195.751196)
				)
				(arc
					(start 386.558536 -195.751196)
					(mid 386.808059 -196.474563)
					(end 387.187948 -197.138798)
				)
				(arc
					(start 381.627888 -200.613772)
					(mid 381.205545 -197.808058)
					(end 379.067822 -195.942458)
				)
			)
		)
	)
	(zone
		(net "P12V_A_COMP")
		(layer "B.Cu")
		(hatch none 0.5)
		(connect_pads
			(clearance 0.5)
		)
		(min_thickness 0.25)
		(fill yes
			(thermal_gap 0.5)
			(thermal_bridge_width 0.5)
			(island_removal_mode 0)
		)
		(polygon
			(pts
				(xy 220.787468 -99.0092) (xy 220.533468 -99.2632) (xy 220.533468 -109.204506) (xy 220.937836 -109.608874)
				(xy 224.900744 -109.608874) (xy 225.201988 -109.30763) (xy 225.201988 -99.488498) (xy 224.72269 -99.0092)
			)
		)
	)
	(zone
		(net "GND")
		(layer "B.Cu")
		(hatch none 0.5)
		(connect_pads
			(clearance 0.5)
		)
		(min_thickness 0.25)
		(fill yes
			(thermal_gap 0.5)
			(thermal_bridge_width 0.5)
			(island_removal_mode 0)
		)
		(polygon
			(pts
				(xy 263.212072 -98.806) (xy 262.576818 -99.441254) (xy 262.576818 -107.716828) (xy 263.37133 -108.51134)
				(xy 266.34313 -108.51134) (xy 267.21435 -107.64012) (xy 267.21435 -105.612692) (xy 269.15491 -103.672132)
				(xy 269.15491 -99.385882) (xy 268.575028 -98.806)
			)
		)
	)
	(zone
		(layer "B.Cu")
		(hatch none 0.5)
		(connect_pads
			(clearance 0)
		)
		(min_thickness 0.25)
		(keepout
			(tracks allowed)
			(vias allowed)
			(pads allowed)
			(copperpour allowed)
			(footprints not_allowed)
		)
		(placement
			(enabled no)
			(sheetname "")
		)
		(fill
			(thermal_gap 0.5)
			(thermal_bridge_width 0.5)
			(island_removal_mode 0)
		)
		(polygon
			(pts
				(arc
					(start 171.45 -164.200078)
					(mid 167.699944 -160.450022)
					(end 163.949888 -164.200078)
				)
				(arc
					(start 163.949888 -164.200078)
					(mid 167.699944 -167.950134)
					(end 171.45 -164.200078)
				)
			)
		)
	)
	(zone
		(layer "B.Cu")
		(hatch none 0.5)
		(connect_pads
			(clearance 0)
		)
		(min_thickness 0.25)
		(keepout
			(tracks allowed)
			(vias allowed)
			(pads allowed)
			(copperpour allowed)
			(footprints allowed)
		)
		(placement
			(enabled no)
			(sheetname "")
		)
		(fill
			(thermal_gap 0.5)
			(thermal_bridge_width 0.5)
			(island_removal_mode 0)
		)
		(polygon
			(pts
				(xy 44.4754 -144.399) (xy 44.4754 -148.082) (xy 42.0116 -148.082) (xy 42.0116 -144.399)
			)
		)
	)
	(zone
		(layer "B.Cu")
		(hatch none 0.5)
		(connect_pads
			(clearance 0)
		)
		(min_thickness 0.25)
		(keepout
			(tracks allowed)
			(vias allowed)
			(pads allowed)
			(copperpour allowed)
			(footprints not_allowed)
		)
		(placement
			(enabled no)
			(sheetname "")
		)
		(fill
			(thermal_gap 0.5)
			(thermal_bridge_width 0.5)
			(island_removal_mode 0)
		)
		(polygon
			(pts
				(arc
					(start 487.19994 -204.199998)
					(mid 483.450138 -200.450196)
					(end 479.700082 -204.199998)
				)
				(arc
					(start 479.700082 -204.199998)
					(mid 483.450138 -207.950054)
					(end 487.19994 -204.199998)
				)
			)
		)
	)
	(zone
		(layer "B.Cu")
		(hatch none 0.5)
		(connect_pads
			(clearance 0)
		)
		(min_thickness 0.25)
		(keepout
			(tracks allowed)
			(vias allowed)
			(pads allowed)
			(copperpour allowed)
			(footprints not_allowed)
		)
		(placement
			(enabled no)
			(sheetname "")
		)
		(fill
			(thermal_gap 0.5)
			(thermal_bridge_width 0.5)
			(island_removal_mode 0)
		)
		(polygon
			(pts
				(xy 251.84989 -209.199988) (xy 225.849942 -209.199988) (xy 225.849942 38.800024) (xy 251.84989 38.800024)
			)
		)
	)
	(zone
		(layer "B.Cu")
		(hatch none 0.5)
		(connect_pads
			(clearance 0)
		)
		(min_thickness 0.25)
		(keepout
			(tracks not_allowed)
			(vias allowed)
			(pads allowed)
			(copperpour not_allowed)
			(footprints allowed)
		)
		(placement
			(enabled no)
			(sheetname "")
		)
		(fill
			(thermal_gap 0.5)
			(thermal_bridge_width 0.5)
			(island_removal_mode 0)
		)
		(polygon
			(pts
				(arc
					(start 400.675094 -92.799916)
					(mid 393.675108 -85.79993)
					(end 386.675122 -92.799916)
				)
				(arc
					(start 386.675122 -98.799904)
					(mid 393.675108 -105.79989)
					(end 400.675094 -98.799904)
				)
			)
		)
	)
	(zone
		(layer "B.Cu")
		(hatch none 0.5)
		(connect_pads
			(clearance 0)
		)
		(min_thickness 0.25)
		(keepout
			(tracks allowed)
			(vias allowed)
			(pads allowed)
			(copperpour allowed)
			(footprints not_allowed)
		)
		(placement
			(enabled no)
			(sheetname "")
		)
		(fill
			(thermal_gap 0.5)
			(thermal_bridge_width 0.5)
			(island_removal_mode 0)
		)
		(polygon
			(pts
				(arc
					(start 316.574932 -13.200126)
					(mid 317.675006 -14.3002)
					(end 318.77508 -13.200126)
				)
				(arc
					(start 318.77508 -13.200126)
					(mid 317.675006 -12.100052)
					(end 316.574932 -13.200126)
				)
			)
		)
	)
	(zone
		(net "P5V_D_LL")
		(layer "B.Cu")
		(hatch none 0.5)
		(connect_pads
			(clearance 0.5)
		)
		(min_thickness 0.25)
		(fill yes
			(thermal_gap 0.5)
			(thermal_bridge_width 0.5)
			(island_removal_mode 0)
		)
		(polygon
			(pts
				(xy 470.230454 -224.611184) (xy 469.722454 -225.119184) (xy 469.722454 -230.581454) (xy 469.975184 -230.834184)
				(xy 474.548454 -230.834184) (xy 474.719904 -230.662734) (xy 474.719904 -225.081084) (xy 474.250004 -224.611184)
			)
		)
		(polygon
			(pts
				(xy 470.5096 -229.8192) (xy 470.3064 -229.8192) (xy 470.3064 -230.3018) (xy 470.5096 -230.3018)
			)
		)
		(polygon
			(pts
				(xy 470.5096 -229.2096) (xy 470.3064 -229.2096) (xy 470.3064 -229.4128) (xy 470.5096 -229.4128)
			)
		)
	)
	(zone
		(layer "B.Cu")
		(hatch none 0.5)
		(connect_pads
			(clearance 0)
		)
		(min_thickness 0.25)
		(keepout
			(tracks allowed)
			(vias allowed)
			(pads allowed)
			(copperpour allowed)
			(footprints not_allowed)
		)
		(placement
			(enabled no)
			(sheetname "")
		)
		(fill
			(thermal_gap 0.5)
			(thermal_bridge_width 0.5)
			(island_removal_mode 0)
		)
		(polygon
			(pts
				(arc
					(start 46.500034 -164.200078)
					(mid 42.749978 -160.450022)
					(end 38.999922 -164.200078)
				)
				(arc
					(start 38.999922 -164.200078)
					(mid 42.749978 -167.950134)
					(end 46.500034 -164.200078)
				)
			)
		)
	)
	(zone
		(layer "B.Cu")
		(hatch none 0.5)
		(connect_pads
			(clearance 0)
		)
		(min_thickness 0.25)
		(keepout
			(tracks allowed)
			(vias allowed)
			(pads allowed)
			(copperpour allowed)
			(footprints allowed)
		)
		(placement
			(enabled no)
			(sheetname "")
		)
		(fill
			(thermal_gap 0.5)
			(thermal_bridge_width 0.5)
			(island_removal_mode 0)
		)
		(polygon
			(pts
				(xy 444.5762 -252.0696) (xy 444.5762 -255.4478) (xy 441.9854 -255.4478) (xy 441.9854 -252.0696)
			)
		)
	)
	(zone
		(net "MB3_CM_GATE_R")
		(layer "B.Cu")
		(hatch none 0.5)
		(connect_pads
			(clearance 0.5)
		)
		(min_thickness 0.25)
		(fill yes
			(thermal_gap 0.5)
			(thermal_bridge_width 0.5)
			(island_removal_mode 0)
		)
		(polygon
			(pts
				(xy 251.714 -369.189) (xy 245.674134 -375.228866) (xy 245.674134 -382.662938) (xy 245.986808 -382.975612)
				(xy 247.950482 -382.975612) (xy 248.222262 -382.703832) (xy 248.222262 -375.467118) (xy 252.96876 -370.72062)
				(xy 274.04314 -370.72062) (xy 274.193 -370.57076) (xy 274.193 -369.443) (xy 273.939 -369.189)
			)
		)
	)
	(zone
		(layer "B.Cu")
		(hatch none 0.5)
		(connect_pads
			(clearance 0)
		)
		(min_thickness 0.25)
		(keepout
			(tracks not_allowed)
			(vias allowed)
			(pads allowed)
			(copperpour not_allowed)
			(footprints allowed)
		)
		(placement
			(enabled no)
			(sheetname "")
		)
		(fill
			(thermal_gap 0.5)
			(thermal_bridge_width 0.5)
			(island_removal_mode 0)
		)
		(polygon
			(pts
				(arc
					(start 210.548728 -407.000456)
					(mid 210.000215 -406.451562)
					(end 209.451448 -407.000202)
				)
				(xy 209.451448 -407.458672)
				(arc
					(start 209.817716 -407.458672)
					(mid 209.83256 -407.457322)
					(end 209.846926 -407.453338)
				)
				(arc
					(start 209.846926 -407.453338)
					(mid 209.885312 -407.425502)
					(end 209.904076 -407.381964)
				)
				(arc
					(start 209.904076 -407.381964)
					(mid 210.000488 -406.606552)
					(end 210.095338 -407.382218)
				)
				(xy 210.095338 -407.408888)
				(arc
					(start 210.092036 -407.41219)
					(mid 210.03271 -407.546015)
					(end 209.913982 -407.631646)
				)
				(arc
					(start 209.913982 -407.631646)
					(mid 209.88767 -407.640099)
					(end 209.860642 -407.64587)
				)
				(xy 209.857086 -407.649172) (xy 209.451448 -407.649172) (xy 209.451448 -407.750772) (xy 209.8548 -407.750772)
				(arc
					(start 209.858102 -407.754074)
					(mid 210.013334 -407.832776)
					(end 210.092036 -407.988008)
				)
				(xy 210.095338 -407.99131)
				(arc
					(start 210.095338 -408.01798)
					(mid 210.000488 -408.793707)
					(end 209.904076 -408.018234)
				)
				(arc
					(start 209.904076 -408.018234)
					(mid 209.874162 -407.963126)
					(end 209.81543 -407.941272)
				)
				(xy 209.451448 -407.941272)
				(arc
					(start 209.451448 -408.399996)
					(mid 210.000088 -408.948636)
					(end 210.548728 -408.399996)
				)
			)
		)
	)
	(zone
		(layer "B.Cu")
		(hatch none 0.5)
		(connect_pads
			(clearance 0)
		)
		(min_thickness 0.25)
		(keepout
			(tracks not_allowed)
			(vias allowed)
			(pads allowed)
			(copperpour not_allowed)
			(footprints allowed)
		)
		(placement
			(enabled no)
			(sheetname "")
		)
		(fill
			(thermal_gap 0.5)
			(thermal_bridge_width 0.5)
			(island_removal_mode 0)
		)
		(polygon
			(pts
				(arc
					(start 463.674968 -207.79994)
					(mid 456.674982 -200.799954)
					(end 449.674996 -207.79994)
				)
				(arc
					(start 449.674996 -213.799928)
					(mid 456.674982 -220.799914)
					(end 463.674968 -213.799928)
				)
			)
		)
	)
	(zone
		(layer "B.Cu")
		(hatch none 0.5)
		(connect_pads
			(clearance 0)
		)
		(min_thickness 0.25)
		(keepout
			(tracks not_allowed)
			(vias allowed)
			(pads allowed)
			(copperpour not_allowed)
			(footprints allowed)
		)
		(placement
			(enabled no)
			(sheetname "")
		)
		(fill
			(thermal_gap 0.5)
			(thermal_bridge_width 0.5)
			(island_removal_mode 0)
		)
		(polygon
			(pts
				(arc
					(start 174.95012 -269.999968)
					(mid 170.200066 -265.249914)
					(end 165.450012 -269.999968)
				)
				(arc
					(start 165.450012 -269.999968)
					(mid 170.200066 -274.750022)
					(end 174.95012 -269.999968)
				)
			)
		)
	)
	(zone
		(layer "B.Cu")
		(hatch none 0.5)
		(connect_pads
			(clearance 0)
		)
		(min_thickness 0.25)
		(keepout
			(tracks not_allowed)
			(vias allowed)
			(pads allowed)
			(copperpour not_allowed)
			(footprints allowed)
		)
		(placement
			(enabled no)
			(sheetname "")
		)
		(fill
			(thermal_gap 0.5)
			(thermal_bridge_width 0.5)
			(island_removal_mode 0)
		)
		(polygon
			(pts
				(arc
					(start 115.098576 -21.950426)
					(mid 114.550063 -21.401532)
					(end 114.001296 -21.950172)
				)
				(xy 114.001296 -22.408896)
				(arc
					(start 114.383566 -22.408896)
					(mid 114.433855 -22.388065)
					(end 114.454686 -22.337776)
				)
				(arc
					(start 114.454686 -22.332188)
					(mid 114.549936 -21.55646)
					(end 114.645186 -22.332188)
				)
				(xy 114.645186 -22.377146)
				(arc
					(start 114.64163 -22.380702)
					(mid 114.568552 -22.522762)
					(end 114.426492 -22.59584)
				)
				(xy 114.422936 -22.599396) (xy 114.0333 -22.599396) (xy 114.001296 -22.600666) (xy 114.001296 -22.700996)
				(xy 114.422936 -22.700996)
				(arc
					(start 114.426492 -22.704552)
					(mid 114.568552 -22.77763)
					(end 114.64163 -22.91969)
				)
				(xy 114.645186 -22.923246)
				(arc
					(start 114.645186 -22.968204)
					(mid 114.549936 -23.743932)
					(end 114.454686 -22.968204)
				)
				(arc
					(start 114.454686 -22.962616)
					(mid 114.433855 -22.912327)
					(end 114.383566 -22.891496)
				)
				(arc
					(start 114.0333 -22.891496)
					(mid 114.017195 -22.892354)
					(end 114.001296 -22.895052)
				)
				(arc
					(start 114.001296 -23.35022)
					(mid 114.549936 -23.89886)
					(end 115.098576 -23.35022)
				)
			)
		)
	)
	(zone
		(net "GND")
		(layer "B.Cu")
		(hatch none 0.5)
		(connect_pads
			(clearance 0.5)
		)
		(min_thickness 0.25)
		(fill yes
			(thermal_gap 0.5)
			(thermal_bridge_width 0.5)
			(island_removal_mode 0)
		)
		(polygon
			(pts
				(arc
					(start 75.52436 -281.711146)
					(mid 71.694969 -285.923801)
					(end 75.783948 -289.884866)
				)
				(arc
					(start 77.672438 -289.884866)
					(mid 77.773891 -290.551002)
					(end 77.983334 -291.191442)
				)
				(arc
					(start 77.983334 -291.191442)
					(mid 77.844584 -291.572855)
					(end 77.74432 -291.966142)
				)
				(arc
					(start 77.74432 -291.966142)
					(mid 75.858016 -291.976399)
					(end 74.17689 -292.832028)
				)
				(arc
					(start 74.17689 -292.832028)
					(mid 74.107916 -292.730511)
					(end 74.03592 -292.631114)
				)
				(arc
					(start 74.03592 -292.631114)
					(mid 73.623989 -290.966391)
					(end 72.565768 -289.616896)
				)
				(arc
					(start 72.565768 -289.616896)
					(mid 72.138409 -288.914662)
					(end 71.579232 -288.312098)
				)
				(arc
					(start 71.579232 -288.312098)
					(mid 71.183415 -287.570932)
					(end 70.644512 -286.926274)
				)
				(arc
					(start 70.644512 -286.926274)
					(mid 71.037628 -283.002121)
					(end 67.933062 -280.569924)
				)
				(arc
					(start 67.933062 -280.569924)
					(mid 68.076247 -279.961099)
					(end 68.124324 -279.337516)
				)
				(xy 68.124324 -279.012904)
				(arc
					(start 74.232008 -279.012904)
					(mid 74.945111 -279.401623)
					(end 75.720956 -279.641808)
				)
				(arc
					(start 75.720956 -279.641808)
					(mid 75.488981 -280.663781)
					(end 75.52436 -281.711146)
				)
			)
		)
	)
	(zone
		(layer "B.Cu")
		(hatch none 0.5)
		(connect_pads
			(clearance 0)
		)
		(min_thickness 0.25)
		(keepout
			(tracks not_allowed)
			(vias allowed)
			(pads allowed)
			(copperpour not_allowed)
			(footprints allowed)
		)
		(placement
			(enabled no)
			(sheetname "")
		)
		(fill
			(thermal_gap 0.5)
			(thermal_bridge_width 0.5)
			(island_removal_mode 0)
		)
		(polygon
			(pts
				(arc
					(start 451.3199 -277.17877)
					(mid 450.939027 -276.797516)
					(end 450.5579 -277.178516)
				)
				(xy 450.5579 -277.527766)
				(arc
					(start 450.762116 -277.527766)
					(mid 450.830772 -277.500691)
					(end 450.862446 -277.43404)
				)
				(arc
					(start 450.862446 -277.43404)
					(mid 450.939022 -276.911799)
					(end 451.0151 -277.43404)
				)
				(xy 451.0151 -277.458678)
				(arc
					(start 451.012814 -277.460964)
					(mid 450.940988 -277.606054)
					(end 450.795898 -277.67788)
				)
				(xy 450.793612 -277.680166) (xy 450.5579 -277.680166) (xy 450.5579 -277.819866) (xy 450.793612 -277.819866)
				(arc
					(start 450.795898 -277.822152)
					(mid 450.940988 -277.893978)
					(end 451.012814 -278.039068)
				)
				(xy 451.0151 -278.041354)
				(arc
					(start 451.0151 -278.065992)
					(mid 450.939022 -278.58816)
					(end 450.862446 -278.065992)
				)
				(arc
					(start 450.862446 -278.065992)
					(mid 450.830758 -277.999356)
					(end 450.762116 -277.972266)
				)
				(xy 450.5579 -277.972266)
				(arc
					(start 450.5579 -278.321516)
					(mid 450.9389 -278.702516)
					(end 451.3199 -278.321516)
				)
			)
		)
	)
	(zone
		(layer "B.Cu")
		(hatch none 0.5)
		(connect_pads
			(clearance 0)
		)
		(min_thickness 0.25)
		(keepout
			(tracks allowed)
			(vias allowed)
			(pads allowed)
			(copperpour allowed)
			(footprints not_allowed)
		)
		(placement
			(enabled no)
			(sheetname "")
		)
		(fill
			(thermal_gap 0.5)
			(thermal_bridge_width 0.5)
			(island_removal_mode 0)
		)
		(polygon
			(pts
				(arc
					(start 463.674968 -92.799916)
					(mid 456.674982 -85.79993)
					(end 449.674996 -92.799916)
				)
				(arc
					(start 449.674996 -98.799904)
					(mid 456.674982 -105.79989)
					(end 463.674968 -98.799904)
				)
			)
		)
	)
	(zone
		(net "GND")
		(layer "B.Cu")
		(hatch none 0.5)
		(connect_pads
			(clearance 0.5)
		)
		(min_thickness 0.25)
		(fill yes
			(thermal_gap 0.5)
			(thermal_bridge_width 0.5)
			(island_removal_mode 0)
		)
		(polygon
			(pts
				(arc
					(start 180.82133 -170.284394)
					(mid 180.581084 -170.305714)
					(end 180.34 -170.312842)
				)
				(arc
					(start 178.008788 -170.312842)
					(mid 177.923826 -170.543695)
					(end 177.825146 -170.769026)
				)
				(arc
					(start 177.825146 -170.769026)
					(mid 180.156485 -172.979035)
					(end 180.172614 -176.191418)
				)
				(arc
					(start 180.172614 -176.191418)
					(mid 179.000921 -180.938182)
					(end 174.117254 -181.170834)
				)
				(arc
					(start 174.117254 -181.170834)
					(mid 172.183043 -183.318394)
					(end 169.312082 -183.651144)
				)
				(arc
					(start 169.312082 -183.651144)
					(mid 168.860733 -184.986032)
					(end 167.983154 -186.088528)
				)
				(arc
					(start 167.983154 -186.088528)
					(mid 169.012743 -190.790594)
					(end 164.855144 -193.216276)
				)
				(arc
					(start 164.855144 -193.216276)
					(mid 162.744958 -194.408214)
					(end 160.330642 -194.196716)
				)
				(arc
					(start 160.330642 -194.196716)
					(mid 160.281595 -195.645624)
					(end 159.730186 -196.986398)
				)
				(arc
					(start 159.730186 -196.986398)
					(mid 167.118509 -200.292933)
					(end 170.145964 -207.79994)
				)
				(arc
					(start 170.145964 -213.794848)
					(mid 169.654313 -217.019303)
					(end 168.2242 -219.950792)
				)
				(xy 176.68367 -219.950792) (xy 176.68367 -219.810076)
				(arc
					(start 177.157888 -219.810076)
					(mid 177.206031 -219.764088)
					(end 177.254916 -219.71889)
				)
				(arc
					(start 177.254916 -219.63761)
					(mid 177.548213 -218.146608)
					(end 178.3842 -216.877646)
				)
				(arc
					(start 178.3842 -214.309198)
					(mid 181.171143 -201.545582)
					(end 188.1632 -212.581236)
				)
				(arc
					(start 188.1632 -214.25281)
					(mid 188.53643 -214.470829)
					(end 188.88456 -214.727028)
				)
				(arc
					(start 188.88456 -214.727028)
					(mid 189.316042 -214.79793)
					(end 189.737492 -214.91448)
				)
				(xy 190.573152 -214.91448)
				(arc
					(start 190.573152 -215.304116)
					(mid 190.69248 -215.379928)
					(end 190.809118 -215.459818)
				)
				(xy 192.42786 -215.459818) (xy 192.828926 -215.058752) (xy 197.001638 -215.058752) (xy 199.540622 -217.597736)
				(xy 199.540622 -224.559622) (xy 201.0664 -226.0854) (xy 203.674726 -226.0854) (xy 213.131146 -216.62898)
				(xy 217.43162 -216.62898) (xy 217.8304 -216.2302)
				(arc
					(start 217.8304 -215.478614)
					(mid 215.873836 -212.769715)
					(end 216.590372 -209.505804)
				)
				(arc
					(start 216.590372 -209.505804)
					(mid 216.417065 -208.969577)
					(end 216.3191 -208.41462)
				)
				(xy 200.316084 -208.41462)
				(arc
					(start 190.094616 -198.193152)
					(mid 186.341609 -198.593693)
					(end 183.858662 -195.751196)
				)
				(arc
					(start 183.858662 -195.751196)
					(mid 183.433025 -195.495682)
					(end 183.038242 -195.194682)
				)
				(arc
					(start 183.038242 -195.194682)
					(mid 178.666636 -193.623683)
					(end 178.583082 -188.979048)
				)
				(arc
					(start 178.583082 -188.979048)
					(mid 176.713508 -183.586212)
					(end 182.055516 -181.575456)
				)
				(arc
					(start 182.055516 -181.575456)
					(mid 182.35522 -180.689626)
					(end 182.84825 -179.894992)
				)
				(arc
					(start 182.84825 -179.894992)
					(mid 182.191436 -178.699733)
					(end 181.964076 -177.354992)
				)
				(arc
					(start 181.964076 -174.814992)
					(mid 182.034405 -174.059694)
					(end 182.242968 -173.330362)
				)
				(arc
					(start 182.242968 -173.330362)
					(mid 181.204906 -171.960123)
					(end 180.82133 -170.284394)
				)
			)
		)
	)
	(zone
		(net "P5V_B_LL")
		(layer "B.Cu")
		(hatch none 0.5)
		(connect_pads
			(clearance 0.5)
		)
		(min_thickness 0.25)
		(fill yes
			(thermal_gap 0.5)
			(thermal_bridge_width 0.5)
			(island_removal_mode 0)
		)
		(polygon
			(pts
				(xy 53.279802 -138.48715) (xy 52.517802 -139.24915) (xy 50.358802 -139.24915) (xy 48.199802 -141.40815)
				(xy 48.199802 -144.07515) (xy 48.371252 -144.2466) (xy 53.952902 -144.2466) (xy 54.422802 -143.7767)
				(xy 54.422802 -139.75715) (xy 53.914802 -139.24915) (xy 53.914802 -138.86815) (xy 53.533802 -138.48715)
			)
		)
	)
	(zone
		(net "GND")
		(layer "B.Cu")
		(hatch none 0.5)
		(connect_pads
			(clearance 0.5)
		)
		(min_thickness 0.25)
		(fill yes
			(thermal_gap 0.5)
			(thermal_bridge_width 0.5)
			(island_removal_mode 0)
		)
		(polygon
			(pts
				(arc
					(start 201.000106 1.23698)
					(mid 200.832534 1.16757)
					(end 200.763124 0.999998)
				)
				(arc
					(start 200.763124 0.999998)
					(mid 200.246749 -0.246641)
					(end 199.00011 -0.763016)
				)
				(arc
					(start 150.999952 -0.763016)
					(mid 150.83238 -0.832426)
					(end 150.76297 -0.999998)
				)
				(arc
					(start 150.76297 -13.999972)
					(mid 150.645719 -14.632178)
					(end 150.30958 -15.18031)
				)
				(arc
					(start 150.30958 -16.734536)
					(mid 151.56547 -15.61586)
					(end 152.031954 -13.999972)
				)
				(xy 152.031954 -2.032) (xy 177.198528 -2.032) (xy 177.198528 -5.842254)
				(arc
					(start 177.198274 -5.842254)
					(mid 176.448135 -7.876184)
					(end 174.896018 -9.389618)
				)
				(arc
					(start 174.896018 -9.389618)
					(mid 171.080327 -16.333381)
					(end 163.203128 -17.184624)
				)
				(arc
					(start 163.203128 -17.184624)
					(mid 162.683944 -17.512399)
					(end 162.127946 -17.772888)
				)
				(xy 184.52465 -22.223984)
				(arc
					(start 199.825356 -19.018758)
					(mid 200.217425 -17.458251)
					(end 201.180954 -16.16964)
				)
				(arc
					(start 201.180954 -16.16964)
					(mid 200.960057 -15.98003)
					(end 200.753218 -15.775178)
				)
				(arc
					(start 200.753218 -15.775178)
					(mid 199.379419 -14.295027)
					(end 198.880984 -12.33805)
				)
				(arc
					(start 198.880984 -11.067796)
					(mid 199.103564 -9.736792)
					(end 199.747124 -8.550656)
				)
				(arc
					(start 199.747124 -8.550656)
					(mid 199.93824 -7.768063)
					(end 200.279 -7.038086)
				)
				(arc
					(start 200.279 -7.038086)
					(mid 198.788357 -6.702012)
					(end 197.525132 -5.842254)
				)
				(arc
					(start 197.522592 -5.842254)
					(mid 196.484049 -4.078271)
					(end 196.429884 -2.032)
				)
				(arc
					(start 199.00011 -2.032)
					(mid 200.741362 -1.482149)
					(end 201.851006 -0.032004)
				)
				(xy 202.368658 -0.032004) (xy 202.368658 1.23698)
			)
		)
	)
	(zone
		(layer "B.Cu")
		(hatch none 0.5)
		(connect_pads
			(clearance 0)
		)
		(min_thickness 0.25)
		(keepout
			(tracks allowed)
			(vias allowed)
			(pads allowed)
			(copperpour allowed)
			(footprints not_allowed)
		)
		(placement
			(enabled no)
			(sheetname "")
		)
		(fill
			(thermal_gap 0.5)
			(thermal_bridge_width 0.5)
			(island_removal_mode 0)
		)
		(polygon
			(pts
				(arc
					(start 307.200046 -138.199876)
					(mid 300.20006 -131.19989)
					(end 293.200074 -138.199876)
				)
				(arc
					(start 293.200074 -144.200118)
					(mid 300.20006 -151.200104)
					(end 307.200046 -144.200118)
				)
			)
		)
	)
	(zone
		(net "GND")
		(layer "B.Cu")
		(hatch none 0.5)
		(connect_pads
			(clearance 0.5)
		)
		(min_thickness 0.25)
		(fill yes
			(thermal_gap 0.5)
			(thermal_bridge_width 0.5)
			(island_removal_mode 0)
		)
		(polygon
			(pts
				(arc
					(start 340.739222 -138.5062)
					(mid 340.890232 -139.076548)
					(end 341.121746 -139.619228)
				)
				(xy 341.121746 -145.977356) (xy 341.206328 -146.061938) (xy 340.32317 -146.061938) (xy 340.32317 -147.30222)
				(xy 340.207346 -147.418044) (xy 340.207346 -152.251156)
				(arc
					(start 333.711042 -152.251156)
					(mid 333.479892 -152.231502)
					(end 333.248 -152.224994)
				)
				(arc
					(start 332.105 -152.224994)
					(mid 331.711897 -152.243876)
					(end 331.322426 -152.300432)
				)
				(arc
					(start 331.322426 -152.300432)
					(mid 331.521916 -151.133365)
					(end 331.378814 -149.958044)
				)
				(arc
					(start 339.619336 -137.979912)
					(mid 340.159256 -138.285665)
					(end 340.739222 -138.5062)
				)
			)
		)
	)
	(zone
		(net "GND")
		(layer "B.Cu")
		(hatch none 0.5)
		(connect_pads
			(clearance 0.5)
		)
		(min_thickness 0.25)
		(fill yes
			(thermal_gap 0.5)
			(thermal_bridge_width 0.5)
			(island_removal_mode 0)
		)
		(polygon
			(pts
				(xy 68.519802 -147.75815) (xy 68.265802 -148.01215) (xy 68.265802 -149.79015) (xy 68.646802 -150.17115)
				(xy 73.853802 -150.17115) (xy 74.107802 -149.91715) (xy 74.107802 -147.88515) (xy 73.980802 -147.75815)
			)
		)
	)
	(zone
		(layer "B.Cu")
		(hatch none 0.5)
		(connect_pads
			(clearance 0)
		)
		(min_thickness 0.25)
		(keepout
			(tracks allowed)
			(vias allowed)
			(pads allowed)
			(copperpour allowed)
			(footprints not_allowed)
		)
		(placement
			(enabled no)
			(sheetname "")
		)
		(fill
			(thermal_gap 0.5)
			(thermal_bridge_width 0.5)
			(island_removal_mode 0)
		)
		(polygon
			(pts
				(arc
					(start 251.599954 6.500114)
					(mid 247.850152 10.249916)
					(end 244.100096 6.500114)
				)
				(arc
					(start 244.100096 6.500114)
					(mid 247.850152 2.750058)
					(end 251.599954 6.500114)
				)
			)
		)
	)
	(zone
		(layer "B.Cu")
		(hatch none 0.5)
		(connect_pads
			(clearance 0)
		)
		(min_thickness 0.25)
		(keepout
			(tracks not_allowed)
			(vias allowed)
			(pads allowed)
			(copperpour not_allowed)
			(footprints allowed)
		)
		(placement
			(enabled no)
			(sheetname "")
		)
		(fill
			(thermal_gap 0.5)
			(thermal_bridge_width 0.5)
			(island_removal_mode 0)
		)
		(polygon
			(pts
				(arc
					(start 382.698752 -21.950426)
					(mid 382.150239 -21.401532)
					(end 381.601472 -21.950172)
				)
				(arc
					(start 381.601472 -23.35022)
					(mid 382.150112 -23.89886)
					(end 382.698752 -23.35022)
				)
				(xy 382.698752 -22.891496) (xy 382.696974 -22.891496)
				(arc
					(start 382.316482 -22.891496)
					(mid 382.266193 -22.912327)
					(end 382.245362 -22.962616)
				)
				(arc
					(start 382.245362 -22.968204)
					(mid 382.150112 -23.743932)
					(end 382.054862 -22.968204)
				)
				(xy 382.054862 -22.923246)
				(arc
					(start 382.058418 -22.91969)
					(mid 382.131496 -22.77763)
					(end 382.273556 -22.704552)
				)
				(xy 382.277112 -22.700996) (xy 382.698752 -22.700996) (xy 382.698752 -22.599396) (xy 382.696974 -22.599396)
				(xy 382.277112 -22.599396)
				(arc
					(start 382.273556 -22.59584)
					(mid 382.131496 -22.522762)
					(end 382.058418 -22.380702)
				)
				(xy 382.054862 -22.377146)
				(arc
					(start 382.054862 -22.332188)
					(mid 382.150112 -21.55646)
					(end 382.245362 -22.332188)
				)
				(arc
					(start 382.245362 -22.337776)
					(mid 382.266193 -22.388065)
					(end 382.316482 -22.408896)
				)
				(xy 382.698752 -22.408896)
			)
		)
	)
	(zone
		(layer "B.Cu")
		(hatch none 0.5)
		(connect_pads
			(clearance 0)
		)
		(min_thickness 0.25)
		(keepout
			(tracks not_allowed)
			(vias allowed)
			(pads allowed)
			(copperpour not_allowed)
			(footprints allowed)
		)
		(placement
			(enabled no)
			(sheetname "")
		)
		(fill
			(thermal_gap 0.5)
			(thermal_bridge_width 0.5)
			(island_removal_mode 0)
		)
		(polygon
			(pts
				(arc
					(start 238.374936 -77.84973)
					(mid 238.699802 -76.875132)
					(end 237.725204 -76.550266)
				)
				(xy 237.723934 -76.54798) (xy 235.724192 -77.547978) (xy 235.724192 -77.548232)
				(arc
					(start 235.725208 -77.550264)
					(mid 235.400342 -78.524862)
					(end 236.37494 -78.849728)
				)
				(xy 236.37621 -78.852014) (xy 236.864652 -78.607666)
				(arc
					(start 237.11662 -78.355952)
					(mid 237.131673 -78.33333)
					(end 237.13694 -78.306676)
				)
				(arc
					(start 237.13694 -78.18882)
					(mid 237.131657 -78.162173)
					(end 237.11662 -78.139544)
				)
				(arc
					(start 236.954568 -77.977492)
					(mid 236.915528 -77.949006)
					(end 236.869732 -77.93355)
				)
				(xy 236.866176 -77.933042)
				(arc
					(start 236.85119 -77.930502)
					(mid 236.80142 -77.930661)
					(end 236.754162 -77.94625)
				)
				(arc
					(start 236.572044 -78.039468)
					(mid 235.564081 -78.449059)
					(end 236.485176 -77.87005)
				)
				(xy 236.667294 -77.776578) (xy 236.702346 -77.758544)
				(arc
					(start 236.705902 -77.759814)
					(mid 236.77166 -77.7426)
					(end 236.839506 -77.738478)
				)
				(xy 236.842554 -77.736192) (xy 236.88167 -77.742542) (xy 236.896656 -77.745082) (xy 236.901228 -77.745844)
				(xy 236.936026 -77.751432)
				(arc
					(start 236.937804 -77.753972)
					(mid 237.000702 -77.77864)
					(end 237.057692 -77.814932)
				)
				(xy 237.061248 -77.814932) (xy 237.089188 -77.842872) (xy 237.179358 -77.933042) (xy 237.27918 -78.032864)
				(arc
					(start 237.27918 -78.037944)
					(mid 237.307656 -78.089381)
					(end 237.323884 -78.145894)
				)
				(xy 237.32744 -78.14945) (xy 237.32744 -78.346046)
				(arc
					(start 237.323884 -78.349602)
					(mid 237.320596 -78.365855)
					(end 237.316264 -78.38186)
				)
				(xy 237.42904 -78.325472)
				(arc
					(start 237.42904 -78.104492)
					(mid 237.416892 -78.043892)
					(end 237.382558 -77.992478)
				)
				(xy 237.382558 -77.992224) (xy 237.237016 -77.846682)
				(arc
					(start 237.237016 -77.841602)
					(mid 237.226537 -77.825825)
					(end 237.217204 -77.809344)
				)
				(arc
					(start 237.217204 -77.808836)
					(mid 237.191186 -77.729503)
					(end 237.191296 -77.646022)
				)
				(arc
					(start 237.191296 -77.645768)
					(mid 237.227217 -77.54973)
					(end 237.29696 -77.474572)
				)
				(xy 237.298484 -77.469746)
				(arc
					(start 237.526576 -77.3557)
					(mid 238.537853 -76.954953)
					(end 237.61192 -77.52588)
				)
				(arc
					(start 237.419134 -77.6224)
					(mid 237.392708 -77.644672)
					(end 237.379256 -77.676502)
				)
				(arc
					(start 237.379256 -77.676502)
					(mid 237.379224 -77.69967)
					(end 237.386368 -77.721714)
				)
				(arc
					(start 237.386368 -77.721714)
					(mid 237.392303 -77.731101)
					(end 237.399576 -77.739494)
				)
				(xy 237.39983 -77.740002) (xy 237.42777 -77.767942) (xy 237.42777 -77.768196) (xy 237.50651 -77.846682)
				(xy 237.517178 -77.857604) (xy 237.517432 -77.857604) (xy 237.545118 -77.885544)
				(arc
					(start 237.545118 -77.8891)
					(mid 237.592944 -77.970916)
					(end 237.617 -78.062582)
				)
				(xy 237.61954 -78.065122) (xy 237.61954 -78.230476) (xy 238.376206 -77.852016)
			)
		)
	)
	(zone
		(layer "B.Cu")
		(hatch none 0.5)
		(connect_pads
			(clearance 0)
		)
		(min_thickness 0.25)
		(keepout
			(tracks not_allowed)
			(vias allowed)
			(pads allowed)
			(copperpour not_allowed)
			(footprints allowed)
		)
		(placement
			(enabled no)
			(sheetname "")
		)
		(fill
			(thermal_gap 0.5)
			(thermal_bridge_width 0.5)
			(island_removal_mode 0)
		)
		(polygon
			(pts
				(arc
					(start 359.298748 -20.950428)
					(mid 358.750235 -20.401534)
					(end 358.201468 -20.950174)
				)
				(arc
					(start 358.201468 -21.42871)
					(mid 358.266971 -21.416437)
					(end 358.333294 -21.409914)
				)
				(xy 358.334564 -21.408898)
				(arc
					(start 358.583738 -21.408898)
					(mid 358.634027 -21.388067)
					(end 358.654858 -21.337778)
				)
				(arc
					(start 358.654858 -21.33219)
					(mid 358.750108 -20.556462)
					(end 358.845358 -21.33219)
				)
				(xy 358.845358 -21.377148)
				(arc
					(start 358.841802 -21.380704)
					(mid 358.768724 -21.522764)
					(end 358.626664 -21.595842)
				)
				(xy 358.623108 -21.599398)
				(arc
					(start 358.373934 -21.599398)
					(mid 358.286692 -21.606021)
					(end 358.201468 -21.625814)
				)
				(arc
					(start 358.201468 -21.73351)
					(mid 358.266023 -21.713421)
					(end 358.332786 -21.702776)
				)
				(xy 358.334564 -21.700998) (xy 358.623108 -21.700998)
				(arc
					(start 358.626664 -21.704554)
					(mid 358.768724 -21.777632)
					(end 358.841802 -21.919692)
				)
				(xy 358.845358 -21.923248)
				(arc
					(start 358.845358 -21.968206)
					(mid 358.750108 -22.743934)
					(end 358.654858 -21.968206)
				)
				(arc
					(start 358.654858 -21.962618)
					(mid 358.634027 -21.912329)
					(end 358.583738 -21.891498)
				)
				(arc
					(start 358.373934 -21.891498)
					(mid 358.282859 -21.906584)
					(end 358.201468 -21.950172)
				)
				(arc
					(start 358.201468 -22.350222)
					(mid 358.750108 -22.898862)
					(end 359.298748 -22.350222)
				)
			)
		)
	)
	(zone
		(net "P12V_B_COMP")
		(layer "B.Cu")
		(hatch none 0.5)
		(connect_pads
			(clearance 0.5)
		)
		(min_thickness 0.25)
		(fill yes
			(thermal_gap 0.5)
			(thermal_bridge_width 0.5)
			(island_removal_mode 0)
		)
		(polygon
			(pts
				(xy 270.59382 -98.2472) (xy 269.927578 -98.913442) (xy 269.927578 -104.778302) (xy 269.250414 -105.455466)
				(xy 269.250414 -108.369354) (xy 269.610078 -108.729018) (xy 273.487642 -108.729018) (xy 277.92426 -104.2924)
				(xy 286.8168 -104.2924) (xy 287.6296 -103.4796) (xy 287.6296 -98.8568) (xy 287.02 -98.2472)
			)
		)
	)
	(zone
		(layer "B.Cu")
		(hatch none 0.5)
		(connect_pads
			(clearance 0)
		)
		(min_thickness 0.25)
		(keepout
			(tracks allowed)
			(vias allowed)
			(pads allowed)
			(copperpour allowed)
			(footprints not_allowed)
		)
		(placement
			(enabled no)
			(sheetname "")
		)
		(fill
			(thermal_gap 0.5)
			(thermal_bridge_width 0.5)
			(island_removal_mode 0)
		)
		(polygon
			(pts
				(arc
					(start 7.599934 -120.499886)
					(mid 3.850132 -116.750084)
					(end 0.100076 -120.499886)
				)
				(arc
					(start 0.100076 -120.499886)
					(mid 3.850132 -124.249942)
					(end 7.599934 -120.499886)
				)
			)
		)
	)
	(zone
		(layer "B.Cu")
		(hatch none 0.5)
		(connect_pads
			(clearance 0)
		)
		(min_thickness 0.25)
		(keepout
			(tracks not_allowed)
			(vias allowed)
			(pads allowed)
			(copperpour not_allowed)
			(footprints allowed)
		)
		(placement
			(enabled no)
			(sheetname "")
		)
		(fill
			(thermal_gap 0.5)
			(thermal_bridge_width 0.5)
			(island_removal_mode 0)
		)
		(polygon
			(pts
				(arc
					(start 251.599954 -143.500094)
					(mid 247.850152 -139.750292)
					(end 244.100096 -143.500094)
				)
				(arc
					(start 244.100096 -143.500094)
					(mid 247.850152 -147.25015)
					(end 251.599954 -143.500094)
				)
			)
		)
	)
	(zone
		(layer "B.Cu")
		(hatch none 0.5)
		(connect_pads
			(clearance 0)
		)
		(min_thickness 0.25)
		(keepout
			(tracks allowed)
			(vias allowed)
			(pads allowed)
			(copperpour allowed)
			(footprints not_allowed)
		)
		(placement
			(enabled no)
			(sheetname "")
		)
		(fill
			(thermal_gap 0.5)
			(thermal_bridge_width 0.5)
			(island_removal_mode 0)
		)
		(polygon
			(pts
				(arc
					(start 48.749966 -269.999968)
					(mid 44.000166 -265.250168)
					(end 39.250112 -269.999968)
				)
				(arc
					(start 39.250112 -269.999968)
					(mid 44.000166 -274.750022)
					(end 48.749966 -269.999968)
				)
			)
		)
	)
	(zone
		(layer "B.Cu")
		(hatch none 0.5)
		(connect_pads
			(clearance 0)
		)
		(min_thickness 0.25)
		(keepout
			(tracks not_allowed)
			(vias allowed)
			(pads allowed)
			(copperpour not_allowed)
			(footprints allowed)
		)
		(placement
			(enabled no)
			(sheetname "")
		)
		(fill
			(thermal_gap 0.5)
			(thermal_bridge_width 0.5)
			(island_removal_mode 0)
		)
		(polygon
			(pts
				(arc
					(start 386.298694 -21.950426)
					(mid 385.750181 -21.401532)
					(end 385.201414 -21.950172)
				)
				(arc
					(start 385.201414 -23.35022)
					(mid 385.750054 -23.89886)
					(end 386.298694 -23.35022)
				)
				(xy 386.298694 -22.892004) (xy 386.286756 -22.891496)
				(arc
					(start 385.916424 -22.891496)
					(mid 385.866135 -22.912327)
					(end 385.845304 -22.962616)
				)
				(arc
					(start 385.845304 -22.968204)
					(mid 385.750054 -23.743932)
					(end 385.654804 -22.968204)
				)
				(xy 385.654804 -22.923246)
				(arc
					(start 385.65836 -22.91969)
					(mid 385.731438 -22.77763)
					(end 385.873498 -22.704552)
				)
				(xy 385.877054 -22.700996) (xy 386.298694 -22.700996) (xy 386.298694 -22.59965) (xy 386.286756 -22.599396)
				(xy 385.877054 -22.599396)
				(arc
					(start 385.873498 -22.59584)
					(mid 385.731438 -22.522762)
					(end 385.65836 -22.380702)
				)
				(xy 385.654804 -22.377146)
				(arc
					(start 385.654804 -22.332188)
					(mid 385.750054 -21.55646)
					(end 385.845304 -22.332188)
				)
				(arc
					(start 385.845304 -22.337776)
					(mid 385.866135 -22.388065)
					(end 385.916424 -22.408896)
				)
				(xy 386.298694 -22.408896)
			)
		)
	)
	(zone
		(layer "B.Cu")
		(hatch none 0.5)
		(connect_pads
			(clearance 0)
		)
		(min_thickness 0.25)
		(keepout
			(tracks not_allowed)
			(vias allowed)
			(pads allowed)
			(copperpour not_allowed)
			(footprints allowed)
		)
		(placement
			(enabled no)
			(sheetname "")
		)
		(fill
			(thermal_gap 0.5)
			(thermal_bridge_width 0.5)
			(island_removal_mode 0)
		)
		(polygon
			(pts
				(arc
					(start 356.670102 -162.178746)
					(mid 356.289229 -161.797492)
					(end 355.908102 -162.178492)
				)
				(xy 355.908102 -162.527742)
				(arc
					(start 356.112318 -162.527742)
					(mid 356.180974 -162.500667)
					(end 356.212648 -162.434016)
				)
				(arc
					(start 356.212648 -162.434016)
					(mid 356.289224 -161.911775)
					(end 356.365302 -162.434016)
				)
				(xy 356.365302 -162.458654)
				(arc
					(start 356.363016 -162.46094)
					(mid 356.29119 -162.60603)
					(end 356.1461 -162.677856)
				)
				(xy 356.143814 -162.680142) (xy 355.908102 -162.680142) (xy 355.908102 -162.819842) (xy 356.143814 -162.819842)
				(arc
					(start 356.1461 -162.822128)
					(mid 356.29119 -162.893954)
					(end 356.363016 -163.039044)
				)
				(xy 356.365302 -163.04133)
				(arc
					(start 356.365302 -163.065968)
					(mid 356.289224 -163.588136)
					(end 356.212648 -163.065968)
				)
				(arc
					(start 356.212648 -163.065968)
					(mid 356.18096 -162.999332)
					(end 356.112318 -162.972242)
				)
				(xy 355.908102 -162.972242)
				(arc
					(start 355.908102 -163.321492)
					(mid 356.289102 -163.702492)
					(end 356.670102 -163.321492)
				)
			)
		)
	)
	(zone
		(layer "B.Cu")
		(hatch none 0.5)
		(connect_pads
			(clearance 0)
		)
		(min_thickness 0.25)
		(keepout
			(tracks not_allowed)
			(vias allowed)
			(pads allowed)
			(copperpour not_allowed)
			(footprints allowed)
		)
		(placement
			(enabled no)
			(sheetname "")
		)
		(fill
			(thermal_gap 0.5)
			(thermal_bridge_width 0.5)
			(island_removal_mode 0)
		)
		(polygon
			(pts
				(arc
					(start 178.649884 -208.499964)
					(mid 182.39994 -212.25002)
					(end 186.149996 -208.499964)
				)
				(arc
					(start 186.149996 -208.499964)
					(mid 182.39994 -204.749908)
					(end 178.649884 -208.499964)
				)
			)
		)
	)
	(zone
		(net "GND")
		(layer "B.Cu")
		(hatch none 0.5)
		(connect_pads
			(clearance 0.5)
		)
		(min_thickness 0.25)
		(fill yes
			(thermal_gap 0.5)
			(thermal_bridge_width 0.5)
			(island_removal_mode 0)
		)
		(polygon
			(pts
				(arc
					(start 249.308112 -172.577506)
					(mid 248.089411 -172.474962)
					(end 246.894858 -172.737272)
				)
				(arc
					(start 246.894858 -151.00935)
					(mid 253.391598 -148.656496)
					(end 255.271016 -142.007336)
				)
				(arc
					(start 255.271016 -142.007336)
					(mid 256.481308 -143.168969)
					(end 258.056126 -143.746982)
				)
			)
		)
	)
	(zone
		(layer "B.Cu")
		(hatch none 0.5)
		(connect_pads
			(clearance 0)
		)
		(min_thickness 0.25)
		(keepout
			(tracks allowed)
			(vias allowed)
			(pads allowed)
			(copperpour allowed)
			(footprints allowed)
		)
		(placement
			(enabled no)
			(sheetname "")
		)
		(fill
			(thermal_gap 0.5)
			(thermal_bridge_width 0.5)
			(island_removal_mode 0)
		)
		(polygon
			(pts
				(xy 29.830776 -250.022614) (xy 27.679904 -250.022614) (xy 27.679904 -244.602) (xy 29.830776 -244.602)
			)
		)
	)
	(zone
		(net "GND")
		(layer "B.Cu")
		(hatch none 0.5)
		(connect_pads
			(clearance 0.5)
		)
		(min_thickness 0.25)
		(fill yes
			(thermal_gap 0.5)
			(thermal_bridge_width 0.5)
			(island_removal_mode 0)
		)
		(polygon
			(pts
				(xy 469.559894 -231.053386) (xy 469.343994 -231.269286) (xy 469.343994 -234.056936) (xy 469.642444 -234.355386)
				(xy 477.342454 -234.355386) (xy 477.610678 -234.087162) (xy 478.458276 -234.087162) (xy 478.797366 -233.748072)
				(xy 478.797366 -232.584498) (xy 477.266254 -231.053386)
			)
		)
	)
	(zone
		(layer "B.Cu")
		(hatch none 0.5)
		(connect_pads
			(clearance 0)
		)
		(min_thickness 0.25)
		(keepout
			(tracks not_allowed)
			(vias allowed)
			(pads allowed)
			(copperpour not_allowed)
			(footprints allowed)
		)
		(placement
			(enabled no)
			(sheetname "")
		)
		(fill
			(thermal_gap 0.5)
			(thermal_bridge_width 0.5)
			(island_removal_mode 0)
		)
		(polygon
			(pts
				(arc
					(start 271.970754 -315.92139)
					(mid 271.58696 -316.304803)
					(end 271.9705 -316.68847)
				)
				(arc
					(start 273.1135 -316.68847)
					(mid 273.49704 -316.30493)
					(end 273.1135 -315.92139)
				)
				(arc
					(start 272.768568 -315.92139)
					(mid 272.765366 -315.94823)
					(end 272.76425 -315.975238)
				)
				(arc
					(start 272.76425 -316.123828)
					(mid 272.791127 -316.193946)
					(end 272.857976 -316.228222)
				)
				(arc
					(start 272.857976 -316.228222)
					(mid 273.380217 -316.304676)
					(end 272.857976 -316.38113)
				)
				(xy 272.837656 -316.38113)
				(arc
					(start 272.83537 -316.378844)
					(mid 272.687253 -316.305727)
					(end 272.614136 -316.15761)
				)
				(xy 272.61185 -316.155324) (xy 272.61185 -315.943742) (xy 272.612866 -315.942726) (xy 272.614644 -315.92139)
				(arc
					(start 272.474436 -315.92139)
					(mid 272.472724 -315.94829)
					(end 272.47215 -315.975238)
				)
				(xy 272.47215 -316.155324)
				(arc
					(start 272.469864 -316.15761)
					(mid 272.396747 -316.305727)
					(end 272.24863 -316.378844)
				)
				(xy 272.246344 -316.38113)
				(arc
					(start 272.226024 -316.38113)
					(mid 271.703783 -316.304676)
					(end 272.226024 -316.228222)
				)
				(arc
					(start 272.226024 -316.228222)
					(mid 272.292939 -316.194005)
					(end 272.31975 -316.123828)
				)
				(xy 272.31975 -315.943742) (xy 272.320512 -315.94298) (xy 272.321528 -315.92139)
			)
		)
	)
	(zone
		(net "GND")
		(layer "B.Cu")
		(hatch none 0.5)
		(connect_pads
			(clearance 0.5)
		)
		(min_thickness 0.25)
		(fill yes
			(thermal_gap 0.5)
			(thermal_bridge_width 0.5)
			(island_removal_mode 0)
		)
		(polygon
			(pts
				(xy 343.01303 -94.6658)
				(arc
					(start 349.358712 -85.434678)
					(mid 347.720414 -82.962647)
					(end 348.1832 -80.033368)
				)
				(arc
					(start 348.1832 -78.386686)
					(mid 347.369886 -78.111178)
					(end 346.632022 -77.67193)
				)
				(arc
					(start 346.632022 -77.67193)
					(mid 344.059682 -77.85016)
					(end 341.891874 -76.454)
				)
				(xy 339.397086 -76.454)
				(arc
					(start 337.50377 -77.782166)
					(mid 335.850863 -80.285031)
					(end 332.934818 -80.987138)
				)
				(xy 332.2574 -81.462372) (xy 332.2574 -81.9658)
				(arc
					(start 332.410562 -82.118962)
					(mid 338.917568 -85.788634)
					(end 341.496142 -92.799916)
				)
				(xy 341.496142 -94.277942) (xy 341.884 -94.6658)
			)
		)
	)
	(zone
		(layer "B.Cu")
		(hatch none 0.5)
		(connect_pads
			(clearance 0)
		)
		(min_thickness 0.25)
		(keepout
			(tracks not_allowed)
			(vias allowed)
			(pads allowed)
			(copperpour not_allowed)
			(footprints allowed)
		)
		(placement
			(enabled no)
			(sheetname "")
		)
		(fill
			(thermal_gap 0.5)
			(thermal_bridge_width 0.5)
			(island_removal_mode 0)
		)
		(polygon
			(pts
				(arc
					(start 286.436562 -317.556388)
					(mid 285.887922 -318.105028)
					(end 286.436562 -318.653668)
				)
				(arc
					(start 286.935926 -318.653668)
					(mid 286.921941 -318.584734)
					(end 286.915098 -318.51473)
				)
				(xy 286.914336 -318.513968)
				(arc
					(start 286.914336 -318.232028)
					(mid 286.899457 -318.196107)
					(end 286.863536 -318.181228)
				)
				(arc
					(start 286.822896 -318.181228)
					(mid 286.042785 -318.105028)
					(end 286.822896 -318.028828)
				)
				(xy 286.895032 -318.028828)
				(arc
					(start 286.89808 -318.031876)
					(mid 287.007157 -318.088407)
					(end 287.063688 -318.197484)
				)
				(xy 287.066736 -318.200532)
				(arc
					(start 287.066736 -318.482726)
					(mid 287.073831 -318.569352)
					(end 287.09493 -318.653668)
				)
				(arc
					(start 287.245806 -318.653668)
					(mid 287.220395 -318.586334)
					(end 287.207706 -318.515492)
				)
				(xy 287.206436 -318.513968) (xy 287.206436 -318.200532)
				(arc
					(start 287.209484 -318.197484)
					(mid 287.266015 -318.088407)
					(end 287.375092 -318.031876)
				)
				(xy 287.37814 -318.028828)
				(arc
					(start 287.450276 -318.028828)
					(mid 288.230387 -318.105028)
					(end 287.450276 -318.181228)
				)
				(arc
					(start 287.409636 -318.181228)
					(mid 287.373715 -318.196107)
					(end 287.358836 -318.232028)
				)
				(arc
					(start 287.358836 -318.482472)
					(mid 287.377127 -318.574425)
					(end 287.429194 -318.652398)
				)
				(xy 287.430464 -318.653668)
				(arc
					(start 287.83661 -318.653668)
					(mid 288.38525 -318.105028)
					(end 287.83661 -317.556388)
				)
				(xy 286.436816 -317.556388)
			)
		)
	)
	(zone
		(layer "B.Cu")
		(hatch none 0.5)
		(connect_pads
			(clearance 0)
		)
		(min_thickness 0.25)
		(keepout
			(tracks allowed)
			(vias allowed)
			(pads allowed)
			(copperpour allowed)
			(footprints not_allowed)
		)
		(placement
			(enabled no)
			(sheetname "")
		)
		(fill
			(thermal_gap 0.5)
			(thermal_bridge_width 0.5)
			(island_removal_mode 0)
		)
		(polygon
			(pts
				(arc
					(start 171.224956 -5.199888)
					(mid 172.32503 -6.299962)
					(end 173.425104 -5.199888)
				)
				(arc
					(start 173.425104 -5.199888)
					(mid 172.32503 -4.099814)
					(end 171.224956 -5.199888)
				)
			)
		)
	)
	(zone
		(layer "B.Cu")
		(hatch none 0.5)
		(connect_pads
			(clearance 0)
		)
		(min_thickness 0.25)
		(keepout
			(tracks not_allowed)
			(vias allowed)
			(pads allowed)
			(copperpour not_allowed)
			(footprints allowed)
		)
		(placement
			(enabled no)
			(sheetname "")
		)
		(fill
			(thermal_gap 0.5)
			(thermal_bridge_width 0.5)
			(island_removal_mode 0)
		)
		(polygon
			(pts
				(arc
					(start 388.21995 -277.17877)
					(mid 387.839077 -276.797516)
					(end 387.45795 -277.178516)
				)
				(xy 387.45795 -277.527766)
				(arc
					(start 387.662166 -277.527766)
					(mid 387.730822 -277.500691)
					(end 387.762496 -277.43404)
				)
				(arc
					(start 387.762496 -277.43404)
					(mid 387.839072 -276.911799)
					(end 387.91515 -277.43404)
				)
				(xy 387.91515 -277.458678)
				(arc
					(start 387.912864 -277.460964)
					(mid 387.841038 -277.606054)
					(end 387.695948 -277.67788)
				)
				(xy 387.693662 -277.680166) (xy 387.45795 -277.680166) (xy 387.45795 -277.819866) (xy 387.693662 -277.819866)
				(arc
					(start 387.695948 -277.822152)
					(mid 387.841038 -277.893978)
					(end 387.912864 -278.039068)
				)
				(xy 387.91515 -278.041354)
				(arc
					(start 387.91515 -278.065992)
					(mid 387.839072 -278.58816)
					(end 387.762496 -278.065992)
				)
				(arc
					(start 387.762496 -278.065992)
					(mid 387.730808 -277.999356)
					(end 387.662166 -277.972266)
				)
				(xy 387.45795 -277.972266)
				(arc
					(start 387.45795 -278.321516)
					(mid 387.83895 -278.702516)
					(end 388.21995 -278.321516)
				)
			)
		)
	)
	(zone
		(layer "B.Cu")
		(hatch none 0.5)
		(connect_pads
			(clearance 0)
		)
		(min_thickness 0.25)
		(keepout
			(tracks allowed)
			(vias allowed)
			(pads allowed)
			(copperpour allowed)
			(footprints not_allowed)
		)
		(placement
			(enabled no)
			(sheetname "")
		)
		(fill
			(thermal_gap 0.5)
			(thermal_bridge_width 0.5)
			(island_removal_mode 0)
		)
		(polygon
			(pts
				(arc
					(start 403.349968 -164.200078)
					(mid 407.100024 -167.950134)
					(end 410.85008 -164.200078)
				)
				(arc
					(start 410.85008 -164.200078)
					(mid 407.100024 -160.450022)
					(end 403.349968 -164.200078)
				)
			)
		)
	)
	(zone
		(layer "B.Cu")
		(hatch none 0.5)
		(connect_pads
			(clearance 0)
		)
		(min_thickness 0.25)
		(keepout
			(tracks not_allowed)
			(vias allowed)
			(pads allowed)
			(copperpour not_allowed)
			(footprints allowed)
		)
		(placement
			(enabled no)
			(sheetname "")
		)
		(fill
			(thermal_gap 0.5)
			(thermal_bridge_width 0.5)
			(island_removal_mode 0)
		)
		(polygon
			(pts
				(arc
					(start 7.599934 -5.500116)
					(mid 3.850132 -1.750314)
					(end 0.100076 -5.500116)
				)
				(arc
					(start 0.100076 -5.500116)
					(mid 3.850132 -9.250172)
					(end 7.599934 -5.500116)
				)
			)
		)
	)
	(zone
		(layer "B.Cu")
		(hatch none 0.5)
		(connect_pads
			(clearance 0)
		)
		(min_thickness 0.25)
		(keepout
			(tracks not_allowed)
			(vias allowed)
			(pads allowed)
			(copperpour not_allowed)
			(footprints allowed)
		)
		(placement
			(enabled no)
			(sheetname "")
		)
		(fill
			(thermal_gap 0.5)
			(thermal_bridge_width 0.5)
			(island_removal_mode 0)
		)
		(polygon
			(pts
				(arc
					(start 40.32504 -207.79994)
					(mid 33.325054 -200.799954)
					(end 26.325068 -207.79994)
				)
				(arc
					(start 26.325068 -213.799928)
					(mid 33.325054 -220.799914)
					(end 40.32504 -213.799928)
				)
			)
		)
	)
	(zone
		(net "GND")
		(layer "B.Cu")
		(hatch none 0.5)
		(connect_pads
			(clearance 0.5)
		)
		(min_thickness 0.25)
		(fill yes
			(thermal_gap 0.5)
			(thermal_bridge_width 0.5)
			(island_removal_mode 0)
		)
		(polygon
			(pts
				(arc
					(start 245.287292 -303.087024)
					(mid 246.460896 -303.965069)
					(end 247.868694 -304.373026)
				)
				(xy 247.922542 -304.396394)
				(arc
					(start 243.566442 -308.752494)
					(mid 242.47446 -309.534524)
					(end 241.69243 -310.626506)
				)
				(xy 222.944944 -329.373992)
				(arc
					(start 236.018832 -286.282892)
					(mid 237.411616 -287.627144)
					(end 239.02162 -288.701734)
				)
				(arc
					(start 239.02162 -288.701734)
					(mid 238.362349 -291.525574)
					(end 239.740694 -294.076882)
				)
				(arc
					(start 239.740694 -294.076882)
					(mid 239.497611 -295.026419)
					(end 239.487456 -296.00652)
				)
				(arc
					(start 239.487456 -296.00652)
					(mid 239.55606 -299.138232)
					(end 241.820192 -301.302928)
				)
				(arc
					(start 241.820192 -301.302928)
					(mid 242.679323 -301.914526)
					(end 243.666264 -302.286162)
				)
				(arc
					(start 243.666264 -302.286162)
					(mid 244.431979 -302.777266)
					(end 245.287292 -303.087024)
				)
			)
		)
	)
	(zone
		(layer "B.Cu")
		(hatch none 0.5)
		(connect_pads
			(clearance 0)
		)
		(min_thickness 0.25)
		(keepout
			(tracks allowed)
			(vias allowed)
			(pads allowed)
			(copperpour allowed)
			(footprints not_allowed)
		)
		(placement
			(enabled no)
			(sheetname "")
		)
		(fill
			(thermal_gap 0.5)
			(thermal_bridge_width 0.5)
			(island_removal_mode 0)
		)
		(polygon
			(pts
				(arc
					(start 276.800056 -414.219898)
					(mid 280.550112 -417.969954)
					(end 284.299914 -414.219898)
				)
				(arc
					(start 284.299914 -414.219898)
					(mid 280.550112 -410.470096)
					(end 276.800056 -414.219898)
				)
			)
		)
	)
	(zone
		(layer "B.Cu")
		(hatch none 0.5)
		(connect_pads
			(clearance 0)
		)
		(min_thickness 0.25)
		(keepout
			(tracks allowed)
			(vias allowed)
			(pads allowed)
			(copperpour allowed)
			(footprints not_allowed)
		)
		(placement
			(enabled no)
			(sheetname "")
		)
		(fill
			(thermal_gap 0.5)
			(thermal_bridge_width 0.5)
			(island_removal_mode 0)
		)
		(polygon
			(pts
				(xy 13.850112 -209.199988) (xy 0 -209.199988) (xy 0 -258.99999) (xy 200.000108 -258.99999) (xy 200.000108 -300.999906)
				(xy 0 -300.999906)
				(arc
					(start 0 -348.199964)
					(mid 0.292893 -348.907069)
					(end 0.999998 -349.199962)
				)
				(arc
					(start 189.6999 -349.199962)
					(mid 190.407005 -349.492855)
					(end 190.699898 -350.19996)
				)
				(arc
					(start 190.699898 -372.000018)
					(mid 190.992791 -372.707123)
					(end 191.699896 -373.000016)
				)
				(arc
					(start 199.00011 -373.000016)
					(mid 199.707215 -373.292909)
					(end 200.000108 -374.000014)
				)
				(arc
					(start 200.000108 -420.200074)
					(mid 200.293001 -420.907179)
					(end 201.000106 -421.200072)
				)
				(arc
					(start 308.99989 -421.200072)
					(mid 309.706995 -420.907179)
					(end 309.999888 -420.200074)
				)
				(arc
					(start 309.999888 -375.000012)
					(mid 309.706995 -374.292907)
					(end 308.99989 -374.000014)
				)
				(arc
					(start 296.69994 -374.000014)
					(mid 295.992835 -373.707121)
					(end 295.699942 -373.000016)
				)
				(arc
					(start 295.699942 -350.19996)
					(mid 295.992835 -349.492855)
					(end 296.69994 -349.199962)
				)
				(arc
					(start 490.450124 -349.199962)
					(mid 491.157229 -348.907069)
					(end 491.450122 -348.199964)
				)
				(xy 491.450122 -300.999906) (xy 289.999928 -300.999906) (xy 289.999928 -258.99999) (xy 491.450122 -258.99999)
				(xy 491.450122 -209.199988) (xy 476.25 -209.199988) (xy 476.25 -149.200108) (xy 392.34999 -149.200108)
				(xy 392.34999 -135.359902)
				(arc
					(start 306.598066 -135.359902)
					(mid 307.047904 -136.748339)
					(end 307.200046 -138.199876)
				)
				(arc
					(start 307.200046 -144.200118)
					(mid 300.20006 -151.200104)
					(end 293.200074 -144.200118)
				)
				(arc
					(start 293.200074 -138.199876)
					(mid 293.352225 -136.748341)
					(end 293.802054 -135.359902)
				)
				(xy 281.850084 -135.359902) (xy 281.850084 -99.199954) (xy 251.84989 -99.199954) (xy 251.84989 -209.199988)
				(xy 225.849942 -209.199988) (xy 225.849942 -99.199954) (xy 215.35009 -99.199954) (xy 215.35009 -149.200108)
				(xy 146.349974 -149.200108) (xy 146.349974 -134.199884) (xy 13.850112 -134.199884)
			)
		)
	)
	(zone
		(layer "B.Cu")
		(hatch none 0.5)
		(connect_pads
			(clearance 0)
		)
		(min_thickness 0.25)
		(keepout
			(tracks not_allowed)
			(vias allowed)
			(pads allowed)
			(copperpour not_allowed)
			(footprints allowed)
		)
		(placement
			(enabled no)
			(sheetname "")
		)
		(fill
			(thermal_gap 0.5)
			(thermal_bridge_width 0.5)
			(island_removal_mode 0)
		)
		(polygon
			(pts
				(arc
					(start 286.436562 -299.556424)
					(mid 285.887922 -300.105064)
					(end 286.436562 -300.653704)
				)
				(arc
					(start 286.935926 -300.653704)
					(mid 286.921941 -300.58477)
					(end 286.915098 -300.514766)
				)
				(xy 286.914336 -300.514004)
				(arc
					(start 286.914336 -300.232064)
					(mid 286.899457 -300.196143)
					(end 286.863536 -300.181264)
				)
				(arc
					(start 286.822896 -300.181264)
					(mid 286.042785 -300.105064)
					(end 286.822896 -300.028864)
				)
				(xy 286.895032 -300.028864)
				(arc
					(start 286.89808 -300.031912)
					(mid 287.007157 -300.088443)
					(end 287.063688 -300.19752)
				)
				(xy 287.066736 -300.200568)
				(arc
					(start 287.066736 -300.482762)
					(mid 287.073831 -300.569388)
					(end 287.09493 -300.653704)
				)
				(arc
					(start 287.245806 -300.653704)
					(mid 287.220395 -300.58637)
					(end 287.207706 -300.515528)
				)
				(xy 287.206436 -300.514004) (xy 287.206436 -300.200568)
				(arc
					(start 287.209484 -300.19752)
					(mid 287.266015 -300.088443)
					(end 287.375092 -300.031912)
				)
				(xy 287.37814 -300.028864)
				(arc
					(start 287.450276 -300.028864)
					(mid 288.230387 -300.105064)
					(end 287.450276 -300.181264)
				)
				(arc
					(start 287.409636 -300.181264)
					(mid 287.373715 -300.196143)
					(end 287.358836 -300.232064)
				)
				(arc
					(start 287.358836 -300.482508)
					(mid 287.377127 -300.574461)
					(end 287.429194 -300.652434)
				)
				(xy 287.430464 -300.653704)
				(arc
					(start 287.83661 -300.653704)
					(mid 288.38525 -300.105064)
					(end 287.83661 -299.556424)
				)
				(xy 286.436816 -299.556424)
			)
		)
	)
	(zone
		(net "GND")
		(layer "B.Cu")
		(hatch none 0.5)
		(connect_pads
			(clearance 0.5)
		)
		(min_thickness 0.25)
		(fill yes
			(thermal_gap 0.5)
			(thermal_bridge_width 0.5)
			(island_removal_mode 0)
		)
		(polygon
			(pts
				(xy 267.4112 -325.1454)
				(arc
					(start 266.060428 -323.794628)
					(mid 262.10409 -321.130672)
					(end 263.361424 -316.52972)
				)
				(arc
					(start 263.361424 -316.52972)
					(mid 264.810329 -314.902803)
					(end 266.888976 -314.250578)
				)
				(xy 266.888976 -311.237376) (xy 266.1666 -310.515) (xy 265.483848 -310.515) (xy 261.915402 -314.083446)
				(xy 252.489208 -314.083446)
				(arc
					(start 233.19105 -333.381604)
					(mid 232.940724 -333.819968)
					(end 232.6386 -334.224376)
				)
				(xy 232.6386 -334.4926) (xy 233.0196 -334.8736)
				(arc
					(start 254.433324 -334.8736)
					(mid 256.462069 -332.608718)
					(end 259.493258 -332.369922)
				)
				(arc
					(start 259.493258 -332.369922)
					(mid 261.094803 -332.313471)
					(end 262.595106 -332.876652)
				)
				(arc
					(start 262.595106 -332.876652)
					(mid 264.739788 -332.259949)
					(end 266.888976 -332.86065)
				)
				(arc
					(start 266.888976 -328.905108)
					(mid 267.021701 -327.874778)
					(end 267.4112 -326.911716)
				)
			)
		)
	)
	(zone
		(layer "B.Cu")
		(hatch none 0.5)
		(connect_pads
			(clearance 0)
		)
		(min_thickness 0.25)
		(keepout
			(tracks allowed)
			(vias allowed)
			(pads allowed)
			(copperpour allowed)
			(footprints not_allowed)
		)
		(placement
			(enabled no)
			(sheetname "")
		)
		(fill
			(thermal_gap 0.5)
			(thermal_bridge_width 0.5)
			(island_removal_mode 0)
		)
		(polygon
			(pts
				(arc
					(start 171.075096 -9.19988)
					(mid 166.325042 -4.449826)
					(end 161.574988 -9.19988)
				)
				(arc
					(start 161.574988 -9.19988)
					(mid 166.325042 -13.949934)
					(end 171.075096 -9.19988)
				)
			)
		)
	)
	(zone
		(net "P5V_B_LL_R")
		(layer "B.Cu")
		(hatch none 0.5)
		(connect_pads
			(clearance 0.5)
		)
		(min_thickness 0.25)
		(fill yes
			(thermal_gap 0.5)
			(thermal_bridge_width 0.5)
			(island_removal_mode 0)
		)
		(polygon
			(pts
				(xy 55.108602 -148.44395) (xy 54.930802 -148.62175) (xy 54.930802 -150.163276) (xy 55.144924 -150.377398)
				(xy 55.782972 -150.377398) (xy 55.91429 -150.508716) (xy 55.91429 -151.535638) (xy 56.200802 -151.82215)
				(xy 56.93664 -151.82215) (xy 57.19064 -151.56815) (xy 57.19064 -148.620988) (xy 57.013602 -148.44395)
			)
		)
		(polygon
			(pts
				(xy 56.681624 -150.266654) (xy 56.478424 -150.266654) (xy 56.478424 -150.469854) (xy 56.681624 -150.469854)
			)
		)
		(polygon
			(pts
				(xy 56.681624 -149.657054) (xy 56.478424 -149.657054) (xy 56.478424 -149.860254) (xy 56.681624 -149.860254)
			)
		)
		(polygon
			(pts
				(xy 56.474614 -149.286976) (xy 56.271414 -149.286976) (xy 56.271414 -149.490176) (xy 56.474614 -149.490176)
			)
		)
		(polygon
			(pts
				(xy 55.812944 -148.862796) (xy 55.609744 -148.862796) (xy 55.609744 -149.065996) (xy 55.812944 -149.065996)
			)
		)
		(polygon
			(pts
				(xy 55.254144 -148.862796) (xy 55.050944 -148.862796) (xy 55.050944 -149.065996) (xy 55.254144 -149.065996)
			)
		)
	)
	(zone
		(layer "B.Cu")
		(hatch none 0.5)
		(connect_pads
			(clearance 0)
		)
		(min_thickness 0.25)
		(keepout
			(tracks allowed)
			(vias allowed)
			(pads allowed)
			(copperpour allowed)
			(footprints not_allowed)
		)
		(placement
			(enabled no)
			(sheetname "")
		)
		(fill
			(thermal_gap 0.5)
			(thermal_bridge_width 0.5)
			(island_removal_mode 0)
		)
		(polygon
			(pts
				(arc
					(start 343.250012 -164.200078)
					(mid 347.000068 -167.950134)
					(end 350.750124 -164.200078)
				)
				(arc
					(start 350.750124 -164.200078)
					(mid 347.000068 -160.450022)
					(end 343.250012 -164.200078)
				)
			)
		)
	)
	(zone
		(layer "B.Cu")
		(hatch none 0.5)
		(connect_pads
			(clearance 0)
		)
		(min_thickness 0.25)
		(keepout
			(tracks allowed)
			(vias allowed)
			(pads allowed)
			(copperpour allowed)
			(footprints not_allowed)
		)
		(placement
			(enabled no)
			(sheetname "")
		)
		(fill
			(thermal_gap 0.5)
			(thermal_bridge_width 0.5)
			(island_removal_mode 0)
		)
		(polygon
			(pts
				(arc
					(start 40.32504 -322.799964)
					(mid 33.325054 -315.799978)
					(end 26.325068 -322.799964)
				)
				(arc
					(start 26.325068 -328.799952)
					(mid 33.325054 -335.799938)
					(end 40.32504 -328.799952)
				)
			)
		)
	)
	(zone
		(net "AGND_P5V_D")
		(layer "B.Cu")
		(hatch none 0.5)
		(connect_pads
			(clearance 0.5)
		)
		(min_thickness 0.25)
		(fill yes
			(thermal_gap 0.5)
			(thermal_bridge_width 0.5)
			(island_removal_mode 0)
		)
		(polygon
			(pts
				(xy 479.66884 -231.756458) (xy 479.480372 -231.944926) (xy 479.480372 -234.131866) (xy 479.704654 -234.356148)
				(xy 479.704654 -234.364784) (xy 480.643692 -234.364784) (xy 481.095558 -233.912918) (xy 481.095558 -232.021888)
				(xy 480.830128 -231.756458)
			)
		)
	)
	(zone
		(layer "B.Cu")
		(hatch none 0.5)
		(connect_pads
			(clearance 0)
		)
		(min_thickness 0.25)
		(keepout
			(tracks allowed)
			(vias allowed)
			(pads allowed)
			(copperpour allowed)
			(footprints not_allowed)
		)
		(placement
			(enabled no)
			(sheetname "")
		)
		(fill
			(thermal_gap 0.5)
			(thermal_bridge_width 0.5)
			(island_removal_mode 0)
		)
		(polygon
			(pts
				(arc
					(start 166.325042 -322.799964)
					(mid 159.325056 -315.799978)
					(end 152.32507 -322.799964)
				)
				(arc
					(start 152.32507 -328.799952)
					(mid 159.325056 -335.799938)
					(end 166.325042 -328.799952)
				)
			)
		)
	)
	(zone
		(layer "B.Cu")
		(hatch none 0.5)
		(connect_pads
			(clearance 0)
		)
		(min_thickness 0.25)
		(keepout
			(tracks not_allowed)
			(vias allowed)
			(pads allowed)
			(copperpour not_allowed)
			(footprints allowed)
		)
		(placement
			(enabled no)
			(sheetname "")
		)
		(fill
			(thermal_gap 0.5)
			(thermal_bridge_width 0.5)
			(island_removal_mode 0)
		)
		(polygon
			(pts
				(arc
					(start 388.098538 -20.950428)
					(mid 387.550025 -20.401534)
					(end 387.001258 -20.950174)
				)
				(arc
					(start 387.001258 -22.350222)
					(mid 387.549898 -22.898862)
					(end 388.098538 -22.350222)
				)
				(xy 388.098538 -21.893022) (xy 388.078472 -21.891498)
				(arc
					(start 387.716268 -21.891498)
					(mid 387.665979 -21.912329)
					(end 387.645148 -21.962618)
				)
				(arc
					(start 387.645148 -21.968206)
					(mid 387.549898 -22.743934)
					(end 387.454648 -21.968206)
				)
				(xy 387.454648 -21.923248)
				(arc
					(start 387.458204 -21.919692)
					(mid 387.531282 -21.777632)
					(end 387.673342 -21.704554)
				)
				(xy 387.676898 -21.700998) (xy 388.098538 -21.700998) (xy 388.098538 -21.599906) (xy 388.078472 -21.599398)
				(xy 387.676898 -21.599398)
				(arc
					(start 387.673342 -21.595842)
					(mid 387.531282 -21.522764)
					(end 387.458204 -21.380704)
				)
				(xy 387.454648 -21.377148)
				(arc
					(start 387.454648 -21.33219)
					(mid 387.549898 -20.556462)
					(end 387.645148 -21.33219)
				)
				(arc
					(start 387.645148 -21.337778)
					(mid 387.665979 -21.388067)
					(end 387.716268 -21.408898)
				)
				(xy 388.098538 -21.408898)
			)
		)
	)
	(zone
		(net "GND")
		(layer "B.Cu")
		(hatch none 0.5)
		(connect_pads
			(clearance 0.5)
		)
		(min_thickness 0.25)
		(fill yes
			(thermal_gap 0.5)
			(thermal_bridge_width 0.5)
			(island_removal_mode 0)
		)
		(polygon
			(pts
				(arc
					(start 32.374078 -53.400706)
					(mid 35.33559 -52.25949)
					(end 36.574476 -49.337468)
				)
				(arc
					(start 36.574476 -46.162468)
					(mid 36.552876 -45.744196)
					(end 36.48837 -45.330364)
				)
				(arc
					(start 40.98036 -45.330364)
					(mid 41.743561 -48.028853)
					(end 44.065444 -49.601374)
				)
				(arc
					(start 44.065444 -49.601374)
					(mid 43.849909 -50.648477)
					(end 43.913044 -51.71567)
				)
				(arc
					(start 43.913044 -51.71567)
					(mid 40.146175 -55.954419)
					(end 44.233846 -59.884818)
				)
				(arc
					(start 46.122336 -59.884818)
					(mid 46.223789 -60.550954)
					(end 46.433232 -61.191394)
				)
				(arc
					(start 46.392592 -61.291978)
					(mid 42.931664 -60.766155)
					(end 40.331644 -63.11011)
				)
				(arc
					(start 40.331644 -63.11011)
					(mid 40.279217 -62.35786)
					(end 40.089582 -61.62802)
				)
				(arc
					(start 40.089582 -61.62802)
					(mid 39.276035 -57.495287)
					(end 35.245548 -56.272176)
				)
			)
		)
	)
	(zone
		(layer "B.Cu")
		(hatch none 0.5)
		(connect_pads
			(clearance 0)
		)
		(min_thickness 0.25)
		(keepout
			(tracks allowed)
			(vias allowed)
			(pads allowed)
			(copperpour allowed)
			(footprints allowed)
		)
		(placement
			(enabled no)
			(sheetname "")
		)
		(fill
			(thermal_gap 0.5)
			(thermal_bridge_width 0.5)
			(island_removal_mode 0)
		)
		(polygon
			(pts
				(xy 468.088472 -236.137704) (xy 471.390472 -236.137704) (xy 471.390472 -243.022628) (xy 468.088472 -243.022628)
			)
		)
	)
	(zone
		(net "P5V_B")
		(layer "B.Cu")
		(hatch none 0.5)
		(connect_pads
			(clearance 0.5)
		)
		(min_thickness 0.25)
		(fill yes
			(thermal_gap 0.5)
			(thermal_bridge_width 0.5)
			(island_removal_mode 0)
		)
		(polygon
			(pts
				(xy 239.439196 -350.064578) (xy 230.743252 -358.760522) (xy 221.629478 -358.760522) (xy 220.9038 -359.4862)
				(xy 220.9038 -361.8484) (xy 221.361 -362.3056) (xy 231.74198 -362.3056) (xy 241.602006 -352.445574)
				(xy 248.199148 -352.445574) (xy 259.04571 -363.292136) (xy 289.809936 -363.292136) (xy 290.2966 -363.7788)
				(xy 290.6776 -363.7788) (xy 292.2016 -362.2548) (xy 292.2016 -361.30738) (xy 291.3888 -360.49458)
				(xy 261.48538 -360.49458) (xy 251.055378 -350.064578)
			)
		)
	)
	(zone
		(net "GND")
		(layer "B.Cu")
		(hatch none 0.5)
		(connect_pads
			(clearance 0.5)
		)
		(min_thickness 0.25)
		(fill yes
			(thermal_gap 0.5)
			(thermal_bridge_width 0.5)
			(island_removal_mode 0)
		)
		(polygon
			(pts
				(xy 441.958222 -219.8624) (xy 439.70067 -222.90786)
				(arc
					(start 436.12435 -225.683318)
					(mid 436.52376 -229.824476)
					(end 433.089812 -232.173272)
				)
				(arc
					(start 433.089812 -232.173272)
					(mid 433.292363 -236.712288)
					(end 429.176942 -238.637826)
				)
				(arc
					(start 429.176942 -238.637826)
					(mid 429.93903 -239.382727)
					(end 430.482756 -240.29924)
				)
				(xy 437.782716 -240.29924) (xy 438.610756 -239.4712)
				(arc
					(start 442.818012 -239.4712)
					(mid 445.008 -231.926699)
					(end 447.197988 -239.4712)
				)
				(arc
					(start 447.232786 -239.4712)
					(mid 448.621084 -239.726921)
					(end 449.827142 -240.46053)
				)
				(arc
					(start 449.827142 -240.46053)
					(mid 450.657252 -240.184071)
					(end 451.527164 -240.090452)
				)
				(arc
					(start 452.797164 -240.090452)
					(mid 454.122521 -240.311093)
					(end 455.304906 -240.949226)
				)
				(arc
					(start 455.304906 -240.949226)
					(mid 456.146629 -240.681221)
					(end 457.026264 -240.60023)
				)
				(arc
					(start 457.026264 -240.60023)
					(mid 458.213387 -240.256762)
					(end 459.448916 -240.283492)
				)
				(arc
					(start 459.448916 -239.449356)
					(mid 456.655259 -236.032502)
					(end 458.592428 -232.066846)
				)
				(arc
					(start 458.592428 -232.066846)
					(mid 458.641079 -231.981926)
					(end 458.691742 -231.89819)
				)
				(arc
					(start 458.691742 -231.89819)
					(mid 458.566302 -229.782029)
					(end 459.516988 -227.887276)
				)
				(arc
					(start 459.516988 -227.887276)
					(mid 459.2123 -226.712841)
					(end 459.265528 -225.500692)
				)
				(arc
					(start 459.265528 -225.500692)
					(mid 459.256283 -224.888865)
					(end 459.338426 -224.282508)
				)
				(arc
					(start 459.338426 -224.282508)
					(mid 452.828431 -223.908832)
					(end 447.715132 -219.8624)
				)
			)
		)
	)
	(zone
		(layer "B.Cu")
		(hatch none 0.5)
		(connect_pads
			(clearance 0)
		)
		(min_thickness 0.25)
		(keepout
			(tracks not_allowed)
			(vias allowed)
			(pads allowed)
			(copperpour not_allowed)
			(footprints allowed)
		)
		(placement
			(enabled no)
			(sheetname "")
		)
		(fill
			(thermal_gap 0.5)
			(thermal_bridge_width 0.5)
			(island_removal_mode 0)
		)
		(polygon
			(pts
				(arc
					(start 271.970754 -314.121546)
					(mid 271.58696 -314.504959)
					(end 271.9705 -314.888626)
				)
				(arc
					(start 273.1135 -314.888626)
					(mid 273.49704 -314.505086)
					(end 273.1135 -314.121546)
				)
				(arc
					(start 272.768568 -314.121546)
					(mid 272.765366 -314.148386)
					(end 272.76425 -314.175394)
				)
				(arc
					(start 272.76425 -314.323984)
					(mid 272.791127 -314.394102)
					(end 272.857976 -314.428378)
				)
				(arc
					(start 272.857976 -314.428378)
					(mid 273.380217 -314.504832)
					(end 272.857976 -314.581286)
				)
				(xy 272.837656 -314.581286)
				(arc
					(start 272.83537 -314.579)
					(mid 272.687253 -314.505883)
					(end 272.614136 -314.357766)
				)
				(xy 272.61185 -314.35548) (xy 272.61185 -314.143898) (xy 272.612866 -314.142882) (xy 272.614644 -314.121546)
				(arc
					(start 272.474436 -314.121546)
					(mid 272.472724 -314.148446)
					(end 272.47215 -314.175394)
				)
				(xy 272.47215 -314.35548)
				(arc
					(start 272.469864 -314.357766)
					(mid 272.396747 -314.505883)
					(end 272.24863 -314.579)
				)
				(xy 272.246344 -314.581286)
				(arc
					(start 272.226024 -314.581286)
					(mid 271.703783 -314.504832)
					(end 272.226024 -314.428378)
				)
				(arc
					(start 272.226024 -314.428378)
					(mid 272.292939 -314.394161)
					(end 272.31975 -314.323984)
				)
				(xy 272.31975 -314.143898) (xy 272.320512 -314.143136) (xy 272.321528 -314.121546)
			)
		)
	)
	(zone
		(net "GND")
		(layer "B.Cu")
		(hatch none 0.5)
		(connect_pads
			(clearance 0.5)
		)
		(min_thickness 0.25)
		(fill yes
			(thermal_gap 0.5)
			(thermal_bridge_width 0.5)
			(island_removal_mode 0)
		)
		(polygon
			(pts
				(xy 184.907682 -224.838006) (xy 184.815226 -224.930462) (xy 184.815226 -225.678492) (xy 184.70118 -225.792538)
				(xy 183.41975 -225.792538) (xy 182.850282 -226.362006) (xy 182.189882 -226.362006) (xy 181.961282 -226.590606)
				(xy 181.961282 -227.251006) (xy 182.164482 -227.454206) (xy 183.666384 -227.454206) (xy 184.529984 -226.590606)
				(xy 186.380882 -226.590606) (xy 186.482482 -226.489006) (xy 186.482482 -224.888806) (xy 186.431682 -224.838006)
			)
		)
	)
	(zone
		(net "P12V_A")
		(layer "B.Cu")
		(hatch none 0.5)
		(connect_pads
			(clearance 0.5)
		)
		(min_thickness 0.25)
		(fill yes
			(thermal_gap 0.5)
			(thermal_bridge_width 0.5)
			(island_removal_mode 0)
		)
		(polygon
			(pts
				(xy 174.852838 -149.04847) (xy 174.679102 -149.222206) (xy 174.679102 -155.65247) (xy 175.314102 -156.28747)
				(xy 179.124102 -156.28747) (xy 179.505102 -155.90647) (xy 179.505102 -149.30247) (xy 179.251102 -149.04847)
			)
		)
	)
	(zone
		(layer "B.Cu")
		(hatch none 0.5)
		(connect_pads
			(clearance 0)
		)
		(min_thickness 0.25)
		(keepout
			(tracks not_allowed)
			(vias allowed)
			(pads allowed)
			(copperpour not_allowed)
			(footprints allowed)
		)
		(placement
			(enabled no)
			(sheetname "")
		)
		(fill
			(thermal_gap 0.5)
			(thermal_bridge_width 0.5)
			(island_removal_mode 0)
		)
		(polygon
			(pts
				(arc
					(start 103.324914 -207.79994)
					(mid 96.324928 -200.799954)
					(end 89.324942 -207.79994)
				)
				(arc
					(start 89.324942 -213.799928)
					(mid 96.324928 -220.799914)
					(end 103.324914 -213.799928)
				)
			)
		)
	)
	(zone
		(layer "B.Cu")
		(hatch none 0.5)
		(connect_pads
			(clearance 0)
		)
		(min_thickness 0.25)
		(keepout
			(tracks not_allowed)
			(vias allowed)
			(pads allowed)
			(copperpour not_allowed)
			(footprints allowed)
		)
		(placement
			(enabled no)
			(sheetname "")
		)
		(fill
			(thermal_gap 0.5)
			(thermal_bridge_width 0.5)
			(island_removal_mode 0)
		)
		(polygon
			(pts
				(arc
					(start 400.675094 -322.799964)
					(mid 393.675108 -315.799978)
					(end 386.675122 -322.799964)
				)
				(arc
					(start 386.675122 -328.799952)
					(mid 393.675108 -335.799938)
					(end 400.675094 -328.799952)
				)
			)
		)
	)
	(zone
		(net "P5V_A_LL")
		(layer "B.Cu")
		(hatch none 0.5)
		(connect_pads
			(clearance 0.5)
		)
		(min_thickness 0.25)
		(fill yes
			(thermal_gap 0.5)
			(thermal_bridge_width 0.5)
			(island_removal_mode 0)
		)
		(polygon
			(pts
				(xy 31.5722 -242.9002) (xy 31.258002 -243.214398) (xy 31.258002 -248.72315) (xy 31.429452 -248.8946)
				(xy 37.011102 -248.8946) (xy 37.481002 -248.4247) (xy 37.481002 -243.348002) (xy 37.0332 -242.9002)
			)
		)
	)
	(zone
		(net "P5V_A_3")
		(layer "B.Cu")
		(hatch none 0.5)
		(connect_pads
			(clearance 0.5)
		)
		(min_thickness 0.25)
		(fill yes
			(thermal_gap 0.5)
			(thermal_bridge_width 0.5)
			(island_removal_mode 0)
		)
		(polygon
			(pts
				(xy 458.496162 -245.727982) (xy 458.054202 -246.169942) (xy 458.054202 -251.49175) (xy 458.943202 -252.38075)
				(xy 473.8878 -252.38075) (xy 473.957396 -252.311154) (xy 473.957396 -251.985526) (xy 474.028516 -251.914406)
				(xy 475.411546 -251.914406) (xy 476.215202 -251.11075) (xy 476.215202 -247.556274) (xy 474.831918 -246.17299)
				(xy 468.411052 -246.17299) (xy 467.966044 -245.727982)
			)
		)
	)
	(zone
		(net "GND")
		(layer "B.Cu")
		(hatch none 0.5)
		(connect_pads
			(clearance 0.5)
		)
		(min_thickness 0.25)
		(fill yes
			(thermal_gap 0.5)
			(thermal_bridge_width 0.5)
			(island_removal_mode 0)
		)
		(polygon
			(pts
				(xy 146.594322 -77.809852)
				(arc
					(start 133.639814 -69.247766)
					(mid 131.344872 -74.16151)
					(end 126.18974 -72.477884)
				)
				(arc
					(start 126.18974 -72.477884)
					(mid 125.868485 -72.845546)
					(end 125.505718 -73.17232)
				)
				(arc
					(start 125.505718 -73.17232)
					(mid 126.814166 -74.689936)
					(end 127.330962 -76.625958)
				)
				(arc
					(start 127.330962 -76.625958)
					(mid 126.907175 -83.249319)
					(end 120.758458 -80.751172)
				)
				(arc
					(start 120.758458 -80.751172)
					(mid 120.332821 -80.495658)
					(end 119.938038 -80.194658)
				)
				(arc
					(start 119.938038 -80.194658)
					(mid 116.500094 -79.559555)
					(end 114.808762 -76.49972)
				)
				(arc
					(start 114.808762 -76.49972)
					(mid 110.449799 -77.075073)
					(end 108.086906 -73.367138)
				)
				(arc
					(start 108.086906 -72.300084)
					(mid 108.126108 -71.735371)
					(end 108.242862 -71.181468)
				)
				(xy 108.242862 -68.77304)
				(arc
					(start 107.351068 -68.77304)
					(mid 107.2642 -68.773963)
					(end 107.177332 -68.77304)
				)
				(arc
					(start 107.176316 -68.77304)
					(mid 103.220756 -65.299848)
					(end 105.962704 -60.80633)
				)
				(arc
					(start 105.962704 -59.64809)
					(mid 103.275578 -55.278545)
					(end 106.96956 -51.719226)
				)
				(arc
					(start 106.96956 -51.719226)
					(mid 107.090751 -50.119218)
					(end 107.818174 -48.689006)
				)
				(arc
					(start 107.818174 -48.689006)
					(mid 104.935218 -44.925155)
					(end 107.544362 -40.966644)
				)
				(arc
					(start 105.856786 -38.417246)
					(mid 105.498959 -37.756865)
					(end 105.274618 -37.040058)
				)
				(xy 103.916988 -30.56763) (xy 103.916988 -22.327108)
				(arc
					(start 103.91775 -22.251924)
					(mid 104.19742 -20.725543)
					(end 104.957372 -19.37258)
				)
				(xy 104.957372 -18.957798) (xy 104.887522 -18.887948) (xy 103.424736 -18.887948) (xy 101.896418 -17.35963)
				(xy 101.896418 -16.823944) (xy 101.89718 -16.824198)
				(arc
					(start 101.89718 -15.375382)
					(mid 101.410646 -14.762778)
					(end 101.237034 -13.999972)
				)
				(arc
					(start 101.237034 -0.999998)
					(mid 101.167624 -0.832426)
					(end 101.000052 -0.763016)
				)
				(arc
					(start 0.999998 -0.763016)
					(mid 0.832426 -0.832426)
					(end 0.763016 -0.999998)
				)
				(arc
					(start 0.763016 -2.856484)
					(mid 3.214109 -1.485891)
					(end 5.968746 -2.032)
				)
				(xy 10.60831 -2.032)
				(arc
					(start 10.60831 -2.089912)
					(mid 11.251977 -3.914297)
					(end 11.41222 -5.842254)
				)
				(arc
					(start 11.411966 -5.842254)
					(mid 9.760391 -10.22937)
					(end 5.842254 -12.80287)
				)
				(arc
					(start 5.842254 -12.80287)
					(mid 3.940032 -13.069296)
					(end 2.032 -12.848336)
				)
				(xy 2.032 -10.322306) (xy 1.797812 -10.088118) (xy 1.072388 -10.088118) (xy 0.762254 -10.398252)
				(xy 0.762254 -113.527078) (xy 0.763016 -113.527078)
				(arc
					(start 0.763016 -117.856508)
					(mid 1.347909 -117.297337)
					(end 2.032 -116.865146)
				)
				(arc
					(start 2.032 -113.151158)
					(mid 3.940032 -112.93025)
					(end 5.842254 -113.196624)
				)
				(arc
					(start 5.842254 -113.196878)
					(mid 10.960074 -117.902078)
					(end 10.081006 -124.798328)
				)
				(arc
					(start 10.081006 -126.052834)
					(mid 11.025319 -126.15347)
					(end 11.920982 -126.46914)
				)
				(arc
					(start 11.920982 -126.46914)
					(mid 13.156907 -126.084668)
					(end 14.451076 -126.105666)
				)
				(arc
					(start 14.451076 -126.105666)
					(mid 15.706094 -125.35486)
					(end 17.145 -125.093476)
				)
				(arc
					(start 18.415 -125.093476)
					(mid 22.125607 -127.461887)
					(end 21.539708 -131.82473)
				)
				(arc
					(start 21.539708 -153.806652)
					(mid 22.800574 -153.977595)
					(end 23.947882 -154.527758)
				)
				(arc
					(start 23.947882 -154.527758)
					(mid 24.397443 -152.0693)
					(end 26.143204 -150.280878)
				)
				(arc
					(start 26.143204 -150.280878)
					(mid 27.027928 -148.408361)
					(end 28.716478 -147.209256)
				)
				(xy 28.716478 -145.345404) (xy 28.460446 -145.345404) (xy 25.974548 -142.859506) (xy 25.974548 -136.781794)
				(xy 28.460446 -134.295896) (xy 34.919158 -134.295896) (xy 35.173158 -134.549896)
				(arc
					(start 39.602918 -134.549896)
					(mid 39.565557 -134.132246)
					(end 39.571168 -133.712966)
				)
				(arc
					(start 39.571168 -133.712966)
					(mid 39.513159 -133.63882)
					(end 39.456868 -133.56336)
				)
				(arc
					(start 39.456868 -133.56336)
					(mid 38.124118 -128.11615)
					(end 43.481498 -126.458472)
				)
				(arc
					(start 43.481498 -126.458472)
					(mid 44.718064 -126.073908)
					(end 46.012862 -126.095252)
				)
				(arc
					(start 46.012862 -126.095252)
					(mid 47.263358 -125.352074)
					(end 48.694848 -125.093476)
				)
				(arc
					(start 49.964848 -125.093476)
					(mid 54.003359 -128.531644)
					(end 51.253644 -133.067044)
				)
				(arc
					(start 51.253644 -133.067044)
					(mid 51.354979 -133.869848)
					(end 51.296316 -134.676896)
				)
				(xy 55.112158 -134.676896) (xy 56.1213 -135.686038) (xy 56.769508 -135.686038) (xy 56.88965 -135.565896)
				(xy 59.39155 -135.565896) (xy 59.39155 -132.72008) (xy 60.540138 -131.571492) (xy 60.540138 -131.266438)
				(xy 60.845192 -131.266438) (xy 61.942726 -130.168904)
				(arc
					(start 69.132704 -130.168904)
					(mid 69.743112 -127.982241)
					(end 71.425562 -126.457964)
				)
				(arc
					(start 71.425562 -126.457964)
					(mid 70.834554 -121.144458)
					(end 76.005182 -119.785384)
				)
				(arc
					(start 76.005182 -119.785384)
					(mid 77.361154 -119.385558)
					(end 78.772258 -119.471186)
				)
				(arc
					(start 78.772258 -119.471186)
					(mid 79.495943 -119.266065)
					(end 80.24495 -119.196866)
				)
				(arc
					(start 81.51495 -119.196866)
					(mid 85.30945 -121.758925)
					(end 84.351114 -126.235968)
				)
				(arc
					(start 84.351114 -126.235968)
					(mid 85.503815 -130.093263)
					(end 82.79384 -133.070346)
				)
				(arc
					(start 82.79384 -133.070346)
					(mid 82.33117 -136.051867)
					(end 79.950056 -137.904982)
				)
				(xy 79.950056 -147.685506) (xy 78.58506 -149.050502) (xy 78.554326 -149.166326) (xy 78.554326 -151.379174)
				(xy 77.918056 -151.379174) (xy 77.918056 -151.495506) (xy 77.585824 -151.827738) (xy 77.585824 -153.023824)
				(xy 76.389738 -153.023824) (xy 75.432158 -153.981404) (xy 71.729854 -153.981404) (xy 71.729854 -155.84932)
				(xy 71.695564 -155.883356)
				(arc
					(start 81.22666 -155.883356)
					(mid 83.762933 -153.983916)
					(end 86.89467 -154.466036)
				)
				(arc
					(start 87.029544 -154.331162)
					(mid 87.519331 -152.027239)
					(end 89.153746 -150.33117)
				)
				(arc
					(start 89.153746 -150.33117)
					(mid 93.920718 -147.011878)
					(end 97.199704 -151.806656)
				)
				(xy 110.915196 -151.806656)
				(arc
					(start 113.844578 -154.735784)
					(mid 115.702062 -153.963952)
					(end 117.702838 -154.170888)
				)
				(arc
					(start 118.64594 -153.227786)
					(mid 118.844168 -152.52564)
					(end 119.158766 -151.867362)
				)
				(arc
					(start 119.158766 -151.867362)
					(mid 115.908434 -146.921995)
					(end 121.000266 -143.90624)
				)
				(xy 124.158756 -143.90624)
				(arc
					(start 127.766318 -140.298424)
					(mid 127.729079 -140.120728)
					(end 127.69977 -139.941554)
				)
				(arc
					(start 127.69977 -139.941554)
					(mid 125.672981 -139.644779)
					(end 124.044202 -138.402568)
				)
				(arc
					(start 124.044202 -138.402568)
					(mid 122.257923 -134.596098)
					(end 124.772166 -131.225798)
				)
				(arc
					(start 124.772166 -131.225798)
					(mid 124.983203 -128.454631)
					(end 126.916434 -126.457964)
				)
				(arc
					(start 126.916434 -126.457964)
					(mid 126.173266 -125.534468)
					(end 125.72619 -124.436632)
				)
				(arc
					(start 125.72619 -124.436632)
					(mid 122.122632 -126.253684)
					(end 118.698772 -124.117354)
				)
				(arc
					(start 118.698772 -124.117354)
					(mid 117.925678 -124.297618)
					(end 117.132354 -124.326142)
				)
				(arc
					(start 117.132354 -124.326142)
					(mid 116.823516 -125.502267)
					(end 116.182648 -126.535688)
				)
				(arc
					(start 116.182648 -126.535688)
					(mid 117.001129 -130.29902)
					(end 114.330988 -133.07441)
				)
				(arc
					(start 114.330988 -133.07441)
					(mid 112.869163 -137.183007)
					(end 108.531914 -137.637774)
				)
				(arc
					(start 108.531914 -137.637774)
					(mid 104.453669 -137.368495)
					(end 102.644702 -133.703568)
				)
				(arc
					(start 102.644702 -133.703568)
					(mid 102.586693 -133.629422)
					(end 102.530402 -133.553962)
				)
				(arc
					(start 102.530402 -133.553962)
					(mid 100.673898 -129.876079)
					(end 102.959662 -126.448566)
				)
				(arc
					(start 102.959662 -126.448566)
					(mid 101.745912 -122.57262)
					(end 104.47147 -119.561356)
				)
				(arc
					(start 104.47147 -117.474492)
					(mid 103.821064 -116.779761)
					(end 103.34879 -115.95354)
				)
				(arc
					(start 103.34879 -115.95354)
					(mid 104.085056 -109.724731)
					(end 110.08741 -111.544608)
				)
				(arc
					(start 110.08741 -111.544608)
					(mid 110.604065 -112.221846)
					(end 110.969298 -112.991392)
				)
				(arc
					(start 112.765078 -112.991392)
					(mid 116.305646 -113.095498)
					(end 118.437406 -115.92433)
				)
				(arc
					(start 118.437406 -115.92433)
					(mid 118.9423 -116.241943)
					(end 119.396002 -116.62918)
				)
				(arc
					(start 119.396002 -116.62918)
					(mid 120.307703 -117.323872)
					(end 120.992392 -118.243096)
				)
				(arc
					(start 120.992392 -118.243096)
					(mid 123.809239 -118.309719)
					(end 125.92304 -120.172734)
				)
				(arc
					(start 127.262636 -120.172734)
					(mid 129.325067 -119.38587)
					(end 131.496054 -119.785384)
				)
				(arc
					(start 131.496054 -119.785384)
					(mid 133.341595 -119.359548)
					(end 135.181086 -119.810784)
				)
				(arc
					(start 135.181086 -119.810784)
					(mid 135.452388 -119.783564)
					(end 135.7249 -119.774462)
				)
				(arc
					(start 136.9949 -119.774462)
					(mid 139.960781 -121.047726)
					(end 141.08049 -124.074936)
				)
				(arc
					(start 142.48765 -124.074936)
					(mid 145.65315 -123.572446)
					(end 148.209 -125.50648)
				)
				(arc
					(start 151.924766 -125.50648)
					(mid 154.339564 -123.64701)
					(end 157.369764 -123.97359)
				)
				(arc
					(start 157.369764 -123.97359)
					(mid 158.855673 -123.828755)
					(end 160.294574 -124.226828)
				)
				(arc
					(start 160.294574 -124.226828)
					(mid 161.547486 -123.83749)
					(end 162.859212 -123.864878)
				)
				(arc
					(start 162.859212 -123.864878)
					(mid 163.664687 -123.606191)
					(end 164.506148 -123.518676)
				)
				(arc
					(start 165.776402 -123.518676)
					(mid 168.691932 -124.739871)
					(end 169.866818 -127.67437)
				)
				(arc
					(start 169.866818 -127.67437)
					(mid 171.305435 -131.664895)
					(end 168.431718 -134.7851)
				)
				(xy 168.431718 -137.061956) (xy 171.38015 -137.061956)
				(arc
					(start 177.395124 -143.07693)
					(mid 177.569332 -143.262756)
					(end 177.731166 -143.459454)
				)
				(arc
					(start 177.731166 -143.459454)
					(mid 179.249683 -144.075535)
					(end 180.404516 -145.238216)
				)
				(xy 180.829458 -145.238216) (xy 181.415182 -145.82394) (xy 181.855364 -145.82394) (xy 181.855364 -146.264122)
				(xy 183.315356 -147.724114)
				(arc
					(start 183.315356 -150.66137)
					(mid 183.553885 -150.487849)
					(end 183.803798 -150.33117)
				)
				(arc
					(start 183.803798 -150.33117)
					(mid 186.80142 -147.077013)
					(end 191.005968 -148.45411)
				)
				(xy 206.30261 -133.157468) (xy 208.210658 -133.157468)
				(arc
					(start 209.874866 -131.49326)
					(mid 209.44207 -127.624502)
					(end 212.444076 -125.146054)
				)
				(arc
					(start 212.444076 -124.774452)
					(mid 212.260648 -124.560512)
					(end 212.092286 -124.334524)
				)
				(xy 211.809076 -124.334524) (xy 211.809076 -123.861322) (xy 211.782406 -123.807982)
				(arc
					(start 211.620862 -123.646438)
					(mid 210.776239 -122.38237)
					(end 210.47964 -120.8913)
				)
				(arc
					(start 210.47964 -118.618)
					(mid 210.776233 -117.126928)
					(end 211.620862 -115.862862)
				)
				(xy 211.809076 -115.674648) (xy 211.809076 -115.187476) (xy 212.317076 -115.187476) (xy 212.317076 -112.478566)
				(xy 212.177884 -112.478566) (xy 212.177884 -111.722916) (xy 211.340954 -110.885986) (xy 211.340954 -97.910142)
				(xy 214.05215 -95.198946)
				(arc
					(start 218.112086 -95.198946)
					(mid 218.338494 -93.953558)
					(end 218.934792 -92.837)
				)
				(arc
					(start 218.934792 -92.837)
					(mid 218.136944 -90.849403)
					(end 218.452954 -88.73109)
				)
				(xy 205.788514 -89.853516) (xy 203.554076 -89.398856)
				(arc
					(start 203.554076 -90.012774)
					(mid 200.171278 -96.903371)
					(end 198.277226 -89.464388)
				)
				(xy 198.277226 -88.325198)
				(arc
					(start 160.29178 -80.59674)
					(mid 160.075183 -81.317503)
					(end 159.730186 -81.986374)
				)
				(arc
					(start 159.730186 -81.986374)
					(mid 167.118509 -85.292909)
					(end 170.145964 -92.799916)
				)
				(arc
					(start 170.145964 -98.794316)
					(mid 159.324802 -109.615478)
					(end 148.50364 -98.794316)
				)
				(arc
					(start 148.50364 -97.22866)
					(mid 147.078148 -99.562984)
					(end 144.500346 -100.47732)
				)
				(arc
					(start 143.499586 -100.47732)
					(mid 139.951823 -98.423314)
					(end 139.9667 -94.323916)
				)
				(arc
					(start 139.9667 -94.323916)
					(mid 139.514856 -93.187508)
					(end 139.419076 -91.96832)
				)
				(arc
					(start 139.419076 -91.96832)
					(mid 131.952276 -88.752888)
					(end 139.945618 -90.235532)
				)
				(arc
					(start 139.945618 -90.235532)
					(mid 141.444399 -88.724213)
					(end 143.499586 -88.170512)
				)
				(arc
					(start 144.500346 -88.170512)
					(mid 147.198767 -89.186671)
					(end 148.556726 -91.730322)
				)
				(arc
					(start 148.556726 -91.730322)
					(mid 150.312522 -86.810401)
					(end 154.168602 -83.286346)
				)
				(arc
					(start 154.168602 -83.286346)
					(mid 152.985238 -82.204639)
					(end 152.30856 -80.751172)
				)
				(arc
					(start 152.30856 -80.751172)
					(mid 151.882923 -80.495658)
					(end 151.48814 -80.194658)
				)
				(arc
					(start 151.48814 -80.194658)
					(mid 148.635944 -79.911194)
					(end 146.670014 -77.825346)
				)
			)
		)
		(polygon
			(pts
				(arc
					(start 179.158392 -117.42801)
					(mid 179.158392 -125.61189)
					(end 179.158392 -117.42801)
				)
			)
		)
		(polygon
			(pts
				(arc
					(start 115.0112 -102.819708)
					(mid 115.0112 -111.003588)
					(end 115.0112 -102.819708)
				)
			)
		)
		(polygon
			(pts
				(arc
					(start 74.066654 -102.207822)
					(mid 74.066654 -110.391702)
					(end 74.066654 -102.207822)
				)
			)
		)
		(polygon
			(pts
				(arc
					(start 179.121308 -90.772488)
					(mid 175.130775 -86.142573)
					(end 170.993308 -90.641678)
				)
				(arc
					(start 170.993308 -90.641678)
					(mid 171.331563 -92.888878)
					(end 172.81652 -94.609158)
				)
				(arc
					(start 172.81652 -94.609158)
					(mid 171.205824 -99.440775)
					(end 175.550068 -102.09911)
				)
				(arc
					(start 175.550068 -102.09911)
					(mid 179.994933 -99.126395)
					(end 177.703734 -94.294706)
				)
				(arc
					(start 177.703734 -94.294706)
					(mid 178.845763 -92.707961)
					(end 179.121308 -90.772488)
				)
			)
		)
		(polygon
			(pts
				(arc
					(start 116.675662 -93.955108)
					(mid 119.102456 -87.43051)
					(end 112.181386 -88.1761)
				)
				(arc
					(start 112.181386 -88.1761)
					(mid 108.460356 -90.124184)
					(end 108.415582 -94.32417)
				)
				(arc
					(start 108.415582 -94.32417)
					(mid 108.532898 -98.637671)
					(end 112.450118 -100.447602)
				)
				(arc
					(start 112.450118 -100.447602)
					(mid 116.367474 -98.637629)
					(end 116.484654 -94.323916)
				)
				(arc
					(start 116.484654 -94.323916)
					(mid 116.584837 -94.141935)
					(end 116.675662 -93.955108)
				)
			)
		)
		(polygon
			(pts
				(arc
					(start 94.308676 -14.694662)
					(mid 92.557804 -11.476749)
					(end 88.932258 -10.951718)
				)
				(arc
					(start 88.932258 -10.951718)
					(mid 87.704351 -10.838321)
					(end 86.49843 -11.09599)
				)
				(arc
					(start 86.49843 -11.09599)
					(mid 83.968779 -10.976843)
					(end 81.853786 -12.3698)
				)
				(xy 80.920082 -13.303504)
				(arc
					(start 79.72425 -13.303504)
					(mid 79.268066 -13.277986)
					(end 78.811882 -13.303504)
				)
				(arc
					(start 77.292962 -13.303504)
					(mid 73.97316 -14.596517)
					(end 72.926702 -18.001996)
				)
				(arc
					(start 72.926702 -18.001996)
					(mid 73.117487 -20.064795)
					(end 74.294492 -21.769578)
				)
				(arc
					(start 74.294492 -27.380692)
					(mid 74.603899 -28.936098)
					(end 75.48499 -30.254702)
				)
				(arc
					(start 75.786996 -30.556962)
					(mid 75.94981 -31.318701)
					(end 76.254102 -32.03575)
				)
				(arc
					(start 76.254102 -32.03575)
					(mid 75.854295 -34.741819)
					(end 77.249528 -37.094668)
				)
				(arc
					(start 65.583308 -37.094668)
					(mid 62.515475 -32.041228)
					(end 57.603644 -35.331146)
				)
				(arc
					(start 57.603644 -35.331146)
					(mid 55.958097 -37.048527)
					(end 55.483252 -39.379144)
				)
				(arc
					(start 55.293006 -39.569644)
					(mid 55.056744 -39.826937)
					(end 54.843426 -40.103552)
				)
				(xy 51.940968 -37.201348)
				(arc
					(start 34.003488 -37.201348)
					(mid 31.019689 -32.053364)
					(end 26.053796 -35.331146)
				)
				(arc
					(start 26.053796 -35.331146)
					(mid 24.519385 -36.849444)
					(end 23.920958 -38.923468)
				)
				(arc
					(start 23.040086 -39.804594)
					(mid 22.45003 -40.552388)
					(end 22.050248 -41.416986)
				)
				(arc
					(start 22.050248 -41.416986)
					(mid 20.970193 -42.41474)
					(end 20.312634 -43.72991)
				)
				(arc
					(start 20.312634 -43.72991)
					(mid 18.745965 -43.535069)
					(end 17.222216 -43.948096)
				)
				(arc
					(start 17.222216 -43.948096)
					(mid 10.307041 -43.032304)
					(end 12.631928 -49.608994)
				)
				(arc
					(start 12.631928 -49.608994)
					(mid 12.33439 -50.643335)
					(end 12.316968 -51.71948)
				)
				(arc
					(start 12.316968 -51.71948)
					(mid 8.597213 -55.977594)
					(end 12.683998 -59.884818)
				)
				(arc
					(start 14.572488 -59.884818)
					(mid 14.673941 -60.550954)
					(end 14.883384 -61.191394)
				)
				(arc
					(start 14.842744 -61.291978)
					(mid 8.652974 -65.903862)
					(end 16.367252 -66.17081)
				)
				(arc
					(start 16.367252 -66.17081)
					(mid 21.250887 -65.938119)
					(end 22.422612 -61.191394)
				)
				(arc
					(start 22.422612 -61.191394)
					(mid 22.408775 -57.983931)
					(end 20.085304 -55.772812)
				)
				(arc
					(start 20.085304 -55.772812)
					(mid 20.183191 -55.545565)
					(end 20.267168 -55.312818)
				)
				(arc
					(start 22.591776 -55.312818)
					(mid 22.68845 -55.311676)
					(end 22.78507 -55.308246)
				)
				(arc
					(start 23.088854 -55.61203)
					(mid 23.527193 -57.107414)
					(end 24.492966 -58.330338)
				)
				(arc
					(start 24.492966 -58.330338)
					(mid 24.284396 -59.059668)
					(end 24.214074 -59.814968)
				)
				(arc
					(start 24.214074 -62.354968)
					(mid 24.441489 -63.69969)
					(end 25.098248 -64.894968)
				)
				(arc
					(start 25.098248 -64.894968)
					(mid 24.605199 -65.689593)
					(end 24.305514 -66.575432)
				)
				(arc
					(start 24.305514 -66.575432)
					(mid 18.963256 -68.586071)
					(end 20.83308 -73.979024)
				)
				(arc
					(start 20.83308 -73.979024)
					(mid 20.916535 -78.62373)
					(end 25.28824 -80.194658)
				)
				(arc
					(start 25.28824 -80.194658)
					(mid 25.683022 -80.495659)
					(end 26.10866 -80.751172)
				)
				(arc
					(start 26.10866 -80.751172)
					(mid 26.818789 -82.249634)
					(end 28.065476 -83.342988)
				)
				(arc
					(start 28.065476 -83.342988)
					(mid 23.997375 -87.314384)
					(end 22.503892 -92.799916)
				)
				(arc
					(start 22.503892 -98.794316)
					(mid 33.325054 -109.615478)
					(end 44.146216 -98.794316)
				)
				(arc
					(start 44.146216 -92.799916)
					(mid 41.050236 -85.222376)
					(end 33.533842 -81.980786)
				)
				(arc
					(start 33.533842 -81.980786)
					(mid 34.122342 -79.141768)
					(end 32.681164 -76.625958)
				)
				(arc
					(start 32.681164 -76.625958)
					(mid 32.164564 -74.690149)
					(end 30.856428 -73.172574)
				)
				(arc
					(start 30.856428 -73.172574)
					(mid 31.990994 -71.749407)
					(end 32.395922 -69.974968)
				)
				(arc
					(start 32.395922 -67.434968)
					(mid 32.168507 -66.090246)
					(end 31.511748 -64.894968)
				)
				(arc
					(start 31.511748 -64.894968)
					(mid 31.694831 -64.644871)
					(end 31.858458 -64.381634)
				)
				(arc
					(start 33.045654 -65.56883)
					(mid 33.128405 -65.669233)
					(end 33.21431 -65.76695)
				)
				(arc
					(start 33.21431 -65.76695)
					(mid 36.114647 -71.45829)
					(end 41.030398 -67.379342)
				)
				(arc
					(start 41.030398 -67.379342)
					(mid 44.81379 -68.712566)
					(end 47.9171 -66.17081)
				)
				(arc
					(start 47.9171 -66.17081)
					(mid 52.800735 -65.938119)
					(end 53.97246 -61.191394)
				)
				(arc
					(start 53.97246 -61.191394)
					(mid 53.954265 -57.973863)
					(end 51.614578 -55.765192)
				)
				(arc
					(start 51.614578 -55.765192)
					(mid 51.714057 -55.54178)
					(end 51.799998 -55.312818)
				)
				(arc
					(start 54.139846 -55.312818)
					(mid 54.380931 -55.305693)
					(end 54.621176 -55.28437)
				)
				(arc
					(start 54.621176 -55.28437)
					(mid 55.004664 -56.96014)
					(end 56.042814 -58.330338)
				)
				(arc
					(start 56.042814 -58.330338)
					(mid 55.834244 -59.059668)
					(end 55.763922 -59.814968)
				)
				(arc
					(start 55.763922 -62.354968)
					(mid 55.991337 -63.69969)
					(end 56.648096 -64.894968)
				)
				(arc
					(start 56.648096 -64.894968)
					(mid 56.155047 -65.689593)
					(end 55.855362 -66.575432)
				)
				(arc
					(start 55.855362 -66.575432)
					(mid 50.513104 -68.586071)
					(end 52.382928 -73.979024)
				)
				(arc
					(start 52.382928 -73.979024)
					(mid 52.466383 -78.62373)
					(end 56.838088 -80.194658)
				)
				(arc
					(start 56.838088 -80.194658)
					(mid 57.23287 -80.495659)
					(end 57.658508 -80.751172)
				)
				(arc
					(start 57.658508 -80.751172)
					(mid 63.807173 -83.249236)
					(end 64.231012 -76.625958)
				)
				(arc
					(start 64.231012 -76.625958)
					(mid 63.714412 -74.690149)
					(end 62.406276 -73.172574)
				)
				(arc
					(start 62.406276 -73.172574)
					(mid 63.540842 -71.749407)
					(end 63.94577 -69.974968)
				)
				(arc
					(start 63.94577 -67.434968)
					(mid 63.718355 -66.090246)
					(end 63.061596 -64.894968)
				)
				(arc
					(start 63.061596 -64.894968)
					(mid 63.249413 -64.638102)
					(end 63.416688 -64.36741)
				)
				(arc
					(start 64.595502 -65.546224)
					(mid 64.708465 -65.68156)
					(end 64.82715 -65.811908)
				)
				(arc
					(start 64.82715 -65.811908)
					(mid 67.684014 -71.640059)
					(end 72.572626 -67.370452)
				)
				(arc
					(start 72.572626 -67.370452)
					(mid 76.358057 -68.713668)
					(end 79.467202 -66.17081)
				)
				(arc
					(start 79.467202 -66.17081)
					(mid 84.350837 -65.938119)
					(end 85.522562 -61.191394)
				)
				(arc
					(start 85.522562 -61.191394)
					(mid 85.562687 -58.115259)
					(end 83.447636 -55.88127)
				)
				(arc
					(start 83.447636 -55.88127)
					(mid 83.583418 -55.601798)
					(end 83.697572 -55.312818)
				)
				(arc
					(start 85.689948 -55.312818)
					(mid 85.931033 -55.305693)
					(end 86.171278 -55.28437)
				)
				(arc
					(start 86.171278 -55.28437)
					(mid 86.554766 -56.96014)
					(end 87.592916 -58.330338)
				)
				(arc
					(start 87.592916 -58.330338)
					(mid 87.384346 -59.059668)
					(end 87.314024 -59.814968)
				)
				(arc
					(start 87.314024 -62.354968)
					(mid 87.541439 -63.69969)
					(end 88.198198 -64.894968)
				)
				(arc
					(start 88.198198 -64.894968)
					(mid 87.705149 -65.689593)
					(end 87.405464 -66.575432)
				)
				(arc
					(start 87.405464 -66.575432)
					(mid 82.063206 -68.586071)
					(end 83.93303 -73.979024)
				)
				(arc
					(start 83.93303 -73.979024)
					(mid 84.016485 -78.62373)
					(end 88.38819 -80.194658)
				)
				(arc
					(start 88.38819 -80.194658)
					(mid 88.782972 -80.495659)
					(end 89.20861 -80.751172)
				)
				(arc
					(start 89.20861 -80.751172)
					(mid 89.90178 -82.227009)
					(end 91.116404 -83.314794)
				)
				(arc
					(start 91.116404 -83.314794)
					(mid 87.201998 -86.980258)
					(end 85.52815 -92.075)
				)
				(arc
					(start 85.488018 -92.075)
					(mid 84.040559 -89.135264)
					(end 80.900016 -88.20023)
				)
				(arc
					(start 80.900016 -88.20023)
					(mid 76.9826 -90.010295)
					(end 76.86548 -94.32417)
				)
				(arc
					(start 76.86548 -94.32417)
					(mid 76.982796 -98.637671)
					(end 80.900016 -100.447602)
				)
				(arc
					(start 80.900016 -100.447602)
					(mid 83.861692 -99.655309)
					(end 85.44179 -97.028)
				)
				(xy 85.503766 -97.028)
				(arc
					(start 85.503766 -98.794316)
					(mid 96.324928 -109.615478)
					(end 107.14609 -98.794316)
				)
				(arc
					(start 107.14609 -92.799916)
					(mid 104.084545 -85.257642)
					(end 96.632268 -81.983072)
				)
				(arc
					(start 96.632268 -81.983072)
					(mid 97.222451 -79.143133)
					(end 95.781114 -76.625958)
				)
				(arc
					(start 95.781114 -76.625958)
					(mid 95.264514 -74.690149)
					(end 93.956378 -73.172574)
				)
				(arc
					(start 93.956378 -73.172574)
					(mid 95.078538 -71.774751)
					(end 95.495364 -70.031356)
				)
				(arc
					(start 95.495364 -70.031356)
					(mid 100.445701 -70.454376)
					(end 102.152196 -65.788286)
				)
				(arc
					(start 102.152196 -65.788286)
					(mid 103.173646 -63.805333)
					(end 103.002842 -61.581284)
				)
				(arc
					(start 103.002842 -61.581284)
					(mid 102.500875 -57.908909)
					(end 99.238308 -56.150002)
				)
				(xy 99.238308 -54.755288)
				(arc
					(start 97.4471 -52.963826)
					(mid 99.073116 -51.46534)
					(end 99.674426 -49.337468)
				)
				(arc
					(start 99.674426 -46.162468)
					(mid 98.442963 -43.247578)
					(end 95.494602 -42.098468)
				)
				(arc
					(start 95.494602 -42.098468)
					(mid 95.440845 -41.370733)
					(end 95.258636 -40.66413)
				)
				(arc
					(start 95.258636 -40.66413)
					(mid 95.465159 -40.022946)
					(end 95.568516 -39.3573)
				)
				(arc
					(start 95.568516 -39.3573)
					(mid 96.981565 -34.51865)
					(end 92.62491 -31.983172)
				)
				(arc
					(start 92.62491 -31.983172)
					(mid 93.689291 -29.879681)
					(end 93.415866 -27.538172)
				)
				(arc
					(start 93.415866 -27.538172)
					(mid 98.497908 -27.603016)
					(end 99.719638 -22.6695)
				)
				(arc
					(start 99.719638 -22.6695)
					(mid 99.877629 -21.27657)
					(end 99.556062 -19.912076)
				)
				(arc
					(start 99.558348 -19.913346)
					(mid 98.62564 -18.564623)
					(end 97.238312 -17.690338)
				)
				(arc
					(start 97.239836 -17.692624)
					(mid 96.694954 -17.529067)
					(end 96.13265 -17.442688)
				)
				(arc
					(start 96.13265 -17.442688)
					(mid 96.013407 -17.276539)
					(end 95.886016 -17.116552)
				)
				(arc
					(start 95.886016 -17.116552)
					(mid 95.318382 -15.761655)
					(end 94.308676 -14.694662)
				)
			)
		)
		(polygon
			(pts
				(arc
					(start 36.820602 -7.187692)
					(mid 37.190971 -4.504198)
					(end 36.083494 -2.032)
				)
				(arc
					(start 21.62175 -2.032)
					(mid 18.960818 -4.8104)
					(end 17.782794 -8.472678)
				)
				(arc
					(start 17.78254 -8.472678)
					(mid 17.763971 -8.741185)
					(end 17.753838 -9.010142)
				)
				(arc
					(start 17.753838 -9.010142)
					(mid 16.234721 -15.926565)
					(end 23.203408 -17.184624)
				)
				(arc
					(start 23.203408 -17.184624)
					(mid 31.080677 -16.333258)
					(end 34.896298 -9.389364)
				)
				(arc
					(start 34.896298 -9.389364)
					(mid 36.025979 -8.434944)
					(end 36.820602 -7.187692)
				)
			)
		)
	)
	(zone
		(layer "B.Cu")
		(hatch none 0.5)
		(connect_pads
			(clearance 0)
		)
		(min_thickness 0.25)
		(keepout
			(tracks not_allowed)
			(vias allowed)
			(pads allowed)
			(copperpour not_allowed)
			(footprints allowed)
		)
		(placement
			(enabled no)
			(sheetname "")
		)
		(fill
			(thermal_gap 0.5)
			(thermal_bridge_width 0.5)
			(island_removal_mode 0)
		)
		(polygon
			(pts
				(arc
					(start 46.500034 -164.200078)
					(mid 42.749978 -160.450022)
					(end 38.999922 -164.200078)
				)
				(arc
					(start 38.999922 -164.200078)
					(mid 42.749978 -167.950134)
					(end 46.500034 -164.200078)
				)
			)
		)
	)
	(zone
		(layer "B.Cu")
		(hatch none 0.5)
		(connect_pads
			(clearance 0)
		)
		(min_thickness 0.25)
		(keepout
			(tracks not_allowed)
			(vias allowed)
			(pads allowed)
			(copperpour not_allowed)
			(footprints allowed)
		)
		(placement
			(enabled no)
			(sheetname "")
		)
		(fill
			(thermal_gap 0.5)
			(thermal_bridge_width 0.5)
			(island_removal_mode 0)
		)
		(polygon
			(pts
				(arc
					(start 285.436564 -340.956392)
					(mid 284.887924 -341.505032)
					(end 285.436564 -342.053672)
				)
				(arc
					(start 285.935928 -342.053672)
					(mid 285.921943 -341.984738)
					(end 285.9151 -341.914734)
				)
				(xy 285.914338 -341.913972)
				(arc
					(start 285.914338 -341.632032)
					(mid 285.899459 -341.596111)
					(end 285.863538 -341.581232)
				)
				(arc
					(start 285.822898 -341.581232)
					(mid 285.042787 -341.505032)
					(end 285.822898 -341.428832)
				)
				(xy 285.895034 -341.428832)
				(arc
					(start 285.898082 -341.43188)
					(mid 286.007159 -341.488411)
					(end 286.06369 -341.597488)
				)
				(xy 286.066738 -341.600536)
				(arc
					(start 286.066738 -341.88273)
					(mid 286.073833 -341.969356)
					(end 286.094932 -342.053672)
				)
				(arc
					(start 286.245808 -342.053672)
					(mid 286.220397 -341.986338)
					(end 286.207708 -341.915496)
				)
				(xy 286.206438 -341.913972) (xy 286.206438 -341.600536)
				(arc
					(start 286.209486 -341.597488)
					(mid 286.266017 -341.488411)
					(end 286.375094 -341.43188)
				)
				(xy 286.378142 -341.428832)
				(arc
					(start 286.450278 -341.428832)
					(mid 287.230389 -341.505032)
					(end 286.450278 -341.581232)
				)
				(arc
					(start 286.409638 -341.581232)
					(mid 286.373717 -341.596111)
					(end 286.358838 -341.632032)
				)
				(arc
					(start 286.358838 -341.882476)
					(mid 286.377129 -341.974429)
					(end 286.429196 -342.052402)
				)
				(xy 286.430466 -342.053672)
				(arc
					(start 286.836612 -342.053672)
					(mid 287.385252 -341.505032)
					(end 286.836612 -340.956392)
				)
				(xy 285.436818 -340.956392)
			)
		)
	)
	(zone
		(layer "B.Cu")
		(hatch none 0.5)
		(connect_pads
			(clearance 0)
		)
		(min_thickness 0.25)
		(keepout
			(tracks not_allowed)
			(vias allowed)
			(pads allowed)
			(copperpour not_allowed)
			(footprints allowed)
		)
		(placement
			(enabled no)
			(sheetname "")
		)
		(fill
			(thermal_gap 0.5)
			(thermal_bridge_width 0.5)
			(island_removal_mode 0)
		)
		(polygon
			(pts
				(arc
					(start 271.970754 -308.721506)
					(mid 271.58696 -309.104919)
					(end 271.9705 -309.488586)
				)
				(arc
					(start 273.1135 -309.488586)
					(mid 273.49704 -309.105046)
					(end 273.1135 -308.721506)
				)
				(arc
					(start 272.768568 -308.721506)
					(mid 272.765366 -308.748346)
					(end 272.76425 -308.775354)
				)
				(arc
					(start 272.76425 -308.923944)
					(mid 272.791127 -308.994062)
					(end 272.857976 -309.028338)
				)
				(arc
					(start 272.857976 -309.028338)
					(mid 273.380217 -309.104792)
					(end 272.857976 -309.181246)
				)
				(xy 272.837656 -309.181246)
				(arc
					(start 272.83537 -309.17896)
					(mid 272.687253 -309.105843)
					(end 272.614136 -308.957726)
				)
				(xy 272.61185 -308.95544) (xy 272.61185 -308.743858) (xy 272.612866 -308.742842) (xy 272.614644 -308.721506)
				(arc
					(start 272.474436 -308.721506)
					(mid 272.472724 -308.748406)
					(end 272.47215 -308.775354)
				)
				(xy 272.47215 -308.95544)
				(arc
					(start 272.469864 -308.957726)
					(mid 272.396747 -309.105843)
					(end 272.24863 -309.17896)
				)
				(xy 272.246344 -309.181246)
				(arc
					(start 272.226024 -309.181246)
					(mid 271.703783 -309.104792)
					(end 272.226024 -309.028338)
				)
				(arc
					(start 272.226024 -309.028338)
					(mid 272.292939 -308.994121)
					(end 272.31975 -308.923944)
				)
				(xy 272.31975 -308.743858) (xy 272.320512 -308.743096) (xy 272.321528 -308.721506)
			)
		)
	)
	(zone
		(net "P3V3_STBY_A")
		(layer "B.Cu")
		(hatch none 0.5)
		(connect_pads
			(clearance 0.5)
		)
		(min_thickness 0.25)
		(fill yes
			(thermal_gap 0.5)
			(thermal_bridge_width 0.5)
			(island_removal_mode 0)
		)
		(polygon
			(pts
				(xy 180.4289 -233.322622) (xy 179.864512 -233.88701) (xy 179.864512 -236.762544) (xy 178.723544 -237.903512)
				(xy 178.723544 -238.64697) (xy 179.109624 -239.03305) (xy 180.257196 -239.03305) (xy 180.483764 -239.259618)
				(xy 186.234578 -239.259618) (xy 186.53887 -239.56391) (xy 186.53887 -241.034062) (xy 186.855608 -241.3508)
				(xy 188.722 -241.3508) (xy 188.9506 -241.1222) (xy 188.9506 -235.451142) (xy 188.842142 -235.342684)
				(xy 188.671708 -235.342684) (xy 188.602112 -235.273088) (xy 188.602112 -234.460288) (xy 188.863478 -234.198922)
				(xy 189.938914 -234.198922) (xy 190.013336 -234.1245) (xy 190.013336 -233.386884) (xy 189.949074 -233.322622)
			)
		)
		(polygon
			(pts
				(xy 180.068728 -238.328708) (xy 179.865528 -238.328708) (xy 179.865528 -238.531908) (xy 180.068728 -238.531908)
			)
		)
		(polygon
			(pts
				(xy 179.459128 -238.328708) (xy 179.255928 -238.328708) (xy 179.255928 -238.531908) (xy 179.459128 -238.531908)
			)
		)
	)
	(zone
		(net "GND")
		(layer "B.Cu")
		(hatch none 0.5)
		(connect_pads
			(clearance 0.5)
		)
		(min_thickness 0.25)
		(fill yes
			(thermal_gap 0.5)
			(thermal_bridge_width 0.5)
			(island_removal_mode 0)
		)
		(polygon
			(pts
				(arc
					(start 179.813458 -246.03456)
					(mid 178.305735 -247.670204)
					(end 176.165002 -248.275094)
				)
				(arc
					(start 174.892716 -248.275094)
					(mid 174.661969 -248.268509)
					(end 174.43196 -248.248932)
				)
				(arc
					(start 145.077942 -248.248932)
					(mid 144.847933 -248.268521)
					(end 144.617186 -248.275094)
				)
				(arc
					(start 143.344138 -248.275094)
					(mid 143.093605 -248.267384)
					(end 142.844012 -248.24436)
				)
				(xy 134.950708 -256.13741)
				(arc
					(start 134.950708 -257.10007)
					(mid 137.677625 -258.258811)
					(end 138.906758 -260.954774)
				)
				(arc
					(start 138.906758 -260.954774)
					(mid 140.011088 -260.714912)
					(end 141.13891 -260.786372)
				)
				(arc
					(start 141.13891 -260.786372)
					(mid 145.177785 -263.807305)
					(end 143.213074 -268.4526)
				)
				(xy 146.761454 -272.00098)
				(arc
					(start 147.551902 -272.00098)
					(mid 148.898293 -271.093386)
					(end 150.491698 -270.781018)
				)
				(arc
					(start 150.491698 -270.781018)
					(mid 150.32689 -267.717957)
					(end 152.253696 -265.331194)
				)
				(arc
					(start 152.253696 -265.331194)
					(mid 158.457299 -262.570662)
					(end 158.668466 -269.357348)
				)
				(arc
					(start 158.668466 -269.357348)
					(mid 158.565088 -270.022989)
					(end 158.358586 -270.664178)
				)
				(arc
					(start 158.358586 -270.664178)
					(mid 158.392649 -270.764212)
					(end 158.424118 -270.865092)
				)
				(arc
					(start 159.806132 -270.865092)
					(mid 160.472217 -268.960383)
					(end 161.967926 -267.606018)
				)
				(arc
					(start 161.967926 -267.606018)
					(mid 163.70189 -264.407756)
					(end 166.605966 -262.216392)
				)
				(arc
					(start 166.605966 -262.216392)
					(mid 164.52823 -258.320716)
					(end 167.201088 -254.80645)
				)
				(arc
					(start 167.201088 -254.80645)
					(mid 172.364988 -250.469936)
					(end 174.558706 -256.846324)
				)
				(arc
					(start 174.558706 -256.846324)
					(mid 177.275906 -259.863814)
					(end 176.053496 -263.736074)
				)
				(arc
					(start 176.053496 -263.736074)
					(mid 178.403163 -267.508339)
					(end 178.548538 -271.95018)
				)
				(arc
					(start 179.102004 -271.95018)
					(mid 180.438079 -271.046883)
					(end 182.019448 -270.730218)
				)
				(arc
					(start 182.019448 -270.730218)
					(mid 181.885724 -267.691681)
					(end 183.803798 -265.331194)
				)
				(arc
					(start 183.803798 -265.331194)
					(mid 184.043501 -264.495833)
					(end 184.454292 -263.729978)
				)
				(xy 184.454292 -248.596912) (xy 182.99684 -247.13946) (xy 182.99684 -246.03456)
			)
		)
		(polygon
			(pts
				(arc
					(start 145.1356 -249.9106)
					(mid 145.1356 -258.1402)
					(end 145.1356 -249.9106)
				)
			)
		)
	)
	(zone
		(layer "B.Cu")
		(hatch none 0.5)
		(connect_pads
			(clearance 0)
		)
		(min_thickness 0.25)
		(keepout
			(tracks not_allowed)
			(vias allowed)
			(pads allowed)
			(copperpour not_allowed)
			(footprints allowed)
		)
		(placement
			(enabled no)
			(sheetname "")
		)
		(fill
			(thermal_gap 0.5)
			(thermal_bridge_width 0.5)
			(island_removal_mode 0)
		)
		(polygon
			(pts
				(arc
					(start 215.948768 -406.000204)
					(mid 215.400255 -405.45131)
					(end 214.851488 -405.99995)
				)
				(xy 214.851488 -406.458674)
				(arc
					(start 215.217756 -406.458674)
					(mid 215.2326 -406.457324)
					(end 215.246966 -406.45334)
				)
				(arc
					(start 215.246966 -406.45334)
					(mid 215.285332 -406.425356)
					(end 215.304116 -406.381712)
				)
				(arc
					(start 215.304116 -406.381712)
					(mid 215.400528 -405.6063)
					(end 215.495378 -406.381966)
				)
				(xy 215.495378 -406.40889)
				(arc
					(start 215.492076 -406.412192)
					(mid 215.43275 -406.546017)
					(end 215.314022 -406.631648)
				)
				(arc
					(start 215.314022 -406.631648)
					(mid 215.28771 -406.640101)
					(end 215.260682 -406.645872)
				)
				(xy 215.257126 -406.649174) (xy 214.851488 -406.649174) (xy 214.851488 -406.750774) (xy 215.25484 -406.750774)
				(arc
					(start 215.258142 -406.754076)
					(mid 215.413374 -406.832778)
					(end 215.492076 -406.98801)
				)
				(xy 215.495378 -406.991312)
				(arc
					(start 215.495378 -407.017982)
					(mid 215.400528 -407.793709)
					(end 215.304116 -407.018236)
				)
				(arc
					(start 215.304116 -407.018236)
					(mid 215.274202 -406.963128)
					(end 215.21547 -406.941274)
				)
				(xy 214.851488 -406.941274)
				(arc
					(start 214.851488 -407.399998)
					(mid 215.400128 -407.948638)
					(end 215.948768 -407.399998)
				)
			)
		)
	)
	(zone
		(layer "B.Cu")
		(hatch none 0.5)
		(connect_pads
			(clearance 0)
		)
		(min_thickness 0.25)
		(keepout
			(tracks not_allowed)
			(vias allowed)
			(pads allowed)
			(copperpour not_allowed)
			(footprints allowed)
		)
		(placement
			(enabled no)
			(sheetname "")
		)
		(fill
			(thermal_gap 0.5)
			(thermal_bridge_width 0.5)
			(island_removal_mode 0)
		)
		(polygon
			(pts
				(arc
					(start 11.75004 -224.199958)
					(mid 7.999984 -220.449902)
					(end 4.249928 -224.199958)
				)
				(arc
					(start 4.249928 -224.199958)
					(mid 7.999984 -227.950014)
					(end 11.75004 -224.199958)
				)
			)
		)
	)
	(zone
		(net "GND")
		(layer "B.Cu")
		(hatch none 0.5)
		(connect_pads
			(clearance 0.5)
		)
		(min_thickness 0.25)
		(fill yes
			(thermal_gap 0.5)
			(thermal_bridge_width 0.5)
			(island_removal_mode 0)
		)
		(polygon
			(pts
				(xy 189.962282 -235.252006) (xy 189.708282 -235.506006) (xy 189.708282 -241.221006) (xy 189.962282 -241.475006)
				(xy 191.740282 -241.475006) (xy 192.248282 -240.967006) (xy 192.248282 -236.141006) (xy 191.359282 -235.252006)
			)
		)
	)
	(zone
		(layer "B.Cu")
		(hatch none 0.5)
		(connect_pads
			(clearance 0)
		)
		(min_thickness 0.25)
		(keepout
			(tracks allowed)
			(vias allowed)
			(pads allowed)
			(copperpour allowed)
			(footprints not_allowed)
		)
		(placement
			(enabled no)
			(sheetname "")
		)
		(fill
			(thermal_gap 0.5)
			(thermal_bridge_width 0.5)
			(island_removal_mode 0)
		)
		(polygon
			(pts
				(arc
					(start 186.149996 -208.499964)
					(mid 182.39994 -204.749908)
					(end 178.649884 -208.499964)
				)
				(arc
					(start 178.649884 -208.499964)
					(mid 182.39994 -212.25002)
					(end 186.149996 -208.499964)
				)
			)
		)
	)
	(zone
		(layer "B.Cu")
		(hatch none 0.5)
		(connect_pads
			(clearance 0)
		)
		(min_thickness 0.25)
		(keepout
			(tracks not_allowed)
			(vias allowed)
			(pads allowed)
			(copperpour not_allowed)
			(footprints allowed)
		)
		(placement
			(enabled no)
			(sheetname "")
		)
		(fill
			(thermal_gap 0.5)
			(thermal_bridge_width 0.5)
			(island_removal_mode 0)
		)
		(polygon
			(pts
				(arc
					(start 223.148652 -406.000204)
					(mid 222.600139 -405.45131)
					(end 222.051372 -405.99995)
				)
				(xy 222.051372 -406.458674)
				(arc
					(start 222.41764 -406.458674)
					(mid 222.432484 -406.457324)
					(end 222.44685 -406.45334)
				)
				(arc
					(start 222.44685 -406.45334)
					(mid 222.485216 -406.425356)
					(end 222.504 -406.381712)
				)
				(arc
					(start 222.504 -406.381712)
					(mid 222.600412 -405.6063)
					(end 222.695262 -406.381966)
				)
				(xy 222.695262 -406.40889)
				(arc
					(start 222.69196 -406.412192)
					(mid 222.632634 -406.546017)
					(end 222.513906 -406.631648)
				)
				(arc
					(start 222.513906 -406.631648)
					(mid 222.487594 -406.640101)
					(end 222.460566 -406.645872)
				)
				(xy 222.45701 -406.649174) (xy 222.051372 -406.649174) (xy 222.051372 -406.750774) (xy 222.454724 -406.750774)
				(arc
					(start 222.458026 -406.754076)
					(mid 222.613258 -406.832778)
					(end 222.69196 -406.98801)
				)
				(xy 222.695262 -406.991312)
				(arc
					(start 222.695262 -407.017982)
					(mid 222.600412 -407.793709)
					(end 222.504 -407.018236)
				)
				(arc
					(start 222.504 -407.018236)
					(mid 222.474086 -406.963128)
					(end 222.415354 -406.941274)
				)
				(xy 222.051372 -406.941274)
				(arc
					(start 222.051372 -407.399998)
					(mid 222.600012 -407.948638)
					(end 223.148652 -407.399998)
				)
			)
		)
	)
	(zone
		(layer "B.Cu")
		(hatch none 0.5)
		(connect_pads
			(clearance 0)
		)
		(min_thickness 0.25)
		(keepout
			(tracks not_allowed)
			(vias allowed)
			(pads allowed)
			(copperpour not_allowed)
			(footprints allowed)
		)
		(placement
			(enabled no)
			(sheetname "")
		)
		(fill
			(thermal_gap 0.5)
			(thermal_bridge_width 0.5)
			(island_removal_mode 0)
		)
		(polygon
			(pts
				(arc
					(start 238.374936 -73.849738)
					(mid 238.699802 -72.87514)
					(end 237.725204 -72.550274)
				)
				(xy 237.723934 -72.547988) (xy 235.724192 -73.547986) (xy 235.724192 -73.54824)
				(arc
					(start 235.725208 -73.550272)
					(mid 235.400342 -74.52487)
					(end 236.37494 -74.849736)
				)
				(xy 236.37621 -74.852022) (xy 236.864652 -74.607674)
				(arc
					(start 237.11662 -74.35596)
					(mid 237.131673 -74.333338)
					(end 237.13694 -74.306684)
				)
				(arc
					(start 237.13694 -74.188828)
					(mid 237.131657 -74.162181)
					(end 237.11662 -74.139552)
				)
				(arc
					(start 236.954568 -73.9775)
					(mid 236.915528 -73.949014)
					(end 236.869732 -73.933558)
				)
				(xy 236.866176 -73.93305)
				(arc
					(start 236.85119 -73.93051)
					(mid 236.80142 -73.930669)
					(end 236.754162 -73.946258)
				)
				(arc
					(start 236.572044 -74.039476)
					(mid 235.564081 -74.449067)
					(end 236.485176 -73.870058)
				)
				(xy 236.667294 -73.776586) (xy 236.702346 -73.758552)
				(arc
					(start 236.705902 -73.759822)
					(mid 236.77166 -73.742608)
					(end 236.839506 -73.738486)
				)
				(xy 236.842554 -73.7362) (xy 236.88167 -73.74255) (xy 236.896656 -73.74509) (xy 236.901228 -73.745852)
				(xy 236.936026 -73.75144)
				(arc
					(start 236.937804 -73.75398)
					(mid 237.000702 -73.778648)
					(end 237.057692 -73.81494)
				)
				(xy 237.061248 -73.81494) (xy 237.089188 -73.84288) (xy 237.179358 -73.93305) (xy 237.27918 -74.032872)
				(arc
					(start 237.27918 -74.037952)
					(mid 237.307656 -74.089389)
					(end 237.323884 -74.145902)
				)
				(xy 237.32744 -74.149458) (xy 237.32744 -74.346054)
				(arc
					(start 237.323884 -74.34961)
					(mid 237.320596 -74.365863)
					(end 237.316264 -74.381868)
				)
				(xy 237.42904 -74.32548)
				(arc
					(start 237.42904 -74.1045)
					(mid 237.416892 -74.0439)
					(end 237.382558 -73.992486)
				)
				(xy 237.382558 -73.992232) (xy 237.237016 -73.84669)
				(arc
					(start 237.237016 -73.84161)
					(mid 237.226537 -73.825833)
					(end 237.217204 -73.809352)
				)
				(arc
					(start 237.217204 -73.808844)
					(mid 237.191186 -73.729511)
					(end 237.191296 -73.64603)
				)
				(arc
					(start 237.191296 -73.645776)
					(mid 237.227217 -73.549738)
					(end 237.29696 -73.47458)
				)
				(xy 237.298484 -73.469754)
				(arc
					(start 237.526576 -73.355708)
					(mid 238.537853 -72.954961)
					(end 237.61192 -73.525888)
				)
				(arc
					(start 237.419134 -73.622408)
					(mid 237.392708 -73.64468)
					(end 237.379256 -73.67651)
				)
				(arc
					(start 237.379256 -73.67651)
					(mid 237.379224 -73.699678)
					(end 237.386368 -73.721722)
				)
				(arc
					(start 237.386368 -73.721722)
					(mid 237.392303 -73.731109)
					(end 237.399576 -73.739502)
				)
				(xy 237.39983 -73.74001) (xy 237.42777 -73.76795) (xy 237.42777 -73.768204) (xy 237.50651 -73.84669)
				(xy 237.517178 -73.857612) (xy 237.517432 -73.857612) (xy 237.545118 -73.885552)
				(arc
					(start 237.545118 -73.889108)
					(mid 237.592944 -73.970924)
					(end 237.617 -74.06259)
				)
				(xy 237.61954 -74.06513) (xy 237.61954 -74.230484) (xy 238.376206 -73.852024)
			)
		)
	)
	(zone
		(net "GND")
		(layer "B.Cu")
		(hatch none 0.5)
		(connect_pads
			(clearance 0.5)
		)
		(min_thickness 0.25)
		(fill yes
			(thermal_gap 0.5)
			(thermal_bridge_width 0.5)
			(island_removal_mode 0)
		)
		(polygon
			(pts
				(xy 47.133002 -255.47955) (xy 46.244002 -256.36855) (xy 46.244002 -259.012182) (xy 46.62297 -259.39115)
				(xy 50.496724 -259.39115) (xy 50.978054 -258.90982) (xy 50.978054 -256.404872) (xy 50.052732 -255.47955)
			)
		)
	)
	(zone
		(layer "B.Cu")
		(hatch none 0.5)
		(connect_pads
			(clearance 0)
		)
		(min_thickness 0.25)
		(keepout
			(tracks not_allowed)
			(vias allowed)
			(pads allowed)
			(copperpour not_allowed)
			(footprints allowed)
		)
		(placement
			(enabled no)
			(sheetname "")
		)
		(fill
			(thermal_gap 0.5)
			(thermal_bridge_width 0.5)
			(island_removal_mode 0)
		)
		(polygon
			(pts
				(arc
					(start 307.200046 -393.199874)
					(mid 300.20006 -386.199888)
					(end 293.200074 -393.199874)
				)
				(arc
					(start 293.200074 -399.200116)
					(mid 300.20006 -406.200102)
					(end 307.200046 -399.200116)
				)
			)
		)
	)
	(zone
		(layer "B.Cu")
		(hatch none 0.5)
		(connect_pads
			(clearance 0)
		)
		(min_thickness 0.25)
		(keepout
			(tracks not_allowed)
			(vias allowed)
			(pads allowed)
			(copperpour not_allowed)
			(footprints allowed)
		)
		(placement
			(enabled no)
			(sheetname "")
		)
		(fill
			(thermal_gap 0.5)
			(thermal_bridge_width 0.5)
			(island_removal_mode 0)
		)
		(polygon
			(pts
				(arc
					(start 337.674966 -207.79994)
					(mid 330.67498 -200.799954)
					(end 323.674994 -207.79994)
				)
				(arc
					(start 323.674994 -213.799928)
					(mid 330.67498 -220.799914)
					(end 337.674966 -213.799928)
				)
			)
		)
	)
	(zone
		(layer "B.Cu")
		(hatch none 0.5)
		(connect_pads
			(clearance 0)
		)
		(min_thickness 0.25)
		(keepout
			(tracks not_allowed)
			(vias allowed)
			(pads allowed)
			(copperpour not_allowed)
			(footprints allowed)
		)
		(placement
			(enabled no)
			(sheetname "")
		)
		(fill
			(thermal_gap 0.5)
			(thermal_bridge_width 0.5)
			(island_removal_mode 0)
		)
		(polygon
			(pts
				(arc
					(start 271.970754 -310.52135)
					(mid 271.58696 -310.904763)
					(end 271.9705 -311.28843)
				)
				(arc
					(start 273.1135 -311.28843)
					(mid 273.49704 -310.90489)
					(end 273.1135 -310.52135)
				)
				(arc
					(start 272.768568 -310.52135)
					(mid 272.765366 -310.54819)
					(end 272.76425 -310.575198)
				)
				(arc
					(start 272.76425 -310.723788)
					(mid 272.791127 -310.793906)
					(end 272.857976 -310.828182)
				)
				(arc
					(start 272.857976 -310.828182)
					(mid 273.380217 -310.904636)
					(end 272.857976 -310.98109)
				)
				(xy 272.837656 -310.98109)
				(arc
					(start 272.83537 -310.978804)
					(mid 272.687253 -310.905687)
					(end 272.614136 -310.75757)
				)
				(xy 272.61185 -310.755284) (xy 272.61185 -310.543702) (xy 272.612866 -310.542686) (xy 272.614644 -310.52135)
				(arc
					(start 272.474436 -310.52135)
					(mid 272.472724 -310.54825)
					(end 272.47215 -310.575198)
				)
				(xy 272.47215 -310.755284)
				(arc
					(start 272.469864 -310.75757)
					(mid 272.396747 -310.905687)
					(end 272.24863 -310.978804)
				)
				(xy 272.246344 -310.98109)
				(arc
					(start 272.226024 -310.98109)
					(mid 271.703783 -310.904636)
					(end 272.226024 -310.828182)
				)
				(arc
					(start 272.226024 -310.828182)
					(mid 272.292939 -310.793965)
					(end 272.31975 -310.723788)
				)
				(xy 272.31975 -310.543702) (xy 272.320512 -310.54294) (xy 272.321528 -310.52135)
			)
		)
	)
	(zone
		(layer "B.Cu")
		(hatch none 0.5)
		(connect_pads
			(clearance 0)
		)
		(min_thickness 0.25)
		(keepout
			(tracks not_allowed)
			(vias allowed)
			(pads allowed)
			(copperpour not_allowed)
			(footprints allowed)
		)
		(placement
			(enabled no)
			(sheetname "")
		)
		(fill
			(thermal_gap 0.5)
			(thermal_bridge_width 0.5)
			(island_removal_mode 0)
		)
		(polygon
			(pts
				(arc
					(start 271.970754 -337.52155)
					(mid 271.58696 -337.904963)
					(end 271.9705 -338.28863)
				)
				(arc
					(start 273.1135 -338.28863)
					(mid 273.49704 -337.90509)
					(end 273.1135 -337.52155)
				)
				(arc
					(start 272.768568 -337.52155)
					(mid 272.765366 -337.54839)
					(end 272.76425 -337.575398)
				)
				(arc
					(start 272.76425 -337.723988)
					(mid 272.791127 -337.794106)
					(end 272.857976 -337.828382)
				)
				(arc
					(start 272.857976 -337.828382)
					(mid 273.380217 -337.904836)
					(end 272.857976 -337.98129)
				)
				(xy 272.837656 -337.98129)
				(arc
					(start 272.83537 -337.979004)
					(mid 272.687253 -337.905887)
					(end 272.614136 -337.75777)
				)
				(xy 272.61185 -337.755484) (xy 272.61185 -337.543902) (xy 272.612866 -337.542886) (xy 272.614644 -337.52155)
				(arc
					(start 272.474436 -337.52155)
					(mid 272.472724 -337.54845)
					(end 272.47215 -337.575398)
				)
				(xy 272.47215 -337.755484)
				(arc
					(start 272.469864 -337.75777)
					(mid 272.396747 -337.905887)
					(end 272.24863 -337.979004)
				)
				(xy 272.246344 -337.98129)
				(arc
					(start 272.226024 -337.98129)
					(mid 271.703783 -337.904836)
					(end 272.226024 -337.828382)
				)
				(arc
					(start 272.226024 -337.828382)
					(mid 272.292939 -337.794165)
					(end 272.31975 -337.723988)
				)
				(xy 272.31975 -337.543902) (xy 272.320512 -337.54314) (xy 272.321528 -337.52155)
			)
		)
	)
	(zone
		(layer "B.Cu")
		(hatch none 0.5)
		(connect_pads
			(clearance 0)
		)
		(min_thickness 0.25)
		(keepout
			(tracks not_allowed)
			(vias allowed)
			(pads allowed)
			(copperpour not_allowed)
			(footprints allowed)
		)
		(placement
			(enabled no)
			(sheetname "")
		)
		(fill
			(thermal_gap 0.5)
			(thermal_bridge_width 0.5)
			(island_removal_mode 0)
		)
		(polygon
			(pts
				(arc
					(start 219.54871 -406.000204)
					(mid 219.000197 -405.45131)
					(end 218.45143 -405.99995)
				)
				(xy 218.45143 -406.458674)
				(arc
					(start 218.817698 -406.458674)
					(mid 218.832542 -406.457324)
					(end 218.846908 -406.45334)
				)
				(arc
					(start 218.846908 -406.45334)
					(mid 218.885274 -406.425356)
					(end 218.904058 -406.381712)
				)
				(arc
					(start 218.904058 -406.381712)
					(mid 219.00047 -405.6063)
					(end 219.09532 -406.381966)
				)
				(xy 219.09532 -406.40889)
				(arc
					(start 219.092018 -406.412192)
					(mid 219.032692 -406.546017)
					(end 218.913964 -406.631648)
				)
				(arc
					(start 218.913964 -406.631648)
					(mid 218.887652 -406.640101)
					(end 218.860624 -406.645872)
				)
				(xy 218.857068 -406.649174) (xy 218.45143 -406.649174) (xy 218.45143 -406.750774) (xy 218.854782 -406.750774)
				(arc
					(start 218.858084 -406.754076)
					(mid 219.013316 -406.832778)
					(end 219.092018 -406.98801)
				)
				(xy 219.09532 -406.991312)
				(arc
					(start 219.09532 -407.017982)
					(mid 219.00047 -407.793709)
					(end 218.904058 -407.018236)
				)
				(arc
					(start 218.904058 -407.018236)
					(mid 218.874144 -406.963128)
					(end 218.815412 -406.941274)
				)
				(xy 218.45143 -406.941274)
				(arc
					(start 218.45143 -407.399998)
					(mid 219.00007 -407.948638)
					(end 219.54871 -407.399998)
				)
			)
		)
	)
	(zone
		(layer "B.Cu")
		(hatch none 0.5)
		(connect_pads
			(clearance 0)
		)
		(min_thickness 0.25)
		(keepout
			(tracks not_allowed)
			(vias allowed)
			(pads allowed)
			(copperpour not_allowed)
			(footprints allowed)
		)
		(placement
			(enabled no)
			(sheetname "")
		)
		(fill
			(thermal_gap 0.5)
			(thermal_bridge_width 0.5)
			(island_removal_mode 0)
		)
		(polygon
			(pts
				(arc
					(start 451.3199 -47.178722)
					(mid 450.939027 -46.797468)
					(end 450.5579 -47.178468)
				)
				(xy 450.5579 -47.527718)
				(arc
					(start 450.762116 -47.527718)
					(mid 450.830772 -47.500643)
					(end 450.862446 -47.433992)
				)
				(arc
					(start 450.862446 -47.433992)
					(mid 450.939022 -46.911751)
					(end 451.0151 -47.433992)
				)
				(xy 451.0151 -47.45863)
				(arc
					(start 451.012814 -47.460916)
					(mid 450.940988 -47.606006)
					(end 450.795898 -47.677832)
				)
				(xy 450.793612 -47.680118) (xy 450.5579 -47.680118) (xy 450.5579 -47.819818) (xy 450.793612 -47.819818)
				(arc
					(start 450.795898 -47.822104)
					(mid 450.940988 -47.89393)
					(end 451.012814 -48.03902)
				)
				(xy 451.0151 -48.041306)
				(arc
					(start 451.0151 -48.065944)
					(mid 450.939022 -48.588112)
					(end 450.862446 -48.065944)
				)
				(arc
					(start 450.862446 -48.065944)
					(mid 450.830758 -47.999308)
					(end 450.762116 -47.972218)
				)
				(xy 450.5579 -47.972218)
				(arc
					(start 450.5579 -48.321468)
					(mid 450.9389 -48.702468)
					(end 451.3199 -48.321468)
				)
			)
		)
	)
	(zone
		(layer "B.Cu")
		(hatch none 0.5)
		(connect_pads
			(clearance 0)
		)
		(min_thickness 0.25)
		(keepout
			(tracks not_allowed)
			(vias allowed)
			(pads allowed)
			(copperpour not_allowed)
			(footprints allowed)
		)
		(placement
			(enabled no)
			(sheetname "")
		)
		(fill
			(thermal_gap 0.5)
			(thermal_bridge_width 0.5)
			(island_removal_mode 0)
		)
		(polygon
			(pts
				(arc
					(start 281.074876 -49.849786)
					(mid 281.399742 -48.875188)
					(end 280.425144 -48.550322)
				)
				(xy 280.423874 -48.548036)
				(arc
					(start 279.406858 -49.056544)
					(mid 279.435725 -49.070181)
					(end 279.464008 -49.084992)
				)
				(arc
					(start 279.464262 -49.084992)
					(mid 279.540831 -49.13305)
					(end 279.611328 -49.18964)
				)
				(xy 279.612598 -49.18964) (xy 279.640284 -49.217326) (xy 279.640538 -49.21758) (xy 279.775158 -49.3522)
				(arc
					(start 279.845516 -49.422558)
					(mid 279.884556 -49.451044)
					(end 279.930352 -49.4665)
				)
				(xy 279.933908 -49.467008)
				(arc
					(start 279.948894 -49.469548)
					(mid 279.998664 -49.469389)
					(end 280.045922 -49.4538)
				)
				(arc
					(start 280.22804 -49.360582)
					(mid 280.203915 -49.208924)
					(end 280.22296 -49.056544)
				)
				(arc
					(start 280.22296 -49.056544)
					(mid 281.286157 -49.095637)
					(end 280.314908 -49.53)
				)
				(xy 280.13279 -49.623472) (xy 280.097738 -49.641506)
				(arc
					(start 280.094182 -49.640236)
					(mid 280.028424 -49.65745)
					(end 279.960578 -49.661572)
				)
				(xy 279.95753 -49.663858) (xy 279.918414 -49.657508) (xy 279.903428 -49.654968) (xy 279.898856 -49.654206)
				(xy 279.864058 -49.648618)
				(arc
					(start 279.86228 -49.646078)
					(mid 279.799382 -49.62141)
					(end 279.742392 -49.585118)
				)
				(xy 279.738836 -49.585118) (xy 279.505918 -49.3522)
				(arc
					(start 279.505664 -49.351946)
					(mid 279.442649 -49.297324)
					(end 279.372568 -49.252124)
				)
				(arc
					(start 279.372568 -49.252124)
					(mid 279.266851 -49.206921)
					(end 279.154382 -49.183036)
				)
				(xy 278.958548 -49.280826) (xy 279.127712 -49.280826)
				(arc
					(start 279.12949 -49.282604)
					(mid 279.229597 -49.301764)
					(end 279.323546 -49.341278)
				)
				(arc
					(start 279.323546 -49.341278)
					(mid 279.364913 -49.366858)
					(end 279.403556 -49.396396)
				)
				(xy 279.405842 -49.396396) (xy 279.433528 -49.423828) (xy 279.433782 -49.424336) (xy 279.562814 -49.553368)
				(arc
					(start 279.562814 -49.558194)
					(mid 279.605174 -49.651561)
					(end 279.608788 -49.754028)
				)
				(arc
					(start 279.608788 -49.754282)
					(mid 279.572867 -49.85032)
					(end 279.503124 -49.925478)
				)
				(xy 279.5016 -49.930304)
				(arc
					(start 279.273508 -50.04435)
					(mid 278.262231 -50.445097)
					(end 279.188164 -49.87417)
				)
				(arc
					(start 279.38095 -49.77765)
					(mid 279.407376 -49.755378)
					(end 279.420828 -49.723548)
				)
				(arc
					(start 279.420828 -49.723548)
					(mid 279.418215 -49.689297)
					(end 279.400254 -49.660048)
				)
				(arc
					(start 279.298654 -49.558702)
					(mid 279.266896 -49.531197)
					(end 279.231598 -49.50841)
				)
				(arc
					(start 279.231598 -49.50841)
					(mid 279.162303 -49.480864)
					(end 279.088342 -49.471326)
				)
				(xy 278.577548 -49.471326) (xy 278.424132 -49.548034) (xy 278.424132 -49.548288)
				(arc
					(start 278.425148 -49.55032)
					(mid 278.100282 -50.524918)
					(end 279.07488 -50.849784)
				)
				(xy 279.07615 -50.85207) (xy 281.076146 -49.852072)
			)
		)
	)
	(zone
		(net "GND")
		(layer "B.Cu")
		(hatch none 0.5)
		(connect_pads
			(clearance 0.5)
		)
		(min_thickness 0.25)
		(fill yes
			(thermal_gap 0.5)
			(thermal_bridge_width 0.5)
			(island_removal_mode 0)
		)
		(polygon
			(pts
				(xy 215.630506 -99.0092) (xy 215.151208 -99.488498) (xy 215.151208 -109.30763) (xy 215.452452 -109.608874)
				(xy 219.41536 -109.608874) (xy 219.819728 -109.204506) (xy 219.819728 -99.2632) (xy 219.565728 -99.0092)
			)
		)
	)
	(zone
		(layer "B.Cu")
		(hatch none 0.5)
		(connect_pads
			(clearance 0)
		)
		(min_thickness 0.25)
		(keepout
			(tracks not_allowed)
			(vias allowed)
			(pads allowed)
			(copperpour not_allowed)
			(footprints allowed)
		)
		(placement
			(enabled no)
			(sheetname "")
		)
		(fill
			(thermal_gap 0.5)
			(thermal_bridge_width 0.5)
			(island_removal_mode 0)
		)
		(polygon
			(pts
				(arc
					(start 472.250008 -269.999968)
					(mid 467.499954 -265.249914)
					(end 462.7499 -269.999968)
				)
				(arc
					(start 462.7499 -269.999968)
					(mid 467.499954 -274.750022)
					(end 472.250008 -269.999968)
				)
			)
		)
	)
	(zone
		(layer "B.Cu")
		(hatch none 0.5)
		(connect_pads
			(clearance 0)
		)
		(min_thickness 0.25)
		(keepout
			(tracks not_allowed)
			(vias allowed)
			(pads allowed)
			(copperpour not_allowed)
			(footprints allowed)
		)
		(placement
			(enabled no)
			(sheetname "")
		)
		(fill
			(thermal_gap 0.5)
			(thermal_bridge_width 0.5)
			(island_removal_mode 0)
		)
		(polygon
			(pts
				(arc
					(start 278.23668 -333.756508)
					(mid 277.68804 -334.305148)
					(end 278.23668 -334.853788)
				)
				(xy 278.642826 -334.853788) (xy 278.644096 -334.852518)
				(arc
					(start 278.661876 -334.832706)
					(mid 278.700943 -334.762128)
					(end 278.714454 -334.682592)
				)
				(arc
					(start 278.714454 -334.432148)
					(mid 278.699575 -334.396227)
					(end 278.663654 -334.381348)
				)
				(arc
					(start 278.623014 -334.381348)
					(mid 277.842903 -334.305148)
					(end 278.623014 -334.228948)
				)
				(xy 278.69515 -334.228948)
				(arc
					(start 278.698198 -334.231996)
					(mid 278.807275 -334.288527)
					(end 278.863806 -334.397604)
				)
				(xy 278.866854 -334.400652) (xy 278.866854 -334.714088)
				(arc
					(start 278.865584 -334.715612)
					(mid 278.852891 -334.786453)
					(end 278.827484 -334.853788)
				)
				(arc
					(start 278.97836 -334.853788)
					(mid 278.999445 -334.769598)
					(end 279.006554 -334.6831)
				)
				(xy 279.006554 -334.400652)
				(arc
					(start 279.009602 -334.397604)
					(mid 279.066133 -334.288527)
					(end 279.17521 -334.231996)
				)
				(xy 279.178258 -334.228948)
				(arc
					(start 279.250394 -334.228948)
					(mid 280.030505 -334.305148)
					(end 279.250394 -334.381348)
				)
				(arc
					(start 279.209754 -334.381348)
					(mid 279.173833 -334.396227)
					(end 279.158954 -334.432148)
				)
				(xy 279.158954 -334.6831) (xy 279.158954 -334.714596)
				(arc
					(start 279.158192 -334.715358)
					(mid 279.151335 -334.785109)
					(end 279.137364 -334.853788)
				)
				(arc
					(start 279.636728 -334.853788)
					(mid 280.185368 -334.305148)
					(end 279.636728 -333.756508)
				)
				(xy 278.236934 -333.756508)
			)
		)
	)
	(zone
		(layer "B.Cu")
		(hatch none 0.5)
		(connect_pads
			(clearance 0)
		)
		(min_thickness 0.25)
		(keepout
			(tracks allowed)
			(vias allowed)
			(pads allowed)
			(copperpour allowed)
			(footprints allowed)
		)
		(placement
			(enabled no)
			(sheetname "")
		)
		(fill
			(thermal_gap 0.5)
			(thermal_bridge_width 0.5)
			(island_removal_mode 0)
		)
		(polygon
			(pts
				(xy 216.243408 -118.849902) (xy 216.243408 -120.6246) (xy 215.1634 -120.6246) (xy 215.1634 -118.849902)
			)
		)
	)
	(zone
		(net "AGND_P5V_A")
		(layer "B.Cu")
		(hatch none 0.5)
		(connect_pads
			(clearance 0.5)
		)
		(min_thickness 0.25)
		(fill yes
			(thermal_gap 0.5)
			(thermal_bridge_width 0.5)
			(island_removal_mode 0)
		)
		(polygon
			(pts
				(xy 28.083002 -253.532386) (xy 27.736038 -253.87935) (xy 27.727402 -253.87935) (xy 27.727402 -254.818388)
				(xy 27.803602 -254.894588) (xy 29.988002 -254.894588) (xy 29.988002 -254.89535) (xy 30.445202 -254.89535)
				(xy 30.741112 -254.59944) (xy 30.741112 -253.686056) (xy 30.587442 -253.532386)
			)
		)
		(polygon
			(pts
				(xy 30.236414 -253.953264) (xy 30.033214 -253.953264) (xy 30.033214 -254.156464) (xy 30.236414 -254.156464)
			)
		)
	)
	(zone
		(net "GND")
		(layer "B.Cu")
		(hatch none 0.5)
		(connect_pads
			(clearance 0.5)
		)
		(min_thickness 0.25)
		(fill yes
			(thermal_gap 0.5)
			(thermal_bridge_width 0.5)
			(island_removal_mode 0)
		)
		(polygon
			(pts
				(arc
					(start 229.298754 -226.169728)
					(mid 231.184126 -224.949431)
					(end 233.429556 -224.908618)
				)
				(arc
					(start 241.15268 -199.455532)
					(mid 239.484589 -198.670053)
					(end 238.330994 -197.231762)
				)
				(arc
					(start 238.330994 -197.231762)
					(mid 238.024763 -196.982286)
					(end 237.744 -196.704458)
				)
				(arc
					(start 237.744 -196.704458)
					(mid 236.375001 -195.300013)
					(end 235.817156 -193.41973)
				)
				(arc
					(start 235.817156 -193.41973)
					(mid 235.201585 -190.783144)
					(end 236.367828 -188.33973)
				)
				(arc
					(start 236.367828 -188.33973)
					(mid 236.251734 -188.252879)
					(end 236.138212 -188.162692)
				)
				(xy 220.772228 -188.162692) (xy 215.467946 -179.709318) (xy 215.467946 -178.108356) (xy 215.442546 -178.082956)
				(xy 215.442546 -172.056044) (xy 218.118944 -169.379646) (xy 223.101154 -169.379646) (xy 223.4692 -169.0116)
				(xy 223.4692 -167.361362) (xy 220.075506 -162.329368) (xy 216.117932 -141.965172) (xy 216.178384 -141.654784)
				(xy 214.9856 -140.462) (xy 212.402674 -140.462) (xy 211.577682 -141.286992) (xy 209.669634 -141.286992)
				(arc
					(start 192.891918 -158.064708)
					(mid 193.949024 -159.45599)
					(end 194.324478 -161.162492)
				)
				(arc
					(start 194.324478 -164.337746)
					(mid 194.185719 -165.390839)
					(end 193.778886 -166.372032)
				)
				(arc
					(start 193.778886 -166.372032)
					(mid 195.414457 -168.277326)
					(end 195.628514 -170.779186)
				)
				(arc
					(start 195.628514 -170.779186)
					(mid 195.833893 -171.673952)
					(end 195.834508 -172.591984)
				)
				(arc
					(start 195.834508 -175.128174)
					(mid 207.154711 -174.134307)
					(end 213.12124 -183.805576)
				)
				(arc
					(start 213.12124 -189.799976)
					(mid 210.84548 -196.438688)
					(end 204.97546 -200.285096)
				)
				(arc
					(start 222.726758 -200.285096)
					(mid 225.046791 -200.709077)
					(end 226.74707 -202.343512)
				)
				(arc
					(start 226.74707 -202.343512)
					(mid 229.302494 -204.847811)
					(end 228.910134 -208.404206)
				)
				(arc
					(start 228.910134 -208.404206)
					(mid 228.98805 -208.79555)
					(end 229.027482 -209.192622)
				)
				(arc
					(start 229.027482 -209.192622)
					(mid 229.871297 -209.557043)
					(end 230.612442 -210.100672)
				)
				(arc
					(start 230.612442 -210.100672)
					(mid 233.373793 -214.791816)
					(end 229.02926 -218.0717)
				)
				(arc
					(start 229.02926 -218.0717)
					(mid 228.601086 -220.816263)
					(end 226.51847 -222.654368)
				)
				(arc
					(start 226.51847 -222.654368)
					(mid 226.088772 -223.290814)
					(end 225.547682 -223.835722)
				)
				(arc
					(start 225.547682 -223.835722)
					(mid 227.056033 -224.826068)
					(end 227.991416 -226.369118)
				)
				(arc
					(start 227.991416 -226.369118)
					(mid 228.636974 -226.216254)
					(end 229.298754 -226.169728)
				)
			)
		)
		(polygon
			(pts
				(arc
					(start 201.721974 -164.042598)
					(mid 201.566795 -164.452164)
					(end 201.45629 -164.875972)
				)
				(arc
					(start 201.45629 -164.875972)
					(mid 200.127954 -167.866964)
					(end 201.41692 -170.875198)
				)
				(arc
					(start 201.41692 -170.875198)
					(mid 204.85481 -172.747934)
					(end 208.2927 -170.875198)
				)
				(arc
					(start 208.2927 -170.875198)
					(mid 209.364941 -169.208189)
					(end 209.527902 -167.232838)
				)
				(arc
					(start 209.527902 -167.232838)
					(mid 209.557621 -166.725099)
					(end 209.524092 -166.2176)
				)
				(arc
					(start 209.524092 -166.2176)
					(mid 208.849544 -163.3935)
					(end 206.471266 -161.727896)
				)
				(arc
					(start 206.471266 -161.727896)
					(mid 206.565468 -161.495486)
					(end 206.645256 -161.257742)
				)
				(arc
					(start 206.645256 -161.257742)
					(mid 208.144692 -158.231329)
					(end 206.858108 -155.108402)
				)
				(arc
					(start 206.858108 -155.108402)
					(mid 203.420218 -153.235666)
					(end 199.982328 -155.108402)
				)
				(arc
					(start 199.982328 -155.108402)
					(mid 198.96233 -156.6304)
					(end 198.708772 -158.444946)
				)
				(arc
					(start 198.708772 -158.444946)
					(mid 198.655611 -158.981625)
					(end 198.673466 -159.520636)
				)
				(arc
					(start 198.673466 -159.520636)
					(mid 199.334597 -162.363503)
					(end 201.721974 -164.042598)
				)
			)
		)
	)
	(zone
		(layer "B.Cu")
		(hatch none 0.5)
		(connect_pads
			(clearance 0)
		)
		(min_thickness 0.25)
		(keepout
			(tracks not_allowed)
			(vias allowed)
			(pads allowed)
			(copperpour not_allowed)
			(footprints allowed)
		)
		(placement
			(enabled no)
			(sheetname "")
		)
		(fill
			(thermal_gap 0.5)
			(thermal_bridge_width 0.5)
			(island_removal_mode 0)
		)
		(polygon
			(pts
				(arc
					(start 238.374936 -49.849786)
					(mid 238.699802 -48.875188)
					(end 237.725204 -48.550322)
				)
				(xy 237.723934 -48.548036)
				(arc
					(start 236.706918 -49.056544)
					(mid 236.735785 -49.070181)
					(end 236.764068 -49.084992)
				)
				(arc
					(start 236.764322 -49.084992)
					(mid 236.840891 -49.13305)
					(end 236.911388 -49.18964)
				)
				(xy 236.912658 -49.18964) (xy 236.940344 -49.217326) (xy 236.940598 -49.21758)
				(arc
					(start 237.145576 -49.422558)
					(mid 237.184616 -49.451044)
					(end 237.230412 -49.4665)
				)
				(arc
					(start 237.248954 -49.469548)
					(mid 237.298724 -49.469389)
					(end 237.345982 -49.4538)
				)
				(arc
					(start 237.5281 -49.360582)
					(mid 238.536063 -48.950991)
					(end 237.614968 -49.53)
				)
				(xy 237.43285 -49.623472) (xy 237.397798 -49.641506)
				(arc
					(start 237.394242 -49.640236)
					(mid 237.328484 -49.65745)
					(end 237.260638 -49.661572)
				)
				(xy 237.25759 -49.663858) (xy 237.203488 -49.654968) (xy 237.198916 -49.654206) (xy 237.164118 -49.648618)
				(arc
					(start 237.16234 -49.646078)
					(mid 237.099442 -49.62141)
					(end 237.042452 -49.585118)
				)
				(xy 237.038896 -49.585118) (xy 237.010956 -49.557178)
				(arc
					(start 236.805724 -49.351946)
					(mid 236.742709 -49.297324)
					(end 236.672628 -49.252124)
				)
				(arc
					(start 236.672628 -49.252124)
					(mid 236.566911 -49.206921)
					(end 236.454442 -49.183036)
				)
				(xy 236.258608 -49.280826) (xy 236.427772 -49.280826)
				(arc
					(start 236.42955 -49.282604)
					(mid 236.529657 -49.301764)
					(end 236.623606 -49.341278)
				)
				(arc
					(start 236.623606 -49.341278)
					(mid 236.664973 -49.366858)
					(end 236.703616 -49.396396)
				)
				(xy 236.705902 -49.396396) (xy 236.733588 -49.423828) (xy 236.733842 -49.424336) (xy 236.862874 -49.553368)
				(arc
					(start 236.862874 -49.558194)
					(mid 236.905234 -49.651561)
					(end 236.908848 -49.754028)
				)
				(arc
					(start 236.908848 -49.754282)
					(mid 236.872927 -49.85032)
					(end 236.803184 -49.925478)
				)
				(xy 236.80166 -49.930304)
				(arc
					(start 236.573568 -50.04435)
					(mid 235.562291 -50.445097)
					(end 236.488224 -49.87417)
				)
				(arc
					(start 236.68101 -49.77765)
					(mid 236.707436 -49.755378)
					(end 236.720888 -49.723548)
				)
				(arc
					(start 236.720888 -49.723548)
					(mid 236.718275 -49.689297)
					(end 236.700314 -49.660048)
				)
				(arc
					(start 236.598714 -49.558702)
					(mid 236.566956 -49.531197)
					(end 236.531658 -49.50841)
				)
				(arc
					(start 236.531658 -49.50841)
					(mid 236.462363 -49.480864)
					(end 236.388402 -49.471326)
				)
				(xy 235.877608 -49.471326) (xy 235.724192 -49.548034) (xy 235.724192 -49.548288)
				(arc
					(start 235.725208 -49.55032)
					(mid 235.400342 -50.524918)
					(end 236.37494 -50.849784)
				)
				(xy 236.37621 -50.85207) (xy 238.376206 -49.852072)
			)
		)
	)
	(zone
		(layer "B.Cu")
		(hatch none 0.5)
		(connect_pads
			(clearance 0)
		)
		(min_thickness 0.25)
		(keepout
			(tracks not_allowed)
			(vias allowed)
			(pads allowed)
			(copperpour not_allowed)
			(footprints allowed)
		)
		(placement
			(enabled no)
			(sheetname "")
		)
		(fill
			(thermal_gap 0.5)
			(thermal_bridge_width 0.5)
			(island_removal_mode 0)
		)
		(polygon
			(pts
				(arc
					(start 281.074876 -69.849746)
					(mid 281.399742 -68.875148)
					(end 280.425144 -68.550282)
				)
				(xy 280.423874 -68.547996) (xy 278.424132 -69.547994) (xy 278.424132 -69.548248)
				(arc
					(start 278.425148 -69.55028)
					(mid 278.100282 -70.524878)
					(end 279.07488 -70.849744)
				)
				(xy 279.07615 -70.85203)
				(arc
					(start 280.086562 -70.346824)
					(mid 279.982979 -70.285372)
					(end 279.888696 -70.210426)
				)
				(xy 279.887426 -70.210426)
				(arc
					(start 279.654508 -69.977508)
					(mid 279.615468 -69.949022)
					(end 279.569672 -69.933566)
				)
				(xy 279.566116 -69.933058)
				(arc
					(start 279.55113 -69.930518)
					(mid 279.50136 -69.930677)
					(end 279.454102 -69.946266)
				)
				(arc
					(start 279.271984 -70.039484)
					(mid 278.264021 -70.449075)
					(end 279.185116 -69.870066)
				)
				(xy 279.367234 -69.776594) (xy 279.402286 -69.75856)
				(arc
					(start 279.405842 -69.75983)
					(mid 279.4716 -69.742616)
					(end 279.539446 -69.738494)
				)
				(xy 279.542494 -69.736208) (xy 279.58161 -69.742558) (xy 279.596596 -69.745098) (xy 279.601168 -69.74586)
				(xy 279.635966 -69.751448)
				(arc
					(start 279.637744 -69.753988)
					(mid 279.700642 -69.778656)
					(end 279.757632 -69.814948)
				)
				(xy 279.761188 -69.814948) (xy 279.879298 -69.933058)
				(arc
					(start 279.994106 -70.047866)
					(mid 280.143896 -70.161519)
					(end 280.318718 -70.230746)
				)
				(xy 280.481786 -70.149212) (xy 280.445464 -70.149212)
				(arc
					(start 280.44394 -70.147688)
					(mid 280.258325 -70.104052)
					(end 280.096214 -70.00367)
				)
				(xy 280.094182 -70.00367) (xy 280.066242 -69.97573) (xy 279.93721 -69.846698)
				(arc
					(start 279.93721 -69.841872)
					(mid 279.89485 -69.748505)
					(end 279.891236 -69.646038)
				)
				(arc
					(start 279.891236 -69.645784)
					(mid 279.927157 -69.549746)
					(end 279.9969 -69.474588)
				)
				(xy 279.998424 -69.469762)
				(arc
					(start 280.226516 -69.355716)
					(mid 281.237793 -68.954969)
					(end 280.31186 -69.525896)
				)
				(arc
					(start 280.119074 -69.622416)
					(mid 280.092648 -69.644688)
					(end 280.079196 -69.676518)
				)
				(arc
					(start 280.079196 -69.676518)
					(mid 280.081809 -69.710769)
					(end 280.09977 -69.740018)
				)
				(arc
					(start 280.200862 -69.84111)
					(mid 280.331149 -69.928165)
					(end 280.484834 -69.958712)
				)
				(xy 280.862786 -69.958712) (xy 281.076146 -69.852032)
			)
		)
	)
	(zone
		(layer "B.Cu")
		(hatch none 0.5)
		(connect_pads
			(clearance 0)
		)
		(min_thickness 0.25)
		(keepout
			(tracks not_allowed)
			(vias allowed)
			(pads allowed)
			(copperpour not_allowed)
			(footprints allowed)
		)
		(placement
			(enabled no)
			(sheetname "")
		)
		(fill
			(thermal_gap 0.5)
			(thermal_bridge_width 0.5)
			(island_removal_mode 0)
		)
		(polygon
			(pts
				(arc
					(start 357.49865 -21.950426)
					(mid 356.950137 -21.401532)
					(end 356.40137 -21.950172)
				)
				(arc
					(start 356.40137 -22.428708)
					(mid 356.466873 -22.416435)
					(end 356.533196 -22.409912)
				)
				(xy 356.534466 -22.408896)
				(arc
					(start 356.78364 -22.408896)
					(mid 356.833929 -22.388065)
					(end 356.85476 -22.337776)
				)
				(arc
					(start 356.85476 -22.332188)
					(mid 356.95001 -21.55646)
					(end 357.04526 -22.332188)
				)
				(xy 357.04526 -22.377146)
				(arc
					(start 357.041704 -22.380702)
					(mid 356.968626 -22.522762)
					(end 356.826566 -22.59584)
				)
				(xy 356.82301 -22.599396)
				(arc
					(start 356.573836 -22.599396)
					(mid 356.486594 -22.606019)
					(end 356.40137 -22.625812)
				)
				(arc
					(start 356.40137 -22.733508)
					(mid 356.465925 -22.713419)
					(end 356.532688 -22.702774)
				)
				(xy 356.534466 -22.700996) (xy 356.82301 -22.700996)
				(arc
					(start 356.826566 -22.704552)
					(mid 356.968626 -22.77763)
					(end 357.041704 -22.91969)
				)
				(xy 357.04526 -22.923246)
				(arc
					(start 357.04526 -22.968204)
					(mid 356.95001 -23.743932)
					(end 356.85476 -22.968204)
				)
				(arc
					(start 356.85476 -22.962616)
					(mid 356.833929 -22.912327)
					(end 356.78364 -22.891496)
				)
				(arc
					(start 356.573836 -22.891496)
					(mid 356.482761 -22.906582)
					(end 356.40137 -22.95017)
				)
				(arc
					(start 356.40137 -23.35022)
					(mid 356.95001 -23.89886)
					(end 357.49865 -23.35022)
				)
			)
		)
	)
	(zone
		(layer "B.Cu")
		(hatch none 0.5)
		(connect_pads
			(clearance 0)
		)
		(min_thickness 0.25)
		(keepout
			(tracks allowed)
			(vias allowed)
			(pads allowed)
			(copperpour allowed)
			(footprints allowed)
		)
		(placement
			(enabled no)
			(sheetname "")
		)
		(fill
			(thermal_gap 0.5)
			(thermal_bridge_width 0.5)
			(island_removal_mode 0)
		)
		(polygon
			(pts
				(xy 31.2928 -251.6378) (xy 31.2928 -249.0724) (xy 34.0106 -249.0724) (xy 34.0106 -251.6378)
			)
		)
	)
	(zone
		(layer "B.Cu")
		(hatch none 0.5)
		(connect_pads
			(clearance 0)
		)
		(min_thickness 0.25)
		(keepout
			(tracks allowed)
			(vias allowed)
			(pads allowed)
			(copperpour allowed)
			(footprints not_allowed)
		)
		(placement
			(enabled no)
			(sheetname "")
		)
		(fill
			(thermal_gap 0.5)
			(thermal_bridge_width 0.5)
			(island_removal_mode 0)
		)
		(polygon
			(pts
				(arc
					(start 233.59999 -143.500094)
					(mid 229.849934 -139.750038)
					(end 226.099878 -143.500094)
				)
				(arc
					(start 226.099878 -143.500094)
					(mid 229.849934 -147.25015)
					(end 233.59999 -143.500094)
				)
			)
		)
	)
	(zone
		(net "GND")
		(layer "B.Cu")
		(hatch none 0.5)
		(connect_pads
			(clearance 0.5)
		)
		(min_thickness 0.25)
		(fill yes
			(thermal_gap 0.5)
			(thermal_bridge_width 0.5)
			(island_removal_mode 0)
		)
		(polygon
			(pts
				(xy 63.668656 -150.83155) (xy 63.205868 -151.294338) (xy 63.205868 -154.278584) (xy 63.670434 -154.74315)
				(xy 67.447414 -154.74315) (xy 67.9196 -154.270964) (xy 67.9196 -151.275034) (xy 67.476116 -150.83155)
			)
		)
	)
	(zone
		(layer "B.Cu")
		(hatch none 0.5)
		(connect_pads
			(clearance 0)
		)
		(min_thickness 0.25)
		(keepout
			(tracks allowed)
			(vias allowed)
			(pads allowed)
			(copperpour allowed)
			(footprints not_allowed)
		)
		(placement
			(enabled no)
			(sheetname "")
		)
		(fill
			(thermal_gap 0.5)
			(thermal_bridge_width 0.5)
			(island_removal_mode 0)
		)
		(polygon
			(pts
				(arc
					(start 370.944902 -20.550124)
					(mid 372.150132 -21.755354)
					(end 373.355108 -20.550124)
				)
				(arc
					(start 373.355108 -20.550124)
					(mid 372.150132 -19.345148)
					(end 370.944902 -20.550124)
				)
			)
		)
	)
	(zone
		(layer "B.Cu")
		(hatch none 0.5)
		(connect_pads
			(clearance 0)
		)
		(min_thickness 0.25)
		(keepout
			(tracks not_allowed)
			(vias allowed)
			(pads allowed)
			(copperpour not_allowed)
			(footprints allowed)
		)
		(placement
			(enabled no)
			(sheetname "")
		)
		(fill
			(thermal_gap 0.5)
			(thermal_bridge_width 0.5)
			(island_removal_mode 0)
		)
		(polygon
			(pts
				(arc
					(start 384.498596 -20.950428)
					(mid 383.950083 -20.401534)
					(end 383.401316 -20.950174)
				)
				(arc
					(start 383.401316 -22.350222)
					(mid 383.949956 -22.898862)
					(end 384.498596 -22.350222)
				)
				(xy 384.498596 -21.891498)
				(arc
					(start 384.116326 -21.891498)
					(mid 384.066037 -21.912329)
					(end 384.045206 -21.962618)
				)
				(arc
					(start 384.045206 -21.968206)
					(mid 383.949956 -22.743934)
					(end 383.854706 -21.968206)
				)
				(xy 383.854706 -21.923248)
				(arc
					(start 383.858262 -21.919692)
					(mid 383.93134 -21.777632)
					(end 384.0734 -21.704554)
				)
				(xy 384.076956 -21.700998) (xy 384.498596 -21.700998) (xy 384.498596 -21.599398) (xy 384.076956 -21.599398)
				(arc
					(start 384.0734 -21.595842)
					(mid 383.93134 -21.522764)
					(end 383.858262 -21.380704)
				)
				(xy 383.854706 -21.377148)
				(arc
					(start 383.854706 -21.33219)
					(mid 383.949956 -20.556462)
					(end 384.045206 -21.33219)
				)
				(arc
					(start 384.045206 -21.337778)
					(mid 384.066037 -21.388067)
					(end 384.116326 -21.408898)
				)
				(xy 384.498596 -21.408898)
			)
		)
	)
	(zone
		(layer "B.Cu")
		(hatch none 0.5)
		(connect_pads
			(clearance 0)
		)
		(min_thickness 0.25)
		(keepout
			(tracks not_allowed)
			(vias allowed)
			(pads allowed)
			(copperpour not_allowed)
			(footprints allowed)
		)
		(placement
			(enabled no)
			(sheetname "")
		)
		(fill
			(thermal_gap 0.5)
			(thermal_bridge_width 0.5)
			(island_removal_mode 0)
		)
		(polygon
			(pts
				(arc
					(start 281.07386 -130.147314)
					(mid 281.397456 -129.176018)
					(end 280.42616 -128.852422)
				)
				(arc
					(start 279.487122 -129.321814)
					(mid 279.638469 -129.405624)
					(end 279.768554 -129.51968)
				)
				(xy 279.781762 -129.523998) (xy 279.832308 -129.624074) (xy 279.849834 -129.65938) (xy 279.867614 -129.694432)
				(xy 279.867614 -129.694686)
				(arc
					(start 279.892506 -129.74447)
					(mid 279.932791 -129.779466)
					(end 279.985978 -129.775712)
				)
				(arc
					(start 280.226516 -129.655316)
					(mid 281.23834 -129.255442)
					(end 280.31186 -129.82575)
				)
				(xy 280.071322 -129.945892) (xy 280.036016 -129.963672)
				(arc
					(start 280.03119 -129.962148)
					(mid 279.872501 -129.960135)
					(end 279.744424 -129.86639)
				)
				(xy 279.739598 -129.864866) (xy 279.722072 -129.829814) (xy 279.722072 -129.82956) (xy 279.679654 -129.744724)
				(arc
					(start 279.634696 -129.65557)
					(mid 279.450574 -129.514749)
					(end 279.227534 -129.451608)
				)
				(xy 279.028906 -129.550922) (xy 279.213056 -129.550922)
				(arc
					(start 279.214834 -129.552446)
					(mid 279.379517 -129.593656)
					(end 279.52192 -129.68605)
				)
				(xy 279.539192 -129.691638) (xy 279.623774 -129.860548) (xy 279.640792 -129.877566) (xy 279.640792 -129.89433)
				(xy 279.648412 -129.90957)
				(arc
					(start 279.646634 -129.914396)
					(mid 279.644931 -130.07313)
					(end 279.551384 -130.201416)
				)
				(xy 279.54986 -130.206242) (xy 279.514554 -130.223768)
				(arc
					(start 279.273508 -130.344418)
					(mid 278.261684 -130.744292)
					(end 279.188164 -130.173984)
				)
				(arc
					(start 279.42921 -130.053588)
					(mid 279.462054 -130.018913)
					(end 279.46477 -129.971292)
				)
				(xy 279.450292 -129.95656) (xy 279.450292 -129.939542)
				(arc
					(start 279.393904 -129.82702)
					(mid 279.291818 -129.763585)
					(end 279.173686 -129.741422)
				)
				(xy 278.647906 -129.741422) (xy 278.426418 -129.852166)
				(arc
					(start 278.426418 -129.85242)
					(mid 278.102619 -130.823564)
					(end 279.073864 -131.147312)
				)
			)
		)
	)
	(zone
		(layer "B.Cu")
		(hatch none 0.5)
		(connect_pads
			(clearance 0)
		)
		(min_thickness 0.25)
		(keepout
			(tracks not_allowed)
			(vias allowed)
			(pads allowed)
			(copperpour not_allowed)
			(footprints allowed)
		)
		(placement
			(enabled no)
			(sheetname "")
		)
		(fill
			(thermal_gap 0.5)
			(thermal_bridge_width 0.5)
			(island_removal_mode 0)
		)
		(polygon
			(pts
				(arc
					(start 485.000046 -120.499886)
					(mid 481.24999 -116.74983)
					(end 477.499934 -120.499886)
				)
				(arc
					(start 477.499934 -120.499886)
					(mid 481.24999 -124.249942)
					(end 485.000046 -120.499886)
				)
			)
		)
	)
	(zone
		(net "GND")
		(layer "B.Cu")
		(hatch none 0.5)
		(connect_pads
			(clearance 0.5)
		)
		(min_thickness 0.25)
		(fill yes
			(thermal_gap 0.5)
			(thermal_bridge_width 0.5)
			(island_removal_mode 0)
		)
		(polygon
			(pts
				(xy 291.10178 -170.18) (xy 291.878004 -169.05097) (xy 291.846 -168.878758) (xy 292.548056 -167.856916)
				(xy 292.547802 -167.856154) (xy 293.205916 -166.899082) (xy 293.951152 -165.814502) (xy 293.951914 -165.814248)
				(xy 293.952676 -165.813232) (xy 293.952676 -165.812724) (xy 294.610282 -164.85616) (xy 295.357296 -163.768786)
				(xy 295.358058 -163.768786) (xy 296.060368 -162.747706) (xy 296.233088 -162.715702)
				(arc
					(start 297.405298 -161.010092)
					(mid 294.897281 -157.969614)
					(end 296.121074 -154.222958)
				)
				(arc
					(start 296.121074 -154.222958)
					(mid 293.532337 -152.722848)
					(end 291.453316 -150.5712)
				)
				(xy 290.3474 -150.5712) (xy 289.594798 -151.323802) (xy 289.594798 -169.681398) (xy 290.0934 -170.18)
			)
		)
	)
	(zone
		(net "GND")
		(layer "B.Cu")
		(hatch none 0.5)
		(connect_pads
			(clearance 0.5)
		)
		(min_thickness 0.25)
		(fill yes
			(thermal_gap 0.5)
			(thermal_bridge_width 0.5)
			(island_removal_mode 0)
		)
		(polygon
			(pts
				(arc
					(start 150.692866 -173.330362)
					(mid 150.484296 -174.059692)
					(end 150.413974 -174.814992)
				)
				(arc
					(start 150.413974 -177.354992)
					(mid 150.641389 -178.699714)
					(end 151.298148 -179.894992)
				)
				(arc
					(start 151.298148 -179.894992)
					(mid 150.805099 -180.689617)
					(end 150.505414 -181.575456)
				)
				(arc
					(start 150.505414 -181.575456)
					(mid 145.163156 -183.586095)
					(end 147.03298 -188.979048)
				)
				(arc
					(start 147.03298 -188.979048)
					(mid 147.116435 -193.623754)
					(end 151.48814 -195.194682)
				)
				(arc
					(start 151.48814 -195.194682)
					(mid 151.882922 -195.495683)
					(end 152.30856 -195.751196)
				)
				(arc
					(start 152.30856 -195.751196)
					(mid 152.985214 -197.204681)
					(end 154.168602 -198.28637)
				)
				(arc
					(start 154.168602 -198.28637)
					(mid 150.027136 -202.263703)
					(end 148.50364 -207.79994)
				)
				(arc
					(start 148.50364 -210.543902)
					(mid 147.078148 -208.209578)
					(end 144.500346 -207.295242)
				)
				(arc
					(start 143.499586 -207.295242)
					(mid 142.468172 -207.427464)
					(end 141.5034 -207.815434)
				)
				(arc
					(start 141.5034 -207.815434)
					(mid 136.785431 -200.042768)
					(end 128.288034 -196.807328)
				)
				(arc
					(start 128.288034 -196.807328)
					(mid 128.747737 -195.565912)
					(end 128.78689 -194.24269)
				)
				(arc
					(start 128.78689 -194.24269)
					(mid 131.171555 -194.422018)
					(end 133.248908 -193.237358)
				)
				(arc
					(start 133.248908 -193.237358)
					(mid 137.406522 -190.811682)
					(end 136.376918 -186.10961)
				)
				(arc
					(start 136.376918 -186.10961)
					(mid 137.262705 -184.991991)
					(end 137.710926 -183.63819)
				)
				(arc
					(start 137.710926 -183.63819)
					(mid 140.609576 -183.330548)
					(end 142.567152 -181.170834)
				)
				(arc
					(start 142.567152 -181.170834)
					(mid 147.450787 -180.938143)
					(end 148.622512 -176.191418)
				)
				(arc
					(start 148.622512 -176.191418)
					(mid 148.611073 -172.989525)
					(end 146.296634 -170.7769)
				)
				(arc
					(start 146.296634 -170.7769)
					(mid 146.397459 -170.547739)
					(end 146.484086 -170.312842)
				)
				(arc
					(start 148.789898 -170.312842)
					(mid 148.910219 -170.311057)
					(end 149.030436 -170.30573)
				)
				(arc
					(start 149.284182 -170.559476)
					(mid 149.715074 -172.083945)
					(end 150.692866 -173.330362)
				)
			)
		)
	)
	(zone
		(layer "B.Cu")
		(hatch none 0.5)
		(connect_pads
			(clearance 0)
		)
		(min_thickness 0.25)
		(keepout
			(tracks not_allowed)
			(vias allowed)
			(pads allowed)
			(copperpour not_allowed)
			(footprints allowed)
		)
		(placement
			(enabled no)
			(sheetname "")
		)
		(fill
			(thermal_gap 0.5)
			(thermal_bridge_width 0.5)
			(island_removal_mode 0)
		)
		(polygon
			(pts
				(arc
					(start 285.436564 -344.556588)
					(mid 284.887924 -345.105228)
					(end 285.436564 -345.653868)
				)
				(arc
					(start 285.935928 -345.653868)
					(mid 285.921943 -345.584934)
					(end 285.9151 -345.51493)
				)
				(xy 285.914338 -345.514168)
				(arc
					(start 285.914338 -345.232228)
					(mid 285.899459 -345.196307)
					(end 285.863538 -345.181428)
				)
				(arc
					(start 285.822898 -345.181428)
					(mid 285.042787 -345.105228)
					(end 285.822898 -345.029028)
				)
				(xy 285.895034 -345.029028)
				(arc
					(start 285.898082 -345.032076)
					(mid 286.007159 -345.088607)
					(end 286.06369 -345.197684)
				)
				(xy 286.066738 -345.200732)
				(arc
					(start 286.066738 -345.482926)
					(mid 286.073833 -345.569552)
					(end 286.094932 -345.653868)
				)
				(arc
					(start 286.245808 -345.653868)
					(mid 286.220397 -345.586534)
					(end 286.207708 -345.515692)
				)
				(xy 286.206438 -345.514168) (xy 286.206438 -345.200732)
				(arc
					(start 286.209486 -345.197684)
					(mid 286.266017 -345.088607)
					(end 286.375094 -345.032076)
				)
				(xy 286.378142 -345.029028)
				(arc
					(start 286.450278 -345.029028)
					(mid 287.230389 -345.105228)
					(end 286.450278 -345.181428)
				)
				(arc
					(start 286.409638 -345.181428)
					(mid 286.373717 -345.196307)
					(end 286.358838 -345.232228)
				)
				(arc
					(start 286.358838 -345.482672)
					(mid 286.377129 -345.574625)
					(end 286.429196 -345.652598)
				)
				(xy 286.430466 -345.653868)
				(arc
					(start 286.836612 -345.653868)
					(mid 287.385252 -345.105228)
					(end 286.836612 -344.556588)
				)
				(xy 285.436818 -344.556588)
			)
		)
	)
	(zone
		(layer "B.Cu")
		(hatch none 0.5)
		(connect_pads
			(clearance 0)
		)
		(min_thickness 0.25)
		(keepout
			(tracks not_allowed)
			(vias allowed)
			(pads allowed)
			(copperpour not_allowed)
			(footprints allowed)
		)
		(placement
			(enabled no)
			(sheetname "")
		)
		(fill
			(thermal_gap 0.5)
			(thermal_bridge_width 0.5)
			(island_removal_mode 0)
		)
		(polygon
			(pts
				(arc
					(start 238.374936 -57.84977)
					(mid 238.699802 -56.875172)
					(end 237.725204 -56.550306)
				)
				(xy 237.723934 -56.54802) (xy 235.724192 -57.548018) (xy 235.724192 -57.548272)
				(arc
					(start 235.725208 -57.550304)
					(mid 235.333 -58.316201)
					(end 235.94695 -58.91911)
				)
				(arc
					(start 236.153198 -58.91911)
					(mid 236.266861 -58.893365)
					(end 236.37494 -58.849768)
				)
				(xy 236.37621 -58.852054) (xy 236.864652 -58.607706)
				(arc
					(start 237.11662 -58.355992)
					(mid 237.131673 -58.33337)
					(end 237.13694 -58.306716)
				)
				(arc
					(start 237.13694 -58.18886)
					(mid 237.131657 -58.162213)
					(end 237.11662 -58.139584)
				)
				(arc
					(start 236.954568 -57.977532)
					(mid 236.915528 -57.949046)
					(end 236.869732 -57.93359)
				)
				(arc
					(start 236.85119 -57.930542)
					(mid 236.80142 -57.930701)
					(end 236.754162 -57.94629)
				)
				(arc
					(start 236.572044 -58.039508)
					(mid 235.564081 -58.449099)
					(end 236.485176 -57.87009)
				)
				(xy 236.667294 -57.776618) (xy 236.702346 -57.758584)
				(arc
					(start 236.705902 -57.759854)
					(mid 236.77166 -57.74264)
					(end 236.839506 -57.738518)
				)
				(xy 236.842554 -57.736232) (xy 236.896656 -57.745122) (xy 236.901228 -57.745884) (xy 236.936026 -57.751472)
				(arc
					(start 236.937804 -57.754012)
					(mid 237.000702 -57.77868)
					(end 237.057692 -57.814972)
				)
				(xy 237.061248 -57.814972) (xy 237.27918 -58.032904)
				(arc
					(start 237.27918 -58.037984)
					(mid 237.307656 -58.089421)
					(end 237.323884 -58.145934)
				)
				(xy 237.32744 -58.14949) (xy 237.32744 -58.346086)
				(arc
					(start 237.323884 -58.349642)
					(mid 237.320596 -58.365895)
					(end 237.316264 -58.3819)
				)
				(xy 237.42904 -58.325512)
				(arc
					(start 237.42904 -58.104532)
					(mid 237.416892 -58.043932)
					(end 237.382558 -57.992518)
				)
				(xy 237.237016 -57.846722)
				(arc
					(start 237.237016 -57.841642)
					(mid 237.226537 -57.825865)
					(end 237.217204 -57.809384)
				)
				(arc
					(start 237.217204 -57.808876)
					(mid 237.191186 -57.729543)
					(end 237.191296 -57.646062)
				)
				(arc
					(start 237.191296 -57.645808)
					(mid 237.227217 -57.54977)
					(end 237.29696 -57.474612)
				)
				(xy 237.298484 -57.469786)
				(arc
					(start 237.526576 -57.35574)
					(mid 238.537853 -56.954993)
					(end 237.61192 -57.52592)
				)
				(arc
					(start 237.419134 -57.62244)
					(mid 237.392708 -57.644712)
					(end 237.379256 -57.676542)
				)
				(arc
					(start 237.379256 -57.676542)
					(mid 237.379224 -57.69971)
					(end 237.386368 -57.721754)
				)
				(arc
					(start 237.386368 -57.721754)
					(mid 237.392303 -57.731141)
					(end 237.399576 -57.739534)
				)
				(xy 237.39983 -57.740042) (xy 237.42777 -57.767982) (xy 237.42777 -57.768236) (xy 237.50651 -57.846722)
				(xy 237.517178 -57.857644) (xy 237.517432 -57.857644) (xy 237.545118 -57.885584)
				(arc
					(start 237.545118 -57.88914)
					(mid 237.592944 -57.970956)
					(end 237.617 -58.062622)
				)
				(xy 237.61954 -58.065162) (xy 237.61954 -58.230262) (xy 238.376206 -57.852056)
			)
		)
	)
	(zone
		(net "P5V_A_1")
		(layer "B.Cu")
		(hatch none 0.5)
		(connect_pads
			(clearance 0.5)
		)
		(min_thickness 0.25)
		(fill yes
			(thermal_gap 0.5)
			(thermal_bridge_width 0.5)
			(island_removal_mode 0)
		)
		(polygon
			(pts
				(xy 41.526206 -244.02415) (xy 41.037002 -244.513354) (xy 41.037002 -251.13615) (xy 41.926002 -252.02515)
				(xy 57.139586 -252.02515) (xy 57.201816 -251.96292) (xy 57.201816 -251.66701) (xy 57.362598 -251.506228)
				(xy 58.446924 -251.506228) (xy 59.198002 -250.75515) (xy 59.198002 -245.42115) (xy 57.801002 -244.02415)
			)
		)
	)
	(zone
		(layer "B.Cu")
		(hatch none 0.5)
		(connect_pads
			(clearance 0)
		)
		(min_thickness 0.25)
		(keepout
			(tracks not_allowed)
			(vias allowed)
			(pads allowed)
			(copperpour not_allowed)
			(footprints allowed)
		)
		(placement
			(enabled no)
			(sheetname "")
		)
		(fill
			(thermal_gap 0.5)
			(thermal_bridge_width 0.5)
			(island_removal_mode 0)
		)
		(polygon
			(pts
				(arc
					(start 209.300064 -183.799988)
					(mid 202.300078 -176.800002)
					(end 195.300092 -183.799988)
				)
				(arc
					(start 195.300092 -189.799976)
					(mid 202.300078 -196.799962)
					(end 209.300064 -189.799976)
				)
			)
		)
	)
	(zone
		(net "P3V3_STBY_VBST_RR")
		(layer "B.Cu")
		(hatch none 0.5)
		(connect_pads
			(clearance 0.5)
		)
		(min_thickness 0.25)
		(fill yes
			(thermal_gap 0.5)
			(thermal_bridge_width 0.5)
			(island_removal_mode 0)
		)
		(polygon
			(pts
				(xy 188.692282 -228.648006) (xy 188.057282 -229.283006) (xy 188.057282 -230.045006) (xy 188.692282 -230.680006)
				(xy 189.835282 -230.680006) (xy 189.962282 -230.553006) (xy 189.962282 -228.902006) (xy 189.708282 -228.648006)
			)
		)
		(polygon
			(pts
				(xy 188.768228 -229.819708) (xy 188.565028 -229.819708) (xy 188.565028 -230.022908) (xy 188.768228 -230.022908)
			)
		)
		(polygon
			(pts
				(xy 189.200282 -229.562406) (xy 188.997082 -229.562406) (xy 188.997082 -229.765606) (xy 189.200282 -229.765606)
			)
		)
		(polygon
			(pts
				(xy 188.768228 -229.260908) (xy 188.565028 -229.260908) (xy 188.565028 -229.464108) (xy 188.768228 -229.464108)
			)
		)
	)
	(zone
		(net "P3V3_STBY_SW")
		(layer "B.Cu")
		(hatch none 0.5)
		(connect_pads
			(clearance 0.5)
		)
		(min_thickness 0.25)
		(fill yes
			(thermal_gap 0.5)
			(thermal_bridge_width 0.5)
			(island_removal_mode 0)
		)
		(polygon
			(pts
				(xy 184.755282 -226.743006) (xy 183.612282 -227.886006) (xy 181.580282 -227.886006) (xy 180.437282 -229.029006)
				(xy 180.437282 -231.188006) (xy 181.072282 -231.823006) (xy 185.517282 -231.823006) (xy 186.025282 -231.315006)
				(xy 186.025282 -226.870006) (xy 185.898282 -226.743006)
			)
		)
	)
	(zone
		(layer "B.Cu")
		(hatch none 0.5)
		(connect_pads
			(clearance 0)
		)
		(min_thickness 0.25)
		(keepout
			(tracks allowed)
			(vias allowed)
			(pads allowed)
			(copperpour allowed)
			(footprints not_allowed)
		)
		(placement
			(enabled no)
			(sheetname "")
		)
		(fill
			(thermal_gap 0.5)
			(thermal_bridge_width 0.5)
			(island_removal_mode 0)
		)
		(polygon
			(pts
				(arc
					(start 385.174998 -210.799934)
					(mid 425.175172 -250.800108)
					(end 465.175092 -210.799934)
				)
				(arc
					(start 465.175092 -210.799934)
					(mid 425.175172 -170.800014)
					(end 385.174998 -210.799934)
				)
			)
		)
	)
	(zone
		(layer "B.Cu")
		(hatch none 0.5)
		(connect_pads
			(clearance 0)
		)
		(min_thickness 0.25)
		(keepout
			(tracks not_allowed)
			(vias allowed)
			(pads allowed)
			(copperpour not_allowed)
			(footprints allowed)
		)
		(placement
			(enabled no)
			(sheetname "")
		)
		(fill
			(thermal_gap 0.5)
			(thermal_bridge_width 0.5)
			(island_removal_mode 0)
		)
		(polygon
			(pts
				(arc
					(start 279.236678 -349.956628)
					(mid 278.688038 -350.505268)
					(end 279.236678 -351.053908)
				)
				(xy 279.642824 -351.053908) (xy 279.644094 -351.052638)
				(arc
					(start 279.661874 -351.032826)
					(mid 279.700941 -350.962248)
					(end 279.714452 -350.882712)
				)
				(arc
					(start 279.714452 -350.632268)
					(mid 279.699573 -350.596347)
					(end 279.663652 -350.581468)
				)
				(arc
					(start 279.623012 -350.581468)
					(mid 278.842901 -350.505268)
					(end 279.623012 -350.429068)
				)
				(xy 279.695148 -350.429068)
				(arc
					(start 279.698196 -350.432116)
					(mid 279.807273 -350.488647)
					(end 279.863804 -350.597724)
				)
				(xy 279.866852 -350.600772) (xy 279.866852 -350.914208)
				(arc
					(start 279.865582 -350.915732)
					(mid 279.852889 -350.986573)
					(end 279.827482 -351.053908)
				)
				(arc
					(start 279.978358 -351.053908)
					(mid 279.999443 -350.969718)
					(end 280.006552 -350.88322)
				)
				(xy 280.006552 -350.600772)
				(arc
					(start 280.0096 -350.597724)
					(mid 280.066131 -350.488647)
					(end 280.175208 -350.432116)
				)
				(xy 280.178256 -350.429068)
				(arc
					(start 280.250392 -350.429068)
					(mid 281.030503 -350.505268)
					(end 280.250392 -350.581468)
				)
				(arc
					(start 280.209752 -350.581468)
					(mid 280.173831 -350.596347)
					(end 280.158952 -350.632268)
				)
				(xy 280.158952 -350.88322) (xy 280.158952 -350.914716)
				(arc
					(start 280.15819 -350.915478)
					(mid 280.151333 -350.985229)
					(end 280.137362 -351.053908)
				)
				(arc
					(start 280.636726 -351.053908)
					(mid 281.185366 -350.505268)
					(end 280.636726 -349.956628)
				)
				(xy 279.236932 -349.956628)
			)
		)
	)
	(zone
		(net "GND")
		(layer "B.Cu")
		(hatch none 0.5)
		(connect_pads
			(clearance 0.5)
		)
		(min_thickness 0.25)
		(fill yes
			(thermal_gap 0.5)
			(thermal_bridge_width 0.5)
			(island_removal_mode 0)
		)
		(polygon
			(pts
				(xy 46.58487 -238.758984) (xy 46.267116 -239.076738) (xy 46.267116 -241.888264) (xy 46.752002 -242.37315)
				(xy 50.308002 -242.37315) (xy 50.977038 -241.704114) (xy 50.977038 -239.145826) (xy 50.590196 -238.758984)
			)
		)
	)
	(zone
		(layer "B.Cu")
		(hatch none 0.5)
		(connect_pads
			(clearance 0)
		)
		(min_thickness 0.25)
		(keepout
			(tracks allowed)
			(vias allowed)
			(pads allowed)
			(copperpour allowed)
			(footprints not_allowed)
		)
		(placement
			(enabled no)
			(sheetname "")
		)
		(fill
			(thermal_gap 0.5)
			(thermal_bridge_width 0.5)
			(island_removal_mode 0)
		)
		(polygon
			(pts
				(arc
					(start 251.599954 -143.500094)
					(mid 247.850152 -139.750292)
					(end 244.100096 -143.500094)
				)
				(arc
					(start 244.100096 -143.500094)
					(mid 247.850152 -147.25015)
					(end 251.599954 -143.500094)
				)
			)
		)
	)
	(zone
		(net "P5V_C_LL")
		(layer "B.Cu")
		(hatch none 0.5)
		(connect_pads
			(clearance 0.5)
		)
		(min_thickness 0.25)
		(fill yes
			(thermal_gap 0.5)
			(thermal_bridge_width 0.5)
			(island_removal_mode 0)
		)
		(polygon
			(pts
				(xy 452.781416 -246.18315) (xy 452.019416 -246.94515) (xy 450.434202 -246.94515) (xy 448.275202 -249.10415)
				(xy 448.275202 -251.77115) (xy 448.446652 -251.9426) (xy 454.028302 -251.9426) (xy 454.498202 -251.4727)
				(xy 454.498202 -246.548402) (xy 454.13295 -246.18315)
			)
		)
	)
	(zone
		(layer "B.Cu")
		(hatch none 0.5)
		(connect_pads
			(clearance 0)
		)
		(min_thickness 0.25)
		(keepout
			(tracks not_allowed)
			(vias allowed)
			(pads allowed)
			(copperpour not_allowed)
			(footprints allowed)
		)
		(placement
			(enabled no)
			(sheetname "")
		)
		(fill
			(thermal_gap 0.5)
			(thermal_bridge_width 0.5)
			(island_removal_mode 0)
		)
		(polygon
			(pts
				(arc
					(start 134.898638 -20.950428)
					(mid 134.350125 -20.401534)
					(end 133.801358 -20.950174)
				)
				(arc
					(start 133.801358 -22.350222)
					(mid 134.349998 -22.898862)
					(end 134.898638 -22.350222)
				)
				(arc
					(start 134.898638 -21.895054)
					(mid 134.882737 -21.892375)
					(end 134.866634 -21.891498)
				)
				(arc
					(start 134.516368 -21.891498)
					(mid 134.466079 -21.912329)
					(end 134.445248 -21.962618)
				)
				(arc
					(start 134.445248 -21.968206)
					(mid 134.349998 -22.743934)
					(end 134.254748 -21.968206)
				)
				(xy 134.254748 -21.923248)
				(arc
					(start 134.258304 -21.919692)
					(mid 134.331382 -21.777632)
					(end 134.473442 -21.704554)
				)
				(xy 134.476998 -21.700998) (xy 134.898638 -21.700998) (xy 134.898638 -21.600668) (xy 134.866634 -21.599398)
				(xy 134.476998 -21.599398)
				(arc
					(start 134.473442 -21.595842)
					(mid 134.331382 -21.522764)
					(end 134.258304 -21.380704)
				)
				(xy 134.254748 -21.377148)
				(arc
					(start 134.254748 -21.33219)
					(mid 134.349998 -20.556462)
					(end 134.445248 -21.33219)
				)
				(arc
					(start 134.445248 -21.337778)
					(mid 134.466079 -21.388067)
					(end 134.516368 -21.408898)
				)
				(xy 134.898638 -21.408898)
			)
		)
	)
	(zone
		(layer "B.Cu")
		(hatch none 0.5)
		(connect_pads
			(clearance 0)
		)
		(min_thickness 0.25)
		(keepout
			(tracks not_allowed)
			(vias allowed)
			(pads allowed)
			(copperpour not_allowed)
			(footprints allowed)
		)
		(placement
			(enabled no)
			(sheetname "")
		)
		(fill
			(thermal_gap 0.5)
			(thermal_bridge_width 0.5)
			(island_removal_mode 0)
		)
		(polygon
			(pts
				(arc
					(start 388.21995 -47.178722)
					(mid 387.839077 -46.797468)
					(end 387.45795 -47.178468)
				)
				(xy 387.45795 -47.527718)
				(arc
					(start 387.662166 -47.527718)
					(mid 387.730822 -47.500643)
					(end 387.762496 -47.433992)
				)
				(arc
					(start 387.762496 -47.433992)
					(mid 387.839072 -46.911751)
					(end 387.91515 -47.433992)
				)
				(xy 387.91515 -47.45863)
				(arc
					(start 387.912864 -47.460916)
					(mid 387.841038 -47.606006)
					(end 387.695948 -47.677832)
				)
				(xy 387.693662 -47.680118) (xy 387.45795 -47.680118) (xy 387.45795 -47.819818) (xy 387.693662 -47.819818)
				(arc
					(start 387.695948 -47.822104)
					(mid 387.841038 -47.89393)
					(end 387.912864 -48.03902)
				)
				(xy 387.91515 -48.041306)
				(arc
					(start 387.91515 -48.065944)
					(mid 387.839072 -48.588112)
					(end 387.762496 -48.065944)
				)
				(arc
					(start 387.762496 -48.065944)
					(mid 387.730808 -47.999308)
					(end 387.662166 -47.972218)
				)
				(xy 387.45795 -47.972218)
				(arc
					(start 387.45795 -48.321468)
					(mid 387.83895 -48.702468)
					(end 388.21995 -48.321468)
				)
			)
		)
	)
	(zone
		(layer "B.Cu")
		(hatch none 0.5)
		(connect_pads
			(clearance 0)
		)
		(min_thickness 0.25)
		(keepout
			(tracks allowed)
			(vias allowed)
			(pads allowed)
			(copperpour allowed)
			(footprints not_allowed)
		)
		(placement
			(enabled no)
			(sheetname "")
		)
		(fill
			(thermal_gap 0.5)
			(thermal_bridge_width 0.5)
			(island_removal_mode 0)
		)
		(polygon
			(pts
				(arc
					(start 465.175092 -210.799934)
					(mid 425.175172 -170.800014)
					(end 385.174998 -210.799934)
				)
				(arc
					(start 385.174998 -210.799934)
					(mid 425.175172 -250.800108)
					(end 465.175092 -210.799934)
				)
			)
		)
	)
	(zone
		(layer "B.Cu")
		(hatch none 0.5)
		(connect_pads
			(clearance 0)
		)
		(min_thickness 0.25)
		(keepout
			(tracks not_allowed)
			(vias allowed)
			(pads allowed)
			(copperpour not_allowed)
			(footprints allowed)
		)
		(placement
			(enabled no)
			(sheetname "")
		)
		(fill
			(thermal_gap 0.5)
			(thermal_bridge_width 0.5)
			(island_removal_mode 0)
		)
		(polygon
			(pts
				(arc
					(start 325.12 -277.17877)
					(mid 324.739127 -276.797516)
					(end 324.358 -277.178516)
				)
				(xy 324.358 -277.527766)
				(arc
					(start 324.562216 -277.527766)
					(mid 324.630872 -277.500691)
					(end 324.662546 -277.43404)
				)
				(arc
					(start 324.662546 -277.43404)
					(mid 324.739122 -276.911799)
					(end 324.8152 -277.43404)
				)
				(xy 324.8152 -277.458678)
				(arc
					(start 324.812914 -277.460964)
					(mid 324.741088 -277.606054)
					(end 324.595998 -277.67788)
				)
				(xy 324.593712 -277.680166) (xy 324.358 -277.680166) (xy 324.358 -277.819866) (xy 324.593712 -277.819866)
				(arc
					(start 324.595998 -277.822152)
					(mid 324.741088 -277.893978)
					(end 324.812914 -278.039068)
				)
				(xy 324.8152 -278.041354)
				(arc
					(start 324.8152 -278.065992)
					(mid 324.739122 -278.58816)
					(end 324.662546 -278.065992)
				)
				(arc
					(start 324.662546 -278.065992)
					(mid 324.630858 -277.999356)
					(end 324.562216 -277.972266)
				)
				(xy 324.358 -277.972266)
				(arc
					(start 324.358 -278.321516)
					(mid 324.739 -278.702516)
					(end 325.12 -278.321516)
				)
			)
		)
	)
	(zone
		(layer "B.Cu")
		(hatch none 0.5)
		(connect_pads
			(clearance 0)
		)
		(min_thickness 0.25)
		(keepout
			(tracks not_allowed)
			(vias allowed)
			(pads allowed)
			(copperpour not_allowed)
			(footprints allowed)
		)
		(placement
			(enabled no)
			(sheetname "")
		)
		(fill
			(thermal_gap 0.5)
			(thermal_bridge_width 0.5)
			(island_removal_mode 0)
		)
		(polygon
			(pts
				(arc
					(start 281.07386 -118.147338)
					(mid 281.397456 -117.176042)
					(end 280.42616 -116.852446)
				)
				(arc
					(start 279.487122 -117.321838)
					(mid 279.638469 -117.405648)
					(end 279.768554 -117.519704)
				)
				(xy 279.781762 -117.524022) (xy 279.832308 -117.624098) (xy 279.849834 -117.659404) (xy 279.867614 -117.694456)
				(xy 279.867614 -117.69471)
				(arc
					(start 279.892506 -117.744494)
					(mid 279.932791 -117.77949)
					(end 279.985978 -117.775736)
				)
				(arc
					(start 280.226516 -117.65534)
					(mid 281.23834 -117.255466)
					(end 280.31186 -117.825774)
				)
				(xy 280.071322 -117.945916) (xy 280.036016 -117.963696)
				(arc
					(start 280.03119 -117.962172)
					(mid 279.872501 -117.960159)
					(end 279.744424 -117.866414)
				)
				(xy 279.739598 -117.86489) (xy 279.722072 -117.829838) (xy 279.722072 -117.829584) (xy 279.679654 -117.744748)
				(arc
					(start 279.634696 -117.655594)
					(mid 279.450574 -117.514773)
					(end 279.227534 -117.451632)
				)
				(xy 279.028906 -117.550946) (xy 279.213056 -117.550946)
				(arc
					(start 279.214834 -117.55247)
					(mid 279.379517 -117.59368)
					(end 279.52192 -117.686074)
				)
				(xy 279.539192 -117.691662) (xy 279.623774 -117.860572) (xy 279.640792 -117.87759) (xy 279.640792 -117.894354)
				(xy 279.648412 -117.909594)
				(arc
					(start 279.646634 -117.91442)
					(mid 279.644931 -118.073154)
					(end 279.551384 -118.20144)
				)
				(xy 279.54986 -118.206266) (xy 279.514554 -118.223792)
				(arc
					(start 279.273508 -118.344442)
					(mid 278.261684 -118.744316)
					(end 279.188164 -118.174008)
				)
				(arc
					(start 279.42921 -118.053612)
					(mid 279.462054 -118.018937)
					(end 279.46477 -117.971316)
				)
				(xy 279.450292 -117.956584) (xy 279.450292 -117.939566)
				(arc
					(start 279.393904 -117.827044)
					(mid 279.291818 -117.763609)
					(end 279.173686 -117.741446)
				)
				(xy 278.647906 -117.741446) (xy 278.426418 -117.85219)
				(arc
					(start 278.426418 -117.852444)
					(mid 278.102619 -118.823588)
					(end 279.073864 -119.147336)
				)
			)
		)
	)
	(zone
		(layer "B.Cu")
		(hatch none 0.5)
		(connect_pads
			(clearance 0)
		)
		(min_thickness 0.25)
		(keepout
			(tracks not_allowed)
			(vias allowed)
			(pads allowed)
			(copperpour not_allowed)
			(footprints allowed)
		)
		(placement
			(enabled no)
			(sheetname "")
		)
		(fill
			(thermal_gap 0.5)
			(thermal_bridge_width 0.5)
			(island_removal_mode 0)
		)
		(polygon
			(pts
				(arc
					(start 281.074876 -65.849754)
					(mid 281.399742 -64.875156)
					(end 280.425144 -64.55029)
				)
				(xy 280.423874 -64.548004) (xy 278.424132 -65.548002) (xy 278.424132 -65.548256)
				(arc
					(start 278.425148 -65.550288)
					(mid 278.100282 -66.524886)
					(end 279.07488 -66.849752)
				)
				(xy 279.07615 -66.852038)
				(arc
					(start 280.086562 -66.346832)
					(mid 279.982979 -66.28538)
					(end 279.888696 -66.210434)
				)
				(xy 279.887426 -66.210434)
				(arc
					(start 279.654508 -65.977516)
					(mid 279.615468 -65.94903)
					(end 279.569672 -65.933574)
				)
				(xy 279.566116 -65.933066)
				(arc
					(start 279.55113 -65.930526)
					(mid 279.50136 -65.930685)
					(end 279.454102 -65.946274)
				)
				(arc
					(start 279.271984 -66.039492)
					(mid 278.264021 -66.449083)
					(end 279.185116 -65.870074)
				)
				(xy 279.367234 -65.776602) (xy 279.402286 -65.758568)
				(arc
					(start 279.405842 -65.759838)
					(mid 279.4716 -65.742624)
					(end 279.539446 -65.738502)
				)
				(xy 279.542494 -65.736216) (xy 279.58161 -65.742566) (xy 279.596596 -65.745106) (xy 279.601168 -65.745868)
				(xy 279.635966 -65.751456)
				(arc
					(start 279.637744 -65.753996)
					(mid 279.700642 -65.778664)
					(end 279.757632 -65.814956)
				)
				(xy 279.761188 -65.814956) (xy 279.879298 -65.933066)
				(arc
					(start 279.994106 -66.047874)
					(mid 280.143896 -66.161527)
					(end 280.318718 -66.230754)
				)
				(xy 280.481786 -66.14922) (xy 280.445464 -66.14922)
				(arc
					(start 280.44394 -66.147696)
					(mid 280.258325 -66.10406)
					(end 280.096214 -66.003678)
				)
				(xy 280.094182 -66.003678) (xy 280.066242 -65.975738) (xy 279.93721 -65.846706)
				(arc
					(start 279.93721 -65.84188)
					(mid 279.89485 -65.748513)
					(end 279.891236 -65.646046)
				)
				(arc
					(start 279.891236 -65.645792)
					(mid 279.927157 -65.549754)
					(end 279.9969 -65.474596)
				)
				(xy 279.998424 -65.46977)
				(arc
					(start 280.226516 -65.355724)
					(mid 281.237793 -64.954977)
					(end 280.31186 -65.525904)
				)
				(arc
					(start 280.119074 -65.622424)
					(mid 280.092648 -65.644696)
					(end 280.079196 -65.676526)
				)
				(arc
					(start 280.079196 -65.676526)
					(mid 280.081809 -65.710777)
					(end 280.09977 -65.740026)
				)
				(arc
					(start 280.200862 -65.841118)
					(mid 280.331149 -65.928173)
					(end 280.484834 -65.95872)
				)
				(xy 280.862786 -65.95872) (xy 281.076146 -65.85204)
			)
		)
	)
	(zone
		(layer "B.Cu")
		(hatch none 0.5)
		(connect_pads
			(clearance 0)
		)
		(min_thickness 0.25)
		(keepout
			(tracks not_allowed)
			(vias allowed)
			(pads allowed)
			(copperpour not_allowed)
			(footprints allowed)
		)
		(placement
			(enabled no)
			(sheetname "")
		)
		(fill
			(thermal_gap 0.5)
			(thermal_bridge_width 0.5)
			(island_removal_mode 0)
		)
		(polygon
			(pts
				(arc
					(start 379.098556 -21.950426)
					(mid 378.550043 -21.401532)
					(end 378.001276 -21.950172)
				)
				(arc
					(start 378.001276 -23.35022)
					(mid 378.549916 -23.89886)
					(end 379.098556 -23.35022)
				)
				(xy 379.098556 -22.891496)
				(arc
					(start 378.716286 -22.891496)
					(mid 378.665997 -22.912327)
					(end 378.645166 -22.962616)
				)
				(arc
					(start 378.645166 -22.968204)
					(mid 378.549916 -23.743932)
					(end 378.454666 -22.968204)
				)
				(xy 378.454666 -22.923246)
				(arc
					(start 378.458222 -22.91969)
					(mid 378.5313 -22.77763)
					(end 378.67336 -22.704552)
				)
				(xy 378.676916 -22.700996) (xy 379.098556 -22.700996) (xy 379.098556 -22.599396) (xy 378.676916 -22.599396)
				(arc
					(start 378.67336 -22.59584)
					(mid 378.5313 -22.522762)
					(end 378.458222 -22.380702)
				)
				(xy 378.454666 -22.377146)
				(arc
					(start 378.454666 -22.332188)
					(mid 378.549916 -21.55646)
					(end 378.645166 -22.332188)
				)
				(arc
					(start 378.645166 -22.337776)
					(mid 378.665997 -22.388065)
					(end 378.716286 -22.408896)
				)
				(xy 379.098556 -22.408896)
			)
		)
	)
	(zone
		(layer "B.Cu")
		(hatch none 0.5)
		(connect_pads
			(clearance 0)
		)
		(min_thickness 0.25)
		(keepout
			(tracks not_allowed)
			(vias allowed)
			(pads allowed)
			(copperpour not_allowed)
			(footprints allowed)
		)
		(placement
			(enabled no)
			(sheetname "")
		)
		(fill
			(thermal_gap 0.5)
			(thermal_bridge_width 0.5)
			(island_removal_mode 0)
		)
		(polygon
			(pts
				(arc
					(start 209.300064 -63.799974)
					(mid 202.300078 -56.799988)
					(end 195.300092 -63.799974)
				)
				(arc
					(start 195.300092 -69.799962)
					(mid 202.300078 -76.799948)
					(end 209.300064 -69.799962)
				)
			)
		)
	)
	(zone
		(layer "B.Cu")
		(hatch none 0.5)
		(connect_pads
			(clearance 0)
		)
		(min_thickness 0.25)
		(keepout
			(tracks not_allowed)
			(vias allowed)
			(pads allowed)
			(copperpour not_allowed)
			(footprints allowed)
		)
		(placement
			(enabled no)
			(sheetname "")
		)
		(fill
			(thermal_gap 0.5)
			(thermal_bridge_width 0.5)
			(island_removal_mode 0)
		)
		(polygon
			(pts
				(arc
					(start 400.675094 -207.79994)
					(mid 393.675108 -200.799954)
					(end 386.675122 -207.79994)
				)
				(arc
					(start 386.675122 -213.799928)
					(mid 393.675108 -220.799914)
					(end 400.675094 -213.799928)
				)
			)
		)
	)
	(zone
		(layer "B.Cu")
		(hatch none 0.5)
		(connect_pads
			(clearance 0)
		)
		(min_thickness 0.25)
		(keepout
			(tracks not_allowed)
			(vias allowed)
			(pads allowed)
			(copperpour not_allowed)
			(footprints allowed)
		)
		(placement
			(enabled no)
			(sheetname "")
		)
		(fill
			(thermal_gap 0.5)
			(thermal_bridge_width 0.5)
			(island_removal_mode 0)
		)
		(polygon
			(pts
				(arc
					(start 238.374936 -69.849746)
					(mid 238.699802 -68.875148)
					(end 237.725204 -68.550282)
				)
				(xy 237.723934 -68.547996) (xy 235.724192 -69.547994) (xy 235.724192 -69.548248)
				(arc
					(start 235.725208 -69.55028)
					(mid 235.400342 -70.524878)
					(end 236.37494 -70.849744)
				)
				(xy 236.37621 -70.85203) (xy 236.864652 -70.607682)
				(arc
					(start 237.11662 -70.355968)
					(mid 237.131673 -70.333346)
					(end 237.13694 -70.306692)
				)
				(arc
					(start 237.13694 -70.188836)
					(mid 237.131657 -70.162189)
					(end 237.11662 -70.13956)
				)
				(arc
					(start 236.954568 -69.977508)
					(mid 236.915528 -69.949022)
					(end 236.869732 -69.933566)
				)
				(xy 236.866176 -69.933058)
				(arc
					(start 236.85119 -69.930518)
					(mid 236.80142 -69.930677)
					(end 236.754162 -69.946266)
				)
				(arc
					(start 236.572044 -70.039484)
					(mid 235.564081 -70.449075)
					(end 236.485176 -69.870066)
				)
				(xy 236.667294 -69.776594) (xy 236.702346 -69.75856)
				(arc
					(start 236.705902 -69.75983)
					(mid 236.77166 -69.742616)
					(end 236.839506 -69.738494)
				)
				(xy 236.842554 -69.736208) (xy 236.88167 -69.742558) (xy 236.896656 -69.745098) (xy 236.901228 -69.74586)
				(xy 236.936026 -69.751448)
				(arc
					(start 236.937804 -69.753988)
					(mid 237.000702 -69.778656)
					(end 237.057692 -69.814948)
				)
				(xy 237.061248 -69.814948) (xy 237.089188 -69.842888) (xy 237.179358 -69.933058) (xy 237.27918 -70.03288)
				(arc
					(start 237.27918 -70.03796)
					(mid 237.307656 -70.089397)
					(end 237.323884 -70.14591)
				)
				(xy 237.32744 -70.149466) (xy 237.32744 -70.346062)
				(arc
					(start 237.323884 -70.349618)
					(mid 237.320596 -70.365871)
					(end 237.316264 -70.381876)
				)
				(xy 237.42904 -70.325488)
				(arc
					(start 237.42904 -70.104508)
					(mid 237.416892 -70.043908)
					(end 237.382558 -69.992494)
				)
				(xy 237.382558 -69.99224) (xy 237.237016 -69.846698)
				(arc
					(start 237.237016 -69.841618)
					(mid 237.226537 -69.825841)
					(end 237.217204 -69.80936)
				)
				(arc
					(start 237.217204 -69.808852)
					(mid 237.191186 -69.729519)
					(end 237.191296 -69.646038)
				)
				(arc
					(start 237.191296 -69.645784)
					(mid 237.227217 -69.549746)
					(end 237.29696 -69.474588)
				)
				(xy 237.298484 -69.469762)
				(arc
					(start 237.526576 -69.355716)
					(mid 238.537853 -68.954969)
					(end 237.61192 -69.525896)
				)
				(arc
					(start 237.419134 -69.622416)
					(mid 237.392708 -69.644688)
					(end 237.379256 -69.676518)
				)
				(arc
					(start 237.379256 -69.676518)
					(mid 237.379224 -69.699686)
					(end 237.386368 -69.72173)
				)
				(arc
					(start 237.386368 -69.72173)
					(mid 237.392303 -69.731117)
					(end 237.399576 -69.73951)
				)
				(xy 237.39983 -69.740018) (xy 237.42777 -69.767958) (xy 237.42777 -69.768212) (xy 237.50651 -69.846698)
				(xy 237.517178 -69.85762) (xy 237.517432 -69.85762) (xy 237.545118 -69.88556)
				(arc
					(start 237.545118 -69.889116)
					(mid 237.592944 -69.970932)
					(end 237.617 -70.062598)
				)
				(xy 237.61954 -70.065138) (xy 237.61954 -70.230492) (xy 238.376206 -69.852032)
			)
		)
	)
	(zone
		(layer "B.Cu")
		(hatch none 0.5)
		(connect_pads
			(clearance 0)
		)
		(min_thickness 0.25)
		(keepout
			(tracks not_allowed)
			(vias allowed)
			(pads allowed)
			(copperpour not_allowed)
			(footprints allowed)
		)
		(placement
			(enabled no)
			(sheetname "")
		)
		(fill
			(thermal_gap 0.5)
			(thermal_bridge_width 0.5)
			(island_removal_mode 0)
		)
		(polygon
			(pts
				(arc
					(start 271.970754 -351.924112)
					(mid 271.5895 -352.304985)
					(end 271.9705 -352.686112)
				)
				(arc
					(start 273.1135 -352.686112)
					(mid 273.4945 -352.305112)
					(end 273.1135 -351.924112)
				)
				(arc
					(start 272.76806 -351.924112)
					(mid 272.765209 -351.949696)
					(end 272.76425 -351.97542)
				)
				(arc
					(start 272.76425 -352.12401)
					(mid 272.791127 -352.194128)
					(end 272.857976 -352.228404)
				)
				(arc
					(start 272.857976 -352.228404)
					(mid 273.380217 -352.304858)
					(end 272.857976 -352.381312)
				)
				(xy 272.837656 -352.381312)
				(arc
					(start 272.83537 -352.379026)
					(mid 272.687253 -352.305909)
					(end 272.614136 -352.157792)
				)
				(xy 272.61185 -352.155506) (xy 272.61185 -351.943924) (xy 272.612866 -351.942908) (xy 272.61439 -351.924112)
				(arc
					(start 272.474182 -351.924112)
					(mid 272.472648 -351.949746)
					(end 272.47215 -351.97542)
				)
				(xy 272.47215 -352.155506)
				(arc
					(start 272.469864 -352.157792)
					(mid 272.396747 -352.305909)
					(end 272.24863 -352.379026)
				)
				(xy 272.246344 -352.381312)
				(arc
					(start 272.226024 -352.381312)
					(mid 271.703783 -352.304858)
					(end 272.226024 -352.228404)
				)
				(arc
					(start 272.226024 -352.228404)
					(mid 272.292939 -352.194187)
					(end 272.31975 -352.12401)
				)
				(xy 272.31975 -351.943924) (xy 272.320512 -351.943162) (xy 272.321528 -351.924112)
			)
		)
	)
	(zone
		(layer "B.Cu")
		(hatch none 0.5)
		(connect_pads
			(clearance 0)
		)
		(min_thickness 0.25)
		(keepout
			(tracks not_allowed)
			(vias allowed)
			(pads allowed)
			(copperpour not_allowed)
			(footprints allowed)
		)
		(placement
			(enabled no)
			(sheetname "")
		)
		(fill
			(thermal_gap 0.5)
			(thermal_bridge_width 0.5)
			(island_removal_mode 0)
		)
		(polygon
			(pts
				(arc
					(start 281.07386 -162.14725)
					(mid 281.397456 -161.175954)
					(end 280.42616 -160.852358)
				)
				(arc
					(start 279.487122 -161.32175)
					(mid 279.638469 -161.40556)
					(end 279.768554 -161.519616)
				)
				(xy 279.781762 -161.523934) (xy 279.832308 -161.62401) (xy 279.849834 -161.659316) (xy 279.867614 -161.694368)
				(xy 279.867614 -161.694622)
				(arc
					(start 279.892506 -161.744406)
					(mid 279.932791 -161.779402)
					(end 279.985978 -161.775648)
				)
				(arc
					(start 280.226516 -161.655252)
					(mid 281.23834 -161.255378)
					(end 280.31186 -161.825686)
				)
				(xy 280.071322 -161.945828) (xy 280.036016 -161.963608)
				(arc
					(start 280.03119 -161.962084)
					(mid 279.872501 -161.960071)
					(end 279.744424 -161.866326)
				)
				(xy 279.739598 -161.864802) (xy 279.722072 -161.82975) (xy 279.722072 -161.829496) (xy 279.679654 -161.74466)
				(arc
					(start 279.634696 -161.655506)
					(mid 279.450574 -161.514685)
					(end 279.227534 -161.451544)
				)
				(xy 279.028906 -161.550858) (xy 279.213056 -161.550858)
				(arc
					(start 279.214834 -161.552382)
					(mid 279.379517 -161.593592)
					(end 279.52192 -161.685986)
				)
				(xy 279.539192 -161.691574) (xy 279.623774 -161.860484) (xy 279.640792 -161.877502) (xy 279.640792 -161.894266)
				(xy 279.648412 -161.909506)
				(arc
					(start 279.646634 -161.914332)
					(mid 279.644931 -162.073066)
					(end 279.551384 -162.201352)
				)
				(xy 279.54986 -162.206178) (xy 279.514554 -162.223704)
				(arc
					(start 279.273508 -162.344354)
					(mid 278.261684 -162.744228)
					(end 279.188164 -162.17392)
				)
				(arc
					(start 279.42921 -162.053524)
					(mid 279.462054 -162.018849)
					(end 279.46477 -161.971228)
				)
				(xy 279.450292 -161.956496) (xy 279.450292 -161.939478)
				(arc
					(start 279.393904 -161.826956)
					(mid 279.291818 -161.763521)
					(end 279.173686 -161.741358)
				)
				(xy 278.647906 -161.741358) (xy 278.426418 -161.852102)
				(arc
					(start 278.426418 -161.852356)
					(mid 278.102619 -162.8235)
					(end 279.073864 -163.147248)
				)
			)
		)
	)
	(zone
		(layer "B.Cu")
		(hatch none 0.5)
		(connect_pads
			(clearance 0)
		)
		(min_thickness 0.25)
		(keepout
			(tracks not_allowed)
			(vias allowed)
			(pads allowed)
			(copperpour not_allowed)
			(footprints allowed)
		)
		(placement
			(enabled no)
			(sheetname "")
		)
		(fill
			(thermal_gap 0.5)
			(thermal_bridge_width 0.5)
			(island_removal_mode 0)
		)
		(polygon
			(pts
				(arc
					(start 138.49858 -20.950428)
					(mid 137.950067 -20.401534)
					(end 137.4013 -20.950174)
				)
				(arc
					(start 137.4013 -22.350222)
					(mid 137.94994 -22.898862)
					(end 138.49858 -22.350222)
				)
				(arc
					(start 138.49858 -21.895054)
					(mid 138.482679 -21.892375)
					(end 138.466576 -21.891498)
				)
				(arc
					(start 138.11631 -21.891498)
					(mid 138.066021 -21.912329)
					(end 138.04519 -21.962618)
				)
				(arc
					(start 138.04519 -21.968206)
					(mid 137.94994 -22.743934)
					(end 137.85469 -21.968206)
				)
				(xy 137.85469 -21.923248)
				(arc
					(start 137.858246 -21.919692)
					(mid 137.931324 -21.777632)
					(end 138.073384 -21.704554)
				)
				(xy 138.07694 -21.700998) (xy 138.49858 -21.700998) (xy 138.49858 -21.600668) (xy 138.466576 -21.599398)
				(xy 138.07694 -21.599398)
				(arc
					(start 138.073384 -21.595842)
					(mid 137.931324 -21.522764)
					(end 137.858246 -21.380704)
				)
				(xy 137.85469 -21.377148)
				(arc
					(start 137.85469 -21.33219)
					(mid 137.94994 -20.556462)
					(end 138.04519 -21.33219)
				)
				(arc
					(start 138.04519 -21.337778)
					(mid 138.066021 -21.388067)
					(end 138.11631 -21.408898)
				)
				(xy 138.49858 -21.408898)
			)
		)
	)
	(zone
		(net "P12V_B_COMP")
		(layer "B.Cu")
		(hatch none 0.5)
		(connect_pads
			(clearance 0.5)
		)
		(min_thickness 0.25)
		(fill yes
			(thermal_gap 0.5)
			(thermal_bridge_width 0.5)
			(island_removal_mode 0)
		)
		(polygon
			(pts
				(xy 277.2156 0.762) (xy 276.479 0.0254) (xy 276.479 -7.9756) (xy 277.7998 -9.2964) (xy 286.7914 -9.2964)
				(xy 289.941 -12.446) (xy 289.941 -22.606) (xy 290.449 -23.114) (xy 301.879 -23.114) (xy 302.895 -22.098)
				(xy 302.895 -10.607548) (xy 291.525452 0.762)
			)
		)
	)
	(zone
		(layer "B.Cu")
		(hatch none 0.5)
		(connect_pads
			(clearance 0)
		)
		(min_thickness 0.25)
		(keepout
			(tracks not_allowed)
			(vias allowed)
			(pads allowed)
			(copperpour not_allowed)
			(footprints allowed)
		)
		(placement
			(enabled no)
			(sheetname "")
		)
		(fill
			(thermal_gap 0.5)
			(thermal_bridge_width 0.5)
			(island_removal_mode 0)
		)
		(polygon
			(pts
				(arc
					(start 116.898674 -20.950428)
					(mid 116.350161 -20.401534)
					(end 115.801394 -20.950174)
				)
				(xy 115.801394 -21.408898)
				(arc
					(start 116.183664 -21.408898)
					(mid 116.233953 -21.388067)
					(end 116.254784 -21.337778)
				)
				(arc
					(start 116.254784 -21.33219)
					(mid 116.350034 -20.556462)
					(end 116.445284 -21.33219)
				)
				(xy 116.445284 -21.377148)
				(arc
					(start 116.441728 -21.380704)
					(mid 116.36865 -21.522764)
					(end 116.22659 -21.595842)
				)
				(xy 116.223034 -21.599398) (xy 115.833398 -21.599398) (xy 115.801394 -21.600668) (xy 115.801394 -21.700998)
				(xy 116.223034 -21.700998)
				(arc
					(start 116.22659 -21.704554)
					(mid 116.36865 -21.777632)
					(end 116.441728 -21.919692)
				)
				(xy 116.445284 -21.923248)
				(arc
					(start 116.445284 -21.968206)
					(mid 116.350034 -22.743934)
					(end 116.254784 -21.968206)
				)
				(arc
					(start 116.254784 -21.962618)
					(mid 116.233953 -21.912329)
					(end 116.183664 -21.891498)
				)
				(arc
					(start 115.833398 -21.891498)
					(mid 115.817293 -21.892356)
					(end 115.801394 -21.895054)
				)
				(arc
					(start 115.801394 -22.350222)
					(mid 116.350034 -22.898862)
					(end 116.898674 -22.350222)
				)
			)
		)
	)
	(zone
		(layer "B.Cu")
		(hatch none 0.5)
		(connect_pads
			(clearance 0)
		)
		(min_thickness 0.25)
		(keepout
			(tracks allowed)
			(vias allowed)
			(pads allowed)
			(copperpour allowed)
			(footprints allowed)
		)
		(placement
			(enabled no)
			(sheetname "")
		)
		(fill
			(thermal_gap 0.5)
			(thermal_bridge_width 0.5)
			(island_removal_mode 0)
		)
		(polygon
			(pts
				(xy 474.629734 -233.749088) (xy 474.629734 -235.322618) (xy 470.456514 -235.322618) (xy 470.456514 -233.749088)
			)
		)
	)
	(zone
		(layer "B.Cu")
		(hatch none 0.5)
		(connect_pads
			(clearance 0)
		)
		(min_thickness 0.25)
		(keepout
			(tracks not_allowed)
			(vias allowed)
			(pads allowed)
			(copperpour not_allowed)
			(footprints allowed)
		)
		(placement
			(enabled no)
			(sheetname "")
		)
		(fill
			(thermal_gap 0.5)
			(thermal_bridge_width 0.5)
			(island_removal_mode 0)
		)
		(polygon
			(pts
				(arc
					(start 286.436562 -339.156548)
					(mid 285.887922 -339.705188)
					(end 286.436562 -340.253828)
				)
				(arc
					(start 286.935926 -340.253828)
					(mid 286.921941 -340.184894)
					(end 286.915098 -340.11489)
				)
				(xy 286.914336 -340.114128)
				(arc
					(start 286.914336 -339.832188)
					(mid 286.899457 -339.796267)
					(end 286.863536 -339.781388)
				)
				(arc
					(start 286.822896 -339.781388)
					(mid 286.042785 -339.705188)
					(end 286.822896 -339.628988)
				)
				(xy 286.895032 -339.628988)
				(arc
					(start 286.89808 -339.632036)
					(mid 287.007157 -339.688567)
					(end 287.063688 -339.797644)
				)
				(xy 287.066736 -339.800692)
				(arc
					(start 287.066736 -340.082886)
					(mid 287.073831 -340.169512)
					(end 287.09493 -340.253828)
				)
				(arc
					(start 287.245806 -340.253828)
					(mid 287.220395 -340.186494)
					(end 287.207706 -340.115652)
				)
				(xy 287.206436 -340.114128) (xy 287.206436 -339.800692)
				(arc
					(start 287.209484 -339.797644)
					(mid 287.266015 -339.688567)
					(end 287.375092 -339.632036)
				)
				(xy 287.37814 -339.628988)
				(arc
					(start 287.450276 -339.628988)
					(mid 288.230387 -339.705188)
					(end 287.450276 -339.781388)
				)
				(arc
					(start 287.409636 -339.781388)
					(mid 287.373715 -339.796267)
					(end 287.358836 -339.832188)
				)
				(arc
					(start 287.358836 -340.082632)
					(mid 287.377127 -340.174585)
					(end 287.429194 -340.252558)
				)
				(xy 287.430464 -340.253828)
				(arc
					(start 287.83661 -340.253828)
					(mid 288.38525 -339.705188)
					(end 287.83661 -339.156548)
				)
				(xy 286.436816 -339.156548)
			)
		)
	)
	(zone
		(layer "B.Cu")
		(hatch none 0.5)
		(connect_pads
			(clearance 0)
		)
		(min_thickness 0.25)
		(keepout
			(tracks not_allowed)
			(vias allowed)
			(pads allowed)
			(copperpour not_allowed)
			(footprints allowed)
		)
		(placement
			(enabled no)
			(sheetname "")
		)
		(fill
			(thermal_gap 0.5)
			(thermal_bridge_width 0.5)
			(island_removal_mode 0)
		)
		(polygon
			(pts
				(xy 236.028992 -165.770814) (xy 235.87964 -165.770052) (xy 235.724192 -165.847776) (xy 235.724192 -165.84803)
				(arc
					(start 235.725208 -165.850062)
					(mid 235.400342 -166.82466)
					(end 236.37494 -167.149526)
				)
				(xy 236.37621 -167.151812) (xy 238.376206 -166.151814)
				(arc
					(start 238.374936 -166.149528)
					(mid 238.699802 -165.17493)
					(end 237.725204 -164.850064)
				)
				(xy 237.723934 -164.847778)
				(arc
					(start 236.706918 -165.356286)
					(mid 236.735785 -165.369923)
					(end 236.764068 -165.384734)
				)
				(arc
					(start 236.764322 -165.384734)
					(mid 236.840891 -165.432792)
					(end 236.911388 -165.489382)
				)
				(xy 236.912658 -165.489382) (xy 236.940344 -165.517068) (xy 236.940598 -165.517322)
				(arc
					(start 237.145576 -165.7223)
					(mid 237.184616 -165.750786)
					(end 237.230412 -165.766242)
				)
				(arc
					(start 237.248954 -165.76929)
					(mid 237.298724 -165.769131)
					(end 237.345982 -165.753542)
				)
				(arc
					(start 237.5281 -165.660324)
					(mid 238.536063 -165.250733)
					(end 237.614968 -165.829742)
				)
				(xy 237.43285 -165.923214) (xy 237.397798 -165.941248)
				(arc
					(start 237.394242 -165.939978)
					(mid 237.328484 -165.957192)
					(end 237.260638 -165.961314)
				)
				(xy 237.25759 -165.9636) (xy 237.203488 -165.95471) (xy 237.198916 -165.953948) (xy 237.164118 -165.94836)
				(arc
					(start 237.16234 -165.94582)
					(mid 237.099442 -165.921152)
					(end 237.042452 -165.88486)
				)
				(xy 237.038896 -165.88486)
				(arc
					(start 236.805724 -165.651688)
					(mid 236.742709 -165.597066)
					(end 236.672628 -165.551866)
				)
				(arc
					(start 236.672628 -165.551866)
					(mid 236.566911 -165.506663)
					(end 236.454442 -165.482778)
				)
				(xy 236.258608 -165.580568) (xy 236.427772 -165.580568)
				(arc
					(start 236.42955 -165.582346)
					(mid 236.529657 -165.601506)
					(end 236.623606 -165.64102)
				)
				(arc
					(start 236.623606 -165.64102)
					(mid 236.664973 -165.6666)
					(end 236.703616 -165.696138)
				)
				(xy 236.705902 -165.696138) (xy 236.733588 -165.72357) (xy 236.733842 -165.724078) (xy 236.862874 -165.85311)
				(arc
					(start 236.862874 -165.857936)
					(mid 236.905234 -165.951303)
					(end 236.908848 -166.05377)
				)
				(arc
					(start 236.908848 -166.054024)
					(mid 236.872927 -166.150062)
					(end 236.803184 -166.22522)
				)
				(xy 236.80166 -166.230046) (xy 236.766354 -166.247572)
				(arc
					(start 236.573568 -166.344092)
					(mid 235.562291 -166.744839)
					(end 236.488224 -166.173912)
				)
				(arc
					(start 236.68101 -166.077392)
					(mid 236.707436 -166.05512)
					(end 236.720888 -166.02329)
				)
				(arc
					(start 236.720888 -166.02329)
					(mid 236.718275 -165.989039)
					(end 236.700314 -165.95979)
				)
				(arc
					(start 236.598714 -165.858444)
					(mid 236.566956 -165.830939)
					(end 236.531658 -165.808152)
				)
				(arc
					(start 236.531658 -165.808152)
					(mid 236.462363 -165.780606)
					(end 236.388402 -165.771068)
				)
				(xy 236.107732 -165.771068) (xy 236.107478 -165.771322) (xy 236.068362 -165.771068) (xy 236.029246 -165.771068)
			)
		)
	)
	(zone
		(layer "B.Cu")
		(hatch none 0.5)
		(connect_pads
			(clearance 0)
		)
		(min_thickness 0.25)
		(keepout
			(tracks not_allowed)
			(vias allowed)
			(pads allowed)
			(copperpour not_allowed)
			(footprints allowed)
		)
		(placement
			(enabled no)
			(sheetname "")
		)
		(fill
			(thermal_gap 0.5)
			(thermal_bridge_width 0.5)
			(island_removal_mode 0)
		)
		(polygon
			(pts
				(arc
					(start 367.849912 -220.199966)
					(mid 371.599968 -223.950022)
					(end 375.350024 -220.199966)
				)
				(arc
					(start 375.350024 -220.199966)
					(mid 371.599968 -216.44991)
					(end 367.849912 -220.199966)
				)
			)
		)
	)
	(zone
		(layer "B.Cu")
		(hatch none 0.5)
		(connect_pads
			(clearance 0)
		)
		(min_thickness 0.25)
		(keepout
			(tracks not_allowed)
			(vias allowed)
			(pads allowed)
			(copperpour not_allowed)
			(footprints allowed)
		)
		(placement
			(enabled no)
			(sheetname "")
		)
		(fill
			(thermal_gap 0.5)
			(thermal_bridge_width 0.5)
			(island_removal_mode 0)
		)
		(polygon
			(pts
				(arc
					(start 278.23668 -326.556624)
					(mid 277.68804 -327.105264)
					(end 278.23668 -327.653904)
				)
				(xy 278.642826 -327.653904) (xy 278.644096 -327.652634)
				(arc
					(start 278.661876 -327.632822)
					(mid 278.700943 -327.562244)
					(end 278.714454 -327.482708)
				)
				(arc
					(start 278.714454 -327.232264)
					(mid 278.699575 -327.196343)
					(end 278.663654 -327.181464)
				)
				(arc
					(start 278.623014 -327.181464)
					(mid 277.842903 -327.105264)
					(end 278.623014 -327.029064)
				)
				(xy 278.69515 -327.029064)
				(arc
					(start 278.698198 -327.032112)
					(mid 278.807275 -327.088643)
					(end 278.863806 -327.19772)
				)
				(xy 278.866854 -327.200768) (xy 278.866854 -327.514204)
				(arc
					(start 278.865584 -327.515728)
					(mid 278.852891 -327.586569)
					(end 278.827484 -327.653904)
				)
				(arc
					(start 278.97836 -327.653904)
					(mid 278.999445 -327.569714)
					(end 279.006554 -327.483216)
				)
				(xy 279.006554 -327.200768)
				(arc
					(start 279.009602 -327.19772)
					(mid 279.066133 -327.088643)
					(end 279.17521 -327.032112)
				)
				(xy 279.178258 -327.029064)
				(arc
					(start 279.250394 -327.029064)
					(mid 280.030505 -327.105264)
					(end 279.250394 -327.181464)
				)
				(arc
					(start 279.209754 -327.181464)
					(mid 279.173833 -327.196343)
					(end 279.158954 -327.232264)
				)
				(xy 279.158954 -327.483216) (xy 279.158954 -327.514712)
				(arc
					(start 279.158192 -327.515474)
					(mid 279.151335 -327.585225)
					(end 279.137364 -327.653904)
				)
				(arc
					(start 279.636728 -327.653904)
					(mid 280.185368 -327.105264)
					(end 279.636728 -326.556624)
				)
				(xy 278.236934 -326.556624)
			)
		)
	)
	(zone
		(net "GND")
		(layer "B.Cu")
		(hatch none 0.5)
		(connect_pads
			(clearance 0.5)
		)
		(min_thickness 0.25)
		(fill yes
			(thermal_gap 0.5)
			(thermal_bridge_width 0.5)
			(island_removal_mode 0)
		)
		(polygon
			(pts
				(xy 349.36938 -322.14058)
				(arc
					(start 368.56543 -309.784242)
					(mid 371.507885 -306.400611)
					(end 375.784618 -307.748432)
				)
				(arc
					(start 384.230118 -306.030122)
					(mid 384.871022 -304.37161)
					(end 386.106162 -303.092612)
				)
				(arc
					(start 386.106162 -303.092612)
					(mid 385.190952 -301.983524)
					(end 384.71602 -300.626272)
				)
				(arc
					(start 384.71602 -300.626272)
					(mid 381.104661 -301.485443)
					(end 378.285756 -299.070014)
				)
				(xy 371.498622 -301.939706) (xy 368.3 -302.648874)
				(arc
					(start 368.3 -303.626774)
					(mid 368.720168 -307.925057)
					(end 365.052102 -310.204866)
				)
				(arc
					(start 363.051598 -310.204866)
					(mid 360.519246 -313.575728)
					(end 356.354634 -312.918856)
				)
				(arc
					(start 356.354634 -312.918856)
					(mid 349.322034 -313.461353)
					(end 352.2726 -307.054504)
				)
				(xy 352.2726 -306.7812) (xy 351.798636 -306.307236) (xy 346.780612 -307.419502)
				(arc
					(start 336.90814 -313.954414)
					(mid 340.280931 -317.817649)
					(end 341.496142 -322.799964)
				)
				(xy 341.496142 -323.893942) (xy 342.4174 -324.8152) (xy 344.933016 -324.8152) (xy 345.242642 -324.61581)
				(xy 345.242896 -324.61454) (xy 346.472764 -323.823584) (xy 347.36405 -323.249798) (xy 347.364304 -323.249798)
				(xy 349.158052 -322.09486)
			)
		)
		(polygon
			(pts
				(arc
					(start 344.356182 -311.35066)
					(mid 344.356182 -319.53454)
					(end 344.356182 -311.35066)
				)
			)
		)
	)
	(zone
		(net "GND")
		(layer "B.Cu")
		(hatch none 0.5)
		(connect_pads
			(clearance 0.5)
		)
		(min_thickness 0.25)
		(fill yes
			(thermal_gap 0.5)
			(thermal_bridge_width 0.5)
			(island_removal_mode 0)
		)
		(polygon
			(pts
				(xy 308.77129 -338.10829)
				(arc
					(start 321.944492 -335.188052)
					(mid 320.389802 -332.158029)
					(end 319.853818 -328.794872)
				)
				(arc
					(start 319.853818 -326.408034)
					(mid 318.911639 -326.563969)
					(end 317.958978 -326.497188)
				)
				(xy 310.230774 -331.613002) (xy 307.5432 -335.832958) (xy 307.5432 -336.8802)
			)
		)
	)
	(zone
		(layer "B.Cu")
		(hatch none 0.5)
		(connect_pads
			(clearance 0)
		)
		(min_thickness 0.25)
		(keepout
			(tracks not_allowed)
			(vias allowed)
			(pads allowed)
			(copperpour not_allowed)
			(footprints allowed)
		)
		(placement
			(enabled no)
			(sheetname "")
		)
		(fill
			(thermal_gap 0.5)
			(thermal_bridge_width 0.5)
			(island_removal_mode 0)
		)
		(polygon
			(pts
				(arc
					(start 111.498634 -21.950426)
					(mid 110.950121 -21.401532)
					(end 110.401354 -21.950172)
				)
				(xy 110.401354 -22.408896)
				(arc
					(start 110.783624 -22.408896)
					(mid 110.833913 -22.388065)
					(end 110.854744 -22.337776)
				)
				(arc
					(start 110.854744 -22.332188)
					(mid 110.949994 -21.55646)
					(end 111.045244 -22.332188)
				)
				(xy 111.045244 -22.377146)
				(arc
					(start 111.041688 -22.380702)
					(mid 110.96861 -22.522762)
					(end 110.82655 -22.59584)
				)
				(xy 110.822994 -22.599396) (xy 110.433358 -22.599396) (xy 110.401354 -22.600666) (xy 110.401354 -22.700996)
				(xy 110.822994 -22.700996)
				(arc
					(start 110.82655 -22.704552)
					(mid 110.96861 -22.77763)
					(end 111.041688 -22.91969)
				)
				(xy 111.045244 -22.923246)
				(arc
					(start 111.045244 -22.968204)
					(mid 110.949994 -23.743932)
					(end 110.854744 -22.968204)
				)
				(arc
					(start 110.854744 -22.962616)
					(mid 110.833913 -22.912327)
					(end 110.783624 -22.891496)
				)
				(arc
					(start 110.433358 -22.891496)
					(mid 110.417253 -22.892354)
					(end 110.401354 -22.895052)
				)
				(arc
					(start 110.401354 -23.35022)
					(mid 110.949994 -23.89886)
					(end 111.498634 -23.35022)
				)
			)
		)
	)
	(zone
		(layer "B.Cu")
		(hatch none 0.5)
		(connect_pads
			(clearance 0)
		)
		(min_thickness 0.25)
		(keepout
			(tracks allowed)
			(vias allowed)
			(pads allowed)
			(copperpour allowed)
			(footprints not_allowed)
		)
		(placement
			(enabled no)
			(sheetname "")
		)
		(fill
			(thermal_gap 0.5)
			(thermal_bridge_width 0.5)
			(island_removal_mode 0)
		)
		(polygon
			(pts
				(arc
					(start 251.199904 -360.19994)
					(mid 244.199918 -353.199954)
					(end 237.199932 -360.19994)
				)
				(arc
					(start 237.199932 -366.199928)
					(mid 244.199918 -373.199914)
					(end 251.199904 -366.199928)
				)
			)
		)
	)
	(zone
		(net "GND")
		(layer "B.Cu")
		(hatch none 0.5)
		(connect_pads
			(clearance 0.5)
		)
		(min_thickness 0.25)
		(fill yes
			(thermal_gap 0.5)
			(thermal_bridge_width 0.5)
			(island_removal_mode 0)
		)
		(polygon
			(pts
				(xy 303.445672 -9.986772) (xy 303.293272 -10.139172) (xy 303.293272 -22.262846) (xy 303.729898 -22.699472)
				(xy 308.119272 -22.699472) (xy 308.424072 -22.394672) (xy 308.424072 -12.120372) (xy 306.290472 -9.986772)
			)
		)
	)
	(zone
		(layer "B.Cu")
		(hatch none 0.5)
		(connect_pads
			(clearance 0)
		)
		(min_thickness 0.25)
		(keepout
			(tracks not_allowed)
			(vias allowed)
			(pads allowed)
			(copperpour not_allowed)
			(footprints allowed)
		)
		(placement
			(enabled no)
			(sheetname "")
		)
		(fill
			(thermal_gap 0.5)
			(thermal_bridge_width 0.5)
			(island_removal_mode 0)
		)
		(polygon
			(pts
				(arc
					(start 271.970754 -328.521568)
					(mid 271.58696 -328.904981)
					(end 271.9705 -329.288648)
				)
				(arc
					(start 273.1135 -329.288648)
					(mid 273.49704 -328.905108)
					(end 273.1135 -328.521568)
				)
				(arc
					(start 272.768568 -328.521568)
					(mid 272.765366 -328.548408)
					(end 272.76425 -328.575416)
				)
				(arc
					(start 272.76425 -328.724006)
					(mid 272.791127 -328.794124)
					(end 272.857976 -328.8284)
				)
				(arc
					(start 272.857976 -328.8284)
					(mid 273.380217 -328.904854)
					(end 272.857976 -328.981308)
				)
				(xy 272.837656 -328.981308)
				(arc
					(start 272.83537 -328.979022)
					(mid 272.687253 -328.905905)
					(end 272.614136 -328.757788)
				)
				(xy 272.61185 -328.755502) (xy 272.61185 -328.54392) (xy 272.612866 -328.542904) (xy 272.614644 -328.521568)
				(arc
					(start 272.474436 -328.521568)
					(mid 272.472724 -328.548468)
					(end 272.47215 -328.575416)
				)
				(xy 272.47215 -328.755502)
				(arc
					(start 272.469864 -328.757788)
					(mid 272.396747 -328.905905)
					(end 272.24863 -328.979022)
				)
				(xy 272.246344 -328.981308)
				(arc
					(start 272.226024 -328.981308)
					(mid 271.703783 -328.904854)
					(end 272.226024 -328.8284)
				)
				(arc
					(start 272.226024 -328.8284)
					(mid 272.292939 -328.794183)
					(end 272.31975 -328.724006)
				)
				(xy 272.31975 -328.54392) (xy 272.320512 -328.543158) (xy 272.321528 -328.521568)
			)
		)
	)
	(zone
		(layer "B.Cu")
		(hatch none 0.5)
		(connect_pads
			(clearance 0)
		)
		(min_thickness 0.25)
		(keepout
			(tracks not_allowed)
			(vias allowed)
			(pads allowed)
			(copperpour not_allowed)
			(footprints allowed)
		)
		(placement
			(enabled no)
			(sheetname "")
		)
		(fill
			(thermal_gap 0.5)
			(thermal_bridge_width 0.5)
			(island_removal_mode 0)
		)
		(polygon
			(pts
				(arc
					(start 361.098592 -21.950426)
					(mid 360.550079 -21.401532)
					(end 360.001312 -21.950172)
				)
				(arc
					(start 360.001312 -22.428708)
					(mid 360.066815 -22.416435)
					(end 360.133138 -22.409912)
				)
				(xy 360.134408 -22.408896)
				(arc
					(start 360.383582 -22.408896)
					(mid 360.433871 -22.388065)
					(end 360.454702 -22.337776)
				)
				(arc
					(start 360.454702 -22.332188)
					(mid 360.549952 -21.55646)
					(end 360.645202 -22.332188)
				)
				(xy 360.645202 -22.377146)
				(arc
					(start 360.641646 -22.380702)
					(mid 360.568568 -22.522762)
					(end 360.426508 -22.59584)
				)
				(xy 360.422952 -22.599396)
				(arc
					(start 360.173778 -22.599396)
					(mid 360.086536 -22.606019)
					(end 360.001312 -22.625812)
				)
				(arc
					(start 360.001312 -22.733508)
					(mid 360.065867 -22.713419)
					(end 360.13263 -22.702774)
				)
				(xy 360.134408 -22.700996) (xy 360.422952 -22.700996)
				(arc
					(start 360.426508 -22.704552)
					(mid 360.568568 -22.77763)
					(end 360.641646 -22.91969)
				)
				(xy 360.645202 -22.923246)
				(arc
					(start 360.645202 -22.968204)
					(mid 360.549952 -23.743932)
					(end 360.454702 -22.968204)
				)
				(arc
					(start 360.454702 -22.962616)
					(mid 360.433871 -22.912327)
					(end 360.383582 -22.891496)
				)
				(arc
					(start 360.173778 -22.891496)
					(mid 360.082703 -22.906582)
					(end 360.001312 -22.95017)
				)
				(arc
					(start 360.001312 -23.35022)
					(mid 360.549952 -23.89886)
					(end 361.098592 -23.35022)
				)
			)
		)
	)
	(zone
		(net "GND")
		(layer "B.Cu")
		(hatch none 0.5)
		(connect_pads
			(clearance 0.5)
		)
		(min_thickness 0.25)
		(fill yes
			(thermal_gap 0.5)
			(thermal_bridge_width 0.5)
			(island_removal_mode 0)
		)
		(polygon
			(pts
				(xy 474.331792 -237.512606) (xy 474.242384 -237.602014) (xy 474.242384 -238.242602) (xy 474.483938 -238.484156)
				(xy 474.483938 -242.528344) (xy 474.853762 -242.898168) (xy 479.422714 -242.898168) (xy 479.578924 -242.741958)
				(xy 479.578924 -239.570006) (xy 479.332544 -239.323626) (xy 477.322642 -239.323626) (xy 476.9612 -238.962184)
				(xy 476.21698 -238.962184) (xy 474.767402 -237.512606)
			)
		)
		(polygon
			(pts
				(xy 477.106234 -239.741964) (xy 476.903034 -239.741964) (xy 476.903034 -239.945164) (xy 477.106234 -239.945164)
			)
		)
		(polygon
			(pts
				(xy 476.242634 -239.741964) (xy 476.039434 -239.741964) (xy 476.039434 -239.945164) (xy 476.242634 -239.945164)
			)
		)
	)
	(zone
		(layer "B.Cu")
		(hatch none 0.5)
		(connect_pads
			(clearance 0)
		)
		(min_thickness 0.25)
		(keepout
			(tracks not_allowed)
			(vias allowed)
			(pads allowed)
			(copperpour not_allowed)
			(footprints allowed)
		)
		(placement
			(enabled no)
			(sheetname "")
		)
		(fill
			(thermal_gap 0.5)
			(thermal_bridge_width 0.5)
			(island_removal_mode 0)
		)
		(polygon
			(pts
				(arc
					(start 143.89862 -21.950426)
					(mid 143.350107 -21.401532)
					(end 142.80134 -21.950172)
				)
				(arc
					(start 142.80134 -23.35022)
					(mid 143.34998 -23.89886)
					(end 143.89862 -23.35022)
				)
				(xy 143.89862 -22.891496)
				(arc
					(start 143.51635 -22.891496)
					(mid 143.466061 -22.912327)
					(end 143.44523 -22.962616)
				)
				(arc
					(start 143.44523 -22.968204)
					(mid 143.34998 -23.743932)
					(end 143.25473 -22.968204)
				)
				(xy 143.25473 -22.923246)
				(arc
					(start 143.258286 -22.91969)
					(mid 143.331364 -22.77763)
					(end 143.473424 -22.704552)
				)
				(xy 143.47698 -22.700996) (xy 143.89862 -22.700996) (xy 143.89862 -22.599396) (xy 143.47698 -22.599396)
				(arc
					(start 143.473424 -22.59584)
					(mid 143.331364 -22.522762)
					(end 143.258286 -22.380702)
				)
				(xy 143.25473 -22.377146)
				(arc
					(start 143.25473 -22.332188)
					(mid 143.34998 -21.55646)
					(end 143.44523 -22.332188)
				)
				(arc
					(start 143.44523 -22.337776)
					(mid 143.466061 -22.388065)
					(end 143.51635 -22.408896)
				)
				(xy 143.89862 -22.408896)
			)
		)
	)
	(zone
		(net "P5V_C_LL_R")
		(layer "B.Cu")
		(hatch none 0.5)
		(connect_pads
			(clearance 0.5)
		)
		(min_thickness 0.25)
		(fill yes
			(thermal_gap 0.5)
			(thermal_bridge_width 0.5)
			(island_removal_mode 0)
		)
		(polygon
			(pts
				(xy 455.184002 -256.13995) (xy 455.006202 -256.31775) (xy 455.006202 -257.859276) (xy 455.220324 -258.073398)
				(xy 455.858372 -258.073398) (xy 455.98969 -258.204716) (xy 455.98969 -259.231638) (xy 456.276202 -259.51815)
				(xy 457.01204 -259.51815) (xy 457.26604 -259.26415) (xy 457.26604 -256.316988) (xy 457.089002 -256.13995)
			)
		)
		(polygon
			(pts
				(xy 456.757024 -257.962654) (xy 456.553824 -257.962654) (xy 456.553824 -258.165854) (xy 456.757024 -258.165854)
			)
		)
		(polygon
			(pts
				(xy 456.757024 -257.353054) (xy 456.553824 -257.353054) (xy 456.553824 -257.556254) (xy 456.757024 -257.556254)
			)
		)
		(polygon
			(pts
				(xy 456.550014 -256.982976) (xy 456.346814 -256.982976) (xy 456.346814 -257.186176) (xy 456.550014 -257.186176)
			)
		)
		(polygon
			(pts
				(xy 455.888344 -256.558796) (xy 455.685144 -256.558796) (xy 455.685144 -256.761996) (xy 455.888344 -256.761996)
			)
		)
		(polygon
			(pts
				(xy 455.329544 -256.558796) (xy 455.126344 -256.558796) (xy 455.126344 -256.761996) (xy 455.329544 -256.761996)
			)
		)
	)
	(zone
		(layer "B.Cu")
		(hatch none 0.5)
		(connect_pads
			(clearance 0)
		)
		(min_thickness 0.25)
		(keepout
			(tracks not_allowed)
			(vias allowed)
			(pads allowed)
			(copperpour not_allowed)
			(footprints allowed)
		)
		(placement
			(enabled no)
			(sheetname "")
		)
		(fill
			(thermal_gap 0.5)
			(thermal_bridge_width 0.5)
			(island_removal_mode 0)
		)
		(polygon
			(pts
				(arc
					(start 233.59999 -143.500094)
					(mid 229.849934 -139.750038)
					(end 226.099878 -143.500094)
				)
				(arc
					(start 226.099878 -143.500094)
					(mid 229.849934 -147.25015)
					(end 233.59999 -143.500094)
				)
			)
		)
	)
	(zone
		(net "GND")
		(layer "B.Cu")
		(hatch none 0.5)
		(connect_pads
			(clearance 0.5)
		)
		(min_thickness 0.25)
		(fill yes
			(thermal_gap 0.5)
			(thermal_bridge_width 0.5)
			(island_removal_mode 0)
		)
		(polygon
			(pts
				(xy 222.167704 -69.8373) (xy 222.88373 -69.678804) (xy 223.380808 -69.568314) (xy 223.381062 -69.568314)
				(xy 225.801936 -69.031866) (xy 225.94951 -69.1261) (xy 227.041202 -68.883784) (xy 227.127816 -68.748148)
				(xy 228.24948 -68.49872) (xy 228.473 -68.2752) (xy 228.473 -67.768978)
				(arc
					(start 225.465386 -65.50914)
					(mid 220.214228 -67.749868)
					(end 217.838782 -62.558168)
				)
				(arc
					(start 212.893402 -61.59627)
					(mid 213.064106 -62.694677)
					(end 213.12124 -63.8048)
				)
				(arc
					(start 213.12124 -69.80047)
					(mid 213.069607 -70.85605)
					(end 212.915246 -71.901558)
				)
				(xy 214.137494 -71.630032) (xy 214.137748 -71.630286) (xy 215.327738 -71.365872) (xy 215.327992 -71.366126)
				(xy 216.517982 -71.101712) (xy 216.654888 -71.188834) (xy 219.654628 -70.5231) (xy 219.748608 -70.375018)
				(xy 220.95714 -70.106794) (xy 220.957648 -70.105778) (xy 222.16745 -69.837554)
			)
		)
	)
	(zone
		(net "GND")
		(layer "B.Cu")
		(hatch none 0.5)
		(connect_pads
			(clearance 0.5)
		)
		(min_thickness 0.25)
		(fill yes
			(thermal_gap 0.5)
			(thermal_bridge_width 0.5)
			(island_removal_mode 0)
		)
		(polygon
			(pts
				(xy 275.719794 -194.864228) (xy 268.711934 -189.226444) (xy 268.586458 -188.750448) (xy 268.514576 -188.69279)
				(xy 268.514576 -188.478668) (xy 268.141704 -187.064904) (xy 267.2588 -186.182) (xy 266.509246 -186.182)
				(xy 266.3952 -186.558174) (xy 266.252452 -186.634374) (xy 265.713464 -188.41085) (xy 265.789664 -188.553344)
				(xy 264.709656 -192.113662) (xy 264.709402 -192.113916) (xy 264.356088 -193.27876) (xy 264.213594 -193.35496)
				(xy 259.9944 -207.261206) (xy 259.9944 -207.7212)
				(arc
					(start 260.330188 -208.056988)
					(mid 261.658578 -207.978593)
					(end 262.941816 -208.3308)
				)
				(arc
					(start 263.49579 -208.3308)
					(mid 264.670113 -207.17453)
					(end 266.205462 -206.57566)
				)
				(arc
					(start 266.205462 -206.57566)
					(mid 269.182505 -206.475223)
					(end 271.438116 -208.420716)
				)
				(xy 271.8054 -208.788)
				(arc
					(start 273.054826 -208.788)
					(mid 276.287145 -207.551109)
					(end 279.311354 -209.234024)
				)
				(arc
					(start 279.311354 -209.234024)
					(mid 279.470717 -215.364462)
					(end 273.367246 -214.768176)
				)
				(arc
					(start 273.367246 -214.768176)
					(mid 273.157013 -214.579121)
					(end 272.960338 -214.376)
				)
				(arc
					(start 271.749012 -214.376)
					(mid 269.946064 -216.726756)
					(end 267.02893 -217.24366)
				)
				(arc
					(start 267.02893 -217.24366)
					(mid 266.515603 -217.41625)
					(end 265.983974 -217.519504)
				)
				(arc
					(start 265.983974 -217.519504)
					(mid 265.875694 -217.879692)
					(end 265.7348 -218.228418)
				)
				(arc
					(start 265.7348 -219.254832)
					(mid 267.670073 -221.797079)
					(end 267.186664 -224.955354)
				)
				(arc
					(start 267.186664 -224.955354)
					(mid 271.469187 -227.994781)
					(end 269.22984 -232.744772)
				)
				(arc
					(start 269.22984 -232.744772)
					(mid 269.438104 -233.952621)
					(end 269.279116 -235.167932)
				)
				(arc
					(start 269.279116 -235.167932)
					(mid 269.290988 -235.405532)
					(end 269.289022 -235.64342)
				)
				(arc
					(start 269.289022 -235.64342)
					(mid 269.85665 -235.741068)
					(end 270.405098 -235.916978)
				)
				(arc
					(start 270.405098 -235.916978)
					(mid 270.872429 -235.655271)
					(end 271.36979 -235.456476)
				)
				(arc
					(start 271.36979 -235.456476)
					(mid 272.931584 -233.397045)
					(end 275.416264 -232.685336)
				)
				(xy 275.9202 -232.1814)
				(arc
					(start 275.9202 -231.782874)
					(mid 275.594877 -229.26899)
					(end 276.81301 -227.046028)
				)
				(arc
					(start 276.81301 -227.046028)
					(mid 278.028356 -225.829588)
					(end 279.63622 -225.220022)
				)
				(arc
					(start 279.63622 -225.220022)
					(mid 279.7729 -224.819848)
					(end 279.950164 -224.435924)
				)
				(arc
					(start 279.950164 -224.435924)
					(mid 279.549937 -223.45817)
					(end 279.413462 -222.410528)
				)
				(arc
					(start 279.413462 -221.14002)
					(mid 279.911878 -219.183033)
					(end 281.285696 -217.702892)
				)
				(arc
					(start 281.285696 -217.702892)
					(mid 285.773432 -216.7017)
					(end 288.35731 -220.50502)
				)
				(arc
					(start 288.35731 -223.04502)
					(mid 288.309339 -223.669691)
					(end 288.166556 -224.279714)
				)
				(arc
					(start 288.166556 -224.279714)
					(mid 288.358612 -224.981484)
					(end 288.42335 -225.706178)
				)
				(arc
					(start 288.42335 -228.246178)
					(mid 287.666445 -230.616826)
					(end 285.675832 -232.11028)
				)
				(arc
					(start 285.675832 -232.11028)
					(mid 284.181508 -233.580532)
					(end 282.155138 -234.117642)
				)
				(arc
					(start 279.615138 -234.117642)
					(mid 279.447866 -234.1142)
					(end 279.280874 -234.103926)
				)
				(xy 278.8158 -234.569)
				(arc
					(start 278.8158 -234.78109)
					(mid 279.040867 -235.254043)
					(end 279.203658 -235.751878)
				)
				(arc
					(start 279.203658 -235.751878)
					(mid 279.357599 -235.743136)
					(end 279.51176 -235.740194)
				)
				(arc
					(start 282.053538 -235.740194)
					(mid 285.85677 -238.324107)
					(end 284.855666 -242.811808)
				)
				(arc
					(start 284.855666 -242.811808)
					(mid 283.375515 -244.185607)
					(end 281.418538 -244.684042)
				)
				(arc
					(start 280.148538 -244.684042)
					(mid 278.191551 -244.185626)
					(end 276.71141 -242.811808)
				)
				(arc
					(start 276.71141 -242.811808)
					(mid 276.290283 -242.350456)
					(end 275.94433 -241.830352)
				)
				(arc
					(start 275.94433 -241.830352)
					(mid 273.762083 -243.330595)
					(end 271.117568 -243.190776)
				)
				(arc
					(start 271.117568 -243.190776)
					(mid 268.853751 -243.854024)
					(end 266.597638 -243.165122)
				)
				(arc
					(start 266.597638 -243.165122)
					(mid 265.443933 -244.368262)
					(end 263.906 -245.011194)
				)
				(arc
					(start 263.906 -248.670318)
					(mid 264.924927 -248.914566)
					(end 265.848338 -249.409712)
				)
				(arc
					(start 265.848338 -249.409712)
					(mid 267.224424 -250.182902)
					(end 268.205204 -251.419614)
				)
				(arc
					(start 268.304264 -251.518674)
					(mid 268.919782 -251.581733)
					(end 269.518892 -251.736352)
				)
				(arc
					(start 272.992342 -251.736352)
					(mid 273.955818 -248.371169)
					(end 277.136606 -246.909844)
				)
				(arc
					(start 287.936686 -246.909844)
					(mid 288.666388 -246.973834)
					(end 289.373818 -247.163844)
				)
				(arc
					(start 289.373818 -243.19992)
					(mid 292.76062 -235.336852)
					(end 300.801024 -232.395776)
				)
				(xy 301.9044 -231.2924) (xy 301.9044 -229.503986) (xy 298.80052 -215.500458) (xy 304.296826 -190.703454)
				(xy 300.148244 -190.703454)
				(arc
					(start 298.932346 -189.487556)
					(mid 298.486663 -189.562151)
					(end 298.035472 -189.587124)
				)
				(arc
					(start 297.120818 -189.587124)
					(mid 296.014714 -189.434752)
					(end 294.991028 -188.988954)
				)
				(xy 287.930082 -194.665092) (xy 281.520392 -196.71665) (xy 276.46249 -195.103242)
			)
		)
		(polygon
			(pts
				(arc
					(start 289.102292 -207.343756)
					(mid 289.102292 -215.527636)
					(end 289.102292 -207.343756)
				)
			)
		)
	)
	(zone
		(layer "B.Cu")
		(hatch none 0.5)
		(connect_pads
			(clearance 0)
		)
		(min_thickness 0.25)
		(keepout
			(tracks not_allowed)
			(vias allowed)
			(pads allowed)
			(copperpour not_allowed)
			(footprints allowed)
		)
		(placement
			(enabled no)
			(sheetname "")
		)
		(fill
			(thermal_gap 0.5)
			(thermal_bridge_width 0.5)
			(island_removal_mode 0)
		)
		(polygon
			(pts
				(arc
					(start 364.698534 -21.950426)
					(mid 364.150021 -21.401532)
					(end 363.601254 -21.950172)
				)
				(arc
					(start 363.601254 -22.428708)
					(mid 363.666757 -22.416435)
					(end 363.73308 -22.409912)
				)
				(xy 363.73435 -22.408896)
				(arc
					(start 363.983524 -22.408896)
					(mid 364.033813 -22.388065)
					(end 364.054644 -22.337776)
				)
				(arc
					(start 364.054644 -22.332188)
					(mid 364.149894 -21.55646)
					(end 364.245144 -22.332188)
				)
				(xy 364.245144 -22.377146)
				(arc
					(start 364.241588 -22.380702)
					(mid 364.16851 -22.522762)
					(end 364.02645 -22.59584)
				)
				(xy 364.022894 -22.599396)
				(arc
					(start 363.77372 -22.599396)
					(mid 363.686478 -22.606019)
					(end 363.601254 -22.625812)
				)
				(arc
					(start 363.601254 -22.733508)
					(mid 363.665809 -22.713419)
					(end 363.732572 -22.702774)
				)
				(xy 363.73435 -22.700996) (xy 364.022894 -22.700996)
				(arc
					(start 364.02645 -22.704552)
					(mid 364.16851 -22.77763)
					(end 364.241588 -22.91969)
				)
				(xy 364.245144 -22.923246)
				(arc
					(start 364.245144 -22.968204)
					(mid 364.149894 -23.743932)
					(end 364.054644 -22.968204)
				)
				(arc
					(start 364.054644 -22.962616)
					(mid 364.033813 -22.912327)
					(end 363.983524 -22.891496)
				)
				(arc
					(start 363.77372 -22.891496)
					(mid 363.682645 -22.906582)
					(end 363.601254 -22.95017)
				)
				(arc
					(start 363.601254 -23.35022)
					(mid 364.149894 -23.89886)
					(end 364.698534 -23.35022)
				)
			)
		)
	)
	(zone
		(layer "B.Cu")
		(hatch none 0.5)
		(connect_pads
			(clearance 0)
		)
		(min_thickness 0.25)
		(keepout
			(tracks not_allowed)
			(vias allowed)
			(pads allowed)
			(copperpour not_allowed)
			(footprints allowed)
		)
		(placement
			(enabled no)
			(sheetname "")
		)
		(fill
			(thermal_gap 0.5)
			(thermal_bridge_width 0.5)
			(island_removal_mode 0)
		)
		(polygon
			(pts
				(arc
					(start 166.325042 -207.79994)
					(mid 159.325056 -200.799954)
					(end 152.32507 -207.79994)
				)
				(arc
					(start 152.32507 -213.799928)
					(mid 159.325056 -220.799914)
					(end 166.325042 -213.799928)
				)
			)
		)
	)
	(zone
		(layer "B.Cu")
		(hatch none 0.5)
		(connect_pads
			(clearance 0)
		)
		(min_thickness 0.25)
		(keepout
			(tracks allowed)
			(vias allowed)
			(pads allowed)
			(copperpour allowed)
			(footprints not_allowed)
		)
		(placement
			(enabled no)
			(sheetname "")
		)
		(fill
			(thermal_gap 0.5)
			(thermal_bridge_width 0.5)
			(island_removal_mode 0)
		)
		(polygon
			(pts
				(arc
					(start 463.674968 -207.79994)
					(mid 456.674982 -200.799954)
					(end 449.674996 -207.79994)
				)
				(arc
					(start 449.674996 -213.799928)
					(mid 456.674982 -220.799914)
					(end 463.674968 -213.799928)
				)
			)
		)
	)
	(zone
		(layer "B.Cu")
		(hatch none 0.5)
		(connect_pads
			(clearance 0)
		)
		(min_thickness 0.25)
		(keepout
			(tracks not_allowed)
			(vias allowed)
			(pads allowed)
			(copperpour not_allowed)
			(footprints allowed)
		)
		(placement
			(enabled no)
			(sheetname "")
		)
		(fill
			(thermal_gap 0.5)
			(thermal_bridge_width 0.5)
			(island_removal_mode 0)
		)
		(polygon
			(pts
				(arc
					(start 279.236678 -353.55657)
					(mid 278.688038 -354.10521)
					(end 279.236678 -354.65385)
				)
				(xy 279.642824 -354.65385) (xy 279.644094 -354.65258)
				(arc
					(start 279.661874 -354.632768)
					(mid 279.700941 -354.56219)
					(end 279.714452 -354.482654)
				)
				(arc
					(start 279.714452 -354.23221)
					(mid 279.699573 -354.196289)
					(end 279.663652 -354.18141)
				)
				(arc
					(start 279.623012 -354.18141)
					(mid 278.842901 -354.10521)
					(end 279.623012 -354.02901)
				)
				(xy 279.695148 -354.02901)
				(arc
					(start 279.698196 -354.032058)
					(mid 279.807273 -354.088589)
					(end 279.863804 -354.197666)
				)
				(xy 279.866852 -354.200714) (xy 279.866852 -354.51415)
				(arc
					(start 279.865582 -354.515674)
					(mid 279.852889 -354.586515)
					(end 279.827482 -354.65385)
				)
				(arc
					(start 279.978358 -354.65385)
					(mid 279.999443 -354.56966)
					(end 280.006552 -354.483162)
				)
				(xy 280.006552 -354.200714)
				(arc
					(start 280.0096 -354.197666)
					(mid 280.066131 -354.088589)
					(end 280.175208 -354.032058)
				)
				(xy 280.178256 -354.02901)
				(arc
					(start 280.250392 -354.02901)
					(mid 281.030503 -354.10521)
					(end 280.250392 -354.18141)
				)
				(arc
					(start 280.209752 -354.18141)
					(mid 280.173831 -354.196289)
					(end 280.158952 -354.23221)
				)
				(xy 280.158952 -354.483162) (xy 280.158952 -354.514658)
				(arc
					(start 280.15819 -354.51542)
					(mid 280.151333 -354.585171)
					(end 280.137362 -354.65385)
				)
				(arc
					(start 280.636726 -354.65385)
					(mid 281.185366 -354.10521)
					(end 280.636726 -353.55657)
				)
				(xy 279.236932 -353.55657)
			)
		)
	)
	(zone
		(layer "B.Cu")
		(hatch none 0.5)
		(connect_pads
			(clearance 0)
		)
		(min_thickness 0.25)
		(keepout
			(tracks not_allowed)
			(vias allowed)
			(pads allowed)
			(copperpour not_allowed)
			(footprints allowed)
		)
		(placement
			(enabled no)
			(sheetname "")
		)
		(fill
			(thermal_gap 0.5)
			(thermal_bridge_width 0.5)
			(island_removal_mode 0)
		)
		(polygon
			(pts
				(arc
					(start 171.45 -164.200078)
					(mid 167.699944 -160.450022)
					(end 163.949888 -164.200078)
				)
				(arc
					(start 163.949888 -164.200078)
					(mid 167.699944 -167.950134)
					(end 171.45 -164.200078)
				)
			)
		)
	)
	(zone
		(layer "B.Cu")
		(hatch none 0.5)
		(connect_pads
			(clearance 0)
		)
		(min_thickness 0.25)
		(keepout
			(tracks not_allowed)
			(vias allowed)
			(pads allowed)
			(copperpour not_allowed)
			(footprints allowed)
		)
		(placement
			(enabled no)
			(sheetname "")
		)
		(fill
			(thermal_gap 0.5)
			(thermal_bridge_width 0.5)
			(island_removal_mode 0)
		)
		(polygon
			(pts
				(arc
					(start 285.436564 -301.356522)
					(mid 284.887924 -301.905162)
					(end 285.436564 -302.453802)
				)
				(arc
					(start 285.935928 -302.453802)
					(mid 285.921943 -302.384868)
					(end 285.9151 -302.314864)
				)
				(xy 285.914338 -302.314102)
				(arc
					(start 285.914338 -302.032162)
					(mid 285.899459 -301.996241)
					(end 285.863538 -301.981362)
				)
				(arc
					(start 285.822898 -301.981362)
					(mid 285.042787 -301.905162)
					(end 285.822898 -301.828962)
				)
				(xy 285.895034 -301.828962)
				(arc
					(start 285.898082 -301.83201)
					(mid 286.007159 -301.888541)
					(end 286.06369 -301.997618)
				)
				(xy 286.066738 -302.000666)
				(arc
					(start 286.066738 -302.28286)
					(mid 286.073833 -302.369486)
					(end 286.094932 -302.453802)
				)
				(arc
					(start 286.245808 -302.453802)
					(mid 286.220397 -302.386468)
					(end 286.207708 -302.315626)
				)
				(xy 286.206438 -302.314102) (xy 286.206438 -302.000666)
				(arc
					(start 286.209486 -301.997618)
					(mid 286.266017 -301.888541)
					(end 286.375094 -301.83201)
				)
				(xy 286.378142 -301.828962)
				(arc
					(start 286.450278 -301.828962)
					(mid 287.230389 -301.905162)
					(end 286.450278 -301.981362)
				)
				(arc
					(start 286.409638 -301.981362)
					(mid 286.373717 -301.996241)
					(end 286.358838 -302.032162)
				)
				(arc
					(start 286.358838 -302.282606)
					(mid 286.377129 -302.374559)
					(end 286.429196 -302.452532)
				)
				(xy 286.430466 -302.453802)
				(arc
					(start 286.836612 -302.453802)
					(mid 287.385252 -301.905162)
					(end 286.836612 -301.356522)
				)
				(xy 285.436818 -301.356522)
			)
		)
	)
	(zone
		(layer "B.Cu")
		(hatch none 0.5)
		(connect_pads
			(clearance 0)
		)
		(min_thickness 0.25)
		(keepout
			(tracks not_allowed)
			(vias allowed)
			(pads allowed)
			(copperpour not_allowed)
			(footprints allowed)
		)
		(placement
			(enabled no)
			(sheetname "")
		)
		(fill
			(thermal_gap 0.5)
			(thermal_bridge_width 0.5)
			(island_removal_mode 0)
		)
		(polygon
			(pts
				(arc
					(start 122.40006 -28.079954)
					(mid 126.150116 -24.329898)
					(end 129.899918 -28.079954)
				)
				(arc
					(start 129.899918 -28.079954)
					(mid 126.150116 -31.829756)
					(end 122.40006 -28.079954)
				)
			)
		)
	)
	(zone
		(net "GND")
		(layer "B.Cu")
		(hatch none 0.5)
		(connect_pads
			(clearance 0.5)
		)
		(min_thickness 0.25)
		(fill yes
			(thermal_gap 0.5)
			(thermal_bridge_width 0.5)
			(island_removal_mode 0)
		)
		(polygon
			(pts
				(arc
					(start 351.2312 -243.001292)
					(mid 353.182153 -244.298008)
					(end 354.1014 -246.452644)
				)
				(xy 375.081038 -232.566464) (xy 375.589038 -232.230168) (xy 376.23369 -231.819704)
				(arc
					(start 395.53896 -227.974398)
					(mid 394.871334 -226.319328)
					(end 394.972032 -224.537524)
				)
				(arc
					(start 394.972032 -224.537524)
					(mid 386.496357 -221.891738)
					(end 382.853692 -213.79434)
				)
				(xy 382.853692 -209.329528)
				(arc
					(start 375.190766 -214.118952)
					(mid 378.150979 -222.837544)
					(end 369.975384 -227.072444)
				)
				(arc
					(start 369.975384 -227.072444)
					(mid 369.95653 -227.359977)
					(end 369.917472 -227.645468)
				)
				(arc
					(start 369.917472 -227.645468)
					(mid 369.484487 -234.863556)
					(end 363.761528 -230.443532)
				)
				(arc
					(start 363.761528 -230.443532)
					(mid 362.391218 -229.072416)
					(end 361.806236 -227.224336)
				)
				(arc
					(start 361.806236 -227.224336)
					(mid 360.654322 -225.400412)
					(end 360.590592 -223.244156)
				)
				(arc
					(start 357.743506 -225.02368)
					(mid 357.052405 -227.502886)
					(end 355.017324 -229.078536)
				)
				(arc
					(start 352.612452 -232.71226)
					(mid 352.671541 -232.746314)
					(end 352.730054 -232.781348)
				)
				(arc
					(start 352.730054 -232.781348)
					(mid 357.3722 -237.339848)
					(end 351.746058 -240.607342)
				)
				(xy 350.7486 -241.6048)
				(arc
					(start 350.7486 -241.960146)
					(mid 351.026594 -242.463711)
					(end 351.2312 -243.001292)
				)
			)
		)
	)
	(zone
		(layer "B.Cu")
		(hatch none 0.5)
		(connect_pads
			(clearance 0)
		)
		(min_thickness 0.25)
		(keepout
			(tracks not_allowed)
			(vias allowed)
			(pads allowed)
			(copperpour not_allowed)
			(footprints allowed)
		)
		(placement
			(enabled no)
			(sheetname "")
		)
		(fill
			(thermal_gap 0.5)
			(thermal_bridge_width 0.5)
			(island_removal_mode 0)
		)
		(polygon
			(pts
				(arc
					(start 368.29873 -21.950426)
					(mid 367.750217 -21.401532)
					(end 367.20145 -21.950172)
				)
				(xy 367.20145 -22.408896)
				(arc
					(start 367.58372 -22.408896)
					(mid 367.634009 -22.388065)
					(end 367.65484 -22.337776)
				)
				(arc
					(start 367.65484 -22.332188)
					(mid 367.75009 -21.55646)
					(end 367.84534 -22.332188)
				)
				(xy 367.84534 -22.377146)
				(arc
					(start 367.841784 -22.380702)
					(mid 367.768706 -22.522762)
					(end 367.626646 -22.59584)
				)
				(xy 367.62309 -22.599396) (xy 367.20145 -22.599396) (xy 367.20145 -22.700996) (xy 367.62309 -22.700996)
				(arc
					(start 367.626646 -22.704552)
					(mid 367.768706 -22.77763)
					(end 367.841784 -22.91969)
				)
				(xy 367.84534 -22.923246)
				(arc
					(start 367.84534 -22.968204)
					(mid 367.75009 -23.743932)
					(end 367.65484 -22.968204)
				)
				(arc
					(start 367.65484 -22.962616)
					(mid 367.634009 -22.912327)
					(end 367.58372 -22.891496)
				)
				(xy 367.20145 -22.891496)
				(arc
					(start 367.20145 -23.35022)
					(mid 367.75009 -23.89886)
					(end 368.29873 -23.35022)
				)
			)
		)
	)
	(zone
		(net "GND")
		(layer "B.Cu")
		(hatch none 0.5)
		(connect_pads
			(clearance 0.5)
		)
		(min_thickness 0.25)
		(fill yes
			(thermal_gap 0.5)
			(thermal_bridge_width 0.5)
			(island_removal_mode 0)
		)
		(polygon
			(pts
				(xy 177.643282 -235.506006) (xy 177.389282 -235.760006) (xy 177.389282 -239.744504) (xy 178.617118 -240.97234)
				(xy 181.637432 -240.97234) (xy 182.889398 -242.224306) (xy 185.275982 -242.224306) (xy 185.949082 -241.551206)
				(xy 185.949082 -239.620806) (xy 180.411882 -239.620806) (xy 180.145182 -239.354106) (xy 179.078382 -239.354106)
				(xy 178.405282 -238.681006) (xy 178.405282 -237.792006) (xy 179.167282 -237.030006) (xy 179.167282 -235.760006)
				(xy 178.913282 -235.506006)
			)
		)
		(polygon
			(pts
				(xy 180.068728 -239.852708) (xy 179.865528 -239.852708) (xy 179.865528 -240.055908) (xy 180.068728 -240.055908)
			)
		)
		(polygon
			(pts
				(xy 179.459128 -239.852708) (xy 179.255928 -239.852708) (xy 179.255928 -240.055908) (xy 179.459128 -240.055908)
			)
		)
	)
	(zone
		(layer "B.Cu")
		(hatch none 0.5)
		(connect_pads
			(clearance 0)
		)
		(min_thickness 0.25)
		(keepout
			(tracks allowed)
			(vias allowed)
			(pads allowed)
			(copperpour allowed)
			(footprints not_allowed)
		)
		(placement
			(enabled no)
			(sheetname "")
		)
		(fill
			(thermal_gap 0.5)
			(thermal_bridge_width 0.5)
			(island_removal_mode 0)
		)
		(polygon
			(pts
				(arc
					(start 485.000046 -120.499886)
					(mid 481.24999 -116.74983)
					(end 477.499934 -120.499886)
				)
				(arc
					(start 477.499934 -120.499886)
					(mid 481.24999 -124.249942)
					(end 485.000046 -120.499886)
				)
			)
		)
	)
	(zone
		(layer "B.Cu")
		(hatch none 0.5)
		(connect_pads
			(clearance 0)
		)
		(min_thickness 0.25)
		(keepout
			(tracks not_allowed)
			(vias allowed)
			(pads allowed)
			(copperpour not_allowed)
			(footprints allowed)
		)
		(placement
			(enabled no)
			(sheetname "")
		)
		(fill
			(thermal_gap 0.5)
			(thermal_bridge_width 0.5)
			(island_removal_mode 0)
		)
		(polygon
			(pts
				(arc
					(start 142.098522 -20.950428)
					(mid 141.550009 -20.401534)
					(end 141.001242 -20.950174)
				)
				(arc
					(start 141.001242 -22.350222)
					(mid 141.549882 -22.898862)
					(end 142.098522 -22.350222)
				)
				(arc
					(start 142.098522 -21.950172)
					(mid 142.017155 -21.906513)
					(end 141.926056 -21.891498)
				)
				(arc
					(start 141.716252 -21.891498)
					(mid 141.665963 -21.912329)
					(end 141.645132 -21.962618)
				)
				(arc
					(start 141.645132 -21.968206)
					(mid 141.549882 -22.743934)
					(end 141.454632 -21.968206)
				)
				(xy 141.454632 -21.923248)
				(arc
					(start 141.458188 -21.919692)
					(mid 141.531266 -21.777632)
					(end 141.673326 -21.704554)
				)
				(xy 141.676882 -21.700998) (xy 141.965426 -21.700998)
				(arc
					(start 141.967204 -21.702776)
					(mid 142.033959 -21.713456)
					(end 142.098522 -21.73351)
				)
				(arc
					(start 142.098522 -21.625814)
					(mid 142.013298 -21.606021)
					(end 141.926056 -21.599398)
				)
				(xy 141.676882 -21.599398)
				(arc
					(start 141.673326 -21.595842)
					(mid 141.531266 -21.522764)
					(end 141.458188 -21.380704)
				)
				(xy 141.454632 -21.377148)
				(arc
					(start 141.454632 -21.33219)
					(mid 141.549882 -20.556462)
					(end 141.645132 -21.33219)
				)
				(arc
					(start 141.645132 -21.337778)
					(mid 141.665963 -21.388067)
					(end 141.716252 -21.408898)
				)
				(xy 141.965426 -21.408898)
				(arc
					(start 141.966696 -21.409914)
					(mid 142.033019 -21.416439)
					(end 142.098522 -21.42871)
				)
			)
		)
	)
	(zone
		(net "P12V_A_COMP")
		(layer "B.Cu")
		(hatch none 0.5)
		(connect_pads
			(clearance 0.5)
		)
		(min_thickness 0.25)
		(fill yes
			(thermal_gap 0.5)
			(thermal_bridge_width 0.5)
			(island_removal_mode 0)
		)
		(polygon
			(pts
				(xy 219.5068 -177.3936) (xy 219.2782 -177.6222) (xy 219.2782 -178.6128) (xy 222.879666 -184.352438)
				(xy 237.122462 -184.352438) (xy 239.687354 -181.787546) (xy 239.687354 -179.91709) (xy 239.195864 -179.4256)
				(xy 235.1532 -179.4256) (xy 233.1212 -177.3936)
			)
		)
	)
	(zone
		(layer "B.Cu")
		(hatch none 0.5)
		(connect_pads
			(clearance 0)
		)
		(min_thickness 0.25)
		(keepout
			(tracks not_allowed)
			(vias allowed)
			(pads allowed)
			(copperpour not_allowed)
			(footprints allowed)
		)
		(placement
			(enabled no)
			(sheetname "")
		)
		(fill
			(thermal_gap 0.5)
			(thermal_bridge_width 0.5)
			(island_removal_mode 0)
		)
		(polygon
			(pts
				(arc
					(start 278.23668 -351.756472)
					(mid 277.68804 -352.305112)
					(end 278.23668 -352.853752)
				)
				(xy 278.642826 -352.853752) (xy 278.644096 -352.852482)
				(arc
					(start 278.661876 -352.83267)
					(mid 278.700943 -352.762092)
					(end 278.714454 -352.682556)
				)
				(arc
					(start 278.714454 -352.432112)
					(mid 278.699575 -352.396191)
					(end 278.663654 -352.381312)
				)
				(arc
					(start 278.623014 -352.381312)
					(mid 277.842903 -352.305112)
					(end 278.623014 -352.228912)
				)
				(xy 278.69515 -352.228912)
				(arc
					(start 278.698198 -352.23196)
					(mid 278.807275 -352.288491)
					(end 278.863806 -352.397568)
				)
				(xy 278.866854 -352.400616) (xy 278.866854 -352.714052)
				(arc
					(start 278.865584 -352.715576)
					(mid 278.852891 -352.786417)
					(end 278.827484 -352.853752)
				)
				(arc
					(start 278.97836 -352.853752)
					(mid 278.999445 -352.769562)
					(end 279.006554 -352.683064)
				)
				(xy 279.006554 -352.400616)
				(arc
					(start 279.009602 -352.397568)
					(mid 279.066133 -352.288491)
					(end 279.17521 -352.23196)
				)
				(xy 279.178258 -352.228912)
				(arc
					(start 279.250394 -352.228912)
					(mid 280.030505 -352.305112)
					(end 279.250394 -352.381312)
				)
				(arc
					(start 279.209754 -352.381312)
					(mid 279.173833 -352.396191)
					(end 279.158954 -352.432112)
				)
				(xy 279.158954 -352.683064) (xy 279.158954 -352.71456)
				(arc
					(start 279.158192 -352.715322)
					(mid 279.151335 -352.785073)
					(end 279.137364 -352.853752)
				)
				(arc
					(start 279.636728 -352.853752)
					(mid 280.185368 -352.305112)
					(end 279.636728 -351.756472)
				)
				(xy 278.236934 -351.756472)
			)
		)
	)
	(zone
		(layer "B.Cu")
		(hatch none 0.5)
		(connect_pads
			(clearance 0)
		)
		(min_thickness 0.25)
		(keepout
			(tracks not_allowed)
			(vias allowed)
			(pads allowed)
			(copperpour not_allowed)
			(footprints allowed)
		)
		(placement
			(enabled no)
			(sheetname "")
		)
		(fill
			(thermal_gap 0.5)
			(thermal_bridge_width 0.5)
			(island_removal_mode 0)
		)
		(polygon
			(pts
				(arc
					(start 307.200046 -138.199876)
					(mid 300.20006 -131.19989)
					(end 293.200074 -138.199876)
				)
				(arc
					(start 293.200074 -144.200118)
					(mid 300.20006 -151.200104)
					(end 307.200046 -144.200118)
				)
			)
		)
	)
	(zone
		(layer "B.Cu")
		(hatch none 0.5)
		(connect_pads
			(clearance 0)
		)
		(min_thickness 0.25)
		(keepout
			(tracks not_allowed)
			(vias allowed)
			(pads allowed)
			(copperpour not_allowed)
			(footprints allowed)
		)
		(placement
			(enabled no)
			(sheetname "")
		)
		(fill
			(thermal_gap 0.5)
			(thermal_bridge_width 0.5)
			(island_removal_mode 0)
		)
		(polygon
			(pts
				(arc
					(start 410.85008 -164.200078)
					(mid 407.100024 -160.450022)
					(end 403.349968 -164.200078)
				)
				(arc
					(start 403.349968 -164.200078)
					(mid 407.100024 -167.950134)
					(end 410.85008 -164.200078)
				)
			)
		)
	)
	(zone
		(layer "B.Cu")
		(hatch none 0.5)
		(connect_pads
			(clearance 0)
		)
		(min_thickness 0.25)
		(keepout
			(tracks not_allowed)
			(vias allowed)
			(pads allowed)
			(copperpour not_allowed)
			(footprints allowed)
		)
		(placement
			(enabled no)
			(sheetname "")
		)
		(fill
			(thermal_gap 0.5)
			(thermal_bridge_width 0.5)
			(island_removal_mode 0)
		)
		(polygon
			(pts
				(arc
					(start 419.770052 -162.178746)
					(mid 419.389179 -161.797492)
					(end 419.008052 -162.178492)
				)
				(xy 419.008052 -162.527742)
				(arc
					(start 419.212268 -162.527742)
					(mid 419.280924 -162.500667)
					(end 419.312598 -162.434016)
				)
				(arc
					(start 419.312598 -162.434016)
					(mid 419.389174 -161.911775)
					(end 419.465252 -162.434016)
				)
				(xy 419.465252 -162.458654)
				(arc
					(start 419.462966 -162.46094)
					(mid 419.39114 -162.60603)
					(end 419.24605 -162.677856)
				)
				(xy 419.243764 -162.680142) (xy 419.008052 -162.680142) (xy 419.008052 -162.819842) (xy 419.243764 -162.819842)
				(arc
					(start 419.24605 -162.822128)
					(mid 419.39114 -162.893954)
					(end 419.462966 -163.039044)
				)
				(xy 419.465252 -163.04133)
				(arc
					(start 419.465252 -163.065968)
					(mid 419.389174 -163.588136)
					(end 419.312598 -163.065968)
				)
				(arc
					(start 419.312598 -163.065968)
					(mid 419.28091 -162.999332)
					(end 419.212268 -162.972242)
				)
				(xy 419.008052 -162.972242)
				(arc
					(start 419.008052 -163.321492)
					(mid 419.389052 -163.702492)
					(end 419.770052 -163.321492)
				)
			)
		)
	)
	(zone
		(layer "B.Cu")
		(hatch none 0.5)
		(connect_pads
			(clearance 0)
		)
		(min_thickness 0.25)
		(keepout
			(tracks allowed)
			(vias allowed)
			(pads allowed)
			(copperpour allowed)
			(footprints not_allowed)
		)
		(placement
			(enabled no)
			(sheetname "")
		)
		(fill
			(thermal_gap 0.5)
			(thermal_bridge_width 0.5)
			(island_removal_mode 0)
		)
		(polygon
			(pts
				(arc
					(start 400.675094 -207.79994)
					(mid 393.675108 -200.799954)
					(end 386.675122 -207.79994)
				)
				(arc
					(start 386.675122 -213.799928)
					(mid 393.675108 -220.799914)
					(end 400.675094 -213.799928)
				)
			)
		)
	)
	(zone
		(net "GND")
		(layer "B.Cu")
		(hatch none 0.5)
		(connect_pads
			(clearance 0.5)
		)
		(min_thickness 0.25)
		(fill yes
			(thermal_gap 0.5)
			(thermal_bridge_width 0.5)
			(island_removal_mode 0)
		)
		(polygon
			(pts
				(arc
					(start 382.651 -241.904266)
					(mid 385.952084 -245.914253)
					(end 382.65735 -249.92965)
				)
				(arc
					(start 381 -251.587)
					(mid 380.813525 -253.349326)
					(end 379.899164 -254.86741)
				)
				(arc
					(start 379.899164 -254.86741)
					(mid 379.447123 -255.536306)
					(end 378.872496 -256.103374)
				)
				(arc
					(start 378.872496 -256.103374)
					(mid 379.474462 -257.570315)
					(end 379.473206 -259.155946)
				)
				(arc
					(start 379.473206 -259.155946)
					(mid 377.300922 -265.714947)
					(end 372.296436 -260.951218)
				)
				(arc
					(start 372.296436 -260.951218)
					(mid 371.605906 -259.726141)
					(end 371.371114 -258.33959)
				)
				(arc
					(start 371.371114 -258.33959)
					(mid 364.716958 -254.557413)
					(end 372.2116 -253.003812)
				)
				(arc
					(start 372.2116 -253.003812)
					(mid 372.449444 -251.545826)
					(end 373.189754 -250.26747)
				)
				(arc
					(start 373.189754 -250.26747)
					(mid 372.989774 -250.214075)
					(end 372.792752 -250.15063)
				)
				(arc
					(start 372.792752 -250.15063)
					(mid 372.102721 -250.269003)
					(end 371.40261 -250.267978)
				)
				(arc
					(start 371.40261 -250.267978)
					(mid 368.610558 -249.847978)
					(end 366.755934 -247.719088)
				)
				(arc
					(start 355.81971 -254.95758)
					(mid 353.996672 -258.087884)
					(end 350.402906 -258.54279)
				)
				(arc
					(start 350.125792 -258.726178)
					(mid 350.773075 -262.33283)
					(end 348.271846 -265.010646)
				)
				(arc
					(start 348.271846 -265.010646)
					(mid 348.816461 -265.876517)
					(end 349.254064 -266.801092)
				)
				(arc
					(start 353.44862 -266.801092)
					(mid 354.109496 -265.972209)
					(end 354.953824 -265.331194)
				)
				(arc
					(start 354.953824 -265.331194)
					(mid 359.158622 -261.948585)
					(end 363.057694 -265.679428)
				)
				(arc
					(start 363.22635 -265.679428)
					(mid 364.315746 -265.828274)
					(end 365.325406 -266.263628)
				)
				(arc
					(start 365.325406 -266.263628)
					(mid 368.102515 -265.806028)
					(end 370.517674 -267.25118)
				)
				(arc
					(start 384.758692 -267.25118)
					(mid 385.48225 -266.15584)
					(end 386.503672 -265.331194)
				)
				(arc
					(start 386.503672 -265.331194)
					(mid 390.794901 -261.953216)
					(end 394.618972 -265.852148)
				)
				(arc
					(start 394.949426 -265.852148)
					(mid 395.868177 -265.957466)
					(end 396.739364 -266.267692)
				)
				(arc
					(start 396.739364 -266.267692)
					(mid 399.622431 -265.724382)
					(end 402.12772 -267.25118)
				)
				(arc
					(start 416.308794 -267.25118)
					(mid 417.032352 -266.15584)
					(end 418.053774 -265.331194)
				)
				(arc
					(start 418.053774 -265.331194)
					(mid 419.897257 -262.577792)
					(end 423.175176 -262.093456)
				)
				(arc
					(start 423.175176 -262.093456)
					(mid 422.771394 -261.073019)
					(end 422.65346 -259.981954)
				)
				(arc
					(start 422.65346 -259.981954)
					(mid 420.522044 -255.595135)
					(end 424.105578 -252.28677)
				)
				(arc
					(start 424.105578 -248.221246)
					(mid 421.568312 -245.765898)
					(end 421.888412 -242.249706)
				)
				(arc
					(start 421.888412 -242.249706)
					(mid 422.479467 -240.348919)
					(end 423.897806 -238.952278)
				)
				(arc
					(start 423.897806 -238.952278)
					(mid 425.492454 -238.009393)
					(end 427.339506 -237.866682)
				)
				(arc
					(start 427.339506 -237.866682)
					(mid 425.872318 -233.430554)
					(end 429.522128 -230.513128)
				)
				(arc
					(start 429.522128 -230.513128)
					(mid 429.217378 -230.03109)
					(end 428.982632 -229.511352)
				)
				(arc
					(start 417.874704 -231.723946)
					(mid 419.658304 -234.361435)
					(end 419.010338 -237.478824)
				)
				(arc
					(start 419.010338 -237.478824)
					(mid 417.476044 -241.024861)
					(end 413.673798 -241.711226)
				)
				(arc
					(start 413.673798 -241.711226)
					(mid 414.201099 -242.634617)
					(end 414.472628 -243.662708)
				)
				(arc
					(start 414.472628 -243.662708)
					(mid 417.592258 -249.202509)
					(end 411.52445 -251.101098)
				)
				(arc
					(start 411.52445 -251.101098)
					(mid 409.561549 -251.203834)
					(end 407.777442 -250.378976)
				)
				(arc
					(start 407.777442 -250.378976)
					(mid 406.888111 -250.461862)
					(end 406.001982 -250.349766)
				)
				(arc
					(start 406.001982 -250.349766)
					(mid 405.161156 -250.326546)
					(end 404.342854 -250.131834)
				)
				(arc
					(start 404.342854 -250.131834)
					(mid 403.876285 -250.225142)
					(end 403.402038 -250.26366)
				)
				(arc
					(start 403.402038 -250.26366)
					(mid 402.701832 -251.100893)
					(end 401.80514 -251.723144)
				)
				(arc
					(start 401.80514 -251.723144)
					(mid 404.21106 -252.80798)
					(end 405.453596 -255.136396)
				)
				(arc
					(start 405.453596 -255.136396)
					(mid 409.021093 -255.357663)
					(end 411.052518 -258.298696)
				)
				(arc
					(start 411.052518 -258.298696)
					(mid 414.738371 -264.856484)
					(end 407.452068 -262.984996)
				)
				(arc
					(start 407.452068 -262.984996)
					(mid 404.53317 -262.174066)
					(end 402.972778 -259.577332)
				)
				(arc
					(start 402.972778 -259.577332)
					(mid 397.702021 -257.505583)
					(end 399.553938 -252.15342)
				)
				(arc
					(start 399.553938 -252.15342)
					(mid 395.88354 -248.587121)
					(end 398.567402 -244.229636)
				)
				(arc
					(start 398.567402 -244.229636)
					(mid 400.22264 -242.623626)
					(end 402.483574 -242.168426)
				)
				(arc
					(start 402.483574 -242.168426)
					(mid 403.581585 -242.093483)
					(end 404.659846 -242.313968)
				)
				(arc
					(start 404.659846 -242.313968)
					(mid 405.114719 -242.222372)
					(end 405.57704 -242.182904)
				)
				(arc
					(start 405.57704 -242.182904)
					(mid 407.077574 -240.654144)
					(end 409.144978 -240.093246)
				)
				(arc
					(start 410.414978 -240.093246)
					(mid 411.05322 -240.143337)
					(end 411.675834 -240.292382)
				)
				(arc
					(start 411.675834 -240.292382)
					(mid 410.941083 -238.705274)
					(end 410.93644 -236.956346)
				)
				(arc
					(start 410.93644 -236.956346)
					(mid 409.849989 -236.785572)
					(end 408.848306 -236.331506)
				)
				(arc
					(start 408.848306 -236.331506)
					(mid 407.036638 -236.083684)
					(end 405.514048 -235.071158)
				)
				(arc
					(start 405.514048 -235.071158)
					(mid 403.224926 -235.788889)
					(end 400.927062 -235.099606)
				)
				(arc
					(start 390.178544 -237.240572)
					(mid 388.055781 -239.445209)
					(end 384.997452 -239.559592)
				)
				(arc
					(start 384.997452 -239.559592)
					(mid 383.890586 -240.16761)
					(end 382.651 -240.408968)
				)
			)
		)
	)
	(zone
		(layer "B.Cu")
		(hatch none 0.5)
		(connect_pads
			(clearance 0)
		)
		(min_thickness 0.25)
		(keepout
			(tracks not_allowed)
			(vias allowed)
			(pads allowed)
			(copperpour not_allowed)
			(footprints allowed)
		)
		(placement
			(enabled no)
			(sheetname "")
		)
		(fill
			(thermal_gap 0.5)
			(thermal_bridge_width 0.5)
			(island_removal_mode 0)
		)
		(polygon
			(pts
				(arc
					(start 284.299914 -414.219898)
					(mid 280.550112 -410.470096)
					(end 276.800056 -414.219898)
				)
				(arc
					(start 276.800056 -414.219898)
					(mid 280.550112 -417.969954)
					(end 284.299914 -414.219898)
				)
			)
		)
	)
	(zone
		(net "GND")
		(layer "B.Cu")
		(hatch none 0.5)
		(connect_pads
			(clearance 0.5)
		)
		(min_thickness 0.25)
		(fill yes
			(thermal_gap 0.5)
			(thermal_bridge_width 0.5)
			(island_removal_mode 0)
		)
		(polygon
			(pts
				(xy 34.483802 -142.42415) (xy 34.229802 -142.67815) (xy 34.229802 -144.45615) (xy 36.769802 -146.99615)
				(xy 39.817802 -146.99615) (xy 39.944802 -146.86915) (xy 39.944802 -145.47215) (xy 40.452802 -144.963896)
				(xy 40.452802 -143.82115) (xy 40.960802 -143.31315) (xy 40.960802 -142.67815) (xy 40.833802 -142.55115)
				(xy 40.071802 -142.55115) (xy 39.944802 -142.42415)
			)
		)
		(polygon
			(pts
				(xy 39.673022 -144.90573) (xy 39.469822 -144.90573) (xy 39.469822 -145.10893) (xy 39.673022 -145.10893)
			)
		)
		(polygon
			(pts
				(xy 39.673022 -144.04213) (xy 39.469822 -144.04213) (xy 39.469822 -144.24533) (xy 39.673022 -144.24533)
			)
		)
		(polygon
			(pts
				(xy 40.386 -143.1036) (xy 40.1828 -143.1036) (xy 40.1828 -143.3068) (xy 40.386 -143.3068)
			)
		)
	)
	(zone
		(net "GND")
		(layer "B.Cu")
		(hatch none 0.5)
		(connect_pads
			(clearance 0.5)
		)
		(min_thickness 0.25)
		(fill yes
			(thermal_gap 0.5)
			(thermal_bridge_width 0.5)
			(island_removal_mode 0)
		)
		(polygon
			(pts
				(xy 312.368946 -139.2428) (xy 313.4868 -137.616438)
				(arc
					(start 313.4868 -137.012934)
					(mid 311.796946 -135.917701)
					(end 310.834532 -134.14883)
				)
				(arc
					(start 310.834532 -134.14883)
					(mid 310.575288 -129.039191)
					(end 315.5061 -127.673862)
				)
				(arc
					(start 315.5061 -127.673862)
					(mid 316.544151 -127.267316)
					(end 317.653416 -127.15621)
				)
				(arc
					(start 317.653416 -127.15621)
					(mid 319.479302 -125.376316)
					(end 322.00469 -125.02388)
				)
				(xy 323.012562 -123.5583) (xy 323.171058 -123.52909) (xy 328.837544 -115.286282) (xy 328.805286 -115.1128)
				(xy 330.207874 -113.07318) (xy 330.207874 -113.072672) (xy 330.867766 -112.112806) (xy 331.613002 -111.028226)
				(xy 331.613764 -111.027972) (xy 332.317852 -110.004352) (xy 332.490572 -109.972348)
				(arc
					(start 332.893924 -109.385608)
					(mid 323.852684 -107.194045)
					(end 319.853818 -98.794316)
				)
				(arc
					(start 319.853818 -92.799916)
					(mid 319.95453 -91.327499)
					(end 320.25463 -89.882472)
				)
				(xy 317.08598 -92.105226) (xy 291.439854 -97.790254) (xy 291.439854 -105.057956) (xy 289.594798 -106.903012)
				(arc
					(start 289.594798 -108.49991)
					(mid 289.471119 -109.529208)
					(end 289.107118 -110.499906)
				)
				(arc
					(start 289.107118 -110.499906)
					(mid 289.471113 -111.470605)
					(end 289.594798 -112.499902)
				)
				(xy 289.594798 -130.539998) (xy 290.2712 -131.2164)
				(arc
					(start 291.938964 -131.2164)
					(mid 303.92176 -128.044752)
					(end 311.021222 -138.205718)
				)
				(xy 311.021222 -138.961622) (xy 311.3024 -139.2428)
			)
		)
		(polygon
			(pts
				(arc
					(start 311.41543 -105.407968)
					(mid 311.41543 -113.591848)
					(end 311.41543 -105.407968)
				)
			)
		)
	)
	(zone
		(layer "B.Cu")
		(hatch none 0.5)
		(connect_pads
			(clearance 0)
		)
		(min_thickness 0.25)
		(keepout
			(tracks not_allowed)
			(vias allowed)
			(pads allowed)
			(copperpour not_allowed)
			(footprints allowed)
		)
		(placement
			(enabled no)
			(sheetname "")
		)
		(fill
			(thermal_gap 0.5)
			(thermal_bridge_width 0.5)
			(island_removal_mode 0)
		)
		(polygon
			(pts
				(arc
					(start 271.970754 -333.921354)
					(mid 271.58696 -334.304767)
					(end 271.9705 -334.688434)
				)
				(arc
					(start 273.1135 -334.688434)
					(mid 273.49704 -334.304894)
					(end 273.1135 -333.921354)
				)
				(arc
					(start 272.768568 -333.921354)
					(mid 272.765366 -333.948194)
					(end 272.76425 -333.975202)
				)
				(arc
					(start 272.76425 -334.123792)
					(mid 272.791127 -334.19391)
					(end 272.857976 -334.228186)
				)
				(arc
					(start 272.857976 -334.228186)
					(mid 273.380217 -334.30464)
					(end 272.857976 -334.381094)
				)
				(xy 272.837656 -334.381094)
				(arc
					(start 272.83537 -334.378808)
					(mid 272.687253 -334.305691)
					(end 272.614136 -334.157574)
				)
				(xy 272.61185 -334.155288) (xy 272.61185 -333.943706) (xy 272.612866 -333.94269) (xy 272.614644 -333.921354)
				(arc
					(start 272.474436 -333.921354)
					(mid 272.472724 -333.948254)
					(end 272.47215 -333.975202)
				)
				(xy 272.47215 -334.155288)
				(arc
					(start 272.469864 -334.157574)
					(mid 272.396747 -334.305691)
					(end 272.24863 -334.378808)
				)
				(xy 272.246344 -334.381094)
				(arc
					(start 272.226024 -334.381094)
					(mid 271.703783 -334.30464)
					(end 272.226024 -334.228186)
				)
				(arc
					(start 272.226024 -334.228186)
					(mid 272.292939 -334.193969)
					(end 272.31975 -334.123792)
				)
				(xy 272.31975 -333.943706) (xy 272.320512 -333.942944) (xy 272.321528 -333.921354)
			)
		)
	)
	(zone
		(layer "B.Cu")
		(hatch none 0.5)
		(connect_pads
			(clearance 0)
		)
		(min_thickness 0.25)
		(keepout
			(tracks not_allowed)
			(vias allowed)
			(pads allowed)
			(copperpour not_allowed)
			(footprints allowed)
		)
		(placement
			(enabled no)
			(sheetname "")
		)
		(fill
			(thermal_gap 0.5)
			(thermal_bridge_width 0.5)
			(island_removal_mode 0)
		)
		(polygon
			(pts
				(arc
					(start 419.770052 -277.17877)
					(mid 419.389179 -276.797516)
					(end 419.008052 -277.178516)
				)
				(xy 419.008052 -277.527766)
				(arc
					(start 419.212268 -277.527766)
					(mid 419.280924 -277.500691)
					(end 419.312598 -277.43404)
				)
				(arc
					(start 419.312598 -277.43404)
					(mid 419.389174 -276.911799)
					(end 419.465252 -277.43404)
				)
				(xy 419.465252 -277.458678)
				(arc
					(start 419.462966 -277.460964)
					(mid 419.39114 -277.606054)
					(end 419.24605 -277.67788)
				)
				(xy 419.243764 -277.680166) (xy 419.008052 -277.680166) (xy 419.008052 -277.819866) (xy 419.243764 -277.819866)
				(arc
					(start 419.24605 -277.822152)
					(mid 419.39114 -277.893978)
					(end 419.462966 -278.039068)
				)
				(xy 419.465252 -278.041354)
				(arc
					(start 419.465252 -278.065992)
					(mid 419.389174 -278.58816)
					(end 419.312598 -278.065992)
				)
				(arc
					(start 419.312598 -278.065992)
					(mid 419.28091 -277.999356)
					(end 419.212268 -277.972266)
				)
				(xy 419.008052 -277.972266)
				(arc
					(start 419.008052 -278.321516)
					(mid 419.389052 -278.702516)
					(end 419.770052 -278.321516)
				)
			)
		)
	)
	(zone
		(layer "B.Cu")
		(hatch none 0.5)
		(connect_pads
			(clearance 0)
		)
		(min_thickness 0.25)
		(keepout
			(tracks not_allowed)
			(vias allowed)
			(pads allowed)
			(copperpour not_allowed)
			(footprints allowed)
		)
		(placement
			(enabled no)
			(sheetname "")
		)
		(fill
			(thermal_gap 0.5)
			(thermal_bridge_width 0.5)
			(island_removal_mode 0)
		)
		(polygon
			(pts
				(arc
					(start 307.200046 -243.19992)
					(mid 300.20006 -236.199934)
					(end 293.200074 -243.19992)
				)
				(arc
					(start 293.200074 -249.199908)
					(mid 300.20006 -256.199894)
					(end 307.200046 -249.199908)
				)
			)
		)
	)
	(zone
		(layer "B.Cu")
		(hatch none 0.5)
		(connect_pads
			(clearance 0)
		)
		(min_thickness 0.25)
		(keepout
			(tracks not_allowed)
			(vias allowed)
			(pads allowed)
			(copperpour not_allowed)
			(footprints allowed)
		)
		(placement
			(enabled no)
			(sheetname "")
		)
		(fill
			(thermal_gap 0.5)
			(thermal_bridge_width 0.5)
			(island_removal_mode 0)
		)
		(polygon
			(pts
				(arc
					(start 281.074876 -41.849802)
					(mid 281.399742 -40.875204)
					(end 280.425144 -40.550338)
				)
				(xy 280.423874 -40.548052)
				(arc
					(start 279.406858 -41.05656)
					(mid 279.435725 -41.070197)
					(end 279.464008 -41.085008)
				)
				(arc
					(start 279.464262 -41.085008)
					(mid 279.540831 -41.133066)
					(end 279.611328 -41.189656)
				)
				(xy 279.612598 -41.189656) (xy 279.640284 -41.217342) (xy 279.640538 -41.217596) (xy 279.775158 -41.352216)
				(arc
					(start 279.845516 -41.422574)
					(mid 279.884556 -41.45106)
					(end 279.930352 -41.466516)
				)
				(xy 279.933908 -41.467024)
				(arc
					(start 279.948894 -41.469564)
					(mid 279.998664 -41.469405)
					(end 280.045922 -41.453816)
				)
				(arc
					(start 280.22804 -41.360598)
					(mid 280.203915 -41.20894)
					(end 280.22296 -41.05656)
				)
				(arc
					(start 280.22296 -41.05656)
					(mid 281.286157 -41.095653)
					(end 280.314908 -41.530016)
				)
				(xy 280.13279 -41.623488) (xy 280.097738 -41.641522)
				(arc
					(start 280.094182 -41.640252)
					(mid 280.028424 -41.657466)
					(end 279.960578 -41.661588)
				)
				(xy 279.95753 -41.663874) (xy 279.918414 -41.657524) (xy 279.903428 -41.654984) (xy 279.898856 -41.654222)
				(xy 279.864058 -41.648634)
				(arc
					(start 279.86228 -41.646094)
					(mid 279.799382 -41.621426)
					(end 279.742392 -41.585134)
				)
				(xy 279.738836 -41.585134) (xy 279.505918 -41.352216)
				(arc
					(start 279.505664 -41.351962)
					(mid 279.442649 -41.29734)
					(end 279.372568 -41.25214)
				)
				(arc
					(start 279.372568 -41.25214)
					(mid 279.266851 -41.206937)
					(end 279.154382 -41.183052)
				)
				(xy 278.958548 -41.280842) (xy 279.127712 -41.280842)
				(arc
					(start 279.12949 -41.28262)
					(mid 279.229597 -41.30178)
					(end 279.323546 -41.341294)
				)
				(arc
					(start 279.323546 -41.341294)
					(mid 279.364913 -41.366874)
					(end 279.403556 -41.396412)
				)
				(xy 279.405842 -41.396412) (xy 279.433528 -41.423844) (xy 279.433782 -41.424352) (xy 279.562814 -41.553384)
				(arc
					(start 279.562814 -41.55821)
					(mid 279.605174 -41.651577)
					(end 279.608788 -41.754044)
				)
				(arc
					(start 279.608788 -41.754298)
					(mid 279.572867 -41.850336)
					(end 279.503124 -41.925494)
				)
				(xy 279.5016 -41.93032)
				(arc
					(start 279.273508 -42.044366)
					(mid 278.262231 -42.445113)
					(end 279.188164 -41.874186)
				)
				(arc
					(start 279.38095 -41.777666)
					(mid 279.407376 -41.755394)
					(end 279.420828 -41.723564)
				)
				(arc
					(start 279.420828 -41.723564)
					(mid 279.418215 -41.689313)
					(end 279.400254 -41.660064)
				)
				(arc
					(start 279.298654 -41.558718)
					(mid 279.266896 -41.531213)
					(end 279.231598 -41.508426)
				)
				(arc
					(start 279.231598 -41.508426)
					(mid 279.162303 -41.48088)
					(end 279.088342 -41.471342)
				)
				(xy 278.577548 -41.471342) (xy 278.424132 -41.54805) (xy 278.424132 -41.548304)
				(arc
					(start 278.425148 -41.550336)
					(mid 278.100282 -42.524934)
					(end 279.07488 -42.8498)
				)
				(xy 279.07615 -42.852086) (xy 281.076146 -41.852088)
			)
		)
	)
	(zone
		(layer "B.Cu")
		(hatch none 0.5)
		(connect_pads
			(clearance 0)
		)
		(min_thickness 0.25)
		(keepout
			(tracks not_allowed)
			(vias allowed)
			(pads allowed)
			(copperpour not_allowed)
			(footprints allowed)
		)
		(placement
			(enabled no)
			(sheetname "")
		)
		(fill
			(thermal_gap 0.5)
			(thermal_bridge_width 0.5)
			(island_removal_mode 0)
		)
		(polygon
			(pts
				(arc
					(start 368.400076 -28.079954)
					(mid 372.150132 -24.329898)
					(end 375.899934 -28.079954)
				)
				(arc
					(start 375.899934 -28.079954)
					(mid 372.150132 -31.829756)
					(end 368.400076 -28.079954)
				)
			)
		)
	)
	(zone
		(layer "B.Cu")
		(hatch none 0.5)
		(connect_pads
			(clearance 0)
		)
		(min_thickness 0.25)
		(keepout
			(tracks allowed)
			(vias allowed)
			(pads allowed)
			(copperpour allowed)
			(footprints not_allowed)
		)
		(placement
			(enabled no)
			(sheetname "")
		)
		(fill
			(thermal_gap 0.5)
			(thermal_bridge_width 0.5)
			(island_removal_mode 0)
		)
		(polygon
			(pts
				(arc
					(start 472.250008 -269.999968)
					(mid 467.499954 -265.249914)
					(end 462.7499 -269.999968)
				)
				(arc
					(start 462.7499 -269.999968)
					(mid 467.499954 -274.750022)
					(end 472.250008 -269.999968)
				)
			)
		)
	)
	(zone
		(layer "B.Cu")
		(hatch none 0.5)
		(connect_pads
			(clearance 0)
		)
		(min_thickness 0.25)
		(keepout
			(tracks allowed)
			(vias allowed)
			(pads allowed)
			(copperpour allowed)
			(footprints not_allowed)
		)
		(placement
			(enabled no)
			(sheetname "")
		)
		(fill
			(thermal_gap 0.5)
			(thermal_bridge_width 0.5)
			(island_removal_mode 0)
		)
		(polygon
			(pts
				(arc
					(start 38.999922 -164.200078)
					(mid 42.749978 -167.950134)
					(end 46.500034 -164.200078)
				)
				(arc
					(start 46.500034 -164.200078)
					(mid 42.749978 -160.450022)
					(end 38.999922 -164.200078)
				)
			)
		)
	)
	(zone
		(layer "B.Cu")
		(hatch none 0.5)
		(connect_pads
			(clearance 0)
		)
		(min_thickness 0.25)
		(keepout
			(tracks allowed)
			(vias allowed)
			(pads allowed)
			(copperpour allowed)
			(footprints not_allowed)
		)
		(placement
			(enabled no)
			(sheetname "")
		)
		(fill
			(thermal_gap 0.5)
			(thermal_bridge_width 0.5)
			(island_removal_mode 0)
		)
		(polygon
			(pts
				(arc
					(start 318.92494 -9.19988)
					(mid 323.674994 -13.949934)
					(end 328.425048 -9.19988)
				)
				(arc
					(start 328.425048 -9.19988)
					(mid 323.674994 -4.449826)
					(end 318.92494 -9.19988)
				)
			)
		)
	)
	(zone
		(net "GND")
		(layer "B.Cu")
		(hatch none 0.5)
		(connect_pads
			(clearance 0.5)
		)
		(min_thickness 0.25)
		(fill yes
			(thermal_gap 0.5)
			(thermal_bridge_width 0.5)
			(island_removal_mode 0)
		)
		(polygon
			(pts
				(arc
					(start 447.068702 -261.921244)
					(mid 448.221955 -263.443143)
					(end 449.940426 -264.27557)
				)
				(arc
					(start 449.940426 -264.27557)
					(mid 449.736102 -264.791922)
					(end 449.603622 -265.331194)
				)
				(arc
					(start 449.603622 -265.331194)
					(mid 448.582131 -266.155778)
					(end 447.858642 -267.25118)
				)
				(arc
					(start 433.319174 -267.25118)
					(mid 432.679759 -266.733245)
					(end 431.949606 -266.353798)
				)
				(arc
					(start 431.949606 -266.353798)
					(mid 433.517288 -264.425612)
					(end 433.679346 -261.945882)
				)
				(arc
					(start 433.679346 -261.945882)
					(mid 433.782944 -261.949873)
					(end 433.88661 -261.951216)
				)
				(arc
					(start 436.15356 -261.951216)
					(mid 436.798974 -262.002137)
					(end 437.444388 -261.951216)
				)
				(arc
					(start 439.587894 -261.951216)
					(mid 440.882665 -261.739401)
					(end 442.04255 -261.126224)
				)
				(xy 442.615828 -261.126224) (xy 443.242446 -261.752842)
				(arc
					(start 445.388746 -261.752842)
					(mid 445.964865 -261.798352)
					(end 446.541652 -261.76224)
				)
				(arc
					(start 446.541652 -261.76224)
					(mid 446.802498 -261.850624)
					(end 447.068702 -261.921244)
				)
			)
		)
	)
	(zone
		(layer "B.Cu")
		(hatch none 0.5)
		(connect_pads
			(clearance 0)
		)
		(min_thickness 0.25)
		(keepout
			(tracks allowed)
			(vias allowed)
			(pads allowed)
			(copperpour allowed)
			(footprints allowed)
		)
		(placement
			(enabled no)
			(sheetname "")
		)
		(fill
			(thermal_gap 0.5)
			(thermal_bridge_width 0.5)
			(island_removal_mode 0)
		)
		(polygon
			(pts
				(xy 474.79331 -231.485694) (xy 477.71431 -231.485694) (xy 477.71431 -228.234494) (xy 474.79331 -228.234494)
			)
		)
	)
	(zone
		(layer "B.Cu")
		(hatch none 0.5)
		(connect_pads
			(clearance 0)
		)
		(min_thickness 0.25)
		(keepout
			(tracks not_allowed)
			(vias allowed)
			(pads allowed)
			(copperpour not_allowed)
			(footprints allowed)
		)
		(placement
			(enabled no)
			(sheetname "")
		)
		(fill
			(thermal_gap 0.5)
			(thermal_bridge_width 0.5)
			(island_removal_mode 0)
		)
		(polygon
			(pts
				(arc
					(start 438.6199 -162.178746)
					(mid 438.239027 -161.797492)
					(end 437.8579 -162.178492)
				)
				(xy 437.8579 -162.527742)
				(arc
					(start 438.062116 -162.527742)
					(mid 438.130772 -162.500667)
					(end 438.162446 -162.434016)
				)
				(arc
					(start 438.162446 -162.434016)
					(mid 438.239022 -161.911775)
					(end 438.3151 -162.434016)
				)
				(xy 438.3151 -162.458654)
				(arc
					(start 438.312814 -162.46094)
					(mid 438.240988 -162.60603)
					(end 438.095898 -162.677856)
				)
				(xy 438.093612 -162.680142) (xy 437.8579 -162.680142) (xy 437.8579 -162.819842) (xy 438.093612 -162.819842)
				(arc
					(start 438.095898 -162.822128)
					(mid 438.240988 -162.893954)
					(end 438.312814 -163.039044)
				)
				(xy 438.3151 -163.04133)
				(arc
					(start 438.3151 -163.065968)
					(mid 438.239022 -163.588136)
					(end 438.162446 -163.065968)
				)
				(arc
					(start 438.162446 -163.065968)
					(mid 438.130758 -162.999332)
					(end 438.062116 -162.972242)
				)
				(xy 437.8579 -162.972242)
				(arc
					(start 437.8579 -163.321492)
					(mid 438.2389 -163.702492)
					(end 438.6199 -163.321492)
				)
			)
		)
	)
	(zone
		(net "P12V_B")
		(layer "B.Cu")
		(hatch none 0.5)
		(connect_pads
			(clearance 0.5)
		)
		(min_thickness 0.25)
		(fill yes
			(thermal_gap 0.5)
			(thermal_bridge_width 0.5)
			(island_removal_mode 0)
		)
		(polygon
			(pts
				(xy 246.343678 -414.01873) (xy 246.065802 -414.296606) (xy 246.065802 -418.987732) (xy 246.650002 -419.571932)
				(xy 251.349002 -419.571932) (xy 252.060202 -418.860732) (xy 252.060202 -414.358836) (xy 251.720096 -414.01873)
			)
		)
	)
	(zone
		(layer "B.Cu")
		(hatch none 0.5)
		(connect_pads
			(clearance 0)
		)
		(min_thickness 0.25)
		(keepout
			(tracks allowed)
			(vias allowed)
			(pads allowed)
			(copperpour allowed)
			(footprints not_allowed)
		)
		(placement
			(enabled no)
			(sheetname "")
		)
		(fill
			(thermal_gap 0.5)
			(thermal_bridge_width 0.5)
			(island_removal_mode 0)
		)
		(polygon
			(pts
				(arc
					(start 400.675094 -92.799916)
					(mid 393.675108 -85.79993)
					(end 386.675122 -92.799916)
				)
				(arc
					(start 386.675122 -98.799904)
					(mid 393.675108 -105.79989)
					(end 400.675094 -98.799904)
				)
			)
		)
	)
	(zone
		(layer "B.Cu")
		(hatch none 0.5)
		(connect_pads
			(clearance 0)
		)
		(min_thickness 0.25)
		(keepout
			(tracks not_allowed)
			(vias allowed)
			(pads allowed)
			(copperpour not_allowed)
			(footprints allowed)
		)
		(placement
			(enabled no)
			(sheetname "")
		)
		(fill
			(thermal_gap 0.5)
			(thermal_bridge_width 0.5)
			(island_removal_mode 0)
		)
		(polygon
			(pts
				(arc
					(start 285.436564 -322.956428)
					(mid 284.887924 -323.505068)
					(end 285.436564 -324.053708)
				)
				(arc
					(start 285.935928 -324.053708)
					(mid 285.921943 -323.984774)
					(end 285.9151 -323.91477)
				)
				(xy 285.914338 -323.914008)
				(arc
					(start 285.914338 -323.632068)
					(mid 285.899459 -323.596147)
					(end 285.863538 -323.581268)
				)
				(arc
					(start 285.822898 -323.581268)
					(mid 285.042787 -323.505068)
					(end 285.822898 -323.428868)
				)
				(xy 285.895034 -323.428868)
				(arc
					(start 285.898082 -323.431916)
					(mid 286.007159 -323.488447)
					(end 286.06369 -323.597524)
				)
				(xy 286.066738 -323.600572)
				(arc
					(start 286.066738 -323.882766)
					(mid 286.073833 -323.969392)
					(end 286.094932 -324.053708)
				)
				(arc
					(start 286.245808 -324.053708)
					(mid 286.220397 -323.986374)
					(end 286.207708 -323.915532)
				)
				(xy 286.206438 -323.914008) (xy 286.206438 -323.600572)
				(arc
					(start 286.209486 -323.597524)
					(mid 286.266017 -323.488447)
					(end 286.375094 -323.431916)
				)
				(xy 286.378142 -323.428868)
				(arc
					(start 286.450278 -323.428868)
					(mid 287.230389 -323.505068)
					(end 286.450278 -323.581268)
				)
				(arc
					(start 286.409638 -323.581268)
					(mid 286.373717 -323.596147)
					(end 286.358838 -323.632068)
				)
				(arc
					(start 286.358838 -323.882512)
					(mid 286.377129 -323.974465)
					(end 286.429196 -324.052438)
				)
				(xy 286.430466 -324.053708)
				(arc
					(start 286.836612 -324.053708)
					(mid 287.385252 -323.505068)
					(end 286.836612 -322.956428)
				)
				(xy 285.436818 -322.956428)
			)
		)
	)
	(zone
		(layer "B.Cu")
		(hatch none 0.5)
		(connect_pads
			(clearance 0)
		)
		(min_thickness 0.25)
		(keepout
			(tracks allowed)
			(vias allowed)
			(pads allowed)
			(copperpour allowed)
			(footprints allowed)
		)
		(placement
			(enabled no)
			(sheetname "")
		)
		(fill
			(thermal_gap 0.5)
			(thermal_bridge_width 0.5)
			(island_removal_mode 0)
		)
		(polygon
			(pts
				(xy 474.828108 -234.443016) (xy 478.130108 -234.443016) (xy 478.130108 -237.059216) (xy 474.828108 -237.059216)
			)
		)
	)
	(zone
		(net "GND")
		(layer "B.Cu")
		(hatch none 0.5)
		(connect_pads
			(clearance 0.5)
		)
		(min_thickness 0.25)
		(fill yes
			(thermal_gap 0.5)
			(thermal_bridge_width 0.5)
			(island_removal_mode 0)
		)
		(polygon
			(pts
				(arc
					(start 36.521644 -279.991312)
					(mid 38.179883 -280.133692)
					(end 39.757604 -279.603708)
				)
				(arc
					(start 40.035226 -279.603708)
					(mid 38.781357 -283.140748)
					(end 40.224202 -286.604964)
				)
				(arc
					(start 40.224202 -286.604964)
					(mid 41.643746 -288.960388)
					(end 44.233846 -289.884866)
				)
				(arc
					(start 45.040042 -289.884866)
					(mid 45.071049 -290.309137)
					(end 45.14596 -290.727892)
				)
				(arc
					(start 45.14596 -290.727892)
					(mid 43.562892 -290.630129)
					(end 42.061638 -291.141912)
				)
				(arc
					(start 42.061638 -291.141912)
					(mid 41.29483 -289.985672)
					(end 40.185594 -289.15233)
				)
				(arc
					(start 40.185594 -289.15233)
					(mid 38.310551 -286.710219)
					(end 35.263582 -286.267652)
				)
				(arc
					(start 32.397446 -283.401516)
					(mid 35.099716 -282.47064)
					(end 36.521644 -279.991312)
				)
			)
		)
	)
	(zone
		(layer "B.Cu")
		(hatch none 0.5)
		(connect_pads
			(clearance 0)
		)
		(min_thickness 0.25)
		(keepout
			(tracks not_allowed)
			(vias allowed)
			(pads allowed)
			(copperpour not_allowed)
			(footprints allowed)
		)
		(placement
			(enabled no)
			(sheetname "")
		)
		(fill
			(thermal_gap 0.5)
			(thermal_bridge_width 0.5)
			(island_removal_mode 0)
		)
		(polygon
			(pts
				(arc
					(start 122.298714 -21.950426)
					(mid 121.750201 -21.401532)
					(end 121.201434 -21.950172)
				)
				(xy 121.201434 -22.408896)
				(arc
					(start 121.583704 -22.408896)
					(mid 121.633993 -22.388065)
					(end 121.654824 -22.337776)
				)
				(arc
					(start 121.654824 -22.332188)
					(mid 121.750074 -21.55646)
					(end 121.845324 -22.332188)
				)
				(xy 121.845324 -22.377146)
				(arc
					(start 121.841768 -22.380702)
					(mid 121.76869 -22.522762)
					(end 121.62663 -22.59584)
				)
				(xy 121.623074 -22.599396) (xy 121.233438 -22.599396) (xy 121.201434 -22.600666) (xy 121.201434 -22.700996)
				(xy 121.623074 -22.700996)
				(arc
					(start 121.62663 -22.704552)
					(mid 121.76869 -22.77763)
					(end 121.841768 -22.91969)
				)
				(xy 121.845324 -22.923246)
				(arc
					(start 121.845324 -22.968204)
					(mid 121.750074 -23.743932)
					(end 121.654824 -22.968204)
				)
				(arc
					(start 121.654824 -22.962616)
					(mid 121.633993 -22.912327)
					(end 121.583704 -22.891496)
				)
				(arc
					(start 121.233438 -22.891496)
					(mid 121.217333 -22.892354)
					(end 121.201434 -22.895052)
				)
				(arc
					(start 121.201434 -23.35022)
					(mid 121.750074 -23.89886)
					(end 122.298714 -23.35022)
				)
			)
		)
	)
	(zone
		(layer "B.Cu")
		(hatch none 0.5)
		(connect_pads
			(clearance 0)
		)
		(min_thickness 0.25)
		(keepout
			(tracks not_allowed)
			(vias allowed)
			(pads allowed)
			(copperpour not_allowed)
			(footprints allowed)
		)
		(placement
			(enabled no)
			(sheetname "")
		)
		(fill
			(thermal_gap 0.5)
			(thermal_bridge_width 0.5)
			(island_removal_mode 0)
		)
		(polygon
			(pts
				(arc
					(start 463.674968 -92.799916)
					(mid 456.674982 -85.79993)
					(end 449.674996 -92.799916)
				)
				(arc
					(start 449.674996 -98.799904)
					(mid 456.674982 -105.79989)
					(end 463.674968 -98.799904)
				)
			)
		)
	)
	(zone
		(net "GND")
		(layer "B.Cu")
		(hatch none 0.5)
		(connect_pads
			(clearance 0.5)
		)
		(min_thickness 0.25)
		(fill yes
			(thermal_gap 0.5)
			(thermal_bridge_width 0.5)
			(island_removal_mode 0)
		)
		(polygon
			(pts
				(xy 272.668746 1.603756)
				(arc
					(start 274.805648 3.740404)
					(mid 272.196295 4.203475)
					(end 270.410178 6.161278)
				)
				(arc
					(start 270.410178 6.161278)
					(mid 270.262872 6.178802)
					(end 270.1163 6.201664)
				)
				(arc
					(start 270.1163 6.201664)
					(mid 269.928969 6.181081)
					(end 269.740888 6.169152)
				)
				(arc
					(start 269.740888 6.169152)
					(mid 269.408293 4.645503)
					(end 268.529562 3.357118)
				)
				(arc
					(start 268.529562 3.357118)
					(mid 266.835529 1.82979)
					(end 264.586974 1.447292)
				)
				(arc
					(start 264.586974 1.447292)
					(mid 262.765499 -0.621168)
					(end 260.0452 -1.064514)
				)
				(arc
					(start 260.0452 -1.064514)
					(mid 257.574529 -0.714765)
					(end 255.766824 1.005332)
				)
				(arc
					(start 253.057152 1.005332)
					(mid 250.488403 -0.595464)
					(end 247.497854 -1.061974)
				)
				(xy 247.497854 -8.741156) (xy 246.894858 -9.344152)
				(arc
					(start 246.894858 -12.200128)
					(mid 246.771179 -13.229426)
					(end 246.407178 -14.200124)
				)
				(arc
					(start 246.407178 -14.200124)
					(mid 246.771173 -15.170823)
					(end 246.894858 -16.20012)
				)
				(xy 246.894858 -24.945594)
				(arc
					(start 249.249438 -26.41981)
					(mid 249.889118 -26.920347)
					(end 250.41098 -27.542744)
				)
				(arc
					(start 250.611132 -27.83967)
					(mid 252.756147 -27.883217)
					(end 254.5842 -29.006292)
				)
				(arc
					(start 254.5842 -29.006292)
					(mid 255.957999 -30.486443)
					(end 256.456434 -32.44342)
				)
				(arc
					(start 256.456434 -34.98342)
					(mid 255.814871 -37.182794)
					(end 254.09144 -38.692328)
				)
				(xy 258.27863 -60.227464) (xy 252.742446 -88.711278)
				(arc
					(start 252.720602 -88.74379)
					(mid 253.549435 -94.654129)
					(end 247.59793 -95.099886)
				)
				(arc
					(start 245.181628 -97.042732)
					(mid 246.443031 -98.570729)
					(end 246.894858 -100.499926)
				)
				(arc
					(start 246.894858 -108.49991)
					(mid 246.771179 -109.529208)
					(end 246.407178 -110.499906)
				)
				(arc
					(start 246.407178 -110.499906)
					(mid 246.771173 -111.470605)
					(end 246.894858 -112.499902)
				)
				(arc
					(start 246.894858 -135.99033)
					(mid 250.801871 -136.52928)
					(end 253.907544 -138.960352)
				)
				(arc
					(start 254.591566 -138.960352)
					(mid 256.769346 -134.852317)
					(end 261.382256 -135.43534)
				)
				(xy 269.367 -123.139708) (xy 269.367 -121.285)
				(arc
					(start 268.362938 -120.280938)
					(mid 267.526712 -119.47172)
					(end 266.952222 -118.459758)
				)
				(arc
					(start 266.952222 -118.459758)
					(mid 262.679367 -118.121355)
					(end 261.024624 -114.167412)
				)
				(arc
					(start 261.024624 -114.167412)
					(mid 260.987119 -113.917)
					(end 260.965188 -113.664746)
				)
				(arc
					(start 260.965188 -113.664746)
					(mid 260.476817 -112.869188)
					(end 260.180328 -111.984028)
				)
				(xy 259.556758 -111.984028) (xy 259.556758 -110.085378) (xy 258.766564 -109.295184) (xy 258.766564 -97.862898)
				(arc
					(start 260.652768 -95.976948)
					(mid 263.187472 -93.386317)
					(end 266.78509 -93.82633)
				)
				(arc
					(start 266.78509 -93.82633)
					(mid 267.395368 -94.084065)
					(end 267.95603 -94.436946)
				)
				(xy 269.773654 -94.436946) (xy 270.2052 -94.0054) (xy 270.2052 -92.590366) (xy 267.548614 -88.420194)
				(xy 262.94969 -67.557142) (xy 263.56056 -64.795908) (xy 263.561576 -64.795146) (xy 268.193266 -43.905678)
				(arc
					(start 273.393916 -35.740848)
					(mid 273.8485 -35.157947)
					(end 274.40509 -34.671508)
				)
				(arc
					(start 274.40509 -17.229582)
					(mid 270.895146 -16.22241)
					(end 269.588488 -12.812522)
				)
				(arc
					(start 269.588488 -12.812522)
					(mid 269.44522 -11.848424)
					(end 269.534132 -10.877804)
				)
				(arc
					(start 269.534132 -10.877804)
					(mid 269.535138 -10.71961)
					(end 269.54226 -10.561574)
				)
				(arc
					(start 269.54226 -10.561574)
					(mid 269.491911 -10.06508)
					(end 269.502382 -9.566148)
				)
				(arc
					(start 269.488412 -9.468104)
					(mid 263.906173 -4.901431)
					(end 270.802608 -2.79019)
				)
				(arc
					(start 270.802608 -2.79019)
					(mid 271.664844 -2.13513)
					(end 272.668746 -1.729232)
				)
			)
		)
		(polygon
			(pts
				(arc
					(start 259.1435 -86.633812)
					(mid 259.1435 -94.817692)
					(end 259.1435 -86.633812)
				)
			)
		)
		(polygon
			(pts
				(arc
					(start 269.169896 -25.206198)
					(mid 273.472833 -19.08547)
					(end 266.047982 -20.008088)
				)
				(arc
					(start 266.047982 -20.008088)
					(mid 264.934708 -19.701188)
					(end 263.780016 -19.717512)
				)
				(arc
					(start 263.780016 -19.717512)
					(mid 261.177182 -20.17199)
					(end 259.394706 -22.122384)
				)
				(arc
					(start 259.394706 -22.122384)
					(mid 258.571268 -23.66547)
					(end 258.467352 -25.41143)
				)
				(arc
					(start 258.467352 -25.41143)
					(mid 258.417821 -26.046051)
					(end 258.467352 -26.680668)
				)
				(arc
					(start 258.467352 -26.680668)
					(mid 258.417782 -27.315668)
					(end 258.467352 -27.950668)
				)
				(arc
					(start 258.467352 -27.950668)
					(mid 258.423118 -28.376751)
					(end 258.423664 -28.805124)
				)
				(arc
					(start 258.423664 -28.805124)
					(mid 257.855894 -30.09647)
					(end 257.76047 -31.503874)
				)
				(arc
					(start 257.76047 -31.503874)
					(mid 257.720828 -32.035173)
					(end 257.750564 -32.567118)
				)
				(arc
					(start 257.750564 -32.567118)
					(mid 257.724935 -33.037868)
					(end 257.753612 -33.508442)
				)
				(arc
					(start 257.753612 -33.508442)
					(mid 257.725159 -34.062528)
					(end 257.7719 -34.615374)
				)
				(arc
					(start 257.7719 -34.615374)
					(mid 261.966472 -39.08626)
					(end 265.890756 -34.37636)
				)
				(arc
					(start 265.890756 -34.37636)
					(mid 265.908229 -33.943382)
					(end 265.879834 -33.510982)
				)
				(arc
					(start 265.879834 -33.510982)
					(mid 265.908722 -33.05652)
					(end 265.886946 -32.601662)
				)
				(arc
					(start 265.886946 -32.601662)
					(mid 268.452616 -30.932899)
					(end 269.142972 -27.951176)
				)
				(arc
					(start 269.142972 -27.951176)
					(mid 269.192542 -27.316051)
					(end 269.142972 -26.680922)
				)
				(arc
					(start 269.142972 -26.680922)
					(mid 269.192503 -26.046051)
					(end 269.142972 -25.411176)
				)
				(arc
					(start 269.142972 -25.411176)
					(mid 269.157729 -25.308857)
					(end 269.169896 -25.206198)
				)
			)
		)
		(polygon
			(pts
				(arc
					(start 260.124194 -14.9352)
					(mid 256.7051 -8.595447)
					(end 253.286006 -14.9352)
				)
				(arc
					(start 253.286006 -14.9352)
					(mid 256.7051 -21.274953)
					(end 260.124194 -14.9352)
				)
			)
		)
	)
	(zone
		(layer "B.Cu")
		(hatch none 0.5)
		(connect_pads
			(clearance 0)
		)
		(min_thickness 0.25)
		(keepout
			(tracks not_allowed)
			(vias allowed)
			(pads allowed)
			(copperpour not_allowed)
			(footprints allowed)
		)
		(placement
			(enabled no)
			(sheetname "")
		)
		(fill
			(thermal_gap 0.5)
			(thermal_bridge_width 0.5)
			(island_removal_mode 0)
		)
		(polygon
			(pts
				(arc
					(start 136.698736 -21.950426)
					(mid 136.150223 -21.401532)
					(end 135.601456 -21.950172)
				)
				(arc
					(start 135.601456 -23.35022)
					(mid 136.150096 -23.89886)
					(end 136.698736 -23.35022)
				)
				(arc
					(start 136.698736 -22.895052)
					(mid 136.682835 -22.892373)
					(end 136.666732 -22.891496)
				)
				(arc
					(start 136.316466 -22.891496)
					(mid 136.266177 -22.912327)
					(end 136.245346 -22.962616)
				)
				(arc
					(start 136.245346 -22.968204)
					(mid 136.150096 -23.743932)
					(end 136.054846 -22.968204)
				)
				(xy 136.054846 -22.923246)
				(arc
					(start 136.058402 -22.91969)
					(mid 136.13148 -22.77763)
					(end 136.27354 -22.704552)
				)
				(xy 136.277096 -22.700996) (xy 136.698736 -22.700996) (xy 136.698736 -22.600666) (xy 136.666732 -22.599396)
				(xy 136.277096 -22.599396)
				(arc
					(start 136.27354 -22.59584)
					(mid 136.13148 -22.522762)
					(end 136.058402 -22.380702)
				)
				(xy 136.054846 -22.377146)
				(arc
					(start 136.054846 -22.332188)
					(mid 136.150096 -21.55646)
					(end 136.245346 -22.332188)
				)
				(arc
					(start 136.245346 -22.337776)
					(mid 136.266177 -22.388065)
					(end 136.316466 -22.408896)
				)
				(xy 136.698736 -22.408896)
			)
		)
	)
	(zone
		(net "GND")
		(layer "B.Cu")
		(hatch none 0.5)
		(connect_pads
			(clearance 0.5)
		)
		(min_thickness 0.25)
		(fill yes
			(thermal_gap 0.5)
			(thermal_bridge_width 0.5)
			(island_removal_mode 0)
		)
		(polygon
			(pts
				(arc
					(start 293.287958 -41.595802)
					(mid 293.843898 -42.366667)
					(end 294.20693 -43.245024)
				)
				(xy 324.417182 -23.99919) (xy 326.542146 -23.52802)
				(arc
					(start 326.5678 -23.483824)
					(mid 326.715573 -19.09415)
					(end 330.754736 -17.369282)
				)
				(arc
					(start 330.754736 -17.369282)
					(mid 330.97882 -17.34212)
					(end 331.204062 -17.327372)
				)
				(arc
					(start 331.204062 -17.327372)
					(mid 331.446818 -15.882816)
					(end 332.182978 -14.61643)
				)
				(arc
					(start 332.182978 -14.61643)
					(mid 333.374549 -11.299586)
					(end 336.702908 -10.140696)
				)
				(arc
					(start 336.702908 -10.140696)
					(mid 337.651886 -10.091625)
					(end 338.586572 -10.26287)
				)
				(arc
					(start 338.586572 -10.26287)
					(mid 340.463797 -10.788017)
					(end 341.884762 -12.122404)
				)
				(xy 345.968066 -12.122404)
				(arc
					(start 345.968066 -13.999972)
					(mid 346.208758 -15.183873)
					(end 346.892626 -16.1798)
				)
				(xy 347.897196 -16.1798)
				(arc
					(start 347.897196 -15.375382)
					(mid 347.410662 -14.762778)
					(end 347.23705 -13.999972)
				)
				(arc
					(start 347.23705 -0.999998)
					(mid 347.16764 -0.832426)
					(end 347.000068 -0.763016)
				)
				(arc
					(start 300.999906 -0.763016)
					(mid 299.753267 -0.246641)
					(end 299.236892 0.999998)
				)
				(arc
					(start 299.236892 37.800026)
					(mid 299.167482 37.967598)
					(end 298.99991 38.037008)
				)
				(arc
					(start 221.000066 38.037008)
					(mid 220.832494 37.967598)
					(end 220.763084 37.800026)
				)
				(xy 220.763084 4.156964) (xy 222.032068 4.156964) (xy 222.032068 36.768024) (xy 285.580328 36.768024)
				(arc
					(start 285.580328 32.95777)
					(mid 287.94185 29.117069)
					(end 285.33598 25.437846)
				)
				(arc
					(start 285.33598 25.437846)
					(mid 287.470351 23.09668)
					(end 287.292542 19.933666)
				)
				(arc
					(start 287.292542 19.933666)
					(mid 287.188624 18.736242)
					(end 286.741108 17.620742)
				)
				(arc
					(start 286.741108 17.620742)
					(mid 287.433764 15.714211)
					(end 287.125156 13.709396)
				)
				(arc
					(start 287.125156 13.709396)
					(mid 287.052272 13.259703)
					(end 286.92983 12.820904)
				)
				(arc
					(start 286.92983 12.820904)
					(mid 287.247688 12.791275)
					(end 287.56229 12.737084)
				)
				(arc
					(start 287.56229 12.737084)
					(mid 289.883924 13.637983)
					(end 292.300152 13.035026)
				)
				(arc
					(start 292.300152 13.035026)
					(mid 293.264149 12.85289)
					(end 294.157654 12.447778)
				)
				(xy 294.157654 12.5222) (xy 297.967908 12.5222)
				(arc
					(start 297.967908 0.999998)
					(mid 298.85596 -1.143948)
					(end 300.999906 -2.032)
				)
				(xy 303.518316 -2.032) (xy 303.518316 -5.842254) (xy 303.85258 -6.176518) (xy 307.868828 -6.176518)
				(xy 312.234326 -10.542016) (xy 312.234326 -23.973028) (xy 309.697628 -26.509726)
				(arc
					(start 308.770274 -26.509726)
					(mid 308.038782 -26.719612)
					(end 307.281072 -26.790396)
				)
				(xy 304.741072 -26.790396)
				(arc
					(start 304.712878 -26.790396)
					(mid 303.772524 -28.510395)
					(end 302.139858 -29.595318)
				)
				(arc
					(start 302.139858 -29.595318)
					(mid 297.890179 -30.387571)
					(end 295.303194 -26.924254)
				)
				(xy 289.594798 -26.924254)
				(arc
					(start 289.594798 -38.60419)
					(mid 290.819817 -39.13791)
					(end 291.807392 -40.03802)
				)
				(arc
					(start 291.807392 -40.03802)
					(mid 292.65179 -40.71795)
					(end 293.287958 -41.595802)
				)
			)
		)
		(polygon
			(pts
				(xy 334.548734 -2.032) (xy 315.786516 -2.032)
				(arc
					(start 315.786516 -5.842254)
					(mid 315.294054 -7.393895)
					(end 315.103764 -9.01065)
				)
				(arc
					(start 315.103764 -9.01065)
					(mid 313.585108 -15.92698)
					(end 320.553588 -17.184624)
				)
				(arc
					(start 320.553588 -17.184624)
					(mid 328.430545 -16.333186)
					(end 332.246224 -9.389618)
				)
				(arc
					(start 332.246224 -9.389618)
					(mid 333.798316 -7.876167)
					(end 334.54848 -5.842254)
				)
				(xy 334.548734 -5.842254)
			)
		)
	)
	(zone
		(net "P12V_A")
		(layer "B.Cu")
		(hatch none 0.5)
		(connect_pads
			(clearance 0.5)
		)
		(min_thickness 0.25)
		(fill yes
			(thermal_gap 0.5)
			(thermal_bridge_width 0.5)
			(island_removal_mode 0)
		)
		(polygon
			(pts
				(xy 468.407242 -242.556792) (xy 468.308182 -242.655852) (xy 468.308182 -245.362984) (xy 468.47379 -245.528592)
				(xy 471.777822 -245.528592) (xy 471.91041 -245.396004) (xy 471.91041 -242.63604) (xy 471.831162 -242.556792)
			)
		)
		(polygon
			(pts
				(xy 471.1446 -244.5766) (xy 470.9414 -244.5766) (xy 470.9414 -244.7798) (xy 471.1446 -244.7798)
			)
		)
		(polygon
			(pts
				(xy 470.7509 -244.0559) (xy 470.5477 -244.0559) (xy 470.5477 -244.2591) (xy 470.7509 -244.2591)
			)
		)
		(polygon
			(pts
				(xy 470.7509 -242.6589) (xy 470.5477 -242.6589) (xy 470.5477 -242.8621) (xy 470.7509 -242.8621)
			)
		)
	)
	(zone
		(layer "B.Cu")
		(hatch none 0.5)
		(connect_pads
			(clearance 0)
		)
		(min_thickness 0.25)
		(keepout
			(tracks not_allowed)
			(vias allowed)
			(pads allowed)
			(copperpour not_allowed)
			(footprints allowed)
		)
		(placement
			(enabled no)
			(sheetname "")
		)
		(fill
			(thermal_gap 0.5)
			(thermal_bridge_width 0.5)
			(island_removal_mode 0)
		)
		(polygon
			(pts
				(arc
					(start 355.698552 -20.950428)
					(mid 355.150039 -20.401534)
					(end 354.601272 -20.950174)
				)
				(xy 354.601272 -21.408898)
				(arc
					(start 354.983542 -21.408898)
					(mid 355.033831 -21.388067)
					(end 355.054662 -21.337778)
				)
				(arc
					(start 355.054662 -21.33219)
					(mid 355.149912 -20.556462)
					(end 355.245162 -21.33219)
				)
				(xy 355.245162 -21.377148)
				(arc
					(start 355.241606 -21.380704)
					(mid 355.168528 -21.522764)
					(end 355.026468 -21.595842)
				)
				(xy 355.022912 -21.599398) (xy 354.601272 -21.599398) (xy 354.601272 -21.700998) (xy 355.022912 -21.700998)
				(arc
					(start 355.026468 -21.704554)
					(mid 355.168528 -21.777632)
					(end 355.241606 -21.919692)
				)
				(xy 355.245162 -21.923248)
				(arc
					(start 355.245162 -21.968206)
					(mid 355.149912 -22.743934)
					(end 355.054662 -21.968206)
				)
				(arc
					(start 355.054662 -21.962618)
					(mid 355.033831 -21.912329)
					(end 354.983542 -21.891498)
				)
				(xy 354.601272 -21.891498)
				(arc
					(start 354.601272 -22.350222)
					(mid 355.149912 -22.898862)
					(end 355.698552 -22.350222)
				)
			)
		)
	)
	(zone
		(layer "B.Cu")
		(hatch none 0.5)
		(connect_pads
			(clearance 0)
		)
		(min_thickness 0.25)
		(keepout
			(tracks not_allowed)
			(vias allowed)
			(pads allowed)
			(copperpour not_allowed)
			(footprints allowed)
		)
		(placement
			(enabled no)
			(sheetname "")
		)
		(fill
			(thermal_gap 0.5)
			(thermal_bridge_width 0.5)
			(island_removal_mode 0)
		)
		(polygon
			(pts
				(arc
					(start 389.898636 -21.950426)
					(mid 389.350123 -21.401532)
					(end 388.801356 -21.950172)
				)
				(arc
					(start 388.801356 -23.35022)
					(mid 389.349996 -23.89886)
					(end 389.898636 -23.35022)
				)
				(xy 389.898636 -22.893274) (xy 389.876792 -22.891496)
				(arc
					(start 389.516366 -22.891496)
					(mid 389.466077 -22.912327)
					(end 389.445246 -22.962616)
				)
				(arc
					(start 389.445246 -22.968204)
					(mid 389.349996 -23.743932)
					(end 389.254746 -22.968204)
				)
				(xy 389.254746 -22.923246)
				(arc
					(start 389.258302 -22.91969)
					(mid 389.33138 -22.77763)
					(end 389.47344 -22.704552)
				)
				(xy 389.476996 -22.700996) (xy 389.898636 -22.700996) (xy 389.898636 -22.599904) (xy 389.876792 -22.599396)
				(xy 389.476996 -22.599396)
				(arc
					(start 389.47344 -22.59584)
					(mid 389.33138 -22.522762)
					(end 389.258302 -22.380702)
				)
				(xy 389.254746 -22.377146)
				(arc
					(start 389.254746 -22.332188)
					(mid 389.349996 -21.55646)
					(end 389.445246 -22.332188)
				)
				(arc
					(start 389.445246 -22.337776)
					(mid 389.466077 -22.388065)
					(end 389.516366 -22.408896)
				)
				(xy 389.898636 -22.408896)
			)
		)
	)
	(zone
		(net "P12V_A")
		(layer "B.Cu")
		(hatch none 0.5)
		(connect_pads
			(clearance 0.5)
		)
		(min_thickness 0.25)
		(fill yes
			(thermal_gap 0.5)
			(thermal_bridge_width 0.5)
			(island_removal_mode 0)
		)
		(polygon
			(pts
				(xy 194.407282 -218.869006) (xy 194.026282 -219.250006) (xy 194.026282 -219.758006) (xy 194.034156 -219.76588)
				(xy 194.034156 -220.25102) (xy 192.74917 -221.536006) (xy 192.001394 -221.536006) (xy 191.77 -221.7674)
				(xy 191.77 -223.1644) (xy 191.9478 -223.3422) (xy 192.890394 -223.3422) (xy 193.2432 -223.695006)
				(xy 195.034662 -223.695006) (xy 195.730368 -222.9993) (xy 195.730368 -219.176092) (xy 195.423282 -218.869006)
			)
		)
		(polygon
			(pts
				(xy 192.739518 -222.196406) (xy 192.536318 -222.196406) (xy 192.536318 -222.399606) (xy 192.739518 -222.399606)
			)
		)
	)
	(zone
		(layer "B.Cu")
		(hatch none 0.5)
		(connect_pads
			(clearance 0)
		)
		(min_thickness 0.25)
		(keepout
			(tracks allowed)
			(vias allowed)
			(pads allowed)
			(copperpour allowed)
			(footprints allowed)
		)
		(placement
			(enabled no)
			(sheetname "")
		)
		(fill
			(thermal_gap 0.5)
			(thermal_bridge_width 0.5)
			(island_removal_mode 0)
		)
		(polygon
			(pts
				(xy 184.5564 -225.6282) (xy 184.5564 -224.7392) (xy 183.261 -224.7392) (xy 183.261 -225.6282)
			)
		)
	)
	(zone
		(layer "B.Cu")
		(hatch none 0.5)
		(connect_pads
			(clearance 0)
		)
		(min_thickness 0.25)
		(keepout
			(tracks allowed)
			(vias allowed)
			(pads allowed)
			(copperpour allowed)
			(footprints allowed)
		)
		(placement
			(enabled no)
			(sheetname "")
		)
		(fill
			(thermal_gap 0.5)
			(thermal_bridge_width 0.5)
			(island_removal_mode 0)
		)
		(polygon
			(pts
				(xy 222.745808 -117.452902) (xy 222.745808 -119.2276) (xy 221.6658 -119.2276) (xy 221.6658 -117.452902)
			)
		)
	)
	(zone
		(layer "B.Cu")
		(hatch none 0.5)
		(connect_pads
			(clearance 0)
		)
		(min_thickness 0.25)
		(keepout
			(tracks allowed)
			(vias allowed)
			(pads allowed)
			(copperpour allowed)
			(footprints not_allowed)
		)
		(placement
			(enabled no)
			(sheetname "")
		)
		(fill
			(thermal_gap 0.5)
			(thermal_bridge_width 0.5)
			(island_removal_mode 0)
		)
		(polygon
			(pts
				(arc
					(start 468.574882 -5.199888)
					(mid 469.674956 -6.299962)
					(end 470.77503 -5.199888)
				)
				(arc
					(start 470.77503 -5.199888)
					(mid 469.674956 -4.099814)
					(end 468.574882 -5.199888)
				)
			)
		)
	)
	(zone
		(layer "B.Cu")
		(hatch none 0.5)
		(connect_pads
			(clearance 0)
		)
		(min_thickness 0.25)
		(keepout
			(tracks allowed)
			(vias allowed)
			(pads allowed)
			(copperpour allowed)
			(footprints not_allowed)
		)
		(placement
			(enabled no)
			(sheetname "")
		)
		(fill
			(thermal_gap 0.5)
			(thermal_bridge_width 0.5)
			(island_removal_mode 0)
		)
		(polygon
			(pts
				(arc
					(start 370.875052 -28.079954)
					(mid 372.150132 -29.355034)
					(end 373.424958 -28.079954)
				)
				(arc
					(start 373.424958 -28.079954)
					(mid 372.150132 -26.805128)
					(end 370.875052 -28.079954)
				)
			)
		)
	)
	(zone
		(layer "B.Cu")
		(hatch none 0.5)
		(connect_pads
			(clearance 0)
		)
		(min_thickness 0.25)
		(keepout
			(tracks not_allowed)
			(vias allowed)
			(pads allowed)
			(copperpour not_allowed)
			(footprints allowed)
		)
		(placement
			(enabled no)
			(sheetname "")
		)
		(fill
			(thermal_gap 0.5)
			(thermal_bridge_width 0.5)
			(island_removal_mode 0)
		)
		(polygon
			(pts
				(arc
					(start 118.698518 -21.950426)
					(mid 118.150005 -21.401532)
					(end 117.601238 -21.950172)
				)
				(xy 117.601238 -22.408896)
				(arc
					(start 117.983508 -22.408896)
					(mid 118.033797 -22.388065)
					(end 118.054628 -22.337776)
				)
				(arc
					(start 118.054628 -22.332188)
					(mid 118.149878 -21.55646)
					(end 118.245128 -22.332188)
				)
				(xy 118.245128 -22.377146)
				(arc
					(start 118.241572 -22.380702)
					(mid 118.168494 -22.522762)
					(end 118.026434 -22.59584)
				)
				(xy 118.022878 -22.599396) (xy 117.633242 -22.599396) (xy 117.601238 -22.600666) (xy 117.601238 -22.700996)
				(xy 118.022878 -22.700996)
				(arc
					(start 118.026434 -22.704552)
					(mid 118.168494 -22.77763)
					(end 118.241572 -22.91969)
				)
				(xy 118.245128 -22.923246)
				(arc
					(start 118.245128 -22.968204)
					(mid 118.149878 -23.743932)
					(end 118.054628 -22.968204)
				)
				(arc
					(start 118.054628 -22.962616)
					(mid 118.033797 -22.912327)
					(end 117.983508 -22.891496)
				)
				(arc
					(start 117.633242 -22.891496)
					(mid 117.617137 -22.892354)
					(end 117.601238 -22.895052)
				)
				(arc
					(start 117.601238 -23.35022)
					(mid 118.149878 -23.89886)
					(end 118.698518 -23.35022)
				)
			)
		)
	)
	(zone
		(net "AGND_P5V_B")
		(layer "B.Cu")
		(hatch none 0.5)
		(connect_pads
			(clearance 0.5)
		)
		(min_thickness 0.25)
		(fill yes
			(thermal_gap 0.5)
			(thermal_bridge_width 0.5)
			(island_removal_mode 0)
		)
		(polygon
			(pts
				(xy 45.024802 -148.884386) (xy 44.677838 -149.23135) (xy 44.669202 -149.23135) (xy 44.669202 -150.170388)
				(xy 44.745402 -150.246588) (xy 46.929802 -150.246588) (xy 46.929802 -150.24735) (xy 47.387002 -150.24735)
				(xy 47.682912 -149.95144) (xy 47.682912 -149.038056) (xy 47.529242 -148.884386)
			)
		)
		(polygon
			(pts
				(xy 47.178214 -149.305264) (xy 46.975014 -149.305264) (xy 46.975014 -149.508464) (xy 47.178214 -149.508464)
			)
		)
	)
	(zone
		(layer "B.Cu")
		(hatch none 0.5)
		(connect_pads
			(clearance 0)
		)
		(min_thickness 0.25)
		(keepout
			(tracks not_allowed)
			(vias allowed)
			(pads allowed)
			(copperpour not_allowed)
			(footprints allowed)
		)
		(placement
			(enabled no)
			(sheetname "")
		)
		(fill
			(thermal_gap 0.5)
			(thermal_bridge_width 0.5)
			(island_removal_mode 0)
		)
		(polygon
			(pts
				(arc
					(start 271.970754 -335.721452)
					(mid 271.58696 -336.104865)
					(end 271.9705 -336.488532)
				)
				(arc
					(start 273.1135 -336.488532)
					(mid 273.49704 -336.104992)
					(end 273.1135 -335.721452)
				)
				(arc
					(start 272.768568 -335.721452)
					(mid 272.765366 -335.748292)
					(end 272.76425 -335.7753)
				)
				(arc
					(start 272.76425 -335.92389)
					(mid 272.791127 -335.994008)
					(end 272.857976 -336.028284)
				)
				(arc
					(start 272.857976 -336.028284)
					(mid 273.380217 -336.104738)
					(end 272.857976 -336.181192)
				)
				(xy 272.837656 -336.181192)
				(arc
					(start 272.83537 -336.178906)
					(mid 272.687253 -336.105789)
					(end 272.614136 -335.957672)
				)
				(xy 272.61185 -335.955386) (xy 272.61185 -335.743804) (xy 272.612866 -335.742788) (xy 272.614644 -335.721452)
				(arc
					(start 272.474436 -335.721452)
					(mid 272.472724 -335.748352)
					(end 272.47215 -335.7753)
				)
				(xy 272.47215 -335.955386)
				(arc
					(start 272.469864 -335.957672)
					(mid 272.396747 -336.105789)
					(end 272.24863 -336.178906)
				)
				(xy 272.246344 -336.181192)
				(arc
					(start 272.226024 -336.181192)
					(mid 271.703783 -336.104738)
					(end 272.226024 -336.028284)
				)
				(arc
					(start 272.226024 -336.028284)
					(mid 272.292939 -335.994067)
					(end 272.31975 -335.92389)
				)
				(xy 272.31975 -335.743804) (xy 272.320512 -335.743042) (xy 272.321528 -335.721452)
			)
		)
	)
	(zone
		(layer "B.Cu")
		(hatch none 0.5)
		(connect_pads
			(clearance 0)
		)
		(min_thickness 0.25)
		(keepout
			(tracks not_allowed)
			(vias allowed)
			(pads allowed)
			(copperpour not_allowed)
			(footprints allowed)
		)
		(placement
			(enabled no)
			(sheetname "")
		)
		(fill
			(thermal_gap 0.5)
			(thermal_bridge_width 0.5)
			(island_removal_mode 0)
		)
		(polygon
			(pts
				(arc
					(start 278.23668 -312.156602)
					(mid 277.68804 -312.705242)
					(end 278.23668 -313.253882)
				)
				(xy 278.642572 -313.253882) (xy 278.644096 -313.252358)
				(arc
					(start 278.661876 -313.232546)
					(mid 278.700943 -313.161968)
					(end 278.714454 -313.082432)
				)
				(arc
					(start 278.714454 -312.831988)
					(mid 278.699575 -312.796067)
					(end 278.663654 -312.781188)
				)
				(arc
					(start 278.623014 -312.781188)
					(mid 277.84305 -312.706522)
					(end 278.62276 -312.628788)
				)
				(xy 278.69515 -312.628788)
				(arc
					(start 278.698198 -312.631836)
					(mid 278.807275 -312.688367)
					(end 278.863806 -312.797444)
				)
				(xy 278.866854 -312.800492) (xy 278.866854 -313.113928)
				(arc
					(start 278.865584 -313.115452)
					(mid 278.852904 -313.186419)
					(end 278.827484 -313.253882)
				)
				(arc
					(start 278.97836 -313.253882)
					(mid 278.999465 -313.169567)
					(end 279.006554 -313.08294)
				)
				(xy 279.006554 -312.832242) (xy 279.006554 -312.829194) (xy 279.006554 -312.800492) (xy 279.009348 -312.797698)
				(xy 279.01138 -312.786522)
				(arc
					(start 279.011634 -312.785506)
					(mid 279.070221 -312.683858)
					(end 279.17521 -312.631582)
				)
				(xy 279.178258 -312.628788)
				(arc
					(start 279.250648 -312.628788)
					(mid 280.030403 -312.706522)
					(end 279.250394 -312.781188)
				)
				(arc
					(start 279.2095 -312.781188)
					(mid 279.178008 -312.792058)
					(end 279.15997 -312.82005)
				)
				(xy 279.158954 -312.829956) (xy 279.158954 -313.08294) (xy 279.158954 -313.114436)
				(arc
					(start 279.158192 -313.115198)
					(mid 279.151342 -313.185076)
					(end 279.137364 -313.253882)
				)
				(arc
					(start 279.636728 -313.253882)
					(mid 280.185368 -312.705242)
					(end 279.636728 -312.156602)
				)
				(xy 278.236934 -312.156602)
			)
		)
	)
	(zone
		(layer "B.Cu")
		(hatch none 0.5)
		(connect_pads
			(clearance 0)
		)
		(min_thickness 0.25)
		(keepout
			(tracks allowed)
			(vias allowed)
			(pads allowed)
			(copperpour allowed)
			(footprints not_allowed)
		)
		(placement
			(enabled no)
			(sheetname "")
		)
		(fill
			(thermal_gap 0.5)
			(thermal_bridge_width 0.5)
			(island_removal_mode 0)
		)
		(polygon
			(pts
				(xy 13.850112 0) (xy 13.850112 -134.199884) (xy 146.349974 -134.199884) (xy 146.349974 -149.200108)
				(xy 215.35009 -149.200108) (xy 215.35009 -99.199954) (xy 225.849942 -99.199954) (xy 225.849942 38.800024)
				(arc
					(start 221.000066 38.800024)
					(mid 220.292961 38.507131)
					(end 220.000068 37.800026)
				)
				(arc
					(start 220.000068 2.999994)
					(mid 219.707175 2.292889)
					(end 219.00007 1.999996)
				)
				(arc
					(start 201.000106 1.999996)
					(mid 200.293001 1.707103)
					(end 200.000108 0.999998)
				)
				(arc
					(start 200.000108 0.999998)
					(mid 199.707215 0.292893)
					(end 199.00011 0)
				)
				(arc
					(start 150.999952 0)
					(mid 150.292847 -0.292893)
					(end 149.999954 -0.999998)
				)
				(arc
					(start 149.999954 -13.999972)
					(mid 149.707061 -14.707077)
					(end 148.999956 -14.99997)
				)
				(arc
					(start 103.000048 -14.99997)
					(mid 102.292943 -14.707077)
					(end 102.00005 -13.999972)
				)
				(arc
					(start 102.00005 -0.999998)
					(mid 101.707157 -0.292893)
					(end 101.000052 0)
				)
			)
		)
	)
	(zone
		(layer "B.Cu")
		(hatch none 0.5)
		(connect_pads
			(clearance 0)
		)
		(min_thickness 0.25)
		(keepout
			(tracks allowed)
			(vias allowed)
			(pads allowed)
			(copperpour allowed)
			(footprints not_allowed)
		)
		(placement
			(enabled no)
			(sheetname "")
		)
		(fill
			(thermal_gap 0.5)
			(thermal_bridge_width 0.5)
			(island_removal_mode 0)
		)
		(polygon
			(pts
				(arc
					(start 410.85008 -164.200078)
					(mid 407.100024 -160.450022)
					(end 403.349968 -164.200078)
				)
				(arc
					(start 403.349968 -164.200078)
					(mid 407.100024 -167.950134)
					(end 410.85008 -164.200078)
				)
			)
		)
	)
	(zone
		(layer "B.Cu")
		(hatch none 0.5)
		(connect_pads
			(clearance 0)
		)
		(min_thickness 0.25)
		(keepout
			(tracks allowed)
			(vias allowed)
			(pads allowed)
			(copperpour allowed)
			(footprints not_allowed)
		)
		(placement
			(enabled no)
			(sheetname "")
		)
		(fill
			(thermal_gap 0.5)
			(thermal_bridge_width 0.5)
			(island_removal_mode 0)
		)
		(polygon
			(pts
				(arc
					(start 346.050108 -269.999968)
					(mid 341.300054 -265.249914)
					(end 336.55 -269.999968)
				)
				(arc
					(start 336.55 -269.999968)
					(mid 341.300054 -274.750022)
					(end 346.050108 -269.999968)
				)
			)
		)
	)
	(zone
		(net "GND")
		(layer "B.Cu")
		(hatch none 0.5)
		(connect_pads
			(clearance 0.5)
		)
		(min_thickness 0.25)
		(fill yes
			(thermal_gap 0.5)
			(thermal_bridge_width 0.5)
			(island_removal_mode 0)
		)
		(polygon
			(pts
				(xy 370.512848 -180.4924)
				(arc
					(start 381.009144 -164.0205)
					(mid 379.554689 -162.536435)
					(end 379.023626 -160.527492)
				)
				(xy 379.023626 -160.38068)
				(arc
					(start 372.467632 -160.38068)
					(mid 372.222844 -161.117316)
					(end 371.8433 -161.794444)
				)
				(arc
					(start 371.8433 -161.794444)
					(mid 373.843107 -163.286749)
					(end 374.604026 -165.663118)
				)
				(arc
					(start 374.604026 -169.777918)
					(mid 374.166057 -171.619602)
					(end 372.945914 -173.066964)
				)
				(arc
					(start 372.945914 -173.066964)
					(mid 371.668303 -175.802638)
					(end 368.862102 -176.916842)
				)
				(arc
					(start 366.322102 -176.916842)
					(mid 362.453906 -174.157354)
					(end 363.8042 -169.601642)
				)
				(arc
					(start 363.8042 -168.202102)
					(mid 362.496293 -167.130128)
					(end 361.733846 -165.6207)
				)
				(arc
					(start 361.733846 -165.6207)
					(mid 361.472271 -165.54663)
					(end 361.216194 -165.455346)
				)
				(arc
					(start 361.216194 -165.455346)
					(mid 360.830313 -166.549017)
					(end 360.15295 -167.490394)
				)
				(arc
					(start 360.15295 -170.230038)
					(mid 360.082621 -170.985336)
					(end 359.874058 -171.714668)
				)
				(arc
					(start 359.874058 -171.714668)
					(mid 360.923532 -173.109573)
					(end 361.29595 -174.814992)
				)
				(arc
					(start 361.29595 -177.354992)
					(mid 361.235373 -178.05639)
					(end 361.055412 -178.737006)
				)
				(arc
					(start 361.055412 -178.737006)
					(mid 361.655226 -178.580404)
					(end 362.271818 -178.51628)
				)
				(arc
					(start 362.271818 -178.51628)
					(mid 366.136257 -177.295746)
					(end 369.154202 -180.000402)
				)
				(xy 369.6462 -180.4924)
			)
		)
	)
	(zone
		(layer "B.Cu")
		(hatch none 0.5)
		(connect_pads
			(clearance 0)
		)
		(min_thickness 0.25)
		(keepout
			(tracks allowed)
			(vias allowed)
			(pads allowed)
			(copperpour allowed)
			(footprints not_allowed)
		)
		(placement
			(enabled no)
			(sheetname "")
		)
		(fill
			(thermal_gap 0.5)
			(thermal_bridge_width 0.5)
			(island_removal_mode 0)
		)
		(polygon
			(pts
				(arc
					(start 174.95012 -269.999968)
					(mid 170.200066 -265.249914)
					(end 165.450012 -269.999968)
				)
				(arc
					(start 165.450012 -269.999968)
					(mid 170.200066 -274.750022)
					(end 174.95012 -269.999968)
				)
			)
		)
	)
	(zone
		(layer "B.Cu")
		(hatch none 0.5)
		(connect_pads
			(clearance 0)
		)
		(min_thickness 0.25)
		(keepout
			(tracks allowed)
			(vias allowed)
			(pads allowed)
			(copperpour allowed)
			(footprints not_allowed)
		)
		(placement
			(enabled no)
			(sheetname "")
		)
		(fill
			(thermal_gap 0.5)
			(thermal_bridge_width 0.5)
			(island_removal_mode 0)
		)
		(polygon
			(pts
				(arc
					(start 178.649884 -208.499964)
					(mid 182.39994 -212.25002)
					(end 186.149996 -208.499964)
				)
				(arc
					(start 186.149996 -208.499964)
					(mid 182.39994 -204.749908)
					(end 178.649884 -208.499964)
				)
			)
		)
	)
	(zone
		(net "P5V_D_LL_R")
		(layer "B.Cu")
		(hatch none 0.5)
		(connect_pads
			(clearance 0.5)
		)
		(min_thickness 0.25)
		(fill yes
			(thermal_gap 0.5)
			(thermal_bridge_width 0.5)
			(island_removal_mode 0)
		)
		(polygon
			(pts
				(xy 479.094292 -221.843346) (xy 478.917254 -222.020384) (xy 478.917254 -223.925384) (xy 479.095054 -224.103184)
				(xy 480.63658 -224.103184) (xy 480.850702 -223.889062) (xy 480.850702 -223.251014) (xy 480.98202 -223.119696)
				(xy 482.008942 -223.119696) (xy 482.295454 -222.833184) (xy 482.295454 -222.097346) (xy 482.041454 -221.843346)
			)
		)
		(polygon
			(pts
				(xy 479.5393 -223.779842) (xy 479.3361 -223.779842) (xy 479.3361 -223.983042) (xy 479.5393 -223.983042)
			)
		)
		(polygon
			(pts
				(xy 479.5393 -223.221042) (xy 479.3361 -223.221042) (xy 479.3361 -223.424242) (xy 479.5393 -223.424242)
			)
		)
		(polygon
			(pts
				(xy 479.96348 -222.559372) (xy 479.76028 -222.559372) (xy 479.76028 -222.762572) (xy 479.96348 -222.762572)
			)
		)
		(polygon
			(pts
				(xy 480.943158 -222.352362) (xy 480.739958 -222.352362) (xy 480.739958 -222.555562) (xy 480.943158 -222.555562)
			)
		)
		(polygon
			(pts
				(xy 480.333558 -222.352362) (xy 480.130358 -222.352362) (xy 480.130358 -222.555562) (xy 480.333558 -222.555562)
			)
		)
	)
	(zone
		(layer "B.Cu")
		(hatch none 0.5)
		(connect_pads
			(clearance 0)
		)
		(min_thickness 0.25)
		(keepout
			(tracks not_allowed)
			(vias allowed)
			(pads allowed)
			(copperpour not_allowed)
			(footprints allowed)
		)
		(placement
			(enabled no)
			(sheetname "")
		)
		(fill
			(thermal_gap 0.5)
			(thermal_bridge_width 0.5)
			(island_removal_mode 0)
		)
		(polygon
			(pts
				(arc
					(start 271.970754 -355.524054)
					(mid 271.5895 -355.904927)
					(end 271.9705 -356.286054)
				)
				(arc
					(start 273.1135 -356.286054)
					(mid 273.4945 -355.905054)
					(end 273.1135 -355.524054)
				)
				(arc
					(start 272.76806 -355.524054)
					(mid 272.765209 -355.549638)
					(end 272.76425 -355.575362)
				)
				(arc
					(start 272.76425 -355.723952)
					(mid 272.791127 -355.79407)
					(end 272.857976 -355.828346)
				)
				(arc
					(start 272.857976 -355.828346)
					(mid 273.380217 -355.9048)
					(end 272.857976 -355.981254)
				)
				(xy 272.837656 -355.981254)
				(arc
					(start 272.83537 -355.978968)
					(mid 272.687253 -355.905851)
					(end 272.614136 -355.757734)
				)
				(xy 272.61185 -355.755448) (xy 272.61185 -355.543866) (xy 272.612866 -355.54285) (xy 272.61439 -355.524054)
				(arc
					(start 272.474182 -355.524054)
					(mid 272.472648 -355.549688)
					(end 272.47215 -355.575362)
				)
				(xy 272.47215 -355.755448)
				(arc
					(start 272.469864 -355.757734)
					(mid 272.396747 -355.905851)
					(end 272.24863 -355.978968)
				)
				(xy 272.246344 -355.981254)
				(arc
					(start 272.226024 -355.981254)
					(mid 271.703783 -355.9048)
					(end 272.226024 -355.828346)
				)
				(arc
					(start 272.226024 -355.828346)
					(mid 272.292939 -355.794129)
					(end 272.31975 -355.723952)
				)
				(xy 272.31975 -355.543866) (xy 272.320512 -355.543104) (xy 272.321528 -355.524054)
			)
		)
	)
	(zone
		(layer "B.Cu")
		(hatch none 0.5)
		(connect_pads
			(clearance 0)
		)
		(min_thickness 0.25)
		(keepout
			(tracks allowed)
			(vias allowed)
			(pads allowed)
			(copperpour allowed)
			(footprints not_allowed)
		)
		(placement
			(enabled no)
			(sheetname "")
		)
		(fill
			(thermal_gap 0.5)
			(thermal_bridge_width 0.5)
			(island_removal_mode 0)
		)
		(polygon
			(pts
				(arc
					(start 161.574988 -9.19988)
					(mid 166.325042 -13.949934)
					(end 171.075096 -9.19988)
				)
				(arc
					(start 171.075096 -9.19988)
					(mid 166.325042 -4.449826)
					(end 161.574988 -9.19988)
				)
			)
		)
	)
	(zone
		(layer "B.Cu")
		(hatch none 0.5)
		(connect_pads
			(clearance 0)
		)
		(min_thickness 0.25)
		(keepout
			(tracks not_allowed)
			(vias allowed)
			(pads allowed)
			(copperpour not_allowed)
			(footprints allowed)
		)
		(placement
			(enabled no)
			(sheetname "")
		)
		(fill
			(thermal_gap 0.5)
			(thermal_bridge_width 0.5)
			(island_removal_mode 0)
		)
		(polygon
			(pts
				(arc
					(start 236.531658 -173.808136)
					(mid 236.462854 -173.780718)
					(end 236.389418 -173.771052)
				)
				(xy 235.88091 -173.769528) (xy 235.724192 -173.84776) (xy 235.724192 -173.848014)
				(arc
					(start 235.725208 -173.850046)
					(mid 235.400342 -174.824644)
					(end 236.37494 -175.14951)
				)
				(xy 236.37621 -175.151796) (xy 238.376206 -174.151798)
				(arc
					(start 238.374936 -174.149512)
					(mid 238.699802 -173.174914)
					(end 237.725204 -172.850048)
				)
				(xy 237.723934 -172.847762)
				(arc
					(start 236.706918 -173.35627)
					(mid 236.735785 -173.369907)
					(end 236.764068 -173.384718)
				)
				(arc
					(start 236.764322 -173.384718)
					(mid 236.840891 -173.432776)
					(end 236.911388 -173.489366)
				)
				(xy 236.912658 -173.489366) (xy 236.940344 -173.517052) (xy 236.940598 -173.517306)
				(arc
					(start 237.145576 -173.722284)
					(mid 237.184616 -173.75077)
					(end 237.230412 -173.766226)
				)
				(arc
					(start 237.248954 -173.769274)
					(mid 237.298724 -173.769115)
					(end 237.345982 -173.753526)
				)
				(arc
					(start 237.5281 -173.660308)
					(mid 238.536063 -173.250717)
					(end 237.614968 -173.829726)
				)
				(xy 237.43285 -173.923198) (xy 237.397798 -173.941232)
				(arc
					(start 237.394242 -173.939962)
					(mid 237.328484 -173.957176)
					(end 237.260638 -173.961298)
				)
				(xy 237.25759 -173.963584) (xy 237.203488 -173.954694) (xy 237.198916 -173.953932) (xy 237.164118 -173.948344)
				(arc
					(start 237.16234 -173.945804)
					(mid 237.099442 -173.921136)
					(end 237.042452 -173.884844)
				)
				(xy 237.038896 -173.884844)
				(arc
					(start 236.805724 -173.651672)
					(mid 236.742709 -173.59705)
					(end 236.672628 -173.55185)
				)
				(arc
					(start 236.672628 -173.55185)
					(mid 236.566911 -173.506647)
					(end 236.454442 -173.482762)
				)
				(xy 236.25937 -173.580044) (xy 236.388656 -173.580552) (xy 236.39018 -173.580552) (xy 236.42828 -173.580806)
				(arc
					(start 236.429804 -173.58233)
					(mid 236.529784 -173.601506)
					(end 236.623606 -173.641004)
				)
				(arc
					(start 236.623606 -173.641004)
					(mid 236.664973 -173.666584)
					(end 236.703616 -173.696122)
				)
				(xy 236.705902 -173.696122) (xy 236.733588 -173.723554) (xy 236.733842 -173.724062) (xy 236.862874 -173.853094)
				(arc
					(start 236.862874 -173.85792)
					(mid 236.905234 -173.951287)
					(end 236.908848 -174.053754)
				)
				(arc
					(start 236.908848 -174.054008)
					(mid 236.872927 -174.150046)
					(end 236.803184 -174.225204)
				)
				(xy 236.80166 -174.23003) (xy 236.766354 -174.247556)
				(arc
					(start 236.573568 -174.344076)
					(mid 235.562291 -174.744823)
					(end 236.488224 -174.173896)
				)
				(arc
					(start 236.68101 -174.077376)
					(mid 236.707436 -174.055104)
					(end 236.720888 -174.023274)
				)
				(arc
					(start 236.720888 -174.023274)
					(mid 236.718275 -173.989023)
					(end 236.700314 -173.959774)
				)
				(arc
					(start 236.598714 -173.858428)
					(mid 236.566956 -173.830923)
					(end 236.531658 -173.808136)
				)
			)
		)
	)
	(zone
		(layer "B.Cu")
		(hatch none 0.5)
		(connect_pads
			(clearance 0)
		)
		(min_thickness 0.25)
		(keepout
			(tracks allowed)
			(vias allowed)
			(pads allowed)
			(copperpour allowed)
			(footprints not_allowed)
		)
		(placement
			(enabled no)
			(sheetname "")
		)
		(fill
			(thermal_gap 0.5)
			(thermal_bridge_width 0.5)
			(island_removal_mode 0)
		)
		(polygon
			(pts
				(arc
					(start 337.674966 -92.799916)
					(mid 330.67498 -85.79993)
					(end 323.674994 -92.799916)
				)
				(arc
					(start 323.674994 -98.799904)
					(mid 330.67498 -105.79989)
					(end 337.674966 -98.799904)
				)
			)
		)
	)
	(zone
		(layer "B.Cu")
		(hatch none 0.5)
		(connect_pads
			(clearance 0)
		)
		(min_thickness 0.25)
		(keepout
			(tracks allowed)
			(vias allowed)
			(pads allowed)
			(copperpour allowed)
			(footprints not_allowed)
		)
		(placement
			(enabled no)
			(sheetname "")
		)
		(fill
			(thermal_gap 0.5)
			(thermal_bridge_width 0.5)
			(island_removal_mode 0)
		)
		(polygon
			(pts
				(arc
					(start 328.574908 -5.199888)
					(mid 329.674982 -6.299962)
					(end 330.775056 -5.199888)
				)
				(arc
					(start 330.775056 -5.199888)
					(mid 329.674982 -4.099814)
					(end 328.574908 -5.199888)
				)
			)
		)
	)
	(zone
		(layer "B.Cu")
		(hatch none 0.5)
		(connect_pads
			(clearance 0)
		)
		(min_thickness 0.25)
		(keepout
			(tracks not_allowed)
			(vias allowed)
			(pads allowed)
			(copperpour not_allowed)
			(footprints allowed)
		)
		(placement
			(enabled no)
			(sheetname "")
		)
		(fill
			(thermal_gap 0.5)
			(thermal_bridge_width 0.5)
			(island_removal_mode 0)
		)
		(polygon
			(pts
				(arc
					(start 281.074876 -37.84981)
					(mid 281.399742 -36.875212)
					(end 280.425144 -36.550346)
				)
				(xy 280.423874 -36.54806)
				(arc
					(start 279.406858 -37.056568)
					(mid 279.435725 -37.070205)
					(end 279.464008 -37.085016)
				)
				(arc
					(start 279.464262 -37.085016)
					(mid 279.540831 -37.133074)
					(end 279.611328 -37.189664)
				)
				(xy 279.612598 -37.189664) (xy 279.640284 -37.21735) (xy 279.640538 -37.217604) (xy 279.775158 -37.352224)
				(arc
					(start 279.845516 -37.422582)
					(mid 279.884556 -37.451068)
					(end 279.930352 -37.466524)
				)
				(xy 279.933908 -37.467032)
				(arc
					(start 279.948894 -37.469572)
					(mid 279.998664 -37.469413)
					(end 280.045922 -37.453824)
				)
				(arc
					(start 280.22804 -37.360606)
					(mid 280.203915 -37.208948)
					(end 280.22296 -37.056568)
				)
				(arc
					(start 280.22296 -37.056568)
					(mid 281.286157 -37.095661)
					(end 280.314908 -37.530024)
				)
				(xy 280.13279 -37.623496) (xy 280.097738 -37.64153)
				(arc
					(start 280.094182 -37.64026)
					(mid 280.028424 -37.657474)
					(end 279.960578 -37.661596)
				)
				(xy 279.95753 -37.663882) (xy 279.918414 -37.657532) (xy 279.903428 -37.654992) (xy 279.898856 -37.65423)
				(xy 279.864058 -37.648642)
				(arc
					(start 279.86228 -37.646102)
					(mid 279.799382 -37.621434)
					(end 279.742392 -37.585142)
				)
				(xy 279.738836 -37.585142) (xy 279.505918 -37.352224)
				(arc
					(start 279.505664 -37.35197)
					(mid 279.442649 -37.297348)
					(end 279.372568 -37.252148)
				)
				(arc
					(start 279.372568 -37.252148)
					(mid 279.266851 -37.206945)
					(end 279.154382 -37.18306)
				)
				(xy 278.958548 -37.28085) (xy 279.127712 -37.28085)
				(arc
					(start 279.12949 -37.282628)
					(mid 279.229597 -37.301788)
					(end 279.323546 -37.341302)
				)
				(arc
					(start 279.323546 -37.341302)
					(mid 279.364913 -37.366882)
					(end 279.403556 -37.39642)
				)
				(xy 279.405842 -37.39642) (xy 279.433528 -37.423852) (xy 279.433782 -37.42436) (xy 279.562814 -37.553392)
				(arc
					(start 279.562814 -37.558218)
					(mid 279.605174 -37.651585)
					(end 279.608788 -37.754052)
				)
				(arc
					(start 279.608788 -37.754306)
					(mid 279.572867 -37.850344)
					(end 279.503124 -37.925502)
				)
				(xy 279.5016 -37.930328)
				(arc
					(start 279.273508 -38.044374)
					(mid 278.262231 -38.445121)
					(end 279.188164 -37.874194)
				)
				(arc
					(start 279.38095 -37.777674)
					(mid 279.407376 -37.755402)
					(end 279.420828 -37.723572)
				)
				(arc
					(start 279.420828 -37.723572)
					(mid 279.418215 -37.689321)
					(end 279.400254 -37.660072)
				)
				(arc
					(start 279.298654 -37.558726)
					(mid 279.266896 -37.531221)
					(end 279.231598 -37.508434)
				)
				(arc
					(start 279.231598 -37.508434)
					(mid 279.162303 -37.480888)
					(end 279.088342 -37.47135)
				)
				(xy 278.577548 -37.47135) (xy 278.424132 -37.548058) (xy 278.424132 -37.548312)
				(arc
					(start 278.425148 -37.550344)
					(mid 278.100282 -38.524942)
					(end 279.07488 -38.849808)
				)
				(xy 279.07615 -38.852094) (xy 281.076146 -37.852096)
			)
		)
	)
	(zone
		(layer "B.Cu")
		(hatch none 0.5)
		(connect_pads
			(clearance 0)
		)
		(min_thickness 0.25)
		(keepout
			(tracks not_allowed)
			(vias allowed)
			(pads allowed)
			(copperpour not_allowed)
			(footprints allowed)
		)
		(placement
			(enabled no)
			(sheetname "")
		)
		(fill
			(thermal_gap 0.5)
			(thermal_bridge_width 0.5)
			(island_removal_mode 0)
		)
		(polygon
			(pts
				(arc
					(start 31.075122 -9.19988)
					(mid 26.325068 -4.449826)
					(end 21.575014 -9.19988)
				)
				(arc
					(start 21.575014 -9.19988)
					(mid 26.325068 -13.949934)
					(end 31.075122 -9.19988)
				)
			)
		)
	)
	(zone
		(layer "B.Cu")
		(hatch none 0.5)
		(connect_pads
			(clearance 0)
		)
		(min_thickness 0.25)
		(keepout
			(tracks not_allowed)
			(vias allowed)
			(pads allowed)
			(copperpour not_allowed)
			(footprints allowed)
		)
		(placement
			(enabled no)
			(sheetname "")
		)
		(fill
			(thermal_gap 0.5)
			(thermal_bridge_width 0.5)
			(island_removal_mode 0)
		)
		(polygon
			(pts
				(arc
					(start 366.498632 -20.950428)
					(mid 365.950119 -20.401534)
					(end 365.401352 -20.950174)
				)
				(xy 365.401352 -21.408898)
				(arc
					(start 365.783622 -21.408898)
					(mid 365.833911 -21.388067)
					(end 365.854742 -21.337778)
				)
				(arc
					(start 365.854742 -21.33219)
					(mid 365.949992 -20.556462)
					(end 366.045242 -21.33219)
				)
				(xy 366.045242 -21.377148)
				(arc
					(start 366.041686 -21.380704)
					(mid 365.968608 -21.522764)
					(end 365.826548 -21.595842)
				)
				(xy 365.822992 -21.599398) (xy 365.401352 -21.599398) (xy 365.401352 -21.700998) (xy 365.822992 -21.700998)
				(arc
					(start 365.826548 -21.704554)
					(mid 365.968608 -21.777632)
					(end 366.041686 -21.919692)
				)
				(xy 366.045242 -21.923248)
				(arc
					(start 366.045242 -21.968206)
					(mid 365.949992 -22.743934)
					(end 365.854742 -21.968206)
				)
				(arc
					(start 365.854742 -21.962618)
					(mid 365.833911 -21.912329)
					(end 365.783622 -21.891498)
				)
				(xy 365.401352 -21.891498)
				(arc
					(start 365.401352 -22.350222)
					(mid 365.949992 -22.898862)
					(end 366.498632 -22.350222)
				)
			)
		)
	)
	(zone
		(layer "B.Cu")
		(hatch none 0.5)
		(connect_pads
			(clearance 0)
		)
		(min_thickness 0.25)
		(keepout
			(tracks not_allowed)
			(vias allowed)
			(pads allowed)
			(copperpour not_allowed)
			(footprints allowed)
		)
		(placement
			(enabled no)
			(sheetname "")
		)
		(fill
			(thermal_gap 0.5)
			(thermal_bridge_width 0.5)
			(island_removal_mode 0)
		)
		(polygon
			(pts
				(arc
					(start 113.298732 -20.950428)
					(mid 112.750219 -20.401534)
					(end 112.201452 -20.950174)
				)
				(xy 112.201452 -21.408898)
				(arc
					(start 112.583722 -21.408898)
					(mid 112.634011 -21.388067)
					(end 112.654842 -21.337778)
				)
				(arc
					(start 112.654842 -21.33219)
					(mid 112.750092 -20.556462)
					(end 112.845342 -21.33219)
				)
				(xy 112.845342 -21.377148)
				(arc
					(start 112.841786 -21.380704)
					(mid 112.768708 -21.522764)
					(end 112.626648 -21.595842)
				)
				(xy 112.623092 -21.599398) (xy 112.233456 -21.599398) (xy 112.201452 -21.600668) (xy 112.201452 -21.700998)
				(xy 112.623092 -21.700998)
				(arc
					(start 112.626648 -21.704554)
					(mid 112.768708 -21.777632)
					(end 112.841786 -21.919692)
				)
				(xy 112.845342 -21.923248)
				(arc
					(start 112.845342 -21.968206)
					(mid 112.750092 -22.743934)
					(end 112.654842 -21.968206)
				)
				(arc
					(start 112.654842 -21.962618)
					(mid 112.634011 -21.912329)
					(end 112.583722 -21.891498)
				)
				(arc
					(start 112.233456 -21.891498)
					(mid 112.217351 -21.892356)
					(end 112.201452 -21.895054)
				)
				(arc
					(start 112.201452 -22.350222)
					(mid 112.750092 -22.898862)
					(end 113.298732 -22.350222)
				)
			)
		)
	)
	(zone
		(layer "B.Cu")
		(hatch none 0.5)
		(connect_pads
			(clearance 0)
		)
		(min_thickness 0.25)
		(keepout
			(tracks not_allowed)
			(vias allowed)
			(pads allowed)
			(copperpour not_allowed)
			(footprints allowed)
		)
		(placement
			(enabled no)
			(sheetname "")
		)
		(fill
			(thermal_gap 0.5)
			(thermal_bridge_width 0.5)
			(island_removal_mode 0)
		)
		(polygon
			(pts
				(arc
					(start 325.12 -162.178746)
					(mid 324.739127 -161.797492)
					(end 324.358 -162.178492)
				)
				(xy 324.358 -162.527742)
				(arc
					(start 324.562216 -162.527742)
					(mid 324.630872 -162.500667)
					(end 324.662546 -162.434016)
				)
				(arc
					(start 324.662546 -162.434016)
					(mid 324.739122 -161.911775)
					(end 324.8152 -162.434016)
				)
				(xy 324.8152 -162.458654)
				(arc
					(start 324.812914 -162.46094)
					(mid 324.741088 -162.60603)
					(end 324.595998 -162.677856)
				)
				(xy 324.593712 -162.680142) (xy 324.358 -162.680142) (xy 324.358 -162.819842) (xy 324.593712 -162.819842)
				(arc
					(start 324.595998 -162.822128)
					(mid 324.741088 -162.893954)
					(end 324.812914 -163.039044)
				)
				(xy 324.8152 -163.04133)
				(arc
					(start 324.8152 -163.065968)
					(mid 324.739122 -163.588136)
					(end 324.662546 -163.065968)
				)
				(arc
					(start 324.662546 -163.065968)
					(mid 324.630858 -162.999332)
					(end 324.562216 -162.972242)
				)
				(xy 324.358 -162.972242)
				(arc
					(start 324.358 -163.321492)
					(mid 324.739 -163.702492)
					(end 325.12 -163.321492)
				)
			)
		)
	)
	(zone
		(layer "B.Cu")
		(hatch none 0.5)
		(connect_pads
			(clearance 0)
		)
		(min_thickness 0.25)
		(keepout
			(tracks not_allowed)
			(vias allowed)
			(pads allowed)
			(copperpour not_allowed)
			(footprints allowed)
		)
		(placement
			(enabled no)
			(sheetname "")
		)
		(fill
			(thermal_gap 0.5)
			(thermal_bridge_width 0.5)
			(island_removal_mode 0)
		)
		(polygon
			(pts
				(arc
					(start 212.348826 -406.000204)
					(mid 211.800313 -405.45131)
					(end 211.251546 -405.99995)
				)
				(xy 211.251546 -406.458674)
				(arc
					(start 211.617814 -406.458674)
					(mid 211.632658 -406.457324)
					(end 211.647024 -406.45334)
				)
				(arc
					(start 211.647024 -406.45334)
					(mid 211.68539 -406.425356)
					(end 211.704174 -406.381712)
				)
				(arc
					(start 211.704174 -406.381712)
					(mid 211.800586 -405.6063)
					(end 211.895436 -406.381966)
				)
				(xy 211.895436 -406.40889)
				(arc
					(start 211.892134 -406.412192)
					(mid 211.832808 -406.546017)
					(end 211.71408 -406.631648)
				)
				(arc
					(start 211.71408 -406.631648)
					(mid 211.687768 -406.640101)
					(end 211.66074 -406.645872)
				)
				(xy 211.657184 -406.649174) (xy 211.251546 -406.649174) (xy 211.251546 -406.750774) (xy 211.654898 -406.750774)
				(arc
					(start 211.6582 -406.754076)
					(mid 211.813432 -406.832778)
					(end 211.892134 -406.98801)
				)
				(xy 211.895436 -406.991312)
				(arc
					(start 211.895436 -407.017982)
					(mid 211.800586 -407.793709)
					(end 211.704174 -407.018236)
				)
				(arc
					(start 211.704174 -407.018236)
					(mid 211.67426 -406.963128)
					(end 211.615528 -406.941274)
				)
				(xy 211.251546 -406.941274)
				(arc
					(start 211.251546 -407.399998)
					(mid 211.800186 -407.948638)
					(end 212.348826 -407.399998)
				)
			)
		)
	)
	(zone
		(net "GND")
		(layer "B.Cu")
		(hatch none 0.5)
		(connect_pads
			(clearance 0.5)
		)
		(min_thickness 0.25)
		(fill yes
			(thermal_gap 0.5)
			(thermal_bridge_width 0.5)
			(island_removal_mode 0)
		)
		(polygon
			(pts
				(arc
					(start 63.947294 -168.401492)
					(mid 66.893866 -167.251412)
					(end 68.124324 -164.337492)
				)
				(xy 68.124324 -164.01288)
				(arc
					(start 74.304398 -164.01288)
					(mid 74.979884 -164.38556)
					(end 75.713336 -164.624766)
				)
				(arc
					(start 75.713336 -164.624766)
					(mid 75.428418 -165.652654)
					(end 75.41895 -166.71925)
				)
				(arc
					(start 75.41895 -166.71925)
					(mid 71.697046 -170.976599)
					(end 75.783948 -174.884842)
				)
				(arc
					(start 77.672438 -174.884842)
					(mid 77.773891 -175.550978)
					(end 77.983334 -176.191418)
				)
				(arc
					(start 77.942694 -176.292002)
					(mid 75.190615 -175.62039)
					(end 72.662288 -176.898046)
				)
				(arc
					(start 72.662288 -176.898046)
					(mid 72.187134 -176.663541)
					(end 71.685658 -176.492408)
				)
				(arc
					(start 71.685658 -176.492408)
					(mid 70.783654 -172.44944)
					(end 66.81343 -171.267628)
				)
			)
		)
	)
	(zone
		(net "P12V_A_VIN_U27")
		(layer "B.Cu")
		(hatch none 0.5)
		(connect_pads
			(clearance 0.5)
		)
		(min_thickness 0.25)
		(fill yes
			(thermal_gap 0.5)
			(thermal_bridge_width 0.5)
			(island_removal_mode 0)
		)
		(polygon
			(pts
				(xy 471.024204 -234.517184) (xy 470.551002 -234.990386) (xy 470.551002 -242.044728) (xy 470.662 -242.155726)
				(xy 472.028774 -242.155726) (xy 472.350338 -242.47729) (xy 472.350338 -244.049296) (xy 472.57843 -244.277388)
				(xy 473.766388 -244.277388) (xy 473.93733 -244.106446) (xy 473.93733 -237.37189) (xy 474.597984 -236.711236)
				(xy 474.597984 -234.517184)
			)
		)
		(polygon
			(pts
				(xy 473.8243 -242.6589) (xy 473.6211 -242.6589) (xy 473.6211 -242.8621) (xy 473.8243 -242.8621)
			)
		)
		(polygon
			(pts
				(xy 472.6813 -242.6589) (xy 472.4781 -242.6589) (xy 472.4781 -242.8621) (xy 472.6813 -242.8621)
			)
		)
		(polygon
			(pts
				(xy 473.4306 -238.0742) (xy 473.2274 -238.0742) (xy 473.2274 -238.2774) (xy 473.4306 -238.2774)
			)
		)
		(polygon
			(pts
				(xy 473.4306 -237.4646) (xy 473.2274 -237.4646) (xy 473.2274 -237.6678) (xy 473.4306 -237.6678)
			)
		)
	)
	(zone
		(net "P12V_A_COMP")
		(layer "B.Cu")
		(hatch none 0.5)
		(connect_pads
			(clearance 0.5)
		)
		(min_thickness 0.25)
		(fill yes
			(thermal_gap 0.5)
			(thermal_bridge_width 0.5)
			(island_removal_mode 0)
		)
		(polygon
			(pts
				(xy 159.539178 -149.45487) (xy 159.190436 -149.803612) (xy 159.190436 -154.204924) (xy 159.444182 -154.45867)
				(xy 165.116002 -154.45867) (xy 165.395402 -154.17927) (xy 165.395402 -150.453344) (xy 165.243002 -150.300944)
				(xy 163.523676 -150.300944) (xy 162.677602 -149.45487)
			)
		)
	)
	(zone
		(net "GND")
		(layer "B.Cu")
		(hatch none 0.5)
		(connect_pads
			(clearance 0.5)
		)
		(min_thickness 0.25)
		(fill yes
			(thermal_gap 0.5)
			(thermal_bridge_width 0.5)
			(island_removal_mode 0)
		)
		(polygon
			(pts
				(xy 163.26231 -227.825808) (xy 153.8732 -237.214918) (xy 153.8732 -239.2426) (xy 154.750008 -240.119408)
				(arc
					(start 165.888924 -240.119408)
					(mid 164.788588 -232.968092)
					(end 171.382436 -235.94695)
				)
				(arc
					(start 171.382436 -235.94695)
					(mid 172.362009 -235.898256)
					(end 173.325028 -236.08411)
				)
				(xy 173.325028 -230.87965) (xy 173.742604 -230.462074) (xy 173.742604 -229.754684) (xy 174.449994 -229.754684)
				(xy 174.669958 -229.53472) (xy 174.669958 -227.825808)
			)
		)
	)
	(zone
		(layer "B.Cu")
		(hatch none 0.5)
		(connect_pads
			(clearance 0)
		)
		(min_thickness 0.25)
		(keepout
			(tracks allowed)
			(vias allowed)
			(pads allowed)
			(copperpour allowed)
			(footprints not_allowed)
		)
		(placement
			(enabled no)
			(sheetname "")
		)
		(fill
			(thermal_gap 0.5)
			(thermal_bridge_width 0.5)
			(island_removal_mode 0)
		)
		(polygon
			(pts
				(arc
					(start 87.825072 -210.799934)
					(mid 127.824992 -250.799854)
					(end 167.824912 -210.799934)
				)
				(arc
					(start 167.824912 -210.799934)
					(mid 127.824992 -170.800014)
					(end 87.825072 -210.799934)
				)
			)
		)
	)
	(zone
		(layer "B.Cu")
		(hatch none 0.5)
		(connect_pads
			(clearance 0)
		)
		(min_thickness 0.25)
		(keepout
			(tracks not_allowed)
			(vias allowed)
			(pads allowed)
			(copperpour not_allowed)
			(footprints allowed)
		)
		(placement
			(enabled no)
			(sheetname "")
		)
		(fill
			(thermal_gap 0.5)
			(thermal_bridge_width 0.5)
			(island_removal_mode 0)
		)
		(polygon
			(pts
				(arc
					(start 279.236678 -357.156512)
					(mid 278.688038 -357.705152)
					(end 279.236678 -358.253792)
				)
				(xy 279.642824 -358.253792) (xy 279.644094 -358.252522)
				(arc
					(start 279.661874 -358.23271)
					(mid 279.700941 -358.162132)
					(end 279.714452 -358.082596)
				)
				(arc
					(start 279.714452 -357.832152)
					(mid 279.699573 -357.796231)
					(end 279.663652 -357.781352)
				)
				(arc
					(start 279.623012 -357.781352)
					(mid 278.842901 -357.705152)
					(end 279.623012 -357.628952)
				)
				(xy 279.695148 -357.628952)
				(arc
					(start 279.698196 -357.632)
					(mid 279.807273 -357.688531)
					(end 279.863804 -357.797608)
				)
				(xy 279.866852 -357.800656) (xy 279.866852 -358.114092)
				(arc
					(start 279.865582 -358.115616)
					(mid 279.852889 -358.186457)
					(end 279.827482 -358.253792)
				)
				(arc
					(start 279.978358 -358.253792)
					(mid 279.999443 -358.169602)
					(end 280.006552 -358.083104)
				)
				(xy 280.006552 -357.800656)
				(arc
					(start 280.0096 -357.797608)
					(mid 280.066131 -357.688531)
					(end 280.175208 -357.632)
				)
				(xy 280.178256 -357.628952)
				(arc
					(start 280.250392 -357.628952)
					(mid 281.030503 -357.705152)
					(end 280.250392 -357.781352)
				)
				(arc
					(start 280.209752 -357.781352)
					(mid 280.173831 -357.796231)
					(end 280.158952 -357.832152)
				)
				(xy 280.158952 -358.083104) (xy 280.158952 -358.1146)
				(arc
					(start 280.15819 -358.115362)
					(mid 280.151333 -358.185113)
					(end 280.137362 -358.253792)
				)
				(arc
					(start 280.636726 -358.253792)
					(mid 281.185366 -357.705152)
					(end 280.636726 -357.156512)
				)
				(xy 279.236932 -357.156512)
			)
		)
	)
	(zone
		(layer "B.Cu")
		(hatch none 0.5)
		(connect_pads
			(clearance 0)
		)
		(min_thickness 0.25)
		(keepout
			(tracks not_allowed)
			(vias allowed)
			(pads allowed)
			(copperpour not_allowed)
			(footprints allowed)
		)
		(placement
			(enabled no)
			(sheetname "")
		)
		(fill
			(thermal_gap 0.5)
			(thermal_bridge_width 0.5)
			(island_removal_mode 0)
		)
		(polygon
			(pts
				(arc
					(start 120.498616 -20.950428)
					(mid 119.950103 -20.401534)
					(end 119.401336 -20.950174)
				)
				(xy 119.401336 -21.408898)
				(arc
					(start 119.783606 -21.408898)
					(mid 119.833895 -21.388067)
					(end 119.854726 -21.337778)
				)
				(arc
					(start 119.854726 -21.33219)
					(mid 119.949976 -20.556462)
					(end 120.045226 -21.33219)
				)
				(xy 120.045226 -21.377148)
				(arc
					(start 120.04167 -21.380704)
					(mid 119.968592 -21.522764)
					(end 119.826532 -21.595842)
				)
				(xy 119.822976 -21.599398) (xy 119.43334 -21.599398) (xy 119.401336 -21.600668) (xy 119.401336 -21.700998)
				(xy 119.822976 -21.700998)
				(arc
					(start 119.826532 -21.704554)
					(mid 119.968592 -21.777632)
					(end 120.04167 -21.919692)
				)
				(xy 120.045226 -21.923248)
				(arc
					(start 120.045226 -21.968206)
					(mid 119.949976 -22.743934)
					(end 119.854726 -21.968206)
				)
				(arc
					(start 119.854726 -21.962618)
					(mid 119.833895 -21.912329)
					(end 119.783606 -21.891498)
				)
				(arc
					(start 119.43334 -21.891498)
					(mid 119.417235 -21.892356)
					(end 119.401336 -21.895054)
				)
				(arc
					(start 119.401336 -22.350222)
					(mid 119.949976 -22.898862)
					(end 120.498616 -22.350222)
				)
			)
		)
	)
	(zone
		(layer "B.Cu")
		(hatch none 0.5)
		(connect_pads
			(clearance 0)
		)
		(min_thickness 0.25)
		(keepout
			(tracks not_allowed)
			(vias allowed)
			(pads allowed)
			(copperpour not_allowed)
			(footprints allowed)
		)
		(placement
			(enabled no)
			(sheetname "")
		)
		(fill
			(thermal_gap 0.5)
			(thermal_bridge_width 0.5)
			(island_removal_mode 0)
		)
		(polygon
			(pts
				(arc
					(start 279.236678 -310.356504)
					(mid 278.688038 -310.905144)
					(end 279.236678 -311.453784)
				)
				(xy 279.642824 -311.453784) (xy 279.644094 -311.452514)
				(arc
					(start 279.661874 -311.432702)
					(mid 279.700941 -311.362124)
					(end 279.714452 -311.282588)
				)
				(arc
					(start 279.714452 -311.032144)
					(mid 279.699573 -310.996223)
					(end 279.663652 -310.981344)
				)
				(arc
					(start 279.623012 -310.981344)
					(mid 278.842901 -310.905144)
					(end 279.623012 -310.828944)
				)
				(xy 279.695148 -310.828944)
				(arc
					(start 279.698196 -310.831992)
					(mid 279.807273 -310.888523)
					(end 279.863804 -310.9976)
				)
				(xy 279.866852 -311.000648) (xy 279.866852 -311.314084)
				(arc
					(start 279.865582 -311.315608)
					(mid 279.852889 -311.386449)
					(end 279.827482 -311.453784)
				)
				(arc
					(start 279.978358 -311.453784)
					(mid 279.999443 -311.369594)
					(end 280.006552 -311.283096)
				)
				(xy 280.006552 -311.000648)
				(arc
					(start 280.0096 -310.9976)
					(mid 280.066131 -310.888523)
					(end 280.175208 -310.831992)
				)
				(xy 280.178256 -310.828944)
				(arc
					(start 280.250392 -310.828944)
					(mid 281.030503 -310.905144)
					(end 280.250392 -310.981344)
				)
				(arc
					(start 280.209752 -310.981344)
					(mid 280.173831 -310.996223)
					(end 280.158952 -311.032144)
				)
				(xy 280.158952 -311.283096) (xy 280.158952 -311.314592)
				(arc
					(start 280.15819 -311.315354)
					(mid 280.151333 -311.385105)
					(end 280.137362 -311.453784)
				)
				(arc
					(start 280.636726 -311.453784)
					(mid 281.185366 -310.905144)
					(end 280.636726 -310.356504)
				)
				(xy 279.236932 -310.356504)
			)
		)
	)
	(zone
		(net "P12V_A")
		(layer "B.Cu")
		(hatch none 0.5)
		(connect_pads
			(clearance 0.5)
		)
		(min_thickness 0.25)
		(fill yes
			(thermal_gap 0.5)
			(thermal_bridge_width 0.5)
			(island_removal_mode 0)
		)
		(polygon
			(pts
				(xy 254.889 -363.855) (xy 252.603 -366.141) (xy 252.603 -368.173) (xy 253.238 -368.808) (xy 274.066 -368.808)
				(xy 274.574 -369.316) (xy 274.574 -370.81714) (xy 274.22348 -371.16766) (xy 252.92304 -371.16766)
				(xy 252.598682 -371.492018) (xy 252.598682 -377.096782) (xy 252.82144 -377.31954) (xy 274.37842 -377.31954)
				(xy 274.828 -377.76912) (xy 274.828 -408.836622) (xy 276.026626 -410.035248) (xy 289.047428 -410.035248)
				(xy 291.079682 -408.002994) (xy 291.079682 -370.775738) (xy 291.050472 -370.746528) (xy 291.050472 -366.463072)
				(xy 288.4424 -363.855)
			)
		)
	)
	(zone
		(layer "B.Cu")
		(hatch none 0.5)
		(connect_pads
			(clearance 0)
		)
		(min_thickness 0.25)
		(keepout
			(tracks not_allowed)
			(vias allowed)
			(pads allowed)
			(copperpour not_allowed)
			(footprints allowed)
		)
		(placement
			(enabled no)
			(sheetname "")
		)
		(fill
			(thermal_gap 0.5)
			(thermal_bridge_width 0.5)
			(island_removal_mode 0)
		)
		(polygon
			(pts
				(arc
					(start 281.07386 -154.147266)
					(mid 281.397456 -153.17597)
					(end 280.42616 -152.852374)
				)
				(arc
					(start 279.487122 -153.321766)
					(mid 279.638469 -153.405576)
					(end 279.768554 -153.519632)
				)
				(xy 279.781762 -153.52395) (xy 279.832308 -153.624026) (xy 279.849834 -153.659332) (xy 279.867614 -153.694384)
				(xy 279.867614 -153.694638)
				(arc
					(start 279.892506 -153.744422)
					(mid 279.932791 -153.779418)
					(end 279.985978 -153.775664)
				)
				(arc
					(start 280.226516 -153.655268)
					(mid 281.23834 -153.255394)
					(end 280.31186 -153.825702)
				)
				(xy 280.071322 -153.945844) (xy 280.036016 -153.963624)
				(arc
					(start 280.03119 -153.9621)
					(mid 279.872501 -153.960087)
					(end 279.744424 -153.866342)
				)
				(xy 279.739598 -153.864818) (xy 279.722072 -153.829766) (xy 279.722072 -153.829512) (xy 279.679654 -153.744676)
				(arc
					(start 279.634696 -153.655522)
					(mid 279.450574 -153.514701)
					(end 279.227534 -153.45156)
				)
				(xy 279.028906 -153.550874) (xy 279.213056 -153.550874)
				(arc
					(start 279.214834 -153.552398)
					(mid 279.379517 -153.593608)
					(end 279.52192 -153.686002)
				)
				(xy 279.539192 -153.69159) (xy 279.623774 -153.8605) (xy 279.640792 -153.877518) (xy 279.640792 -153.894282)
				(xy 279.648412 -153.909522)
				(arc
					(start 279.646634 -153.914348)
					(mid 279.644931 -154.073082)
					(end 279.551384 -154.201368)
				)
				(xy 279.54986 -154.206194) (xy 279.514554 -154.22372)
				(arc
					(start 279.273508 -154.34437)
					(mid 278.261684 -154.744244)
					(end 279.188164 -154.173936)
				)
				(arc
					(start 279.42921 -154.05354)
					(mid 279.462054 -154.018865)
					(end 279.46477 -153.971244)
				)
				(xy 279.450292 -153.956512) (xy 279.450292 -153.939494)
				(arc
					(start 279.393904 -153.826972)
					(mid 279.291818 -153.763537)
					(end 279.173686 -153.741374)
				)
				(xy 278.647906 -153.741374) (xy 278.426418 -153.852118)
				(arc
					(start 278.426418 -153.852372)
					(mid 278.102619 -154.823516)
					(end 279.073864 -155.147264)
				)
			)
		)
	)
	(zone
		(layer "B.Cu")
		(hatch none 0.5)
		(connect_pads
			(clearance 0)
		)
		(min_thickness 0.25)
		(keepout
			(tracks not_allowed)
			(vias allowed)
			(pads allowed)
			(copperpour not_allowed)
			(footprints allowed)
		)
		(placement
			(enabled no)
			(sheetname "")
		)
		(fill
			(thermal_gap 0.5)
			(thermal_bridge_width 0.5)
			(island_removal_mode 0)
		)
		(polygon
			(pts
				(arc
					(start 337.674966 -92.799916)
					(mid 330.67498 -85.79993)
					(end 323.674994 -92.799916)
				)
				(arc
					(start 323.674994 -98.799904)
					(mid 330.67498 -105.79989)
					(end 337.674966 -98.799904)
				)
			)
		)
	)
	(zone
		(net "P12V_A_COMP")
		(layer "B.Cu")
		(hatch none 0.5)
		(connect_pads
			(clearance 0.5)
		)
		(min_thickness 0.25)
		(fill yes
			(thermal_gap 0.5)
			(thermal_bridge_width 0.5)
			(island_removal_mode 0)
		)
		(polygon
			(pts
				(xy 230.461566 -1.016) (xy 225.348038 -6.129528) (xy 225.348038 -11.32205) (xy 224.671636 -11.998452)
				(xy 220.855286 -11.998452) (xy 220.458792 -12.394946) (xy 220.458792 -19.880834) (xy 221.997778 -21.41982)
				(xy 232.399078 -21.41982) (xy 234.254802 -19.564096) (xy 234.254802 -9.889998) (xy 235.9406 -8.2042)
				(xy 242.6462 -8.2042) (xy 243.6876 -7.1628) (xy 243.6876 -2.3114) (xy 242.3922 -1.016)
			)
		)
	)
	(zone
		(layer "B.Cu")
		(hatch none 0.5)
		(connect_pads
			(clearance 0)
		)
		(min_thickness 0.25)
		(keepout
			(tracks allowed)
			(vias allowed)
			(pads allowed)
			(copperpour allowed)
			(footprints not_allowed)
		)
		(placement
			(enabled no)
			(sheetname "")
		)
		(fill
			(thermal_gap 0.5)
			(thermal_bridge_width 0.5)
			(island_removal_mode 0)
		)
		(polygon
			(pts
				(arc
					(start 21.575014 -9.19988)
					(mid 26.325068 -13.949934)
					(end 31.075122 -9.19988)
				)
				(arc
					(start 31.075122 -9.19988)
					(mid 26.325068 -4.449826)
					(end 21.575014 -9.19988)
				)
			)
		)
	)
	(zone
		(layer "B.Cu")
		(hatch none 0.5)
		(connect_pads
			(clearance 0)
		)
		(min_thickness 0.25)
		(keepout
			(tracks not_allowed)
			(vias allowed)
			(pads allowed)
			(copperpour not_allowed)
			(footprints allowed)
		)
		(placement
			(enabled no)
			(sheetname "")
		)
		(fill
			(thermal_gap 0.5)
			(thermal_bridge_width 0.5)
			(island_removal_mode 0)
		)
		(polygon
			(pts
				(arc
					(start 131.298696 -20.950428)
					(mid 130.750183 -20.401534)
					(end 130.201416 -20.950174)
				)
				(arc
					(start 130.201416 -22.350222)
					(mid 130.750056 -22.898862)
					(end 131.298696 -22.350222)
				)
				(arc
					(start 131.298696 -21.895054)
					(mid 131.282795 -21.892375)
					(end 131.266692 -21.891498)
				)
				(arc
					(start 130.916426 -21.891498)
					(mid 130.866137 -21.912329)
					(end 130.845306 -21.962618)
				)
				(arc
					(start 130.845306 -21.968206)
					(mid 130.750056 -22.743934)
					(end 130.654806 -21.968206)
				)
				(xy 130.654806 -21.923248)
				(arc
					(start 130.658362 -21.919692)
					(mid 130.73144 -21.777632)
					(end 130.8735 -21.704554)
				)
				(xy 130.877056 -21.700998) (xy 131.298696 -21.700998) (xy 131.298696 -21.600668) (xy 131.266692 -21.599398)
				(xy 130.877056 -21.599398)
				(arc
					(start 130.8735 -21.595842)
					(mid 130.73144 -21.522764)
					(end 130.658362 -21.380704)
				)
				(xy 130.654806 -21.377148)
				(arc
					(start 130.654806 -21.33219)
					(mid 130.750056 -20.556462)
					(end 130.845306 -21.33219)
				)
				(arc
					(start 130.845306 -21.337778)
					(mid 130.866137 -21.388067)
					(end 130.916426 -21.408898)
				)
				(xy 131.298696 -21.408898)
			)
		)
	)
	(zone
		(layer "B.Cu")
		(hatch none 0.5)
		(connect_pads
			(clearance 0)
		)
		(min_thickness 0.25)
		(keepout
			(tracks allowed)
			(vias allowed)
			(pads allowed)
			(copperpour allowed)
			(footprints allowed)
		)
		(placement
			(enabled no)
			(sheetname "")
		)
		(fill
			(thermal_gap 0.5)
			(thermal_bridge_width 0.5)
			(island_removal_mode 0)
		)
		(polygon
			(pts
				(xy 33.822386 -143.546576) (xy 33.822386 -141.395704) (xy 41.987724 -141.395704) (xy 41.987724 -143.546576)
			)
		)
	)
	(zone
		(net "GND")
		(layer "B.Cu")
		(hatch none 0.5)
		(connect_pads
			(clearance 0.5)
		)
		(min_thickness 0.25)
		(fill yes
			(thermal_gap 0.5)
			(thermal_bridge_width 0.5)
			(island_removal_mode 0)
		)
		(polygon
			(pts
				(arc
					(start 199.926956 -331.293216)
					(mid 200.562728 -331.130987)
					(end 201.21626 -331.07249)
				)
				(xy 204.5716 -320.013838) (xy 204.5716 -319.0748)
				(arc
					(start 203.51877 -318.02197)
					(mid 202.046978 -317.388784)
					(end 200.931272 -316.23889)
				)
				(arc
					(start 200.931272 -316.23889)
					(mid 199.702401 -313.956398)
					(end 200.092056 -311.393586)
				)
				(arc
					(start 200.092056 -311.393586)
					(mid 196.686699 -310.553958)
					(end 195.183252 -307.385212)
				)
				(arc
					(start 195.183252 -306.318412)
					(mid 195.184604 -306.214746)
					(end 195.188586 -306.111148)
				)
				(arc
					(start 195.188586 -306.111148)
					(mid 194.243916 -304.757709)
					(end 193.910966 -303.141126)
				)
				(arc
					(start 193.910966 -299.839126)
					(mid 193.913795 -299.688782)
					(end 193.922142 -299.538644)
				)
				(arc
					(start 193.922142 -299.538644)
					(mid 192.140491 -300.509726)
					(end 190.11138 -300.505114)
				)
				(arc
					(start 190.11138 -300.505114)
					(mid 189.618 -301.985054)
					(end 188.60643 -303.172622)
				)
				(arc
					(start 188.60643 -303.172622)
					(mid 189.914585 -304.690186)
					(end 190.431166 -306.626006)
				)
				(arc
					(start 190.431166 -306.626006)
					(mid 190.007379 -313.249367)
					(end 183.858662 -310.75122)
				)
				(arc
					(start 183.858662 -310.75122)
					(mid 183.433025 -310.495706)
					(end 183.038242 -310.194706)
				)
				(arc
					(start 183.038242 -310.194706)
					(mid 178.666636 -308.623707)
					(end 178.583082 -303.979072)
				)
				(arc
					(start 178.583082 -303.979072)
					(mid 176.713508 -298.586236)
					(end 182.055516 -296.57548)
				)
				(arc
					(start 182.055516 -296.57548)
					(mid 182.35522 -295.68965)
					(end 182.84825 -294.895016)
				)
				(arc
					(start 182.84825 -294.895016)
					(mid 182.191436 -293.699757)
					(end 181.964076 -292.355016)
				)
				(arc
					(start 181.964076 -289.815016)
					(mid 182.034405 -289.059718)
					(end 182.242968 -288.330386)
				)
				(arc
					(start 182.242968 -288.330386)
					(mid 181.449976 -287.409541)
					(end 180.962554 -286.296354)
				)
				(xy 180.594 -285.9278) (xy 179.197 -285.9278) (xy 179.07 -286.0548)
				(arc
					(start 179.07 -286.50311)
					(mid 180.443816 -288.971605)
					(end 179.889912 -291.74186)
				)
				(arc
					(start 179.889912 -291.74186)
					(mid 178.211752 -296.197897)
					(end 173.452536 -296.04589)
				)
				(arc
					(start 173.452536 -296.04589)
					(mid 171.716232 -298.181525)
					(end 169.019728 -298.73321)
				)
				(arc
					(start 169.019728 -298.73321)
					(mid 169.347059 -300.474092)
					(end 168.907714 -302.19015)
				)
				(arc
					(start 168.907714 -302.19015)
					(mid 168.058065 -307.034438)
					(end 163.168076 -307.560218)
				)
				(arc
					(start 163.168076 -307.560218)
					(mid 163.400217 -310.129698)
					(end 162.04819 -312.327036)
				)
				(arc
					(start 162.04819 -312.327036)
					(mid 167.219488 -315.399086)
					(end 169.9514 -320.757804)
				)
				(arc
					(start 169.9514 -320.757804)
					(mid 172.744842 -324.533954)
					(end 170.145964 -328.446638)
				)
				(arc
					(start 170.145964 -328.794364)
					(mid 167.944041 -335.337014)
					(end 162.234372 -339.217)
				)
				(arc
					(start 156.415232 -339.217)
					(mid 150.705586 -335.336997)
					(end 148.50364 -328.794364)
				)
				(arc
					(start 148.50364 -322.799964)
					(mid 150.070464 -317.191508)
					(end 154.317192 -313.207146)
				)
				(arc
					(start 154.317192 -313.207146)
					(mid 153.48253 -312.606315)
					(end 152.82418 -311.816242)
				)
				(arc
					(start 152.82418 -311.816242)
					(mid 148.125284 -311.823445)
					(end 146.520408 -307.407056)
				)
				(arc
					(start 146.520408 -307.407056)
					(mid 146.395628 -305.636083)
					(end 147.03298 -303.979072)
				)
				(arc
					(start 147.03298 -303.979072)
					(mid 145.504172 -302.652233)
					(end 144.798796 -300.754796)
				)
				(xy 144.272 -300.228) (xy 139.8016 -300.228)
				(arc
					(start 137.447274 -302.582326)
					(mid 135.665088 -307.816313)
					(end 130.296666 -306.492402)
				)
				(arc
					(start 129.058162 -306.492402)
					(mid 128.145531 -306.389312)
					(end 127.278892 -306.08524)
				)
				(arc
					(start 127.278892 -306.08524)
					(mid 126.865827 -308.779498)
					(end 124.968762 -310.736742)
				)
				(arc
					(start 124.968762 -310.736742)
					(mid 120.536008 -313.816441)
					(end 116.909088 -309.81904)
				)
				(arc
					(start 116.909088 -309.81904)
					(mid 114.917344 -307.21132)
					(end 115.482878 -303.979072)
				)
				(arc
					(start 115.482878 -303.979072)
					(mid 114.011146 -302.732522)
					(end 113.274348 -300.950122)
				)
				(arc
					(start 113.274348 -300.950122)
					(mid 110.303334 -300.694284)
					(end 108.295694 -298.48937)
				)
				(arc
					(start 108.295694 -298.48937)
					(mid 106.66775 -298.562234)
					(end 105.055416 -298.325794)
				)
				(arc
					(start 105.055416 -298.325794)
					(mid 104.947676 -298.511116)
					(end 104.830372 -298.690538)
				)
				(arc
					(start 104.830372 -298.690538)
					(mid 105.353644 -299.214222)
					(end 105.773982 -299.823632)
				)
				(arc
					(start 105.773982 -299.823632)
					(mid 107.220665 -303.10349)
					(end 105.527856 -306.263294)
				)
				(arc
					(start 105.527856 -306.263294)
					(mid 109.97874 -310.519436)
					(end 105.166668 -314.362338)
				)
				(arc
					(start 105.166668 -314.362338)
					(mid 104.897822 -315.069019)
					(end 104.503474 -315.714126)
				)
				(arc
					(start 104.503474 -315.714126)
					(mid 106.463941 -319.018676)
					(end 107.14609 -322.799964)
				)
				(arc
					(start 107.14609 -328.794364)
					(mid 106.924038 -330.975257)
					(end 106.266996 -333.066644)
				)
				(arc
					(start 106.266996 -333.066644)
					(mid 108.746145 -336.111326)
					(end 107.518962 -339.841078)
				)
				(arc
					(start 107.518962 -339.841078)
					(mid 108.42873 -340.535204)
					(end 109.110526 -341.454232)
				)
				(arc
					(start 109.110526 -341.454232)
					(mid 109.379592 -341.711219)
					(end 109.624368 -341.991442)
				)
				(xy 109.716062 -342.05672)
				(arc
					(start 109.716062 -342.08593)
					(mid 111.257109 -344.401936)
					(end 110.96117 -347.167962)
				)
				(xy 101.426772 -347.167962) (xy 101.426772 -343.357708)
				(arc
					(start 101.42728 -343.357708)
					(mid 101.774915 -341.757406)
					(end 102.722426 -340.421722)
				)
				(arc
					(start 102.722426 -340.421722)
					(mid 101.713838 -339.623871)
					(end 101.002846 -338.552282)
				)
				(arc
					(start 101.002846 -338.552282)
					(mid 90.559563 -337.951899)
					(end 85.503766 -328.794364)
				)
				(arc
					(start 85.503766 -322.799964)
					(mid 87.01203 -317.289295)
					(end 91.116404 -313.314842)
				)
				(arc
					(start 91.116404 -313.314842)
					(mid 89.901768 -312.227066)
					(end 89.20861 -310.75122)
				)
				(arc
					(start 89.20861 -310.75122)
					(mid 88.782973 -310.495706)
					(end 88.38819 -310.194706)
				)
				(arc
					(start 88.38819 -310.194706)
					(mid 86.117698 -310.143842)
					(end 84.224368 -308.889654)
				)
				(arc
					(start 84.224368 -308.889654)
					(mid 80.238481 -313.13074)
					(end 76.047092 -309.0926)
				)
				(arc
					(start 74.395584 -309.0926)
					(mid 73.758797 -309.288464)
					(end 73.09866 -309.37835)
				)
				(arc
					(start 73.09866 -309.37835)
					(mid 68.694504 -316.021652)
					(end 69.739256 -308.11978)
				)
				(arc
					(start 69.739256 -308.11978)
					(mid 68.391878 -307.550836)
					(end 67.330828 -306.544218)
				)
				(xy 67.206876 -306.545996)
				(arc
					(start 65.936876 -306.545996)
					(mid 65.041259 -306.446748)
					(end 64.189102 -306.15382)
				)
				(arc
					(start 64.189102 -306.15382)
					(mid 64.216301 -306.389359)
					(end 64.231012 -306.626006)
				)
				(arc
					(start 64.231012 -306.626006)
					(mid 63.807225 -313.249367)
					(end 57.658508 -310.75122)
				)
				(arc
					(start 57.658508 -310.75122)
					(mid 57.232871 -310.495706)
					(end 56.838088 -310.194706)
				)
				(arc
					(start 56.838088 -310.194706)
					(mid 52.466482 -308.623707)
					(end 52.382928 -303.979072)
				)
				(arc
					(start 52.382928 -303.979072)
					(mid 50.513354 -298.586236)
					(end 55.855362 -296.57548)
				)
				(arc
					(start 55.855362 -296.57548)
					(mid 56.155122 -295.689359)
					(end 56.64835 -294.894508)
				)
				(arc
					(start 56.64835 -294.894508)
					(mid 55.868102 -293.269174)
					(end 55.862474 -291.46627)
				)
				(arc
					(start 55.862474 -291.46627)
					(mid 55.690243 -289.90523)
					(end 56.119014 -288.394394)
				)
				(arc
					(start 56.119014 -288.394394)
					(mid 55.099379 -287.149921)
					(end 54.638448 -285.608522)
				)
				(arc
					(start 54.337966 -285.30804)
					(mid 54.238935 -285.311652)
					(end 54.139846 -285.312866)
				)
				(arc
					(start 51.173126 -285.312866)
					(mid 50.907064 -285.64482)
					(end 50.607976 -285.947358)
				)
				(arc
					(start 50.606198 -285.985712)
					(mid 52.562161 -287.576009)
					(end 53.21427 -290.011104)
				)
				(arc
					(start 53.21427 -290.011104)
					(mid 53.304016 -295.44584)
					(end 47.9171 -296.170858)
				)
				(arc
					(start 47.9171 -296.170858)
					(mid 45.98929 -298.315107)
					(end 43.125898 -298.654724)
				)
				(arc
					(start 43.125898 -298.654724)
					(mid 43.090371 -298.993083)
					(end 43.026838 -299.327316)
				)
				(arc
					(start 43.026838 -299.327316)
					(mid 43.171256 -300.845794)
					(end 42.749216 -302.311562)
				)
				(arc
					(start 42.749216 -302.311562)
					(mid 42.78732 -305.809887)
					(end 40.1066 -308.057804)
				)
				(arc
					(start 40.1066 -308.831234)
					(mid 41.739516 -311.721995)
					(end 40.690038 -314.871862)
				)
				(arc
					(start 40.690038 -314.871862)
					(mid 43.244619 -318.475613)
					(end 44.146216 -322.799964)
				)
				(arc
					(start 44.146216 -328.794364)
					(mid 35.949622 -339.29242)
					(end 23.77694 -333.88681)
				)
				(arc
					(start 23.77694 -333.88681)
					(mid 21.883047 -335.236321)
					(end 19.580352 -335.561432)
				)
				(arc
					(start 19.580352 -335.561432)
					(mid 18.086007 -337.768498)
					(end 15.580614 -338.678012)
				)
				(arc
					(start 15.580614 -338.678012)
					(mid 15.053471 -341.5666)
					(end 12.72667 -343.357708)
				)
				(arc
					(start 12.732766 -343.357708)
					(mid 11.561572 -343.528899)
					(end 10.390378 -343.357708)
				)
				(arc
					(start 10.396474 -343.357708)
					(mid 10.331661 -343.337798)
					(end 10.267188 -343.316814)
				)
				(xy 10.259822 -343.316306) (xy 10.229088 -343.305892)
				(arc
					(start 10.125456 -343.305892)
					(mid 6.455657 -338.698745)
					(end 11.195304 -335.201514)
				)
				(arc
					(start 11.195304 -335.201514)
					(mid 12.023065 -331.709793)
					(end 15.204186 -330.049124)
				)
				(arc
					(start 15.204186 -330.049124)
					(mid 17.887523 -326.290247)
					(end 22.503892 -326.428608)
				)
				(arc
					(start 22.503892 -322.799964)
					(mid 23.679076 -317.895613)
					(end 26.9494 -314.056522)
				)
				(arc
					(start 26.9494 -312.41365)
					(mid 26.433105 -311.630945)
					(end 26.10866 -310.75122)
				)
				(arc
					(start 26.10866 -310.75122)
					(mid 25.683023 -310.495706)
					(end 25.28824 -310.194706)
				)
				(arc
					(start 25.28824 -310.194706)
					(mid 20.916634 -308.623707)
					(end 20.83308 -303.979072)
				)
				(arc
					(start 20.83308 -303.979072)
					(mid 18.963506 -298.586236)
					(end 24.305514 -296.57548)
				)
				(arc
					(start 24.305514 -296.57548)
					(mid 24.605218 -295.68965)
					(end 25.098248 -294.895016)
				)
				(arc
					(start 25.098248 -294.895016)
					(mid 24.441434 -293.699757)
					(end 24.214074 -292.355016)
				)
				(arc
					(start 24.214074 -289.815016)
					(mid 24.284403 -289.059718)
					(end 24.492966 -288.330386)
				)
				(arc
					(start 24.492966 -288.330386)
					(mid 23.521631 -287.096299)
					(end 23.086822 -285.587186)
				)
				(arc
					(start 22.806406 -285.307024)
					(mid 22.698241 -285.311374)
					(end 22.589998 -285.312866)
				)
				(arc
					(start 20.258786 -285.312866)
					(mid 20.173824 -285.543719)
					(end 20.075144 -285.76905)
				)
				(arc
					(start 20.075144 -285.76905)
					(mid 22.406483 -287.979059)
					(end 22.422612 -291.191442)
				)
				(arc
					(start 22.422612 -291.191442)
					(mid 21.250919 -295.938206)
					(end 16.367252 -296.170858)
				)
				(arc
					(start 16.367252 -296.170858)
					(mid 15.204372 -297.801692)
					(end 13.406628 -298.68495)
				)
				(arc
					(start 13.406628 -298.68495)
					(mid 12.813676 -300.284558)
					(end 11.619738 -301.50308)
				)
				(arc
					(start 11.619738 -301.50308)
					(mid 11.448589 -303.802734)
					(end 10.06094 -305.64455)
				)
				(xy 10.06094 -307.362352)
				(arc
					(start 10.065258 -307.364892)
					(mid 13.692392 -309.666213)
					(end 13.262356 -313.94019)
				)
				(arc
					(start 13.262356 -313.94019)
					(mid 9.843758 -316.517033)
					(end 5.99948 -314.633356)
				)
				(xy 2.032 -314.633356) (xy 2.032 -279.383744)
				(arc
					(start 6.820154 -279.383744)
					(mid 7.426534 -279.433784)
					(end 8.01878 -279.573228)
				)
				(arc
					(start 8.01878 -279.573228)
					(mid 10.018229 -280.290365)
					(end 11.388344 -281.913584)
				)
				(arc
					(start 11.388344 -281.913584)
					(mid 11.84801 -281.789317)
					(end 12.319 -281.719274)
				)
				(arc
					(start 12.319 -281.719274)
					(mid 12.329688 -280.644463)
					(end 12.61999 -279.60955)
				)
				(arc
					(start 12.61999 -279.60955)
					(mid 10.293075 -273.031132)
					(end 17.209516 -273.954494)
				)
				(arc
					(start 17.209516 -273.954494)
					(mid 18.751039 -273.534726)
					(end 20.335748 -273.737578)
				)
				(arc
					(start 20.335748 -273.737578)
					(mid 21.817287 -271.594954)
					(end 24.291798 -270.781018)
				)
				(arc
					(start 24.291798 -270.781018)
					(mid 24.12699 -267.717957)
					(end 26.053796 -265.331194)
				)
				(arc
					(start 26.053796 -265.331194)
					(mid 32.257399 -262.570662)
					(end 32.468566 -269.357348)
				)
				(arc
					(start 32.468566 -269.357348)
					(mid 32.365188 -270.022989)
					(end 32.158686 -270.664178)
				)
				(xy 32.192468 -270.763492)
				(arc
					(start 35.460686 -270.763492)
					(mid 37.169429 -264.81867)
					(end 42.433748 -261.570978)
				)
				(xy 42.433748 -260.280404)
				(arc
					(start 36.5252 -260.280404)
					(mid 32.929227 -261.228985)
					(end 30.051502 -258.873244)
				)
				(arc
					(start 30.051502 -258.873244)
					(mid 29.7853 -258.802616)
					(end 29.524452 -258.71424)
				)
				(arc
					(start 29.524452 -258.71424)
					(mid 28.947665 -258.750384)
					(end 28.371546 -258.704842)
				)
				(xy 26.225246 -258.704842) (xy 25.598628 -258.078224) (xy 24.509476 -258.078224) (xy 24.509476 -256.989072)
				(arc
					(start 24.031702 -256.511298)
					(mid 23.491686 -256.622895)
					(end 22.941534 -256.660396)
				)
				(arc
					(start 20.854416 -256.660396)
					(mid 20.209002 -256.71132)
					(end 19.563588 -256.660396)
				)
				(arc
					(start 17.93494 -256.660396)
					(mid 16.379534 -256.350989)
					(end 15.06093 -255.469898)
				)
				(xy 14.563852 -254.973074) (xy 11.876278 -254.973074) (xy 11.876278 -252.287024) (xy 11.618976 -252.287024)
				(arc
					(start 11.618976 -251.856494)
					(mid 10.686716 -249.3151)
					(end 11.545824 -246.748046)
				)
				(xy 11.545824 -243.43995) (xy 11.618976 -243.366798) (xy 11.618976 -241.336576) (xy 13.649198 -241.336576)
				(xy 13.650976 -241.334798) (xy 13.650976 -241.311176) (xy 13.674598 -241.311176) (xy 13.965428 -241.020346)
				(arc
					(start 14.55166 -241.020346)
					(mid 15.767963 -240.331987)
					(end 17.145 -240.093246)
				)
				(arc
					(start 18.415 -240.093246)
					(mid 19.792037 -240.331988)
					(end 21.00834 -241.020346)
				)
				(arc
					(start 27.216608 -241.020346)
					(mid 28.171075 -240.232609)
					(end 29.317442 -239.766348)
				)
				(xy 29.993844 -239.089946) (xy 38.611556 -239.089946) (xy 39.735506 -240.213896) (xy 42.456862 -240.213896)
				(xy 42.456862 -237.498382) (xy 43.598338 -236.356906) (xy 43.598338 -235.914438) (xy 44.040806 -235.914438)
				(xy 45.006514 -234.94873)
				(arc
					(start 46.709838 -234.94873)
					(mid 48.832603 -230.892965)
					(end 53.387752 -231.346248)
				)
				(arc
					(start 53.387752 -231.346248)
					(mid 60.677093 -232.904934)
					(end 54.8132 -237.506764)
				)
				(arc
					(start 54.8132 -240.04905)
					(mid 54.928977 -240.044106)
					(end 55.044848 -240.042446)
				)
				(arc
					(start 56.314848 -240.042446)
					(mid 56.907063 -240.085536)
					(end 57.486804 -240.213896)
				)
				(xy 59.379358 -240.213896) (xy 63.008256 -243.842794)
				(arc
					(start 63.008256 -246.96166)
					(mid 63.29901 -247.179201)
					(end 63.569342 -247.421654)
				)
				(arc
					(start 63.569342 -247.421654)
					(mid 64.070765 -247.395414)
					(end 64.571626 -247.430798)
				)
				(arc
					(start 64.571626 -247.430798)
					(mid 66.152967 -245.905692)
					(end 68.295266 -245.418864)
				)
				(arc
					(start 68.295266 -245.418864)
					(mid 73.199071 -247.792477)
					(end 71.394066 -252.932946)
				)
				(arc
					(start 71.394066 -252.932946)
					(mid 75.042898 -255.321383)
					(end 74.463148 -259.643626)
				)
				(arc
					(start 74.463148 -259.643626)
					(mid 75.269405 -260.986083)
					(end 75.512168 -262.53313)
				)
				(arc
					(start 75.512168 -262.53313)
					(mid 75.578183 -263.658252)
					(end 75.334622 -264.758678)
				)
				(arc
					(start 75.334622 -264.758678)
					(mid 77.499292 -265.610655)
					(end 78.84922 -267.50518)
				)
				(arc
					(start 78.84922 -267.50518)
					(mid 80.700995 -268.801494)
					(end 81.581498 -270.88338)
				)
				(xy 86.299548 -270.88338)
				(arc
					(start 86.374224 -270.884142)
					(mid 86.873272 -270.788568)
					(end 87.380318 -270.755618)
				)
				(arc
					(start 87.380318 -270.755618)
					(mid 87.101178 -268.201822)
					(end 88.334342 -265.94816)
				)
				(arc
					(start 88.334342 -265.94816)
					(mid 86.45977 -258.776501)
					(end 93.161104 -261.944866)
				)
				(arc
					(start 93.161104 -261.944866)
					(mid 97.073134 -264.771557)
					(end 95.568516 -269.357348)
				)
				(arc
					(start 95.568516 -269.357348)
					(mid 95.471609 -269.995121)
					(end 95.279972 -270.611092)
				)
				(arc
					(start 101.962712 -270.611092)
					(mid 103.30916 -263.999537)
					(end 108.99013 -267.6398)
				)
				(arc
					(start 110.915196 -267.6398)
					(mid 111.548148 -267.452548)
					(end 112.202976 -267.369544)
				)
				(arc
					(start 112.202976 -267.369544)
					(mid 113.097783 -267.040053)
					(end 114.04473 -266.928092)
				)
				(arc
					(start 119.123714 -266.928092)
					(mid 119.807028 -266.024151)
					(end 120.703594 -265.331194)
				)
				(arc
					(start 120.703594 -265.331194)
					(mid 123.30404 -262.202469)
					(end 127.318008 -262.865362)
				)
				(arc
					(start 127.318008 -262.865362)
					(mid 126.937725 -261.457296)
					(end 127.075692 -260.005322)
				)
				(xy 127.075692 -252.875542)
				(arc
					(start 139.468098 -240.482882)
					(mid 140.022235 -236.789937)
					(end 143.3449 -235.085636)
				)
				(arc
					(start 144.6149 -235.085636)
					(mid 144.736619 -235.087379)
					(end 144.858232 -235.092748)
				)
				(xy 150.967694 -228.983286)
				(arc
					(start 150.967694 -228.170232)
					(mid 147.360139 -226.696454)
					(end 146.624548 -222.869506)
				)
				(arc
					(start 146.624548 -222.869506)
					(mid 147.498759 -220.321579)
					(end 149.767798 -218.869768)
				)
				(arc
					(start 149.767798 -218.869768)
					(mid 149.063113 -217.228464)
					(end 148.638006 -215.4936)
				)
				(arc
					(start 141.014958 -215.4936)
					(mid 127.650367 -224.799049)
					(end 114.521996 -215.163146)
				)
				(arc
					(start 114.521996 -215.163146)
					(mid 113.751772 -215.397841)
					(end 112.950498 -215.47709)
				)
				(arc
					(start 111.949738 -215.47709)
					(mid 108.43052 -213.472014)
					(end 108.360972 -209.422238)
				)
				(arc
					(start 108.360972 -209.422238)
					(mid 108.430457 -205.372425)
					(end 111.949738 -203.367386)
				)
				(arc
					(start 112.950498 -203.367386)
					(mid 114.278292 -203.58895)
					(end 115.462304 -204.229462)
				)
				(arc
					(start 115.462304 -204.229462)
					(mid 118.298058 -200.541051)
					(end 122.185938 -197.985634)
				)
				(arc
					(start 122.185938 -197.985634)
					(mid 121.286125 -196.98729)
					(end 120.758458 -195.751196)
				)
				(arc
					(start 120.758458 -195.751196)
					(mid 120.332821 -195.495682)
					(end 119.938038 -195.194682)
				)
				(arc
					(start 119.938038 -195.194682)
					(mid 115.566432 -193.623683)
					(end 115.482878 -188.979048)
				)
				(arc
					(start 115.482878 -188.979048)
					(mid 113.613304 -183.586212)
					(end 118.955312 -181.575456)
				)
				(arc
					(start 118.955312 -181.575456)
					(mid 119.255016 -180.689626)
					(end 119.748046 -179.894992)
				)
				(arc
					(start 119.748046 -179.894992)
					(mid 119.091232 -178.699733)
					(end 118.863872 -177.354992)
				)
				(arc
					(start 118.863872 -174.814992)
					(mid 118.934201 -174.059694)
					(end 119.142764 -173.330362)
				)
				(arc
					(start 119.142764 -173.330362)
					(mid 118.165033 -172.083914)
					(end 117.73408 -170.559476)
				)
				(arc
					(start 117.480334 -170.30573)
					(mid 117.360117 -170.311053)
					(end 117.239796 -170.312842)
				)
				(arc
					(start 114.933984 -170.312842)
					(mid 114.847368 -170.547743)
					(end 114.746532 -170.7769)
				)
				(arc
					(start 114.746532 -170.7769)
					(mid 117.061004 -172.989511)
					(end 117.07241 -176.191418)
				)
				(arc
					(start 117.07241 -176.191418)
					(mid 115.900717 -180.938182)
					(end 111.01705 -181.170834)
				)
				(arc
					(start 111.01705 -181.170834)
					(mid 109.068152 -183.325938)
					(end 106.179874 -183.643016)
				)
				(arc
					(start 106.179874 -183.643016)
					(mid 105.725558 -184.958401)
					(end 104.856534 -186.045348)
				)
				(arc
					(start 104.856534 -186.045348)
					(mid 106.057654 -187.925933)
					(end 106.093006 -190.1571)
				)
				(arc
					(start 106.093006 -190.1571)
					(mid 107.370035 -194.853658)
					(end 103.251 -197.446392)
				)
				(arc
					(start 103.251 -197.446392)
					(mid 102.455016 -197.811778)
					(end 101.599492 -197.99935)
				)
				(arc
					(start 101.599492 -198.351394)
					(mid 105.657023 -202.321791)
					(end 107.14609 -207.79994)
				)
				(arc
					(start 107.14609 -213.79434)
					(mid 96.324928 -224.615502)
					(end 85.503766 -213.79434)
				)
				(arc
					(start 85.503766 -211.692744)
					(mid 84.010594 -214.567125)
					(end 80.900016 -215.470486)
				)
				(arc
					(start 80.900016 -215.470486)
					(mid 76.284779 -211.386166)
					(end 80.900016 -207.301846)
				)
				(arc
					(start 80.900016 -207.301846)
					(mid 84.010626 -208.205168)
					(end 85.503766 -211.079588)
				)
				(arc
					(start 85.503766 -207.79994)
					(mid 86.89931 -202.484371)
					(end 90.726006 -198.539862)
				)
				(arc
					(start 90.726006 -198.054976)
					(mid 89.767195 -197.034885)
					(end 89.20861 -195.751196)
				)
				(arc
					(start 89.20861 -195.751196)
					(mid 88.782973 -195.495682)
					(end 88.38819 -195.194682)
				)
				(arc
					(start 88.38819 -195.194682)
					(mid 84.016584 -193.623683)
					(end 83.93303 -188.979048)
				)
				(arc
					(start 83.93303 -188.979048)
					(mid 82.063456 -183.586212)
					(end 87.405464 -181.575456)
				)
				(arc
					(start 87.405464 -181.575456)
					(mid 87.705168 -180.689626)
					(end 88.198198 -179.894992)
				)
				(arc
					(start 88.198198 -179.894992)
					(mid 87.541384 -178.699733)
					(end 87.314024 -177.354992)
				)
				(arc
					(start 87.314024 -174.814992)
					(mid 87.384353 -174.059694)
					(end 87.592916 -173.330362)
				)
				(arc
					(start 87.592916 -173.330362)
					(mid 86.621581 -172.096275)
					(end 86.186772 -170.587162)
				)
				(arc
					(start 85.906356 -170.307)
					(mid 85.798191 -170.31135)
					(end 85.689948 -170.312842)
				)
				(arc
					(start 83.358736 -170.312842)
					(mid 83.273774 -170.543695)
					(end 83.175094 -170.769026)
				)
				(arc
					(start 83.175094 -170.769026)
					(mid 85.506433 -172.979035)
					(end 85.522562 -176.191418)
				)
				(arc
					(start 85.522562 -176.191418)
					(mid 84.350869 -180.938182)
					(end 79.467202 -181.170834)
				)
				(arc
					(start 79.467202 -181.170834)
					(mid 77.525789 -183.322103)
					(end 74.646282 -183.647334)
				)
				(arc
					(start 74.646282 -183.647334)
					(mid 74.193118 -184.970502)
					(end 73.320656 -186.063636)
				)
				(arc
					(start 73.320656 -186.063636)
					(mid 74.354948 -190.754945)
					(end 70.216014 -193.19367)
				)
				(arc
					(start 70.216014 -193.19367)
					(mid 68.096977 -194.385757)
					(end 65.675764 -194.164458)
				)
				(arc
					(start 65.675764 -194.164458)
					(mid 62.426981 -198.797702)
					(end 57.658508 -195.751196)
				)
				(arc
					(start 57.658508 -195.751196)
					(mid 57.232871 -195.495682)
					(end 56.838088 -195.194682)
				)
				(arc
					(start 56.838088 -195.194682)
					(mid 52.466482 -193.623683)
					(end 52.382928 -188.979048)
				)
				(arc
					(start 52.382928 -188.979048)
					(mid 50.513354 -183.586212)
					(end 55.855362 -181.575456)
				)
				(arc
					(start 55.855362 -181.575456)
					(mid 56.155066 -180.689626)
					(end 56.648096 -179.894992)
				)
				(arc
					(start 56.648096 -179.894992)
					(mid 55.991282 -178.699733)
					(end 55.763922 -177.354992)
				)
				(arc
					(start 55.763922 -174.814992)
					(mid 55.834251 -174.059694)
					(end 56.042814 -173.330362)
				)
				(arc
					(start 56.042814 -173.330362)
					(mid 55.071479 -172.096275)
					(end 54.63667 -170.587162)
				)
				(arc
					(start 54.356254 -170.307)
					(mid 54.248089 -170.31135)
					(end 54.139846 -170.312842)
				)
				(arc
					(start 50.351944 -170.312842)
					(mid 50.363641 -170.414946)
					(end 50.372772 -170.517312)
				)
				(arc
					(start 50.372772 -170.517312)
					(mid 53.656617 -172.412871)
					(end 53.97246 -176.191418)
				)
				(arc
					(start 53.97246 -176.191418)
					(mid 52.800767 -180.938182)
					(end 47.9171 -181.170834)
				)
				(arc
					(start 47.9171 -181.170834)
					(mid 45.973933 -183.323003)
					(end 43.09237 -183.646318)
				)
				(arc
					(start 43.09237 -183.646318)
					(mid 42.645177 -185.006153)
					(end 41.756838 -186.12866)
				)
				(arc
					(start 41.756838 -186.12866)
					(mid 42.786427 -190.830726)
					(end 38.628828 -193.256408)
				)
				(arc
					(start 38.628828 -193.256408)
					(mid 36.53645 -194.444446)
					(end 34.138108 -194.250564)
				)
				(arc
					(start 34.138108 -194.250564)
					(mid 34.076514 -195.668919)
					(end 33.533842 -196.98081)
				)
				(arc
					(start 33.533842 -196.98081)
					(mid 41.050062 -200.2225)
					(end 44.145962 -207.79994)
				)
				(arc
					(start 44.145962 -213.79434)
					(mid 33.3248 -224.615502)
					(end 22.503638 -213.79434)
				)
				(arc
					(start 22.503638 -207.79994)
					(mid 23.997173 -202.314238)
					(end 28.065476 -198.342758)
				)
				(arc
					(start 28.065476 -198.342758)
					(mid 26.81889 -197.249483)
					(end 26.10866 -195.751196)
				)
				(arc
					(start 26.10866 -195.751196)
					(mid 25.683023 -195.495682)
					(end 25.28824 -195.194682)
				)
				(arc
					(start 25.28824 -195.194682)
					(mid 20.916634 -193.623683)
					(end 20.83308 -188.979048)
				)
				(arc
					(start 20.83308 -188.979048)
					(mid 18.963506 -183.586212)
					(end 24.305514 -181.575456)
				)
				(arc
					(start 24.305514 -181.575456)
					(mid 24.605218 -180.689626)
					(end 25.098248 -179.894992)
				)
				(arc
					(start 25.098248 -179.894992)
					(mid 24.441434 -178.699733)
					(end 24.214074 -177.354992)
				)
				(arc
					(start 24.214074 -174.814992)
					(mid 24.284403 -174.059694)
					(end 24.492966 -173.330362)
				)
				(arc
					(start 24.492966 -173.330362)
					(mid 23.521631 -172.096275)
					(end 23.086822 -170.587162)
				)
				(arc
					(start 22.806406 -170.307)
					(mid 22.698241 -170.31135)
					(end 22.589998 -170.312842)
				)
				(arc
					(start 20.258786 -170.312842)
					(mid 20.173824 -170.543695)
					(end 20.075144 -170.769026)
				)
				(arc
					(start 20.075144 -170.769026)
					(mid 22.406483 -172.979035)
					(end 22.422612 -176.191418)
				)
				(arc
					(start 22.422612 -176.191418)
					(mid 21.250919 -180.938182)
					(end 16.367252 -181.170834)
				)
				(arc
					(start 16.367252 -181.170834)
					(mid 13.467963 -183.671285)
					(end 9.770364 -182.67807)
				)
				(arc
					(start 9.770364 -182.67807)
					(mid 8.862456 -183.018569)
					(end 7.899908 -183.135778)
				)
				(xy 2.032 -183.135778) (xy 2.032 -164.329872)
				(arc
					(start 6.894576 -164.329872)
					(mid 7.517279 -164.37763)
					(end 8.12546 -164.51961)
				)
				(arc
					(start 8.12546 -164.51961)
					(mid 10.132742 -165.242201)
					(end 11.503152 -166.877238)
				)
				(arc
					(start 11.503152 -166.877238)
					(mid 11.907054 -166.777476)
					(end 12.319 -166.71925)
				)
				(arc
					(start 12.319 -166.71925)
					(mid 12.32997 -165.642939)
					(end 12.62126 -164.606732)
				)
				(arc
					(start 12.62126 -164.606732)
					(mid 9.413187 -160.211168)
					(end 13.410692 -156.519118)
				)
				(arc
					(start 13.410692 -137.85977)
					(mid 9.614349 -137.242182)
					(end 8.009128 -133.747002)
				)
				(arc
					(start 8.009128 -133.747002)
					(mid 7.934134 -133.650311)
					(end 7.862062 -133.551422)
				)
				(arc
					(start 7.862062 -133.551422)
					(mid 6.265527 -131.503595)
					(end 6.223508 -128.907286)
				)
				(xy 6.223508 -128.069594)
				(arc
					(start 3.93573 -128.069594)
					(mid 2.976842 -128.019603)
					(end 2.032 -127.848614)
				)
				(arc
					(start 2.032 -124.134626)
					(mid 1.347921 -123.70242)
					(end 0.763016 -123.143264)
				)
				(xy 0.763016 -241.199924) (xy 0.762254 -241.199924) (xy 0.762254 -261.199884) (xy 0.763016 -261.199884)
				(arc
					(start 0.763016 -348.199964)
					(mid 0.832426 -348.367536)
					(end 0.999998 -348.436946)
				)
				(arc
					(start 189.6999 -348.436946)
					(mid 190.946539 -348.953321)
					(end 191.462914 -350.19996)
				)
				(arc
					(start 191.462914 -372.000018)
					(mid 191.532324 -372.16759)
					(end 191.699896 -372.237)
				)
				(arc
					(start 199.00011 -372.237)
					(mid 200.246749 -372.753375)
					(end 200.763124 -374.000014)
				)
				(arc
					(start 200.763124 -420.200074)
					(mid 200.832534 -420.367646)
					(end 201.000106 -420.437056)
				)
				(xy 203.021692 -420.437056) (xy 203.021692 -419.168072) (xy 202.032108 -419.168072)
				(arc
					(start 202.032108 -374.000014)
					(mid 201.159358 -371.871479)
					(end 199.043544 -370.96827)
				)
				(arc
					(start 199.043544 -370.96827)
					(mid 199.437653 -370.486398)
					(end 199.900286 -370.069872)
				)
				(arc
					(start 199.900286 -370.069872)
					(mid 200.27053 -369.211736)
					(end 200.825862 -368.46002)
				)
				(xy 200.825862 -367.40592) (xy 198.740776 -358.189784) (xy 200.335642 -350.988376)
				(arc
					(start 198.20128 -341.544656)
					(mid 197.777828 -341.497215)
					(end 197.361556 -341.406226)
				)
				(arc
					(start 197.361556 -341.406226)
					(mid 195.113323 -341.360963)
					(end 193.228722 -340.134194)
				)
				(arc
					(start 193.228722 -340.134194)
					(mid 191.520131 -335.842861)
					(end 194.90055 -332.695296)
				)
				(arc
					(start 194.90055 -332.695296)
					(mid 196.048715 -332.089028)
					(end 197.329044 -331.873098)
				)
				(arc
					(start 197.329044 -331.873098)
					(mid 198.579826 -331.367349)
					(end 199.926956 -331.293216)
				)
			)
		)
		(polygon
			(pts
				(arc
					(start 113.76787 -229.9462)
					(mid 107.648249 -229.504928)
					(end 107.893104 -235.635546)
				)
				(arc
					(start 107.893104 -235.635546)
					(mid 108.093092 -235.875248)
					(end 108.31068 -236.099096)
				)
				(arc
					(start 108.31068 -236.099096)
					(mid 107.709502 -238.775933)
					(end 108.924598 -241.235738)
				)
				(arc
					(start 108.924598 -241.235738)
					(mid 107.808823 -245.205313)
					(end 110.69574 -248.149364)
				)
				(arc
					(start 110.69574 -248.149364)
					(mid 111.35838 -248.89552)
					(end 112.181132 -249.460258)
				)
				(arc
					(start 112.181132 -249.460258)
					(mid 109.273441 -250.916958)
					(end 108.331508 -254.029718)
				)
				(arc
					(start 108.331508 -254.029718)
					(mid 107.949529 -254.209999)
					(end 107.58805 -254.428498)
				)
				(arc
					(start 107.58805 -254.428498)
					(mid 100.022975 -254.415307)
					(end 105.233978 -259.899404)
				)
				(arc
					(start 105.233978 -259.899404)
					(mid 108.381247 -262.599208)
					(end 112.280446 -261.188454)
				)
				(arc
					(start 112.280446 -261.188454)
					(mid 112.39811 -261.101495)
					(end 112.512602 -261.0104)
				)
				(arc
					(start 114.809524 -261.0104)
					(mid 122.157254 -259.602618)
					(end 116.2939 -254.955802)
				)
				(arc
					(start 116.2939 -254.955802)
					(mid 116.251315 -252.067017)
					(end 114.320066 -249.91822)
				)
				(arc
					(start 114.320066 -249.91822)
					(mid 117.932834 -247.258065)
					(end 116.966746 -242.876832)
				)
				(arc
					(start 116.966746 -242.876832)
					(mid 116.549108 -241.994718)
					(end 115.935506 -241.235738)
				)
				(arc
					(start 115.935506 -241.235738)
					(mid 117.086171 -239.160407)
					(end 116.899436 -236.794802)
				)
				(arc
					(start 116.899436 -236.794802)
					(mid 117.030223 -233.592877)
					(end 114.82451 -231.26827)
				)
				(arc
					(start 114.82451 -231.26827)
					(mid 114.364872 -230.552347)
					(end 113.76787 -229.9462)
				)
			)
		)
		(polygon
			(pts
				(arc
					(start 174.990252 -343.357708)
					(mid 170.942 -339.851285)
					(end 166.893748 -343.357708)
				)
				(arc
					(start 166.89197 -343.357708)
					(mid 167.146019 -345.469133)
					(end 168.425368 -347.167962)
				)
				(arc
					(start 173.458632 -347.167962)
					(mid 174.73806 -345.469165)
					(end 174.99203 -343.357708)
				)
			)
		)
		(polygon
			(pts
				(arc
					(start 45.259498 -343.357708)
					(mid 41.529 -337.590735)
					(end 37.798502 -343.357708)
				)
				(arc
					(start 37.79647 -343.357708)
					(mid 41.529 -345.772719)
					(end 45.26153 -343.357708)
				)
			)
		)
		(polygon
			(pts
				(arc
					(start 75.40244 -335.02981)
					(mid 73.942268 -333.756181)
					(end 72.0598 -333.297276)
				)
				(arc
					(start 71.0946 -333.297276)
					(mid 67.144329 -336.324708)
					(end 69.040756 -340.926166)
				)
				(arc
					(start 69.040756 -340.926166)
					(mid 68.640351 -342.109096)
					(end 68.61556 -343.357708)
				)
				(arc
					(start 68.613782 -343.357708)
					(mid 72.270289 -346.885859)
					(end 76.542138 -344.134694)
				)
				(arc
					(start 76.542138 -344.134694)
					(mid 77.237372 -343.808274)
					(end 77.859382 -343.357708)
				)
				(arc
					(start 77.856842 -343.357708)
					(mid 78.964251 -341.782614)
					(end 79.228442 -339.875368)
				)
				(arc
					(start 79.228442 -339.875368)
					(mid 78.419627 -336.580702)
					(end 75.40244 -335.02981)
				)
			)
		)
		(polygon
			(pts
				(arc
					(start 136.236964 -337.154012)
					(mid 131.744128 -332.260444)
					(end 128.53924 -338.079588)
				)
				(arc
					(start 128.53924 -338.079588)
					(mid 126.460839 -340.309577)
					(end 126.501906 -343.357708)
				)
				(xy 126.48311 -343.357708) (xy 126.48311 -347.167962) (xy 143.383 -347.167962)
				(arc
					(start 143.383 -344.900758)
					(mid 144.696389 -342.12484)
					(end 143.708882 -339.217)
				)
				(arc
					(start 143.740124 -339.217)
					(mid 140.760571 -337.777622)
					(end 137.68451 -338.997036)
				)
				(arc
					(start 137.68451 -338.997036)
					(mid 137.094703 -337.970302)
					(end 136.236964 -337.154012)
				)
			)
		)
		(polygon
			(pts
				(arc
					(start 186.525408 -319.815718)
					(mid 180.499116 -318.653806)
					(end 180.021484 -324.772528)
				)
				(arc
					(start 180.021484 -324.772528)
					(mid 180.642584 -325.594013)
					(end 181.448202 -326.235568)
				)
				(arc
					(start 181.448202 -326.235568)
					(mid 181.514934 -326.299315)
					(end 181.583076 -326.361552)
				)
				(arc
					(start 181.583076 -326.361552)
					(mid 182.27087 -327.122905)
					(end 183.125618 -327.69048)
				)
				(arc
					(start 183.125618 -327.69048)
					(mid 189.220956 -326.852237)
					(end 187.669678 -320.898266)
				)
				(arc
					(start 187.669678 -320.898266)
					(mid 187.14984 -320.30171)
					(end 186.525408 -319.815718)
				)
			)
		)
		(polygon
			(pts
				(arc
					(start 132.808218 -308.583838)
					(mid 132.808218 -316.813438)
					(end 132.808218 -308.583838)
				)
			)
		)
		(polygon
			(pts
				(arc
					(start 85.434932 -239.53851)
					(mid 88.68416 -233.298432)
					(end 81.648808 -233.297476)
				)
				(arc
					(start 81.648808 -233.297476)
					(mid 76.45648 -235.344755)
					(end 78.081124 -240.684304)
				)
				(arc
					(start 78.081124 -240.684304)
					(mid 76.38582 -245.611867)
					(end 80.87995 -248.249694)
				)
				(arc
					(start 80.87995 -248.249694)
					(mid 81.312146 -248.293932)
					(end 81.746598 -248.292366)
				)
				(arc
					(start 81.746598 -248.292366)
					(mid 82.647334 -249.754909)
					(end 84.066634 -250.722384)
				)
				(arc
					(start 84.066634 -250.722384)
					(mid 88.833148 -256.805817)
					(end 89.119964 -249.082814)
				)
				(arc
					(start 89.119964 -249.082814)
					(mid 89.161476 -244.812369)
					(end 85.392006 -242.805204)
				)
				(arc
					(start 85.392006 -242.805204)
					(mid 84.978766 -241.962711)
					(end 84.385404 -241.235738)
				)
				(arc
					(start 84.385404 -241.235738)
					(mid 85.014621 -240.451714)
					(end 85.434932 -239.53851)
				)
			)
		)
		(polygon
			(pts
				(arc
					(start 6.821932 -231.16286)
					(mid 15.036772 -224.79093)
					(end 7.99973 -217.137996)
				)
				(xy 7.999476 -217.137996) (xy 7.999476 -217.13825) (xy 2.032 -217.13825) (xy 2.032 -231.16286)
			)
		)
	)
	(zone
		(layer "B.Cu")
		(hatch none 0.5)
		(connect_pads
			(clearance 0)
		)
		(min_thickness 0.25)
		(keepout
			(tracks not_allowed)
			(vias allowed)
			(pads allowed)
			(copperpour not_allowed)
			(footprints allowed)
		)
		(placement
			(enabled no)
			(sheetname "")
		)
		(fill
			(thermal_gap 0.5)
			(thermal_bridge_width 0.5)
			(island_removal_mode 0)
		)
		(polygon
			(pts
				(arc
					(start 281.074876 -53.849778)
					(mid 281.399742 -52.87518)
					(end 280.425144 -52.550314)
				)
				(xy 280.423874 -52.548028) (xy 278.424132 -53.548026) (xy 278.424132 -53.54828)
				(arc
					(start 278.425148 -53.550312)
					(mid 278.100282 -54.52491)
					(end 279.07488 -54.849776)
				)
				(xy 279.07615 -54.852062)
				(arc
					(start 280.086562 -54.346856)
					(mid 279.982979 -54.285404)
					(end 279.888696 -54.210458)
				)
				(xy 279.887426 -54.210458)
				(arc
					(start 279.654508 -53.97754)
					(mid 279.615468 -53.949054)
					(end 279.569672 -53.933598)
				)
				(xy 279.566116 -53.93309)
				(arc
					(start 279.55113 -53.93055)
					(mid 279.50136 -53.930709)
					(end 279.454102 -53.946298)
				)
				(arc
					(start 279.271984 -54.039516)
					(mid 278.264021 -54.449107)
					(end 279.185116 -53.870098)
				)
				(xy 279.367234 -53.776626) (xy 279.402286 -53.758592)
				(arc
					(start 279.405842 -53.759862)
					(mid 279.4716 -53.742648)
					(end 279.539446 -53.738526)
				)
				(xy 279.542494 -53.73624) (xy 279.58161 -53.74259) (xy 279.596596 -53.74513) (xy 279.601168 -53.745892)
				(xy 279.635966 -53.75148)
				(arc
					(start 279.637744 -53.75402)
					(mid 279.700642 -53.778688)
					(end 279.757632 -53.81498)
				)
				(xy 279.761188 -53.81498) (xy 279.879298 -53.93309)
				(arc
					(start 279.994106 -54.047898)
					(mid 280.143896 -54.161551)
					(end 280.318718 -54.230778)
				)
				(xy 280.481786 -54.149244) (xy 280.445464 -54.149244)
				(arc
					(start 280.44394 -54.14772)
					(mid 280.258325 -54.104084)
					(end 280.096214 -54.003702)
				)
				(xy 280.094182 -54.003702) (xy 280.066242 -53.975762) (xy 279.93721 -53.84673)
				(arc
					(start 279.93721 -53.841904)
					(mid 279.89485 -53.748537)
					(end 279.891236 -53.64607)
				)
				(arc
					(start 279.891236 -53.645816)
					(mid 279.927157 -53.549778)
					(end 279.9969 -53.47462)
				)
				(xy 279.998424 -53.469794)
				(arc
					(start 280.226516 -53.355748)
					(mid 281.237793 -52.955001)
					(end 280.31186 -53.525928)
				)
				(arc
					(start 280.119074 -53.622448)
					(mid 280.092648 -53.64472)
					(end 280.079196 -53.67655)
				)
				(arc
					(start 280.079196 -53.67655)
					(mid 280.081809 -53.710801)
					(end 280.09977 -53.74005)
				)
				(arc
					(start 280.200862 -53.841142)
					(mid 280.331149 -53.928197)
					(end 280.484834 -53.958744)
				)
				(xy 280.862786 -53.958744) (xy 281.076146 -53.852064)
			)
		)
	)
	(zone
		(layer "B.Cu")
		(hatch none 0.5)
		(connect_pads
			(clearance 0)
		)
		(min_thickness 0.25)
		(keepout
			(tracks allowed)
			(vias allowed)
			(pads allowed)
			(copperpour allowed)
			(footprints not_allowed)
		)
		(placement
			(enabled no)
			(sheetname "")
		)
		(fill
			(thermal_gap 0.5)
			(thermal_bridge_width 0.5)
			(island_removal_mode 0)
		)
		(polygon
			(pts
				(arc
					(start 31.075122 -9.19988)
					(mid 26.325068 -4.449826)
					(end 21.575014 -9.19988)
				)
				(arc
					(start 21.575014 -9.19988)
					(mid 26.325068 -13.949934)
					(end 31.075122 -9.19988)
				)
			)
		)
	)
	(zone
		(net "GND")
		(layer "B.Cu")
		(hatch none 0.5)
		(connect_pads
			(clearance 0.5)
		)
		(min_thickness 0.25)
		(fill yes
			(thermal_gap 0.5)
			(thermal_bridge_width 0.5)
			(island_removal_mode 0)
		)
		(polygon
			(pts
				(xy 401.063714 -71.21906)
				(arc
					(start 408.140662 -66.623692)
					(mid 408.382876 -65.762733)
					(end 408.806396 -64.974978)
				)
				(arc
					(start 408.806396 -64.974978)
					(mid 407.963585 -63.669505)
					(end 407.668476 -62.143894)
				)
				(arc
					(start 407.668476 -61.10224)
					(mid 407.703447 -60.56873)
					(end 407.807668 -60.04433)
				)
				(arc
					(start 400.463766 -65.296796)
					(mid 400.799728 -68.308633)
					(end 398.970754 -70.72503)
				)
				(xy 398.970754 -71.21906)
			)
		)
	)
	(zone
		(layer "B.Cu")
		(hatch none 0.5)
		(connect_pads
			(clearance 0)
		)
		(min_thickness 0.25)
		(keepout
			(tracks allowed)
			(vias allowed)
			(pads allowed)
			(copperpour allowed)
			(footprints not_allowed)
		)
		(placement
			(enabled no)
			(sheetname "")
		)
		(fill
			(thermal_gap 0.5)
			(thermal_bridge_width 0.5)
			(island_removal_mode 0)
		)
		(polygon
			(pts
				(arc
					(start 468.425022 -9.19988)
					(mid 463.674968 -4.449826)
					(end 458.924914 -9.19988)
				)
				(arc
					(start 458.924914 -9.19988)
					(mid 463.674968 -13.949934)
					(end 468.425022 -9.19988)
				)
			)
		)
	)
	(zone
		(layer "B.Cu")
		(hatch none 0.5)
		(connect_pads
			(clearance 0)
		)
		(min_thickness 0.25)
		(keepout
			(tracks not_allowed)
			(vias allowed)
			(pads allowed)
			(copperpour not_allowed)
			(footprints allowed)
		)
		(placement
			(enabled no)
			(sheetname "")
		)
		(fill
			(thermal_gap 0.5)
			(thermal_bridge_width 0.5)
			(island_removal_mode 0)
		)
		(polygon
			(pts
				(arc
					(start 285.436564 -315.756544)
					(mid 284.887924 -316.305184)
					(end 285.436564 -316.853824)
				)
				(arc
					(start 285.935928 -316.853824)
					(mid 285.921943 -316.78489)
					(end 285.9151 -316.714886)
				)
				(xy 285.914338 -316.714124)
				(arc
					(start 285.914338 -316.432184)
					(mid 285.899459 -316.396263)
					(end 285.863538 -316.381384)
				)
				(arc
					(start 285.822898 -316.381384)
					(mid 285.042787 -316.305184)
					(end 285.822898 -316.228984)
				)
				(xy 285.895034 -316.228984)
				(arc
					(start 285.898082 -316.232032)
					(mid 286.007159 -316.288563)
					(end 286.06369 -316.39764)
				)
				(xy 286.066738 -316.400688)
				(arc
					(start 286.066738 -316.682882)
					(mid 286.073833 -316.769508)
					(end 286.094932 -316.853824)
				)
				(arc
					(start 286.245808 -316.853824)
					(mid 286.220397 -316.78649)
					(end 286.207708 -316.715648)
				)
				(xy 286.206438 -316.714124) (xy 286.206438 -316.400688)
				(arc
					(start 286.209486 -316.39764)
					(mid 286.266017 -316.288563)
					(end 286.375094 -316.232032)
				)
				(xy 286.378142 -316.228984)
				(arc
					(start 286.450278 -316.228984)
					(mid 287.230389 -316.305184)
					(end 286.450278 -316.381384)
				)
				(arc
					(start 286.409638 -316.381384)
					(mid 286.373717 -316.396263)
					(end 286.358838 -316.432184)
				)
				(arc
					(start 286.358838 -316.682628)
					(mid 286.377129 -316.774581)
					(end 286.429196 -316.852554)
				)
				(xy 286.430466 -316.853824)
				(arc
					(start 286.836612 -316.853824)
					(mid 287.385252 -316.305184)
					(end 286.836612 -315.756544)
				)
				(xy 285.436818 -315.756544)
			)
		)
	)
	(zone
		(net "GND")
		(layer "B.Cu")
		(hatch none 0.5)
		(connect_pads
			(clearance 0.5)
		)
		(min_thickness 0.25)
		(fill yes
			(thermal_gap 0.5)
			(thermal_bridge_width 0.5)
			(island_removal_mode 0)
		)
		(polygon
			(pts
				(xy 406.884886 -301.421038)
				(arc
					(start 411.44825 -298.40047)
					(mid 410.936757 -297.374335)
					(end 410.730192 -296.24655)
				)
				(arc
					(start 410.730192 -296.24655)
					(mid 410.497745 -296.256341)
					(end 410.265118 -296.2529)
				)
				(arc
					(start 410.265118 -296.2529)
					(mid 405.821061 -298.454635)
					(end 400.901408 -297.826938)
				)
				(arc
					(start 400.901408 -297.826938)
					(mid 399.986783 -299.856098)
					(end 398.145 -301.105824)
				)
				(arc
					(start 398.145 -302.32604)
					(mid 398.712162 -302.610159)
					(end 399.228564 -302.978566)
				)
			)
		)
	)
	(zone
		(net "GND")
		(layer "B.Cu")
		(hatch none 0.5)
		(connect_pads
			(clearance 0.5)
		)
		(min_thickness 0.25)
		(fill yes
			(thermal_gap 0.5)
			(thermal_bridge_width 0.5)
			(island_removal_mode 0)
		)
		(polygon
			(pts
				(xy 482.944932 -210.812126) (xy 482.401372 -211.355686) (xy 482.401372 -214.886794) (xy 483.000304 -215.485726)
				(xy 485.88803 -215.485726) (xy 486.312972 -215.060784) (xy 486.312972 -211.160868) (xy 485.96423 -210.812126)
			)
		)
	)
	(zone
		(net "P3V3_STBY_VIN")
		(layer "B.Cu")
		(hatch none 0.5)
		(connect_pads
			(clearance 0.5)
		)
		(min_thickness 0.25)
		(fill yes
			(thermal_gap 0.5)
			(thermal_bridge_width 0.5)
			(island_removal_mode 0)
		)
		(polygon
			(pts
				(xy 189.632082 -224.965006) (xy 188.641482 -225.955606) (xy 187.828682 -225.955606) (xy 187.650882 -225.777806)
				(xy 186.761882 -225.777806) (xy 186.685682 -225.854006) (xy 186.685682 -226.514406) (xy 188.184282 -228.013006)
				(xy 194.788282 -228.013006) (xy 195.042282 -227.759006) (xy 195.042282 -225.219006) (xy 194.788282 -224.965006)
			)
		)
		(polygon
			(pts
				(xy 191.152272 -227.253292) (xy 190.949072 -227.253292) (xy 190.949072 -227.456492) (xy 191.152272 -227.456492)
			)
		)
		(polygon
			(pts
				(xy 190.542672 -227.253292) (xy 190.339472 -227.253292) (xy 190.339472 -227.456492) (xy 190.542672 -227.456492)
			)
		)
	)
	(zone
		(layer "B.Cu")
		(hatch none 0.5)
		(connect_pads
			(clearance 0)
		)
		(min_thickness 0.25)
		(keepout
			(tracks not_allowed)
			(vias allowed)
			(pads allowed)
			(copperpour not_allowed)
			(footprints allowed)
		)
		(placement
			(enabled no)
			(sheetname "")
		)
		(fill
			(thermal_gap 0.5)
			(thermal_bridge_width 0.5)
			(island_removal_mode 0)
		)
		(polygon
			(pts
				(arc
					(start 278.23668 -304.956464)
					(mid 277.68804 -305.505104)
					(end 278.23668 -306.053744)
				)
				(xy 278.642826 -306.053744) (xy 278.644096 -306.052474)
				(arc
					(start 278.661876 -306.032662)
					(mid 278.700943 -305.962084)
					(end 278.714454 -305.882548)
				)
				(arc
					(start 278.714454 -305.632104)
					(mid 278.699575 -305.596183)
					(end 278.663654 -305.581304)
				)
				(arc
					(start 278.623014 -305.581304)
					(mid 277.842903 -305.505104)
					(end 278.623014 -305.428904)
				)
				(xy 278.69515 -305.428904)
				(arc
					(start 278.698198 -305.431952)
					(mid 278.807275 -305.488483)
					(end 278.863806 -305.59756)
				)
				(xy 278.866854 -305.600608) (xy 278.866854 -305.914044)
				(arc
					(start 278.865584 -305.915568)
					(mid 278.852891 -305.986409)
					(end 278.827484 -306.053744)
				)
				(arc
					(start 278.97836 -306.053744)
					(mid 278.999445 -305.969554)
					(end 279.006554 -305.883056)
				)
				(xy 279.006554 -305.600608)
				(arc
					(start 279.009602 -305.59756)
					(mid 279.066133 -305.488483)
					(end 279.17521 -305.431952)
				)
				(xy 279.178258 -305.428904)
				(arc
					(start 279.250394 -305.428904)
					(mid 280.030505 -305.505104)
					(end 279.250394 -305.581304)
				)
				(arc
					(start 279.209754 -305.581304)
					(mid 279.173833 -305.596183)
					(end 279.158954 -305.632104)
				)
				(xy 279.158954 -305.883056) (xy 279.158954 -305.914552)
				(arc
					(start 279.158192 -305.915314)
					(mid 279.151335 -305.985065)
					(end 279.137364 -306.053744)
				)
				(arc
					(start 279.636728 -306.053744)
					(mid 280.185368 -305.505104)
					(end 279.636728 -304.956464)
				)
				(xy 278.236934 -304.956464)
			)
		)
	)
	(zone
		(layer "B.Cu")
		(hatch none 0.5)
		(connect_pads
			(clearance 0)
		)
		(min_thickness 0.25)
		(keepout
			(tracks not_allowed)
			(vias allowed)
			(pads allowed)
			(copperpour not_allowed)
			(footprints allowed)
		)
		(placement
			(enabled no)
			(sheetname "")
		)
		(fill
			(thermal_gap 0.5)
			(thermal_bridge_width 0.5)
			(island_removal_mode 0)
		)
		(polygon
			(pts
				(arc
					(start 251.199904 -273.200114)
					(mid 244.199918 -266.200128)
					(end 237.199932 -273.200114)
				)
				(arc
					(start 237.199932 -279.200102)
					(mid 244.199918 -286.200088)
					(end 251.199904 -279.200102)
				)
			)
		)
	)
	(zone
		(layer "B.Cu")
		(hatch none 0.5)
		(connect_pads
			(clearance 0)
		)
		(min_thickness 0.25)
		(keepout
			(tracks allowed)
			(vias allowed)
			(pads allowed)
			(copperpour allowed)
			(footprints not_allowed)
		)
		(placement
			(enabled no)
			(sheetname "")
		)
		(fill
			(thermal_gap 0.5)
			(thermal_bridge_width 0.5)
			(island_removal_mode 0)
		)
		(polygon
			(pts
				(arc
					(start 111.849916 -289.999928)
					(mid 107.100116 -285.250128)
					(end 102.350062 -289.999928)
				)
				(arc
					(start 102.350062 -289.999928)
					(mid 107.100116 -294.749982)
					(end 111.849916 -289.999928)
				)
			)
		)
	)
	(zone
		(layer "B.Cu")
		(hatch none 0.5)
		(connect_pads
			(clearance 0)
		)
		(min_thickness 0.25)
		(keepout
			(tracks allowed)
			(vias allowed)
			(pads allowed)
			(copperpour allowed)
			(footprints allowed)
		)
		(placement
			(enabled no)
			(sheetname "")
		)
		(fill
			(thermal_gap 0.5)
			(thermal_bridge_width 0.5)
			(island_removal_mode 0)
		)
		(polygon
			(pts
				(xy 186.6138 -225.6536) (xy 186.6138 -224.7392) (xy 188.4172 -224.7392) (xy 188.4172 -225.6536)
			)
		)
	)
	(zone
		(net "P5V_A_4")
		(layer "B.Cu")
		(hatch none 0.5)
		(connect_pads
			(clearance 0.5)
		)
		(min_thickness 0.25)
		(fill yes
			(thermal_gap 0.5)
			(thermal_bridge_width 0.5)
			(island_removal_mode 0)
		)
		(polygon
			(pts
				(xy 472.912694 -202.531726) (xy 472.549982 -202.894438) (xy 472.549982 -203.901548) (xy 472.1225 -204.32903)
				(xy 472.1225 -212.865716) (xy 467.877398 -217.110818) (xy 467.877398 -220.056202) (xy 468.513922 -220.692726)
				(xy 478.057972 -220.692726) (xy 478.946972 -219.803726) (xy 478.946972 -202.935332) (xy 478.543366 -202.531726)
			)
		)
	)
	(zone
		(net "GND")
		(layer "B.Cu")
		(hatch none 0.5)
		(connect_pads
			(clearance 0.5)
		)
		(min_thickness 0.25)
		(fill yes
			(thermal_gap 0.5)
			(thermal_bridge_width 0.5)
			(island_removal_mode 0)
		)
		(polygon
			(pts
				(xy 463.707226 -238.82096) (xy 463.25917 -239.269016) (xy 463.25917 -241.939318) (xy 463.769202 -242.44935)
				(xy 467.440518 -242.44935) (xy 467.723728 -242.16614) (xy 467.723728 -239.380014) (xy 467.164674 -238.82096)
			)
		)
	)
	(zone
		(layer "B.Cu")
		(hatch none 0.5)
		(connect_pads
			(clearance 0)
		)
		(min_thickness 0.25)
		(keepout
			(tracks allowed)
			(vias allowed)
			(pads allowed)
			(copperpour allowed)
			(footprints not_allowed)
		)
		(placement
			(enabled no)
			(sheetname "")
		)
		(fill
			(thermal_gap 0.5)
			(thermal_bridge_width 0.5)
			(island_removal_mode 0)
		)
		(polygon
			(pts
				(arc
					(start 245.247668 3.800094)
					(mid 249.316803 3.049042)
					(end 251.599954 6.500114)
				)
				(arc
					(start 251.599954 6.500114)
					(mid 251.176012 8.232132)
					(end 250.000008 9.572498)
				)
				(xy 250.000008 24.800052) (xy 230.000048 24.800052)
				(arc
					(start 230.000048 10.247122)
					(mid 227.251889 9.204327)
					(end 226.099878 6.500114)
				)
				(arc
					(start 226.099878 6.500114)
					(mid 228.38305 3.048858)
					(end 232.452418 3.800094)
				)
			)
		)
	)
	(zone
		(net "GND")
		(layer "B.Cu")
		(hatch none 0.5)
		(connect_pads
			(clearance 0.5)
		)
		(min_thickness 0.25)
		(fill yes
			(thermal_gap 0.5)
			(thermal_bridge_width 0.5)
			(island_removal_mode 0)
		)
		(polygon
			(pts
				(xy 219.6973 -173.1899) (xy 219.2528 -173.6344) (xy 219.2528 -176.5046) (xy 219.4306 -176.6824)
				(xy 224.9932 -176.6824) (xy 225.2472 -176.4284) (xy 225.2472 -173.6217) (xy 224.8154 -173.1899)
			)
		)
	)
	(zone
		(layer "B.Cu")
		(hatch none 0.5)
		(connect_pads
			(clearance 0)
		)
		(min_thickness 0.25)
		(keepout
			(tracks not_allowed)
			(vias allowed)
			(pads allowed)
			(copperpour not_allowed)
			(footprints allowed)
		)
		(placement
			(enabled no)
			(sheetname "")
		)
		(fill
			(thermal_gap 0.5)
			(thermal_bridge_width 0.5)
			(island_removal_mode 0)
		)
		(polygon
			(pts
				(arc
					(start 271.970754 -330.321412)
					(mid 271.58696 -330.704825)
					(end 271.9705 -331.088492)
				)
				(arc
					(start 273.1135 -331.088492)
					(mid 273.49704 -330.704952)
					(end 273.1135 -330.321412)
				)
				(arc
					(start 272.768568 -330.321412)
					(mid 272.765366 -330.348252)
					(end 272.76425 -330.37526)
				)
				(arc
					(start 272.76425 -330.52385)
					(mid 272.791127 -330.593968)
					(end 272.857976 -330.628244)
				)
				(arc
					(start 272.857976 -330.628244)
					(mid 273.380217 -330.704698)
					(end 272.857976 -330.781152)
				)
				(xy 272.837656 -330.781152)
				(arc
					(start 272.83537 -330.778866)
					(mid 272.687253 -330.705749)
					(end 272.614136 -330.557632)
				)
				(xy 272.61185 -330.555346) (xy 272.61185 -330.343764) (xy 272.612866 -330.342748) (xy 272.614644 -330.321412)
				(arc
					(start 272.474436 -330.321412)
					(mid 272.472724 -330.348312)
					(end 272.47215 -330.37526)
				)
				(xy 272.47215 -330.555346)
				(arc
					(start 272.469864 -330.557632)
					(mid 272.396747 -330.705749)
					(end 272.24863 -330.778866)
				)
				(xy 272.246344 -330.781152)
				(arc
					(start 272.226024 -330.781152)
					(mid 271.703783 -330.704698)
					(end 272.226024 -330.628244)
				)
				(arc
					(start 272.226024 -330.628244)
					(mid 272.292939 -330.594027)
					(end 272.31975 -330.52385)
				)
				(xy 272.31975 -330.343764) (xy 272.320512 -330.343002) (xy 272.321528 -330.321412)
			)
		)
	)
	(zone
		(layer "B.Cu")
		(hatch none 0.5)
		(connect_pads
			(clearance 0)
		)
		(min_thickness 0.25)
		(keepout
			(tracks not_allowed)
			(vias allowed)
			(pads allowed)
			(copperpour not_allowed)
			(footprints allowed)
		)
		(placement
			(enabled no)
			(sheetname "")
		)
		(fill
			(thermal_gap 0.5)
			(thermal_bridge_width 0.5)
			(island_removal_mode 0)
		)
		(polygon
			(pts
				(arc
					(start 485.000046 -5.500116)
					(mid 481.24999 -1.75006)
					(end 477.499934 -5.500116)
				)
				(arc
					(start 477.499934 -5.500116)
					(mid 481.24999 -9.250172)
					(end 485.000046 -5.500116)
				)
			)
		)
	)
	(zone
		(layer "B.Cu")
		(hatch none 0.5)
		(connect_pads
			(clearance 0)
		)
		(min_thickness 0.25)
		(keepout
			(tracks allowed)
			(vias allowed)
			(pads allowed)
			(copperpour allowed)
			(footprints allowed)
		)
		(placement
			(enabled no)
			(sheetname "")
		)
		(fill
			(thermal_gap 0.5)
			(thermal_bridge_width 0.5)
			(island_removal_mode 0)
		)
		(polygon
			(pts
				(xy 27.5082 -249.0724) (xy 27.5082 -252.3236) (xy 25.0444 -252.3236) (xy 25.0444 -249.0724)
			)
		)
	)
	(zone
		(layer "B.Cu")
		(hatch none 0.5)
		(connect_pads
			(clearance 0)
		)
		(min_thickness 0.25)
		(keepout
			(tracks not_allowed)
			(vias allowed)
			(pads allowed)
			(copperpour not_allowed)
			(footprints allowed)
		)
		(placement
			(enabled no)
			(sheetname "")
		)
		(fill
			(thermal_gap 0.5)
			(thermal_bridge_width 0.5)
			(island_removal_mode 0)
		)
		(polygon
			(pts
				(arc
					(start 238.374936 -41.849802)
					(mid 238.699802 -40.875204)
					(end 237.725204 -40.550338)
				)
				(xy 237.723934 -40.548052)
				(arc
					(start 236.706918 -41.05656)
					(mid 236.735785 -41.070197)
					(end 236.764068 -41.085008)
				)
				(arc
					(start 236.764322 -41.085008)
					(mid 236.840891 -41.133066)
					(end 236.911388 -41.189656)
				)
				(xy 236.912658 -41.189656) (xy 236.940344 -41.217342) (xy 236.940598 -41.217596)
				(arc
					(start 237.145576 -41.422574)
					(mid 237.184616 -41.45106)
					(end 237.230412 -41.466516)
				)
				(arc
					(start 237.248954 -41.469564)
					(mid 237.298724 -41.469405)
					(end 237.345982 -41.453816)
				)
				(arc
					(start 237.5281 -41.360598)
					(mid 238.536063 -40.951007)
					(end 237.614968 -41.530016)
				)
				(xy 237.43285 -41.623488) (xy 237.397798 -41.641522)
				(arc
					(start 237.394242 -41.640252)
					(mid 237.328484 -41.657466)
					(end 237.260638 -41.661588)
				)
				(xy 237.25759 -41.663874) (xy 237.203488 -41.654984) (xy 237.198916 -41.654222) (xy 237.164118 -41.648634)
				(arc
					(start 237.16234 -41.646094)
					(mid 237.099442 -41.621426)
					(end 237.042452 -41.585134)
				)
				(xy 237.038896 -41.585134) (xy 237.010956 -41.557194)
				(arc
					(start 236.805724 -41.351962)
					(mid 236.742709 -41.29734)
					(end 236.672628 -41.25214)
				)
				(arc
					(start 236.672628 -41.25214)
					(mid 236.566911 -41.206937)
					(end 236.454442 -41.183052)
				)
				(xy 236.258608 -41.280842) (xy 236.427772 -41.280842)
				(arc
					(start 236.42955 -41.28262)
					(mid 236.529657 -41.30178)
					(end 236.623606 -41.341294)
				)
				(arc
					(start 236.623606 -41.341294)
					(mid 236.664973 -41.366874)
					(end 236.703616 -41.396412)
				)
				(xy 236.705902 -41.396412) (xy 236.733588 -41.423844) (xy 236.733842 -41.424352) (xy 236.862874 -41.553384)
				(arc
					(start 236.862874 -41.55821)
					(mid 236.905234 -41.651577)
					(end 236.908848 -41.754044)
				)
				(arc
					(start 236.908848 -41.754298)
					(mid 236.872927 -41.850336)
					(end 236.803184 -41.925494)
				)
				(xy 236.80166 -41.93032)
				(arc
					(start 236.573568 -42.044366)
					(mid 235.562291 -42.445113)
					(end 236.488224 -41.874186)
				)
				(arc
					(start 236.68101 -41.777666)
					(mid 236.707436 -41.755394)
					(end 236.720888 -41.723564)
				)
				(arc
					(start 236.720888 -41.723564)
					(mid 236.718275 -41.689313)
					(end 236.700314 -41.660064)
				)
				(arc
					(start 236.598714 -41.558718)
					(mid 236.566956 -41.531213)
					(end 236.531658 -41.508426)
				)
				(arc
					(start 236.531658 -41.508426)
					(mid 236.462363 -41.48088)
					(end 236.388402 -41.471342)
				)
				(xy 235.877608 -41.471342) (xy 235.724192 -41.54805) (xy 235.724192 -41.548304)
				(arc
					(start 235.725208 -41.550336)
					(mid 235.400342 -42.524934)
					(end 236.37494 -42.8498)
				)
				(xy 236.37621 -42.852086) (xy 238.376206 -41.852088)
			)
		)
	)
	(zone
		(layer "B.Cu")
		(hatch none 0.5)
		(connect_pads
			(clearance 0)
		)
		(min_thickness 0.25)
		(keepout
			(tracks allowed)
			(vias allowed)
			(pads allowed)
			(copperpour allowed)
			(footprints not_allowed)
		)
		(placement
			(enabled no)
			(sheetname "")
		)
		(fill
			(thermal_gap 0.5)
			(thermal_bridge_width 0.5)
			(island_removal_mode 0)
		)
		(polygon
			(pts
				(arc
					(start 103.324914 -322.799964)
					(mid 96.324928 -315.799978)
					(end 89.324942 -322.799964)
				)
				(arc
					(start 89.324942 -328.799952)
					(mid 96.324928 -335.799938)
					(end 103.324914 -328.799952)
				)
			)
		)
	)
	(zone
		(layer "B.Cu")
		(hatch none 0.5)
		(connect_pads
			(clearance 0)
		)
		(min_thickness 0.25)
		(keepout
			(tracks not_allowed)
			(vias allowed)
			(pads allowed)
			(copperpour not_allowed)
			(footprints allowed)
		)
		(placement
			(enabled no)
			(sheetname "")
		)
		(fill
			(thermal_gap 0.5)
			(thermal_bridge_width 0.5)
			(island_removal_mode 0)
		)
		(polygon
			(pts
				(arc
					(start 214.14867 -407.000456)
					(mid 213.600157 -406.451562)
					(end 213.05139 -407.000202)
				)
				(xy 213.05139 -407.458672)
				(arc
					(start 213.417658 -407.458672)
					(mid 213.432502 -407.457322)
					(end 213.446868 -407.453338)
				)
				(arc
					(start 213.446868 -407.453338)
					(mid 213.485254 -407.425502)
					(end 213.504018 -407.381964)
				)
				(arc
					(start 213.504018 -407.381964)
					(mid 213.60043 -406.606552)
					(end 213.69528 -407.382218)
				)
				(xy 213.69528 -407.408888)
				(arc
					(start 213.691978 -407.41219)
					(mid 213.632652 -407.546015)
					(end 213.513924 -407.631646)
				)
				(arc
					(start 213.513924 -407.631646)
					(mid 213.487612 -407.640099)
					(end 213.460584 -407.64587)
				)
				(xy 213.457028 -407.649172) (xy 213.05139 -407.649172) (xy 213.05139 -407.750772) (xy 213.454742 -407.750772)
				(arc
					(start 213.458044 -407.754074)
					(mid 213.613276 -407.832776)
					(end 213.691978 -407.988008)
				)
				(xy 213.69528 -407.99131)
				(arc
					(start 213.69528 -408.01798)
					(mid 213.60043 -408.793707)
					(end 213.504018 -408.018234)
				)
				(arc
					(start 213.504018 -408.018234)
					(mid 213.474104 -407.963126)
					(end 213.415372 -407.941272)
				)
				(xy 213.05139 -407.941272)
				(arc
					(start 213.05139 -408.399996)
					(mid 213.60003 -408.948636)
					(end 214.14867 -408.399996)
				)
			)
		)
	)
	(zone
		(layer "B.Cu")
		(hatch none 0.5)
		(connect_pads
			(clearance 0)
		)
		(min_thickness 0.25)
		(keepout
			(tracks not_allowed)
			(vias allowed)
			(pads allowed)
			(copperpour not_allowed)
			(footprints allowed)
		)
		(placement
			(enabled no)
			(sheetname "")
		)
		(fill
			(thermal_gap 0.5)
			(thermal_bridge_width 0.5)
			(island_removal_mode 0)
		)
		(polygon
			(pts
				(arc
					(start 238.374936 -37.84981)
					(mid 238.699802 -36.875212)
					(end 237.725204 -36.550346)
				)
				(xy 237.723934 -36.54806)
				(arc
					(start 236.706918 -37.056568)
					(mid 236.735785 -37.070205)
					(end 236.764068 -37.085016)
				)
				(arc
					(start 236.764322 -37.085016)
					(mid 236.840891 -37.133074)
					(end 236.911388 -37.189664)
				)
				(xy 236.912658 -37.189664) (xy 236.940344 -37.21735) (xy 236.940598 -37.217604)
				(arc
					(start 237.145576 -37.422582)
					(mid 237.184616 -37.451068)
					(end 237.230412 -37.466524)
				)
				(arc
					(start 237.248954 -37.469572)
					(mid 237.298724 -37.469413)
					(end 237.345982 -37.453824)
				)
				(arc
					(start 237.5281 -37.360606)
					(mid 238.536063 -36.951015)
					(end 237.614968 -37.530024)
				)
				(xy 237.43285 -37.623496) (xy 237.397798 -37.64153)
				(arc
					(start 237.394242 -37.64026)
					(mid 237.328484 -37.657474)
					(end 237.260638 -37.661596)
				)
				(xy 237.25759 -37.663882) (xy 237.203488 -37.654992) (xy 237.198916 -37.65423) (xy 237.164118 -37.648642)
				(arc
					(start 237.16234 -37.646102)
					(mid 237.099442 -37.621434)
					(end 237.042452 -37.585142)
				)
				(xy 237.038896 -37.585142) (xy 237.010956 -37.557202)
				(arc
					(start 236.805724 -37.35197)
					(mid 236.742709 -37.297348)
					(end 236.672628 -37.252148)
				)
				(arc
					(start 236.672628 -37.252148)
					(mid 236.566911 -37.206945)
					(end 236.454442 -37.18306)
				)
				(xy 236.258608 -37.28085) (xy 236.427772 -37.28085)
				(arc
					(start 236.42955 -37.282628)
					(mid 236.529657 -37.301788)
					(end 236.623606 -37.341302)
				)
				(arc
					(start 236.623606 -37.341302)
					(mid 236.664973 -37.366882)
					(end 236.703616 -37.39642)
				)
				(xy 236.705902 -37.39642) (xy 236.733588 -37.423852) (xy 236.733842 -37.42436) (xy 236.862874 -37.553392)
				(arc
					(start 236.862874 -37.558218)
					(mid 236.905234 -37.651585)
					(end 236.908848 -37.754052)
				)
				(arc
					(start 236.908848 -37.754306)
					(mid 236.872927 -37.850344)
					(end 236.803184 -37.925502)
				)
				(xy 236.80166 -37.930328)
				(arc
					(start 236.573568 -38.044374)
					(mid 235.562291 -38.445121)
					(end 236.488224 -37.874194)
				)
				(arc
					(start 236.68101 -37.777674)
					(mid 236.707436 -37.755402)
					(end 236.720888 -37.723572)
				)
				(arc
					(start 236.720888 -37.723572)
					(mid 236.718275 -37.689321)
					(end 236.700314 -37.660072)
				)
				(arc
					(start 236.598714 -37.558726)
					(mid 236.566956 -37.531221)
					(end 236.531658 -37.508434)
				)
				(arc
					(start 236.531658 -37.508434)
					(mid 236.462363 -37.480888)
					(end 236.388402 -37.47135)
				)
				(xy 235.877608 -37.47135) (xy 235.724192 -37.548058) (xy 235.724192 -37.548312)
				(arc
					(start 235.725208 -37.550344)
					(mid 235.400342 -38.524942)
					(end 236.37494 -38.849808)
				)
				(xy 236.37621 -38.852094) (xy 238.376206 -37.852096)
			)
		)
	)
	(zone
		(net "GND")
		(layer "B.Cu")
		(hatch none 0.5)
		(connect_pads
			(clearance 0.5)
		)
		(min_thickness 0.25)
		(fill yes
			(thermal_gap 0.5)
			(thermal_bridge_width 0.5)
			(island_removal_mode 0)
		)
		(polygon
			(pts
				(xy 469.474042 -204.3684) (xy 468.966042 -204.8764) (xy 468.966042 -209.128868) (xy 470.047574 -210.2104)
				(xy 471.379042 -210.2104) (xy 471.760042 -209.8294) (xy 471.760042 -204.6224) (xy 471.506042 -204.3684)
			)
		)
	)
	(zone
		(layer "B.Cu")
		(hatch none 0.5)
		(connect_pads
			(clearance 0)
		)
		(min_thickness 0.25)
		(keepout
			(tracks not_allowed)
			(vias allowed)
			(pads allowed)
			(copperpour not_allowed)
			(footprints allowed)
		)
		(placement
			(enabled no)
			(sheetname "")
		)
		(fill
			(thermal_gap 0.5)
			(thermal_bridge_width 0.5)
			(island_removal_mode 0)
		)
		(polygon
			(pts
				(arc
					(start 40.32504 -92.799916)
					(mid 33.325054 -85.79993)
					(end 26.325068 -92.799916)
				)
				(arc
					(start 26.325068 -98.799904)
					(mid 33.325054 -105.79989)
					(end 40.32504 -98.799904)
				)
			)
		)
	)
	(zone
		(layer "B.Cu")
		(hatch none 0.5)
		(connect_pads
			(clearance 0)
		)
		(min_thickness 0.25)
		(keepout
			(tracks not_allowed)
			(vias allowed)
			(pads allowed)
			(copperpour not_allowed)
			(footprints allowed)
		)
		(placement
			(enabled no)
			(sheetname "")
		)
		(fill
			(thermal_gap 0.5)
			(thermal_bridge_width 0.5)
			(island_removal_mode 0)
		)
		(polygon
			(pts
				(arc
					(start 271.970754 -350.124014)
					(mid 271.5895 -350.504887)
					(end 271.9705 -350.886014)
				)
				(arc
					(start 273.1135 -350.886014)
					(mid 273.4945 -350.505014)
					(end 273.1135 -350.124014)
				)
				(arc
					(start 272.76806 -350.124014)
					(mid 272.765209 -350.149598)
					(end 272.76425 -350.175322)
				)
				(arc
					(start 272.76425 -350.323912)
					(mid 272.791127 -350.39403)
					(end 272.857976 -350.428306)
				)
				(arc
					(start 272.857976 -350.428306)
					(mid 273.380217 -350.50476)
					(end 272.857976 -350.581214)
				)
				(xy 272.837656 -350.581214)
				(arc
					(start 272.83537 -350.578928)
					(mid 272.687253 -350.505811)
					(end 272.614136 -350.357694)
				)
				(xy 272.61185 -350.355408) (xy 272.61185 -350.143826) (xy 272.612866 -350.14281) (xy 272.61439 -350.124014)
				(arc
					(start 272.474182 -350.124014)
					(mid 272.472648 -350.149648)
					(end 272.47215 -350.175322)
				)
				(xy 272.47215 -350.355408)
				(arc
					(start 272.469864 -350.357694)
					(mid 272.396747 -350.505811)
					(end 272.24863 -350.578928)
				)
				(xy 272.246344 -350.581214)
				(arc
					(start 272.226024 -350.581214)
					(mid 271.703783 -350.50476)
					(end 272.226024 -350.428306)
				)
				(arc
					(start 272.226024 -350.428306)
					(mid 272.292939 -350.394089)
					(end 272.31975 -350.323912)
				)
				(xy 272.31975 -350.143826) (xy 272.320512 -350.143064) (xy 272.321528 -350.124014)
			)
		)
	)
	(zone
		(layer "B.Cu")
		(hatch none 0.5)
		(connect_pads
			(clearance 0)
		)
		(min_thickness 0.25)
		(keepout
			(tracks not_allowed)
			(vias allowed)
			(pads allowed)
			(copperpour not_allowed)
			(footprints allowed)
		)
		(placement
			(enabled no)
			(sheetname "")
		)
		(fill
			(thermal_gap 0.5)
			(thermal_bridge_width 0.5)
			(island_removal_mode 0)
		)
		(polygon
			(pts
				(arc
					(start 281.07386 -158.147258)
					(mid 281.397456 -157.175962)
					(end 280.42616 -156.852366)
				)
				(arc
					(start 279.487122 -157.321758)
					(mid 279.638469 -157.405568)
					(end 279.768554 -157.519624)
				)
				(xy 279.781762 -157.523942) (xy 279.832308 -157.624018) (xy 279.849834 -157.659324) (xy 279.867614 -157.694376)
				(xy 279.867614 -157.69463)
				(arc
					(start 279.892506 -157.744414)
					(mid 279.932791 -157.77941)
					(end 279.985978 -157.775656)
				)
				(arc
					(start 280.226516 -157.65526)
					(mid 281.23834 -157.255386)
					(end 280.31186 -157.825694)
				)
				(xy 280.071322 -157.945836) (xy 280.036016 -157.963616)
				(arc
					(start 280.03119 -157.962092)
					(mid 279.872501 -157.960079)
					(end 279.744424 -157.866334)
				)
				(xy 279.739598 -157.86481) (xy 279.722072 -157.829758) (xy 279.722072 -157.829504) (xy 279.679654 -157.744668)
				(arc
					(start 279.634696 -157.655514)
					(mid 279.450574 -157.514693)
					(end 279.227534 -157.451552)
				)
				(xy 279.028906 -157.550866) (xy 279.213056 -157.550866)
				(arc
					(start 279.214834 -157.55239)
					(mid 279.379517 -157.5936)
					(end 279.52192 -157.685994)
				)
				(xy 279.539192 -157.691582) (xy 279.623774 -157.860492) (xy 279.640792 -157.87751) (xy 279.640792 -157.894274)
				(xy 279.648412 -157.909514)
				(arc
					(start 279.646634 -157.91434)
					(mid 279.644931 -158.073074)
					(end 279.551384 -158.20136)
				)
				(xy 279.54986 -158.206186) (xy 279.514554 -158.223712)
				(arc
					(start 279.273508 -158.344362)
					(mid 278.261684 -158.744236)
					(end 279.188164 -158.173928)
				)
				(arc
					(start 279.42921 -158.053532)
					(mid 279.462054 -158.018857)
					(end 279.46477 -157.971236)
				)
				(xy 279.450292 -157.956504) (xy 279.450292 -157.939486)
				(arc
					(start 279.393904 -157.826964)
					(mid 279.291818 -157.763529)
					(end 279.173686 -157.741366)
				)
				(xy 278.647906 -157.741366) (xy 278.426418 -157.85211)
				(arc
					(start 278.426418 -157.852364)
					(mid 278.102619 -158.823508)
					(end 279.073864 -159.147256)
				)
			)
		)
	)
	(zone
		(layer "B.Cu")
		(hatch none 0.5)
		(connect_pads
			(clearance 0)
		)
		(min_thickness 0.25)
		(keepout
			(tracks not_allowed)
			(vias allowed)
			(pads allowed)
			(copperpour not_allowed)
			(footprints allowed)
		)
		(placement
			(enabled no)
			(sheetname "")
		)
		(fill
			(thermal_gap 0.5)
			(thermal_bridge_width 0.5)
			(island_removal_mode 0)
		)
		(polygon
			(pts
				(arc
					(start 482.870002 -47.178722)
					(mid 482.489129 -46.797468)
					(end 482.108002 -47.178468)
				)
				(xy 482.108002 -47.527718)
				(arc
					(start 482.312218 -47.527718)
					(mid 482.380874 -47.500643)
					(end 482.412548 -47.433992)
				)
				(arc
					(start 482.412548 -47.433992)
					(mid 482.489124 -46.911751)
					(end 482.565202 -47.433992)
				)
				(xy 482.565202 -47.45863)
				(arc
					(start 482.562916 -47.460916)
					(mid 482.49109 -47.606006)
					(end 482.346 -47.677832)
				)
				(xy 482.343714 -47.680118) (xy 482.108002 -47.680118) (xy 482.108002 -47.819818) (xy 482.343714 -47.819818)
				(arc
					(start 482.346 -47.822104)
					(mid 482.49109 -47.89393)
					(end 482.562916 -48.03902)
				)
				(xy 482.565202 -48.041306)
				(arc
					(start 482.565202 -48.065944)
					(mid 482.489124 -48.588112)
					(end 482.412548 -48.065944)
				)
				(arc
					(start 482.412548 -48.065944)
					(mid 482.38086 -47.999308)
					(end 482.312218 -47.972218)
				)
				(xy 482.108002 -47.972218)
				(arc
					(start 482.108002 -48.321468)
					(mid 482.489002 -48.702468)
					(end 482.870002 -48.321468)
				)
			)
		)
	)
	(zone
		(layer "B.Cu")
		(hatch none 0.5)
		(connect_pads
			(clearance 0)
		)
		(min_thickness 0.25)
		(keepout
			(tracks not_allowed)
			(vias allowed)
			(pads allowed)
			(copperpour not_allowed)
			(footprints allowed)
		)
		(placement
			(enabled no)
			(sheetname "")
		)
		(fill
			(thermal_gap 0.5)
			(thermal_bridge_width 0.5)
			(island_removal_mode 0)
		)
		(polygon
			(pts
				(arc
					(start 238.374936 -81.849722)
					(mid 238.699802 -80.875124)
					(end 237.725204 -80.550258)
				)
				(xy 237.723934 -80.547972) (xy 235.724192 -81.54797) (xy 235.724192 -81.548224)
				(arc
					(start 235.725208 -81.550256)
					(mid 235.400342 -82.524854)
					(end 236.37494 -82.84972)
				)
				(xy 236.37621 -82.852006) (xy 236.864652 -82.607658)
				(arc
					(start 237.11662 -82.355944)
					(mid 237.131673 -82.333322)
					(end 237.13694 -82.306668)
				)
				(arc
					(start 237.13694 -82.188812)
					(mid 237.131657 -82.162165)
					(end 237.11662 -82.139536)
				)
				(arc
					(start 236.954568 -81.977484)
					(mid 236.915528 -81.948998)
					(end 236.869732 -81.933542)
				)
				(xy 236.866176 -81.933034)
				(arc
					(start 236.85119 -81.930494)
					(mid 236.80142 -81.930653)
					(end 236.754162 -81.946242)
				)
				(arc
					(start 236.572044 -82.03946)
					(mid 235.564081 -82.449051)
					(end 236.485176 -81.870042)
				)
				(xy 236.667294 -81.77657) (xy 236.702346 -81.758536)
				(arc
					(start 236.705902 -81.759806)
					(mid 236.77166 -81.742592)
					(end 236.839506 -81.73847)
				)
				(xy 236.842554 -81.736184) (xy 236.88167 -81.742534) (xy 236.896656 -81.745074) (xy 236.901228 -81.745836)
				(xy 236.936026 -81.751424)
				(arc
					(start 236.937804 -81.753964)
					(mid 237.000702 -81.778632)
					(end 237.057692 -81.814924)
				)
				(xy 237.061248 -81.814924) (xy 237.089188 -81.842864) (xy 237.179358 -81.933034) (xy 237.27918 -82.032856)
				(arc
					(start 237.27918 -82.037936)
					(mid 237.307656 -82.089373)
					(end 237.323884 -82.145886)
				)
				(xy 237.32744 -82.149442) (xy 237.32744 -82.346038)
				(arc
					(start 237.323884 -82.349594)
					(mid 237.320596 -82.365847)
					(end 237.316264 -82.381852)
				)
				(xy 237.42904 -82.325464)
				(arc
					(start 237.42904 -82.104484)
					(mid 237.416892 -82.043884)
					(end 237.382558 -81.99247)
				)
				(xy 237.382558 -81.992216) (xy 237.237016 -81.846674)
				(arc
					(start 237.237016 -81.841594)
					(mid 237.226537 -81.825817)
					(end 237.217204 -81.809336)
				)
				(arc
					(start 237.217204 -81.808828)
					(mid 237.191186 -81.729495)
					(end 237.191296 -81.646014)
				)
				(arc
					(start 237.191296 -81.64576)
					(mid 237.227217 -81.549722)
					(end 237.29696 -81.474564)
				)
				(xy 237.298484 -81.469738)
				(arc
					(start 237.526576 -81.355692)
					(mid 238.537853 -80.954945)
					(end 237.61192 -81.525872)
				)
				(arc
					(start 237.419134 -81.622392)
					(mid 237.392708 -81.644664)
					(end 237.379256 -81.676494)
				)
				(arc
					(start 237.379256 -81.676494)
					(mid 237.379224 -81.699662)
					(end 237.386368 -81.721706)
				)
				(arc
					(start 237.386368 -81.721706)
					(mid 237.392303 -81.731093)
					(end 237.399576 -81.739486)
				)
				(xy 237.39983 -81.739994) (xy 237.42777 -81.767934) (xy 237.42777 -81.768188) (xy 237.50651 -81.846674)
				(xy 237.517178 -81.857596) (xy 237.517432 -81.857596) (xy 237.545118 -81.885536)
				(arc
					(start 237.545118 -81.889092)
					(mid 237.592944 -81.970908)
					(end 237.617 -82.062574)
				)
				(xy 237.61954 -82.065114) (xy 237.61954 -82.230468) (xy 238.376206 -81.852008)
			)
		)
	)
	(zone
		(layer "B.Cu")
		(hatch none 0.5)
		(connect_pads
			(clearance 0)
		)
		(min_thickness 0.25)
		(keepout
			(tracks not_allowed)
			(vias allowed)
			(pads allowed)
			(copperpour not_allowed)
			(footprints allowed)
		)
		(placement
			(enabled no)
			(sheetname "")
		)
		(fill
			(thermal_gap 0.5)
			(thermal_bridge_width 0.5)
			(island_removal_mode 0)
		)
		(polygon
			(pts
				(arc
					(start 271.970754 -359.123996)
					(mid 271.5895 -359.504869)
					(end 271.9705 -359.885996)
				)
				(arc
					(start 273.1135 -359.885996)
					(mid 273.4945 -359.504996)
					(end 273.1135 -359.123996)
				)
				(arc
					(start 272.76806 -359.123996)
					(mid 272.765209 -359.14958)
					(end 272.76425 -359.175304)
				)
				(arc
					(start 272.76425 -359.323894)
					(mid 272.791127 -359.394012)
					(end 272.857976 -359.428288)
				)
				(arc
					(start 272.857976 -359.428288)
					(mid 273.380217 -359.504742)
					(end 272.857976 -359.581196)
				)
				(xy 272.837656 -359.581196)
				(arc
					(start 272.83537 -359.57891)
					(mid 272.687253 -359.505793)
					(end 272.614136 -359.357676)
				)
				(xy 272.61185 -359.35539) (xy 272.61185 -359.143808) (xy 272.612866 -359.142792) (xy 272.61439 -359.123996)
				(arc
					(start 272.474182 -359.123996)
					(mid 272.472648 -359.14963)
					(end 272.47215 -359.175304)
				)
				(xy 272.47215 -359.35539)
				(arc
					(start 272.469864 -359.357676)
					(mid 272.396747 -359.505793)
					(end 272.24863 -359.57891)
				)
				(xy 272.246344 -359.581196)
				(arc
					(start 272.226024 -359.581196)
					(mid 271.703783 -359.504742)
					(end 272.226024 -359.428288)
				)
				(arc
					(start 272.226024 -359.428288)
					(mid 272.292939 -359.394071)
					(end 272.31975 -359.323894)
				)
				(xy 272.31975 -359.143808) (xy 272.320512 -359.143046) (xy 272.321528 -359.123996)
			)
		)
	)
	(zone
		(layer "B.Cu")
		(hatch none 0.5)
		(connect_pads
			(clearance 0)
		)
		(min_thickness 0.25)
		(keepout
			(tracks not_allowed)
			(vias allowed)
			(pads allowed)
			(copperpour not_allowed)
			(footprints allowed)
		)
		(placement
			(enabled no)
			(sheetname "")
		)
		(fill
			(thermal_gap 0.5)
			(thermal_bridge_width 0.5)
			(island_removal_mode 0)
		)
		(polygon
			(pts
				(arc
					(start 238.374936 -61.849762)
					(mid 238.699802 -60.875164)
					(end 237.725204 -60.550298)
				)
				(xy 237.723934 -60.548012) (xy 235.724192 -61.54801) (xy 235.724192 -61.548264)
				(arc
					(start 235.725208 -61.550296)
					(mid 235.333 -62.316193)
					(end 235.94695 -62.919102)
				)
				(arc
					(start 236.153198 -62.919102)
					(mid 236.266861 -62.893357)
					(end 236.37494 -62.84976)
				)
				(xy 236.37621 -62.852046) (xy 236.864144 -62.607952) (xy 236.8804 -62.59195) (xy 236.908086 -62.56401)
				(xy 236.90834 -62.56401)
				(arc
					(start 237.119922 -62.352428)
					(mid 237.132561 -62.331103)
					(end 237.13694 -62.306708)
				)
				(arc
					(start 237.13694 -62.188852)
					(mid 237.131657 -62.162205)
					(end 237.11662 -62.139576)
				)
				(arc
					(start 236.954568 -61.977524)
					(mid 236.915528 -61.949038)
					(end 236.869732 -61.933582)
				)
				(arc
					(start 236.85119 -61.930534)
					(mid 236.80142 -61.930693)
					(end 236.754162 -61.946282)
				)
				(arc
					(start 236.572044 -62.0395)
					(mid 235.564081 -62.449091)
					(end 236.485176 -61.870082)
				)
				(xy 236.667294 -61.77661) (xy 236.702346 -61.758576)
				(arc
					(start 236.705902 -61.759846)
					(mid 236.77166 -61.742632)
					(end 236.839506 -61.73851)
				)
				(xy 236.842554 -61.736224) (xy 236.896656 -61.745114) (xy 236.901228 -61.745876) (xy 236.936026 -61.751464)
				(arc
					(start 236.937804 -61.754004)
					(mid 237.000702 -61.778672)
					(end 237.057692 -61.814964)
				)
				(xy 237.061248 -61.814964) (xy 237.27918 -62.032896)
				(arc
					(start 237.27918 -62.037976)
					(mid 237.307656 -62.089413)
					(end 237.323884 -62.145926)
				)
				(xy 237.32744 -62.149482) (xy 237.32744 -62.346078)
				(arc
					(start 237.323884 -62.349634)
					(mid 237.320596 -62.365887)
					(end 237.316264 -62.381892)
				)
				(xy 237.42904 -62.325504)
				(arc
					(start 237.42904 -62.104524)
					(mid 237.416892 -62.043924)
					(end 237.382558 -61.99251)
				)
				(xy 237.237016 -61.846714)
				(arc
					(start 237.237016 -61.841634)
					(mid 237.226537 -61.825857)
					(end 237.217204 -61.809376)
				)
				(arc
					(start 237.217204 -61.808868)
					(mid 237.191186 -61.729535)
					(end 237.191296 -61.646054)
				)
				(arc
					(start 237.191296 -61.6458)
					(mid 237.227217 -61.549762)
					(end 237.29696 -61.474604)
				)
				(xy 237.298484 -61.469778)
				(arc
					(start 237.526576 -61.355732)
					(mid 238.537853 -60.954985)
					(end 237.61192 -61.525912)
				)
				(arc
					(start 237.419134 -61.622432)
					(mid 237.392708 -61.644704)
					(end 237.379256 -61.676534)
				)
				(arc
					(start 237.379256 -61.676534)
					(mid 237.379224 -61.699702)
					(end 237.386368 -61.721746)
				)
				(arc
					(start 237.386368 -61.721746)
					(mid 237.392303 -61.731133)
					(end 237.399576 -61.739526)
				)
				(xy 237.39983 -61.740034) (xy 237.42777 -61.767974) (xy 237.42777 -61.768228) (xy 237.50651 -61.846714)
				(xy 237.517178 -61.857636) (xy 237.517432 -61.857636) (xy 237.545118 -61.885576)
				(arc
					(start 237.545118 -61.889132)
					(mid 237.592944 -61.970948)
					(end 237.617 -62.062614)
				)
				(xy 237.61954 -62.065154) (xy 237.61954 -62.230254) (xy 238.376206 -61.852048)
			)
		)
	)
	(zone
		(layer "B.Cu")
		(hatch none 0.5)
		(connect_pads
			(clearance 0)
		)
		(min_thickness 0.25)
		(keepout
			(tracks allowed)
			(vias allowed)
			(pads allowed)
			(copperpour allowed)
			(footprints not_allowed)
		)
		(placement
			(enabled no)
			(sheetname "")
		)
		(fill
			(thermal_gap 0.5)
			(thermal_bridge_width 0.5)
			(island_removal_mode 0)
		)
		(polygon
			(pts
				(arc
					(start 31.224982 -5.199888)
					(mid 32.325056 -6.299962)
					(end 33.424876 -5.199888)
				)
				(arc
					(start 33.424876 -5.199888)
					(mid 32.325056 -4.100068)
					(end 31.224982 -5.199888)
				)
			)
		)
	)
	(zone
		(layer "B.Cu")
		(hatch none 0.5)
		(connect_pads
			(clearance 0)
		)
		(min_thickness 0.25)
		(keepout
			(tracks allowed)
			(vias allowed)
			(pads allowed)
			(copperpour allowed)
			(footprints not_allowed)
		)
		(placement
			(enabled no)
			(sheetname "")
		)
		(fill
			(thermal_gap 0.5)
			(thermal_bridge_width 0.5)
			(island_removal_mode 0)
		)
		(polygon
			(pts
				(arc
					(start 485.000046 -5.500116)
					(mid 481.24999 -1.75006)
					(end 477.499934 -5.500116)
				)
				(arc
					(start 477.499934 -5.500116)
					(mid 481.24999 -9.250172)
					(end 485.000046 -5.500116)
				)
			)
		)
	)
	(zone
		(layer "B.Cu")
		(hatch none 0.5)
		(connect_pads
			(clearance 0)
		)
		(min_thickness 0.25)
		(keepout
			(tracks not_allowed)
			(vias allowed)
			(pads allowed)
			(copperpour not_allowed)
			(footprints allowed)
		)
		(placement
			(enabled no)
			(sheetname "")
		)
		(fill
			(thermal_gap 0.5)
			(thermal_bridge_width 0.5)
			(island_removal_mode 0)
		)
		(polygon
			(pts
				(arc
					(start 103.324914 -92.799916)
					(mid 96.324928 -85.79993)
					(end 89.324942 -92.799916)
				)
				(arc
					(start 89.324942 -98.799904)
					(mid 96.324928 -105.79989)
					(end 103.324914 -98.799904)
				)
			)
		)
	)
	(zone
		(layer "B.Cu")
		(hatch none 0.5)
		(connect_pads
			(clearance 0)
		)
		(min_thickness 0.25)
		(keepout
			(tracks allowed)
			(vias allowed)
			(pads allowed)
			(copperpour allowed)
			(footprints not_allowed)
		)
		(placement
			(enabled no)
			(sheetname "")
		)
		(fill
			(thermal_gap 0.5)
			(thermal_bridge_width 0.5)
			(island_removal_mode 0)
		)
		(polygon
			(pts
				(arc
					(start 463.674968 -322.799964)
					(mid 456.674982 -315.799978)
					(end 449.674996 -322.799964)
				)
				(arc
					(start 449.674996 -328.799952)
					(mid 456.674982 -335.799938)
					(end 463.674968 -328.799952)
				)
			)
		)
	)
	(zone
		(layer "B.Cu")
		(hatch none 0.5)
		(connect_pads
			(clearance 0)
		)
		(min_thickness 0.25)
		(keepout
			(tracks allowed)
			(vias allowed)
			(pads allowed)
			(copperpour allowed)
			(footprints allowed)
		)
		(placement
			(enabled no)
			(sheetname "")
		)
		(fill
			(thermal_gap 0.5)
			(thermal_bridge_width 0.5)
			(island_removal_mode 0)
		)
		(polygon
			(pts
				(xy 268.491462 -104.594152) (xy 270.65351 -104.594152) (xy 270.65351 -98.591878) (xy 268.491462 -98.591878)
			)
		)
	)
	(zone
		(layer "B.Cu")
		(hatch none 0.5)
		(connect_pads
			(clearance 0)
		)
		(min_thickness 0.25)
		(keepout
			(tracks allowed)
			(vias allowed)
			(pads allowed)
			(copperpour allowed)
			(footprints not_allowed)
		)
		(placement
			(enabled no)
			(sheetname "")
		)
		(fill
			(thermal_gap 0.5)
			(thermal_bridge_width 0.5)
			(island_removal_mode 0)
		)
		(polygon
			(pts
				(arc
					(start 195.300092 -189.799976)
					(mid 202.300078 -196.799962)
					(end 209.300064 -189.799976)
				)
				(arc
					(start 209.300064 -183.799988)
					(mid 202.300078 -176.800002)
					(end 195.300092 -183.799988)
				)
			)
		)
	)
	(zone
		(net "GND")
		(layer "B.Cu")
		(hatch none 0.5)
		(connect_pads
			(clearance 0.5)
		)
		(min_thickness 0.25)
		(fill yes
			(thermal_gap 0.5)
			(thermal_bridge_width 0.5)
			(island_removal_mode 0)
		)
		(polygon
			(pts
				(arc
					(start 258.67995 -299.734478)
					(mid 257.624161 -298.941055)
					(end 256.370582 -298.525438)
				)
				(arc
					(start 256.370582 -298.525438)
					(mid 254.168107 -296.888586)
					(end 251.426726 -297.012106)
				)
				(arc
					(start 251.426726 -297.012106)
					(mid 251.329952 -296.962936)
					(end 251.231908 -296.916348)
				)
				(arc
					(start 251.231908 -296.916348)
					(mid 252.23348 -295.074886)
					(end 252.191266 -292.979094)
				)
				(arc
					(start 252.191266 -292.979094)
					(mid 253.029179 -292.999687)
					(end 253.853696 -292.849046)
				)
				(arc
					(start 253.853696 -292.849046)
					(mid 255.071114 -293.040532)
					(end 256.290318 -292.86073)
				)
				(arc
					(start 256.290318 -292.86073)
					(mid 256.561282 -292.927448)
					(end 256.836164 -292.975538)
				)
				(arc
					(start 256.836164 -292.975538)
					(mid 260.424343 -293.950742)
					(end 263.319514 -291.6174)
				)
				(arc
					(start 263.319514 -291.6174)
					(mid 263.543711 -292.38961)
					(end 263.914636 -293.103046)
				)
				(arc
					(start 263.914636 -293.103046)
					(mid 261.912624 -295.817901)
					(end 262.631174 -299.113702)
				)
				(arc
					(start 261.050786 -300.693836)
					(mid 259.942279 -300.024099)
					(end 258.67995 -299.734478)
				)
			)
		)
	)
	(zone
		(layer "B.Cu")
		(hatch none 0.5)
		(connect_pads
			(clearance 0)
		)
		(min_thickness 0.25)
		(keepout
			(tracks not_allowed)
			(vias allowed)
			(pads allowed)
			(copperpour not_allowed)
			(footprints allowed)
		)
		(placement
			(enabled no)
			(sheetname "")
		)
		(fill
			(thermal_gap 0.5)
			(thermal_bridge_width 0.5)
			(island_removal_mode 0)
		)
		(polygon
			(pts
				(arc
					(start 279.236678 -328.356468)
					(mid 278.688038 -328.905108)
					(end 279.236678 -329.453748)
				)
				(xy 279.642824 -329.453748) (xy 279.644094 -329.452478)
				(arc
					(start 279.661874 -329.432666)
					(mid 279.700941 -329.362088)
					(end 279.714452 -329.282552)
				)
				(arc
					(start 279.714452 -329.032108)
					(mid 279.699573 -328.996187)
					(end 279.663652 -328.981308)
				)
				(arc
					(start 279.623012 -328.981308)
					(mid 278.842901 -328.905108)
					(end 279.623012 -328.828908)
				)
				(xy 279.695148 -328.828908)
				(arc
					(start 279.698196 -328.831956)
					(mid 279.807273 -328.888487)
					(end 279.863804 -328.997564)
				)
				(xy 279.866852 -329.000612) (xy 279.866852 -329.314048)
				(arc
					(start 279.865582 -329.315572)
					(mid 279.852889 -329.386413)
					(end 279.827482 -329.453748)
				)
				(arc
					(start 279.978358 -329.453748)
					(mid 279.999443 -329.369558)
					(end 280.006552 -329.28306)
				)
				(xy 280.006552 -329.000612)
				(arc
					(start 280.0096 -328.997564)
					(mid 280.066131 -328.888487)
					(end 280.175208 -328.831956)
				)
				(xy 280.178256 -328.828908)
				(arc
					(start 280.250392 -328.828908)
					(mid 281.030503 -328.905108)
					(end 280.250392 -328.981308)
				)
				(arc
					(start 280.209752 -328.981308)
					(mid 280.173831 -328.996187)
					(end 280.158952 -329.032108)
				)
				(xy 280.158952 -329.28306) (xy 280.158952 -329.314556)
				(arc
					(start 280.15819 -329.315318)
					(mid 280.151333 -329.385069)
					(end 280.137362 -329.453748)
				)
				(arc
					(start 280.636726 -329.453748)
					(mid 281.185366 -328.905108)
					(end 280.636726 -328.356468)
				)
				(xy 279.236932 -328.356468)
			)
		)
	)
	(zone
		(net "MB3_P12V_IN_R")
		(layer "B.Cu")
		(hatch none 0.5)
		(connect_pads
			(clearance 0.5)
		)
		(min_thickness 0.25)
		(fill yes
			(thermal_gap 0.5)
			(thermal_bridge_width 0.5)
			(island_removal_mode 0)
		)
		(polygon
			(pts
				(xy 252.70206 -377.825) (xy 252.49886 -378.0282) (xy 252.49886 -388.38886) (xy 254.281432 -390.171432)
				(xy 273.904456 -390.171432) (xy 274.465542 -389.610346) (xy 274.465542 -378.077222) (xy 274.21332 -377.825)
			)
		)
	)
	(zone
		(layer "B.Cu")
		(hatch none 0.5)
		(connect_pads
			(clearance 0)
		)
		(min_thickness 0.25)
		(keepout
			(tracks allowed)
			(vias allowed)
			(pads allowed)
			(copperpour allowed)
			(footprints not_allowed)
		)
		(placement
			(enabled no)
			(sheetname "")
		)
		(fill
			(thermal_gap 0.5)
			(thermal_bridge_width 0.5)
			(island_removal_mode 0)
		)
		(polygon
			(pts
				(arc
					(start 233.59999 6.500114)
					(mid 229.849934 10.25017)
					(end 226.099878 6.500114)
				)
				(arc
					(start 226.099878 6.500114)
					(mid 229.849934 2.750058)
					(end 233.59999 6.500114)
				)
			)
		)
	)
	(zone
		(layer "B.Cu")
		(hatch none 0.5)
		(connect_pads
			(clearance 0)
		)
		(min_thickness 0.25)
		(keepout
			(tracks not_allowed)
			(vias allowed)
			(pads allowed)
			(copperpour not_allowed)
			(footprints allowed)
		)
		(placement
			(enabled no)
			(sheetname "")
		)
		(fill
			(thermal_gap 0.5)
			(thermal_bridge_width 0.5)
			(island_removal_mode 0)
		)
		(polygon
			(pts
				(arc
					(start 140.298678 -21.950426)
					(mid 139.750165 -21.401532)
					(end 139.201398 -21.950172)
				)
				(arc
					(start 139.201398 -23.35022)
					(mid 139.750038 -23.89886)
					(end 140.298678 -23.35022)
				)
				(arc
					(start 140.298678 -22.895052)
					(mid 140.282777 -22.892373)
					(end 140.266674 -22.891496)
				)
				(arc
					(start 139.916408 -22.891496)
					(mid 139.866119 -22.912327)
					(end 139.845288 -22.962616)
				)
				(arc
					(start 139.845288 -22.968204)
					(mid 139.750038 -23.743932)
					(end 139.654788 -22.968204)
				)
				(xy 139.654788 -22.923246)
				(arc
					(start 139.658344 -22.91969)
					(mid 139.731422 -22.77763)
					(end 139.873482 -22.704552)
				)
				(xy 139.877038 -22.700996) (xy 140.298678 -22.700996) (xy 140.298678 -22.600666) (xy 140.266674 -22.599396)
				(xy 139.877038 -22.599396)
				(arc
					(start 139.873482 -22.59584)
					(mid 139.731422 -22.522762)
					(end 139.658344 -22.380702)
				)
				(xy 139.654788 -22.377146)
				(arc
					(start 139.654788 -22.332188)
					(mid 139.750038 -21.55646)
					(end 139.845288 -22.332188)
				)
				(arc
					(start 139.845288 -22.337776)
					(mid 139.866119 -22.388065)
					(end 139.916408 -22.408896)
				)
				(xy 140.298678 -22.408896)
			)
		)
	)
	(zone
		(layer "B.Cu")
		(hatch none 0.5)
		(connect_pads
			(clearance 0)
		)
		(min_thickness 0.25)
		(keepout
			(tracks not_allowed)
			(vias allowed)
			(pads allowed)
			(copperpour not_allowed)
			(footprints allowed)
		)
		(placement
			(enabled no)
			(sheetname "")
		)
		(fill
			(thermal_gap 0.5)
			(thermal_bridge_width 0.5)
			(island_removal_mode 0)
		)
		(polygon
			(pts
				(arc
					(start 281.074876 -45.849794)
					(mid 281.399742 -44.875196)
					(end 280.425144 -44.55033)
				)
				(xy 280.423874 -44.548044)
				(arc
					(start 279.406858 -45.056552)
					(mid 279.435725 -45.070189)
					(end 279.464008 -45.085)
				)
				(arc
					(start 279.464262 -45.085)
					(mid 279.540831 -45.133058)
					(end 279.611328 -45.189648)
				)
				(xy 279.612598 -45.189648) (xy 279.640284 -45.217334) (xy 279.640538 -45.217588) (xy 279.775158 -45.352208)
				(arc
					(start 279.845516 -45.422566)
					(mid 279.884556 -45.451052)
					(end 279.930352 -45.466508)
				)
				(xy 279.933908 -45.467016)
				(arc
					(start 279.948894 -45.469556)
					(mid 279.998664 -45.469397)
					(end 280.045922 -45.453808)
				)
				(arc
					(start 280.22804 -45.36059)
					(mid 280.203915 -45.208932)
					(end 280.22296 -45.056552)
				)
				(arc
					(start 280.22296 -45.056552)
					(mid 281.286157 -45.095645)
					(end 280.314908 -45.530008)
				)
				(xy 280.13279 -45.62348) (xy 280.097738 -45.641514)
				(arc
					(start 280.094182 -45.640244)
					(mid 280.028424 -45.657458)
					(end 279.960578 -45.66158)
				)
				(xy 279.95753 -45.663866) (xy 279.918414 -45.657516) (xy 279.903428 -45.654976) (xy 279.898856 -45.654214)
				(xy 279.864058 -45.648626)
				(arc
					(start 279.86228 -45.646086)
					(mid 279.799382 -45.621418)
					(end 279.742392 -45.585126)
				)
				(xy 279.738836 -45.585126) (xy 279.505918 -45.352208)
				(arc
					(start 279.505664 -45.351954)
					(mid 279.442649 -45.297332)
					(end 279.372568 -45.252132)
				)
				(arc
					(start 279.372568 -45.252132)
					(mid 279.266851 -45.206929)
					(end 279.154382 -45.183044)
				)
				(xy 278.958548 -45.280834) (xy 279.127712 -45.280834)
				(arc
					(start 279.12949 -45.282612)
					(mid 279.229597 -45.301772)
					(end 279.323546 -45.341286)
				)
				(arc
					(start 279.323546 -45.341286)
					(mid 279.364913 -45.366866)
					(end 279.403556 -45.396404)
				)
				(xy 279.405842 -45.396404) (xy 279.433528 -45.423836) (xy 279.433782 -45.424344) (xy 279.562814 -45.553376)
				(arc
					(start 279.562814 -45.558202)
					(mid 279.605174 -45.651569)
					(end 279.608788 -45.754036)
				)
				(arc
					(start 279.608788 -45.75429)
					(mid 279.572867 -45.850328)
					(end 279.503124 -45.925486)
				)
				(xy 279.5016 -45.930312)
				(arc
					(start 279.273508 -46.044358)
					(mid 278.262231 -46.445105)
					(end 279.188164 -45.874178)
				)
				(arc
					(start 279.38095 -45.777658)
					(mid 279.407376 -45.755386)
					(end 279.420828 -45.723556)
				)
				(arc
					(start 279.420828 -45.723556)
					(mid 279.418215 -45.689305)
					(end 279.400254 -45.660056)
				)
				(arc
					(start 279.298654 -45.55871)
					(mid 279.266896 -45.531205)
					(end 279.231598 -45.508418)
				)
				(arc
					(start 279.231598 -45.508418)
					(mid 279.162303 -45.480872)
					(end 279.088342 -45.471334)
				)
				(xy 278.577548 -45.471334) (xy 278.424132 -45.548042) (xy 278.424132 -45.548296)
				(arc
					(start 278.425148 -45.550328)
					(mid 278.100282 -46.524926)
					(end 279.07488 -46.849792)
				)
				(xy 279.07615 -46.852078) (xy 281.076146 -45.85208)
			)
		)
	)
	(zone
		(net "GND")
		(layer "B.Cu")
		(hatch none 0.5)
		(connect_pads
			(clearance 0.5)
		)
		(min_thickness 0.25)
		(fill yes
			(thermal_gap 0.5)
			(thermal_bridge_width 0.5)
			(island_removal_mode 0)
		)
		(polygon
			(pts
				(xy 470.958672 -186.182) (xy 464.60029 -195.797424)
				(arc
					(start 461.559402 -198.143876)
					(mid 464.117029 -199.944256)
					(end 466.052916 -202.400916)
				)
				(xy 466.410294 -202.043538) (xy 466.410294 -200.857866) (xy 467.595966 -200.857866) (xy 467.895686 -200.558146)
				(xy 468.02548 -200.558146) (xy 468.02548 -199.461374)
				(arc
					(start 470.238328 -199.461374)
					(mid 470.465116 -199.404808)
					(end 470.694766 -199.361298)
				)
				(xy 471.334338 -198.721472)
				(arc
					(start 478.993708 -198.721472)
					(mid 480.390819 -197.834947)
					(end 481.955856 -197.297802)
				)
				(arc
					(start 481.955856 -197.297802)
					(mid 481.500113 -196.56417)
					(end 481.208588 -195.751196)
				)
				(arc
					(start 481.208588 -195.751196)
					(mid 480.782951 -195.495682)
					(end 480.388168 -195.194682)
				)
				(arc
					(start 480.388168 -195.194682)
					(mid 476.016562 -193.623683)
					(end 475.933008 -188.979048)
				)
				(arc
					(start 475.933008 -188.979048)
					(mid 474.532368 -187.82669)
					(end 473.767658 -186.182)
				)
			)
		)
	)
	(zone
		(layer "B.Cu")
		(hatch none 0.5)
		(connect_pads
			(clearance 0)
		)
		(min_thickness 0.25)
		(keepout
			(tracks allowed)
			(vias allowed)
			(pads allowed)
			(copperpour allowed)
			(footprints not_allowed)
		)
		(placement
			(enabled no)
			(sheetname "")
		)
		(fill
			(thermal_gap 0.5)
			(thermal_bridge_width 0.5)
			(island_removal_mode 0)
		)
		(polygon
			(pts
				(arc
					(start 328.425048 -9.19988)
					(mid 323.674994 -4.449826)
					(end 318.92494 -9.19988)
				)
				(arc
					(start 318.92494 -9.19988)
					(mid 323.674994 -13.949934)
					(end 328.425048 -9.19988)
				)
			)
		)
	)
	(zone
		(layer "B.Cu")
		(hatch none 0.5)
		(connect_pads
			(clearance 0)
		)
		(min_thickness 0.25)
		(keepout
			(tracks allowed)
			(vias allowed)
			(pads allowed)
			(copperpour allowed)
			(footprints allowed)
		)
		(placement
			(enabled no)
			(sheetname "")
		)
		(fill
			(thermal_gap 0.5)
			(thermal_bridge_width 0.5)
			(island_removal_mode 0)
		)
		(polygon
			(pts
				(xy 48.2346 -146.9898) (xy 48.2346 -144.4244) (xy 50.9524 -144.4244) (xy 50.9524 -146.9898)
			)
		)
	)
	(zone
		(net "GND")
		(layer "B.Cu")
		(hatch none 0.5)
		(connect_pads
			(clearance 0.5)
		)
		(min_thickness 0.25)
		(fill yes
			(thermal_gap 0.5)
			(thermal_bridge_width 0.5)
			(island_removal_mode 0)
		)
		(polygon
			(pts
				(arc
					(start 76.608686 -306.97297)
					(mid 76.708835 -303.858149)
					(end 74.585576 -301.576994)
				)
				(arc
					(start 74.585576 -301.576994)
					(mid 74.739263 -300.478638)
					(end 74.59218 -299.379386)
				)
				(arc
					(start 74.59218 -299.379386)
					(mid 77.599977 -299.966683)
					(end 80.171544 -298.299632)
				)
				(arc
					(start 80.171544 -298.299632)
					(mid 80.591928 -300.490141)
					(end 82.09915 -302.13427)
				)
				(arc
					(start 82.09915 -302.13427)
					(mid 82.865544 -303.206317)
					(end 83.93303 -303.979072)
				)
				(arc
					(start 83.93303 -303.979072)
					(mid 83.403715 -305.13272)
					(end 83.25358 -306.393088)
				)
				(arc
					(start 83.25358 -306.393088)
					(mid 79.781408 -304.967208)
					(end 76.608686 -306.97297)
				)
			)
		)
	)
	(zone
		(net "P12V_A_VIN_U20")
		(layer "B.Cu")
		(hatch none 0.5)
		(connect_pads
			(clearance 0.5)
		)
		(min_thickness 0.25)
		(fill yes
			(thermal_gap 0.5)
			(thermal_bridge_width 0.5)
			(island_removal_mode 0)
		)
		(polygon
			(pts
				(xy 15.543784 -244.8306) (xy 15.356078 -245.018306) (xy 15.356078 -246.400828) (xy 15.5194 -246.56415)
				(xy 23.003002 -246.56415) (xy 23.384002 -246.94515) (xy 24.146002 -246.94515) (xy 24.400002 -247.19915)
				(xy 24.400002 -248.21515) (xy 24.654002 -248.46915) (xy 25.289002 -248.46915) (xy 25.670002 -248.85015)
				(xy 27.575002 -248.85015) (xy 27.575002 -245.80215) (xy 26.603452 -244.8306)
			)
		)
		(polygon
			(pts
				(xy 24.0538 -246.2276) (xy 23.8506 -246.2276) (xy 23.8506 -246.4308) (xy 24.0538 -246.4308)
			)
		)
		(polygon
			(pts
				(xy 23.4442 -246.2276) (xy 23.241 -246.2276) (xy 23.241 -246.4308) (xy 23.4442 -246.4308)
			)
		)
		(polygon
			(pts
				(xy 16.9291 -245.1735) (xy 16.7259 -245.1735) (xy 16.7259 -245.3767) (xy 16.9291 -245.3767)
			)
		)
	)
	(zone
		(layer "B.Cu")
		(hatch none 0.5)
		(connect_pads
			(clearance 0)
		)
		(min_thickness 0.25)
		(keepout
			(tracks not_allowed)
			(vias allowed)
			(pads allowed)
			(copperpour not_allowed)
			(footprints allowed)
		)
		(placement
			(enabled no)
			(sheetname "")
		)
		(fill
			(thermal_gap 0.5)
			(thermal_bridge_width 0.5)
			(island_removal_mode 0)
		)
		(polygon
			(pts
				(arc
					(start 281.074876 -73.849738)
					(mid 281.399742 -72.87514)
					(end 280.425144 -72.550274)
				)
				(xy 280.423874 -72.547988) (xy 278.424132 -73.547986) (xy 278.424132 -73.54824)
				(arc
					(start 278.425148 -73.550272)
					(mid 278.100282 -74.52487)
					(end 279.07488 -74.849736)
				)
				(xy 279.07615 -74.852022)
				(arc
					(start 280.086562 -74.346816)
					(mid 279.982979 -74.285364)
					(end 279.888696 -74.210418)
				)
				(xy 279.887426 -74.210418)
				(arc
					(start 279.654508 -73.9775)
					(mid 279.615468 -73.949014)
					(end 279.569672 -73.933558)
				)
				(xy 279.566116 -73.93305)
				(arc
					(start 279.55113 -73.93051)
					(mid 279.50136 -73.930669)
					(end 279.454102 -73.946258)
				)
				(arc
					(start 279.271984 -74.039476)
					(mid 278.264021 -74.449067)
					(end 279.185116 -73.870058)
				)
				(xy 279.367234 -73.776586) (xy 279.402286 -73.758552)
				(arc
					(start 279.405842 -73.759822)
					(mid 279.4716 -73.742608)
					(end 279.539446 -73.738486)
				)
				(xy 279.542494 -73.7362) (xy 279.58161 -73.74255) (xy 279.596596 -73.74509) (xy 279.601168 -73.745852)
				(xy 279.635966 -73.75144)
				(arc
					(start 279.637744 -73.75398)
					(mid 279.700642 -73.778648)
					(end 279.757632 -73.81494)
				)
				(xy 279.761188 -73.81494) (xy 279.879298 -73.93305)
				(arc
					(start 279.994106 -74.047858)
					(mid 280.143896 -74.161511)
					(end 280.318718 -74.230738)
				)
				(xy 280.481786 -74.149204) (xy 280.445464 -74.149204)
				(arc
					(start 280.44394 -74.14768)
					(mid 280.258325 -74.104044)
					(end 280.096214 -74.003662)
				)
				(xy 280.094182 -74.003662) (xy 280.066242 -73.975722) (xy 279.93721 -73.84669)
				(arc
					(start 279.93721 -73.841864)
					(mid 279.89485 -73.748497)
					(end 279.891236 -73.64603)
				)
				(arc
					(start 279.891236 -73.645776)
					(mid 279.927157 -73.549738)
					(end 279.9969 -73.47458)
				)
				(xy 279.998424 -73.469754)
				(arc
					(start 280.226516 -73.355708)
					(mid 281.237793 -72.954961)
					(end 280.31186 -73.525888)
				)
				(arc
					(start 280.119074 -73.622408)
					(mid 280.092648 -73.64468)
					(end 280.079196 -73.67651)
				)
				(arc
					(start 280.079196 -73.67651)
					(mid 280.081809 -73.710761)
					(end 280.09977 -73.74001)
				)
				(arc
					(start 280.200862 -73.841102)
					(mid 280.331149 -73.928157)
					(end 280.484834 -73.958704)
				)
				(xy 280.862786 -73.958704) (xy 281.076146 -73.852024)
			)
		)
	)
	(zone
		(layer "B.Cu")
		(hatch none 0.5)
		(connect_pads
			(clearance 0)
		)
		(min_thickness 0.25)
		(keepout
			(tracks not_allowed)
			(vias allowed)
			(pads allowed)
			(copperpour not_allowed)
			(footprints allowed)
		)
		(placement
			(enabled no)
			(sheetname "")
		)
		(fill
			(thermal_gap 0.5)
			(thermal_bridge_width 0.5)
			(island_removal_mode 0)
		)
		(polygon
			(pts
				(arc
					(start 285.436564 -297.75658)
					(mid 284.887924 -298.30522)
					(end 285.436564 -298.85386)
				)
				(arc
					(start 285.935928 -298.85386)
					(mid 285.921943 -298.784926)
					(end 285.9151 -298.714922)
				)
				(xy 285.914338 -298.71416)
				(arc
					(start 285.914338 -298.43222)
					(mid 285.899459 -298.396299)
					(end 285.863538 -298.38142)
				)
				(arc
					(start 285.822898 -298.38142)
					(mid 285.042787 -298.30522)
					(end 285.822898 -298.22902)
				)
				(xy 285.895034 -298.22902)
				(arc
					(start 285.898082 -298.232068)
					(mid 286.007159 -298.288599)
					(end 286.06369 -298.397676)
				)
				(xy 286.066738 -298.400724)
				(arc
					(start 286.066738 -298.682918)
					(mid 286.073833 -298.769544)
					(end 286.094932 -298.85386)
				)
				(arc
					(start 286.245808 -298.85386)
					(mid 286.220397 -298.786526)
					(end 286.207708 -298.715684)
				)
				(xy 286.206438 -298.71416) (xy 286.206438 -298.400724)
				(arc
					(start 286.209486 -298.397676)
					(mid 286.266017 -298.288599)
					(end 286.375094 -298.232068)
				)
				(xy 286.378142 -298.22902)
				(arc
					(start 286.450278 -298.22902)
					(mid 287.230389 -298.30522)
					(end 286.450278 -298.38142)
				)
				(arc
					(start 286.409638 -298.38142)
					(mid 286.373717 -298.396299)
					(end 286.358838 -298.43222)
				)
				(arc
					(start 286.358838 -298.682664)
					(mid 286.377129 -298.774617)
					(end 286.429196 -298.85259)
				)
				(xy 286.430466 -298.85386)
				(arc
					(start 286.836612 -298.85386)
					(mid 287.385252 -298.30522)
					(end 286.836612 -297.75658)
				)
				(xy 285.436818 -297.75658)
			)
		)
	)
	(zone
		(net "GND")
		(layer "B.Cu")
		(hatch none 0.5)
		(connect_pads
			(clearance 0.5)
		)
		(min_thickness 0.25)
		(fill yes
			(thermal_gap 0.5)
			(thermal_bridge_width 0.5)
			(island_removal_mode 0)
		)
		(polygon
			(pts
				(arc
					(start 396.999968 -0.763016)
					(mid 396.832396 -0.832426)
					(end 396.762986 -0.999998)
				)
				(arc
					(start 396.762986 -13.999972)
					(mid 396.645735 -14.632178)
					(end 396.309596 -15.18031)
				)
				(xy 396.309596 -20.479004)
				(arc
					(start 396.251684 -20.476972)
					(mid 394.862923 -20.503786)
					(end 393.54252 -20.072604)
				)
				(arc
					(start 393.54252 -20.567396)
					(mid 394.084861 -21.696187)
					(end 394.288264 -22.931882)
				)
				(xy 394.28928 -23.023576)
				(arc
					(start 394.28928 -37.328856)
					(mid 394.74418 -37.251035)
					(end 395.20495 -37.22497)
				)
				(arc
					(start 396.350236 -37.22497)
					(mid 396.580983 -37.231555)
					(end 396.810992 -37.251132)
				)
				(arc
					(start 400.207226 -37.251132)
					(mid 402.782278 -29.983195)
					(end 405.35733 -37.251132)
				)
				(arc
					(start 416.308794 -37.251132)
					(mid 417.032352 -36.155792)
					(end 418.053774 -35.331146)
				)
				(arc
					(start 418.053774 -35.331146)
					(mid 423.044979 -32.059714)
					(end 425.988226 -37.251132)
				)
				(arc
					(start 426.29201 -37.251132)
					(mid 426.522019 -37.231543)
					(end 426.752766 -37.22497)
				)
				(arc
					(start 427.900338 -37.22497)
					(mid 428.131085 -37.231555)
					(end 428.361094 -37.251132)
				)
				(arc
					(start 447.858642 -37.251132)
					(mid 448.5822 -36.155792)
					(end 449.603622 -35.331146)
				)
				(arc
					(start 449.603622 -35.331146)
					(mid 454.619949 -32.065877)
					(end 457.522326 -37.300408)
				)
				(arc
					(start 457.522326 -37.300408)
					(mid 457.911291 -37.243889)
					(end 458.303884 -37.22497)
				)
				(arc
					(start 459.450186 -37.22497)
					(mid 459.680933 -37.231555)
					(end 459.910942 -37.251132)
				)
				(arc
					(start 463.856324 -37.251132)
					(mid 466.993391 -34.81194)
					(end 470.721436 -36.187888)
				)
				(arc
					(start 472.63685 -36.187888)
					(mid 474.192299 -36.497398)
					(end 475.51086 -37.37864)
				)
				(arc
					(start 476.586296 -38.453822)
					(mid 477.823307 -38.287796)
					(end 479.052382 -38.504876)
				)
				(arc
					(start 479.052382 -38.504876)
					(mid 479.730877 -36.671589)
					(end 481.153724 -35.331146)
				)
				(arc
					(start 481.153724 -35.331146)
					(mid 482.717727 -32.771141)
					(end 485.607868 -31.966916)
				)
				(xy 489.418122 -31.966916) (xy 489.418122 -313.853068) (xy 485.607868 -313.853068) (xy 485.585262 -313.855354)
				(arc
					(start 484.78059 -313.855354)
					(mid 482.50004 -312.872356)
					(end 481.208588 -310.75122)
				)
				(arc
					(start 481.208588 -310.75122)
					(mid 480.782951 -310.495706)
					(end 480.388168 -310.194706)
				)
				(arc
					(start 480.388168 -310.194706)
					(mid 476.016562 -308.623707)
					(end 475.933008 -303.979072)
				)
				(arc
					(start 475.933008 -303.979072)
					(mid 474.019005 -301.962004)
					(end 473.837 -299.187362)
				)
				(arc
					(start 473.837 -297.01998)
					(mid 472.785515 -296.959179)
					(end 471.784426 -296.631868)
				)
				(arc
					(start 471.784426 -296.631868)
					(mid 469.95513 -297.02392)
					(end 468.142574 -296.560494)
				)
				(arc
					(start 468.142574 -296.560494)
					(mid 467.68039 -296.606405)
					(end 467.215982 -296.59961)
				)
				(arc
					(start 467.215982 -296.59961)
					(mid 465.358618 -296.525737)
					(end 463.725768 -295.637458)
				)
				(arc
					(start 463.725768 -295.637458)
					(mid 463.923733 -298.217145)
					(end 462.534 -300.39945)
				)
				(arc
					(start 462.534 -303.161954)
					(mid 463.497368 -307.640195)
					(end 459.7019 -310.204866)
				)
				(arc
					(start 457.701396 -310.204866)
					(mid 457.494859 -311.131945)
					(end 457.080112 -311.986422)
				)
				(arc
					(start 457.080112 -311.986422)
					(mid 464.468594 -315.292872)
					(end 467.496144 -322.799964)
				)
				(arc
					(start 467.496144 -328.794364)
					(mid 456.674982 -339.615526)
					(end 445.85382 -328.794364)
				)
				(arc
					(start 445.85382 -322.799964)
					(mid 447.377227 -317.263783)
					(end 451.518528 -313.286394)
				)
				(arc
					(start 451.518528 -313.286394)
					(mid 450.335164 -312.204687)
					(end 449.658486 -310.75122)
				)
				(arc
					(start 449.658486 -310.75122)
					(mid 449.451296 -310.634833)
					(end 449.250562 -310.507634)
				)
				(arc
					(start 449.250562 -310.507634)
					(mid 444.131272 -311.665882)
					(end 442.087 -306.831746)
				)
				(xy 442.087 -304.81397)
				(arc
					(start 435.700424 -306.11318)
					(mid 436.462823 -307.594883)
					(end 436.570882 -309.2577)
				)
				(arc
					(start 436.570882 -309.2577)
					(mid 436.835207 -309.427259)
					(end 437.08574 -309.616602)
				)
				(arc
					(start 437.08574 -309.616602)
					(mid 439.160395 -315.488303)
					(end 433.033424 -316.602364)
				)
				(arc
					(start 433.033424 -316.602364)
					(mid 430.972649 -314.859013)
					(end 430.446688 -312.211466)
				)
				(arc
					(start 430.446688 -312.211466)
					(mid 429.40495 -311.335882)
					(end 428.708058 -310.16702)
				)
				(arc
					(start 428.708058 -310.16702)
					(mid 428.431587 -310.195366)
					(end 428.15383 -310.204866)
				)
				(arc
					(start 426.151548 -310.204866)
					(mid 422.360189 -313.865778)
					(end 418.108638 -310.75122)
				)
				(arc
					(start 418.108638 -310.75122)
					(mid 417.518791 -310.378777)
					(end 416.993832 -309.91937)
				)
				(arc
					(start 412.344108 -310.86552)
					(mid 410.619014 -318.07904)
					(end 406.212548 -312.112914)
				)
				(arc
					(start 399.255234 -313.52871)
					(mid 403.095119 -317.474986)
					(end 404.496016 -322.799964)
				)
				(arc
					(start 404.496016 -328.794364)
					(mid 393.674854 -339.615526)
					(end 382.853692 -328.794364)
				)
				(arc
					(start 382.853692 -322.799964)
					(mid 383.38202 -319.459996)
					(end 384.91541 -316.446154)
				)
				(arc
					(start 377.712478 -317.911734)
					(mid 375.506008 -319.571951)
					(end 372.747286 -319.451736)
				)
				(xy 353.822 -331.510386)
				(arc
					(start 353.822 -334.77962)
					(mid 354.651929 -339.514418)
					(end 350.406208 -341.76843)
				)
				(arc
					(start 350.406208 -341.76843)
					(mid 350.743673 -342.536719)
					(end 350.917256 -343.357708)
				)
				(arc
					(start 350.919034 -343.357708)
					(mid 350.564218 -345.505878)
					(end 349.157798 -347.167962)
				)
				(arc
					(start 344.54211 -347.167962)
					(mid 343.135679 -345.505883)
					(end 342.780874 -343.357708)
				)
				(arc
					(start 342.782652 -343.357708)
					(mid 343.362942 -341.651313)
					(end 344.620342 -340.36)
				)
				(arc
					(start 344.620342 -340.36)
					(mid 343.995239 -339.208716)
					(end 343.7636 -337.919314)
				)
				(xy 338.30514 -341.397082) (xy 329.46086 -343.357708) (xy 329.46086 -347.133672) (xy 329.42657 -347.167962)
				(arc
					(start 296.69994 -347.167962)
					(mid 294.555994 -348.056014)
					(end 293.667942 -350.19996)
				)
				(arc
					(start 293.667942 -373.000016)
					(mid 294.555994 -375.143962)
					(end 296.69994 -376.032014)
				)
				(xy 307.967888 -376.032014) (xy 307.967888 -409.271724)
				(arc
					(start 304.157634 -409.271724)
					(mid 299.451279 -409.995439)
					(end 294.889936 -408.62885)
				)
				(xy 294.889936 -409.58135) (xy 290.625784 -413.845502)
				(arc
					(start 288.110422 -413.845502)
					(mid 288.115052 -414.487812)
					(end 288.06521 -415.128202)
				)
				(xy 288.059876 -415.133536)
				(arc
					(start 288.059876 -415.171636)
					(mid 288.047499 -415.264807)
					(end 288.033968 -415.357818)
				)
				(xy 288.033714 -415.358072) (xy 288.033714 -419.168072) (xy 272.183606 -419.168072) (xy 272.183606 -420.437056)
				(arc
					(start 308.99989 -420.437056)
					(mid 309.167462 -420.367646)
					(end 309.236872 -420.200074)
				)
				(arc
					(start 309.236872 -375.000012)
					(mid 309.167462 -374.83244)
					(end 308.99989 -374.76303)
				)
				(arc
					(start 296.69994 -374.76303)
					(mid 295.453301 -374.246655)
					(end 294.936926 -373.000016)
				)
				(arc
					(start 294.936926 -350.19996)
					(mid 295.453301 -348.953321)
					(end 296.69994 -348.436946)
				)
				(arc
					(start 490.450124 -348.436946)
					(mid 490.617696 -348.367536)
					(end 490.687106 -348.199964)
				)
				(arc
					(start 490.687106 -0.999998)
					(mid 490.617696 -0.832426)
					(end 490.450124 -0.763016)
				)
			)
		)
		(polygon
			(pts
				(arc
					(start 416.65525 -343.357708)
					(mid 412.623 -338.581161)
					(end 408.59075 -343.357708)
				)
				(arc
					(start 408.589226 -343.357708)
					(mid 412.623 -346.763142)
					(end 416.656774 -343.357708)
				)
			)
		)
		(polygon
			(pts
				(arc
					(start 445.856106 -343.357708)
					(mid 441.96 -338.022376)
					(end 438.063894 -343.357708)
				)
				(arc
					(start 438.062116 -343.357708)
					(mid 441.96 -346.204518)
					(end 445.857884 -343.357708)
				)
			)
		)
		(polygon
			(pts
				(arc
					(start 471.86215 -342.546432)
					(mid 467.868 -337.438153)
					(end 463.87385 -342.546432)
				)
				(arc
					(start 463.898234 -342.546432)
					(mid 467.868 -345.645787)
					(end 471.837766 -342.546432)
				)
			)
		)
		(polygon
			(pts
				(arc
					(start 485.607868 -337.258406)
					(mid 482.25916 -337.869342)
					(end 480.115372 -340.513416)
				)
				(arc
					(start 480.115372 -340.513416)
					(mid 483.208552 -346.738672)
					(end 489.418122 -343.614248)
				)
				(arc
					(start 489.418122 -340.560152)
					(mid 487.969931 -338.381904)
					(end 485.607868 -337.258152)
				)
			)
		)
		(polygon
			(pts
				(arc
					(start 383.1971 -337.266788)
					(mid 377.95687 -335.589685)
					(end 375.731786 -340.62162)
				)
				(arc
					(start 375.731786 -340.62162)
					(mid 375.012953 -341.904001)
					(end 374.794018 -343.357708)
				)
				(arc
					(start 374.79224 -343.357708)
					(mid 375.657896 -345.749685)
					(end 377.769628 -347.167962)
				)
				(arc
					(start 379.994668 -347.167962)
					(mid 381.580961 -346.305924)
					(end 382.641856 -344.845132)
				)
				(arc
					(start 382.641856 -344.845132)
					(mid 383.795151 -344.266604)
					(end 384.71094 -343.357708)
				)
				(arc
					(start 384.708654 -343.357708)
					(mid 385.376204 -339.95903)
					(end 383.1971 -337.266788)
				)
			)
		)
		(polygon
			(pts
				(arc
					(start 475.869 -333.47406)
					(mid 475.869 -341.65794)
					(end 475.869 -333.47406)
				)
			)
		)
		(polygon
			(pts
				(arc
					(start 483.368604 -2.032)
					(mid 481.24999 -1.436084)
					(end 479.131376 -2.032)
				)
				(xy 455.786744 -2.032) (xy 455.786744 -5.842)
				(arc
					(start 455.78649 -5.842254)
					(mid 455.294028 -7.393895)
					(end 455.103738 -9.01065)
				)
				(arc
					(start 455.103738 -9.01065)
					(mid 453.276845 -15.395439)
					(end 459.477618 -17.773396)
				)
				(arc
					(start 459.477618 -17.773396)
					(mid 464.610937 -24.572892)
					(end 467.844632 -16.690848)
				)
				(arc
					(start 467.844632 -16.690848)
					(mid 471.017251 -13.626118)
					(end 472.246198 -9.389618)
				)
				(arc
					(start 472.246198 -9.389618)
					(mid 473.22603 -8.59902)
					(end 473.97289 -7.585456)
				)
				(arc
					(start 473.97289 -7.585456)
					(mid 478.731654 -12.63894)
					(end 485.607868 -11.689842)
				)
				(xy 489.418122 -11.689842) (xy 489.418122 -2.032)
			)
		)
	)
	(zone
		(layer "B.Cu")
		(hatch none 0.5)
		(connect_pads
			(clearance 0)
		)
		(min_thickness 0.25)
		(keepout
			(tracks not_allowed)
			(vias allowed)
			(pads allowed)
			(copperpour not_allowed)
			(footprints allowed)
		)
		(placement
			(enabled no)
			(sheetname "")
		)
		(fill
			(thermal_gap 0.5)
			(thermal_bridge_width 0.5)
			(island_removal_mode 0)
		)
		(polygon
			(pts
				(xy 279.047448 -165.771068) (xy 278.580596 -165.769544) (xy 278.424132 -165.847776) (xy 278.424132 -165.84803)
				(arc
					(start 278.425148 -165.850062)
					(mid 278.100282 -166.82466)
					(end 279.07488 -167.149526)
				)
				(xy 279.07615 -167.151812) (xy 281.076146 -166.151814)
				(arc
					(start 281.074876 -166.149528)
					(mid 281.399742 -165.17493)
					(end 280.425144 -164.850064)
				)
				(xy 280.423874 -164.847778)
				(arc
					(start 279.406858 -165.356286)
					(mid 279.435725 -165.369923)
					(end 279.464008 -165.384734)
				)
				(arc
					(start 279.464262 -165.384734)
					(mid 279.540831 -165.432792)
					(end 279.611328 -165.489382)
				)
				(xy 279.612598 -165.489382) (xy 279.640284 -165.517068) (xy 279.640538 -165.517322) (xy 279.775158 -165.651942)
				(arc
					(start 279.845516 -165.7223)
					(mid 279.884556 -165.750786)
					(end 279.930352 -165.766242)
				)
				(arc
					(start 279.948894 -165.76929)
					(mid 279.998664 -165.769131)
					(end 280.045922 -165.753542)
				)
				(arc
					(start 280.22804 -165.660324)
					(mid 281.236003 -165.250733)
					(end 280.314908 -165.829742)
				)
				(xy 280.13279 -165.923214) (xy 280.097738 -165.941248)
				(arc
					(start 280.094182 -165.939978)
					(mid 280.028424 -165.957192)
					(end 279.960578 -165.961314)
				)
				(xy 279.95753 -165.9636) (xy 279.903428 -165.95471) (xy 279.898856 -165.953948) (xy 279.864058 -165.94836)
				(arc
					(start 279.86228 -165.94582)
					(mid 279.799382 -165.921152)
					(end 279.742392 -165.88486)
				)
				(xy 279.738836 -165.88486) (xy 279.679146 -165.82517) (xy 279.505918 -165.651942)
				(arc
					(start 279.505664 -165.651688)
					(mid 279.442649 -165.597066)
					(end 279.372568 -165.551866)
				)
				(arc
					(start 279.372568 -165.551866)
					(mid 279.266851 -165.506663)
					(end 279.154382 -165.482778)
				)
				(xy 278.95931 -165.58006) (xy 279.087326 -165.580568) (xy 279.127712 -165.580568)
				(arc
					(start 279.12949 -165.582346)
					(mid 279.229597 -165.601506)
					(end 279.323546 -165.64102)
				)
				(arc
					(start 279.323546 -165.64102)
					(mid 279.364913 -165.6666)
					(end 279.403556 -165.696138)
				)
				(xy 279.405842 -165.696138) (xy 279.433528 -165.72357) (xy 279.433782 -165.724078) (xy 279.534874 -165.82517)
				(xy 279.562814 -165.85311)
				(arc
					(start 279.562814 -165.857936)
					(mid 279.605174 -165.951303)
					(end 279.608788 -166.05377)
				)
				(arc
					(start 279.608788 -166.054024)
					(mid 279.572867 -166.150062)
					(end 279.503124 -166.22522)
				)
				(xy 279.5016 -166.230046)
				(arc
					(start 279.273508 -166.344092)
					(mid 278.262231 -166.744839)
					(end 279.188164 -166.173912)
				)
				(arc
					(start 279.38095 -166.077392)
					(mid 279.407376 -166.05512)
					(end 279.420828 -166.02329)
				)
				(arc
					(start 279.420828 -166.02329)
					(mid 279.418215 -165.989039)
					(end 279.400254 -165.95979)
				)
				(xy 279.299162 -165.858698)
				(arc
					(start 279.298654 -165.858444)
					(mid 279.266896 -165.830939)
					(end 279.231598 -165.808152)
				)
				(arc
					(start 279.231598 -165.808152)
					(mid 279.163286 -165.780863)
					(end 279.090374 -165.771068)
				)
				(xy 279.086818 -165.771068) (xy 279.047702 -165.771068)
			)
		)
	)
	(zone
		(layers "B.Cu" "In2.Cu" "In4.Cu" "In7.Cu")
		(hatch none 0.5)
		(connect_pads
			(clearance 0)
		)
		(min_thickness 0.25)
		(keepout
			(tracks not_allowed)
			(vias allowed)
			(pads allowed)
			(copperpour not_allowed)
			(footprints allowed)
		)
		(placement
			(enabled no)
			(sheetname "")
		)
		(fill yes
			(thermal_gap 0.5)
			(thermal_bridge_width 0.5)
			(island_removal_mode 0)
		)
		(polygon
			(pts
				(arc
					(start 320.3702 -158.368492)
					(mid 319.9892 -157.987492)
					(end 319.6082 -158.368492)
				)
				(arc
					(start 319.6082 -159.511238)
					(mid 319.987803 -159.89249)
					(end 320.3702 -159.514032)
				)
				(arc
					(start 320.2559 -159.514032)
					(mid 319.9892 -159.778204)
					(end 319.7225 -159.514032)
				)
				(arc
					(start 319.7225 -159.511492)
					(mid 319.9892 -159.244792)
					(end 320.2559 -159.511492)
				)
				(xy 320.3702 -159.511492) (xy 320.3702 -158.371032)
				(arc
					(start 320.2559 -158.371032)
					(mid 319.9892 -158.635204)
					(end 319.7225 -158.371032)
				)
				(arc
					(start 319.7225 -158.368492)
					(mid 319.9892 -158.101792)
					(end 320.2559 -158.368492)
				)
			)
		)
	)
	(zone
		(layers "B.Cu" "In2.Cu" "In4.Cu" "In7.Cu")
		(hatch none 0.5)
		(connect_pads
			(clearance 0)
		)
		(min_thickness 0.25)
		(keepout
			(tracks not_allowed)
			(vias allowed)
			(pads allowed)
			(copperpour not_allowed)
			(footprints allowed)
		)
		(placement
			(enabled no)
			(sheetname "")
		)
		(fill yes
			(thermal_gap 0.5)
			(thermal_bridge_width 0.5)
			(island_removal_mode 0)
		)
		(polygon
			(pts
				(arc
					(start 440.2201 -158.368492)
					(mid 439.8391 -157.987492)
					(end 439.4581 -158.368492)
				)
				(arc
					(start 439.4581 -159.511238)
					(mid 439.837703 -159.89249)
					(end 440.2201 -159.514032)
				)
				(arc
					(start 440.1058 -159.514032)
					(mid 439.8391 -159.778204)
					(end 439.5724 -159.514032)
				)
				(arc
					(start 439.5724 -159.511492)
					(mid 439.8391 -159.244792)
					(end 440.1058 -159.511492)
				)
				(xy 440.2201 -159.511492) (xy 440.2201 -158.371032)
				(arc
					(start 440.1058 -158.371032)
					(mid 439.8391 -158.635204)
					(end 439.5724 -158.371032)
				)
				(arc
					(start 439.5724 -158.368492)
					(mid 439.8391 -158.101792)
					(end 440.1058 -158.368492)
				)
			)
		)
	)
	(zone
		(layers "B.Cu" "In2.Cu" "In4.Cu" "In7.Cu")
		(hatch none 0.5)
		(connect_pads
			(clearance 0)
		)
		(min_thickness 0.25)
		(keepout
			(tracks not_allowed)
			(vias allowed)
			(pads allowed)
			(copperpour not_allowed)
			(footprints allowed)
		)
		(placement
			(enabled no)
			(sheetname "")
		)
		(fill yes
			(thermal_gap 0.5)
			(thermal_bridge_width 0.5)
			(island_removal_mode 0)
		)
		(polygon
			(pts
				(arc
					(start 415.020252 -273.368516)
					(mid 414.639252 -272.987516)
					(end 414.258252 -273.368516)
				)
				(arc
					(start 414.258252 -274.511262)
					(mid 414.637855 -274.892514)
					(end 415.020252 -274.514056)
				)
				(arc
					(start 414.905952 -274.514056)
					(mid 414.639252 -274.778228)
					(end 414.372552 -274.514056)
				)
				(arc
					(start 414.372552 -274.511516)
					(mid 414.639252 -274.244816)
					(end 414.905952 -274.511516)
				)
				(xy 415.020252 -274.511516) (xy 415.020252 -273.371056)
				(arc
					(start 414.905952 -273.371056)
					(mid 414.639252 -273.635228)
					(end 414.372552 -273.371056)
				)
				(arc
					(start 414.372552 -273.368516)
					(mid 414.639252 -273.101816)
					(end 414.905952 -273.368516)
				)
			)
		)
	)
	(zone
		(layers "B.Cu" "In2.Cu" "In4.Cu" "In7.Cu")
		(hatch none 0.5)
		(connect_pads
			(clearance 0)
		)
		(min_thickness 0.25)
		(keepout
			(tracks not_allowed)
			(vias allowed)
			(pads allowed)
			(copperpour not_allowed)
			(footprints allowed)
		)
		(placement
			(enabled no)
			(sheetname "")
		)
		(fill yes
			(thermal_gap 0.5)
			(thermal_bridge_width 0.5)
			(island_removal_mode 0)
		)
		(polygon
			(pts
				(arc
					(start 478.120202 -43.368468)
					(mid 477.739202 -42.987468)
					(end 477.358202 -43.368468)
				)
				(arc
					(start 477.358202 -44.511214)
					(mid 477.737805 -44.892466)
					(end 478.120202 -44.514008)
				)
				(arc
					(start 478.005902 -44.514008)
					(mid 477.739202 -44.77818)
					(end 477.472502 -44.514008)
				)
				(arc
					(start 477.472502 -44.511468)
					(mid 477.739202 -44.244768)
					(end 478.005902 -44.511468)
				)
				(xy 478.120202 -44.511468) (xy 478.120202 -43.371008)
				(arc
					(start 478.005902 -43.371008)
					(mid 477.739202 -43.63518)
					(end 477.472502 -43.371008)
				)
				(arc
					(start 477.472502 -43.368468)
					(mid 477.739202 -43.101768)
					(end 478.005902 -43.368468)
				)
			)
		)
	)
	(zone
		(layers "B.Cu" "In2.Cu" "In4.Cu" "In7.Cu")
		(hatch none 0.5)
		(connect_pads
			(clearance 0)
		)
		(min_thickness 0.25)
		(keepout
			(tracks not_allowed)
			(vias allowed)
			(pads allowed)
			(copperpour not_allowed)
			(footprints allowed)
		)
		(placement
			(enabled no)
			(sheetname "")
		)
		(fill yes
			(thermal_gap 0.5)
			(thermal_bridge_width 0.5)
			(island_removal_mode 0)
		)
		(polygon
			(pts
				(arc
					(start 382.7653 -45.7708)
					(mid 382.3843 -46.1518)
					(end 382.7653 -46.5328)
				)
				(arc
					(start 383.908046 -46.5328)
					(mid 384.176718 -46.422194)
					(end 384.2893 -46.15434)
				)
				(arc
					(start 384.175 -46.15434)
					(mid 383.9083 -46.418512)
					(end 383.6416 -46.15434)
				)
				(arc
					(start 383.032 -46.15434)
					(mid 382.7653 -46.418512)
					(end 382.4986 -46.15434)
				)
				(arc
					(start 382.4986 -46.1518)
					(mid 382.7653 -45.8851)
					(end 383.032 -46.1518)
				)
				(arc
					(start 383.6416 -46.1518)
					(mid 383.9083 -45.8851)
					(end 384.175 -46.1518)
				)
				(arc
					(start 384.2893 -46.1518)
					(mid 384.177708 -45.882392)
					(end 383.9083 -45.7708)
				)
			)
		)
	)
	(zone
		(layers "B.Cu" "In2.Cu" "In4.Cu" "In7.Cu")
		(hatch none 0.5)
		(connect_pads
			(clearance 0)
		)
		(min_thickness 0.25)
		(keepout
			(tracks not_allowed)
			(vias allowed)
			(pads allowed)
			(copperpour not_allowed)
			(footprints allowed)
		)
		(placement
			(enabled no)
			(sheetname "")
		)
		(fill yes
			(thermal_gap 0.5)
			(thermal_bridge_width 0.5)
			(island_removal_mode 0)
		)
		(polygon
			(pts
				(arc
					(start 415.020252 -43.368468)
					(mid 414.639252 -42.987468)
					(end 414.258252 -43.368468)
				)
				(arc
					(start 414.258252 -44.511214)
					(mid 414.637855 -44.892466)
					(end 415.020252 -44.514008)
				)
				(arc
					(start 414.905952 -44.514008)
					(mid 414.639252 -44.77818)
					(end 414.372552 -44.514008)
				)
				(arc
					(start 414.372552 -44.511468)
					(mid 414.639252 -44.244768)
					(end 414.905952 -44.511468)
				)
				(xy 415.020252 -44.511468) (xy 415.020252 -43.371008)
				(arc
					(start 414.905952 -43.371008)
					(mid 414.639252 -43.63518)
					(end 414.372552 -43.371008)
				)
				(arc
					(start 414.372552 -43.368468)
					(mid 414.639252 -43.101768)
					(end 414.905952 -43.368468)
				)
			)
		)
	)
	(zone
		(layers "B.Cu" "In2.Cu" "In4.Cu" "In7.Cu")
		(hatch none 0.5)
		(connect_pads
			(clearance 0)
		)
		(min_thickness 0.25)
		(keepout
			(tracks not_allowed)
			(vias allowed)
			(pads allowed)
			(copperpour not_allowed)
			(footprints allowed)
		)
		(placement
			(enabled no)
			(sheetname "")
		)
		(fill yes
			(thermal_gap 0.5)
			(thermal_bridge_width 0.5)
			(island_removal_mode 0)
		)
		(polygon
			(pts
				(arc
					(start 351.920302 -158.368492)
					(mid 351.539302 -157.987492)
					(end 351.158302 -158.368492)
				)
				(arc
					(start 351.158302 -159.511238)
					(mid 351.537905 -159.89249)
					(end 351.920302 -159.514032)
				)
				(arc
					(start 351.806002 -159.514032)
					(mid 351.539302 -159.778204)
					(end 351.272602 -159.514032)
				)
				(arc
					(start 351.272602 -159.511492)
					(mid 351.539302 -159.244792)
					(end 351.806002 -159.511492)
				)
				(xy 351.920302 -159.511492) (xy 351.920302 -158.371032)
				(arc
					(start 351.806002 -158.371032)
					(mid 351.539302 -158.635204)
					(end 351.272602 -158.371032)
				)
				(arc
					(start 351.272602 -158.368492)
					(mid 351.539302 -158.101792)
					(end 351.806002 -158.368492)
				)
			)
		)
	)
	(zone
		(layers "B.Cu" "In2.Cu" "In4.Cu" "In7.Cu")
		(hatch none 0.5)
		(connect_pads
			(clearance 0)
		)
		(min_thickness 0.25)
		(keepout
			(tracks not_allowed)
			(vias allowed)
			(pads allowed)
			(copperpour not_allowed)
			(footprints allowed)
		)
		(placement
			(enabled no)
			(sheetname "")
		)
		(fill yes
			(thermal_gap 0.5)
			(thermal_bridge_width 0.5)
			(island_removal_mode 0)
		)
		(polygon
			(pts
				(arc
					(start 383.47015 -158.368492)
					(mid 383.08915 -157.987492)
					(end 382.70815 -158.368492)
				)
				(arc
					(start 382.70815 -159.511238)
					(mid 383.087753 -159.89249)
					(end 383.47015 -159.514032)
				)
				(arc
					(start 383.35585 -159.514032)
					(mid 383.08915 -159.778204)
					(end 382.82245 -159.514032)
				)
				(arc
					(start 382.82245 -159.511492)
					(mid 383.08915 -159.244792)
					(end 383.35585 -159.511492)
				)
				(xy 383.47015 -159.511492) (xy 383.47015 -158.371032)
				(arc
					(start 383.35585 -158.371032)
					(mid 383.08915 -158.635204)
					(end 382.82245 -158.371032)
				)
				(arc
					(start 382.82245 -158.368492)
					(mid 383.08915 -158.101792)
					(end 383.35585 -158.368492)
				)
			)
		)
	)
	(zone
		(layers "B.Cu" "In2.Cu" "In4.Cu" "In7.Cu")
		(hatch none 0.5)
		(connect_pads
			(clearance 0)
		)
		(min_thickness 0.25)
		(keepout
			(tracks not_allowed)
			(vias allowed)
			(pads allowed)
			(copperpour not_allowed)
			(footprints allowed)
		)
		(placement
			(enabled no)
			(sheetname "")
		)
		(fill yes
			(thermal_gap 0.5)
			(thermal_bridge_width 0.5)
			(island_removal_mode 0)
		)
		(polygon
			(pts
				(arc
					(start 383.47015 -273.368516)
					(mid 383.08915 -272.987516)
					(end 382.70815 -273.368516)
				)
				(arc
					(start 382.70815 -274.511262)
					(mid 383.087753 -274.892514)
					(end 383.47015 -274.514056)
				)
				(arc
					(start 383.35585 -274.514056)
					(mid 383.08915 -274.778228)
					(end 382.82245 -274.514056)
				)
				(arc
					(start 382.82245 -274.511516)
					(mid 383.08915 -274.244816)
					(end 383.35585 -274.511516)
				)
				(xy 383.47015 -274.511516) (xy 383.47015 -273.371056)
				(arc
					(start 383.35585 -273.371056)
					(mid 383.08915 -273.635228)
					(end 382.82245 -273.371056)
				)
				(arc
					(start 382.82245 -273.368516)
					(mid 383.08915 -273.101816)
					(end 383.35585 -273.368516)
				)
			)
		)
	)
	(zone
		(layers "B.Cu" "In2.Cu" "In4.Cu" "In7.Cu")
		(hatch none 0.5)
		(connect_pads
			(clearance 0)
		)
		(min_thickness 0.25)
		(keepout
			(tracks not_allowed)
			(vias allowed)
			(pads allowed)
			(copperpour not_allowed)
			(footprints allowed)
		)
		(placement
			(enabled no)
			(sheetname "")
		)
		(fill yes
			(thermal_gap 0.5)
			(thermal_bridge_width 0.5)
			(island_removal_mode 0)
		)
		(polygon
			(pts
				(arc
					(start 446.5701 -43.368468)
					(mid 446.1891 -42.987468)
					(end 445.8081 -43.368468)
				)
				(arc
					(start 445.8081 -44.511214)
					(mid 446.187703 -44.892466)
					(end 446.5701 -44.514008)
				)
				(arc
					(start 446.4558 -44.514008)
					(mid 446.1891 -44.77818)
					(end 445.9224 -44.514008)
				)
				(arc
					(start 445.9224 -44.511468)
					(mid 446.1891 -44.244768)
					(end 446.4558 -44.511468)
				)
				(xy 446.5701 -44.511468) (xy 446.5701 -43.371008)
				(arc
					(start 446.4558 -43.371008)
					(mid 446.1891 -43.63518)
					(end 445.9224 -43.371008)
				)
				(arc
					(start 445.9224 -43.368468)
					(mid 446.1891 -43.101768)
					(end 446.4558 -43.368468)
				)
			)
		)
	)
	(zone
		(layers "B.Cu" "In2.Cu" "In4.Cu" "In7.Cu")
		(hatch none 0.5)
		(connect_pads
			(clearance 0)
		)
		(min_thickness 0.25)
		(keepout
			(tracks not_allowed)
			(vias allowed)
			(pads allowed)
			(copperpour not_allowed)
			(footprints allowed)
		)
		(placement
			(enabled no)
			(sheetname "")
		)
		(fill yes
			(thermal_gap 0.5)
			(thermal_bridge_width 0.5)
			(island_removal_mode 0)
		)
		(polygon
			(pts
				(arc
					(start 415.020252 -158.368492)
					(mid 414.639252 -157.987492)
					(end 414.258252 -158.368492)
				)
				(arc
					(start 414.258252 -159.511238)
					(mid 414.637855 -159.89249)
					(end 415.020252 -159.514032)
				)
				(arc
					(start 414.905952 -159.514032)
					(mid 414.639252 -159.778204)
					(end 414.372552 -159.514032)
				)
				(arc
					(start 414.372552 -159.511492)
					(mid 414.639252 -159.244792)
					(end 414.905952 -159.511492)
				)
				(xy 415.020252 -159.511492) (xy 415.020252 -158.371032)
				(arc
					(start 414.905952 -158.371032)
					(mid 414.639252 -158.635204)
					(end 414.372552 -158.371032)
				)
				(arc
					(start 414.372552 -158.368492)
					(mid 414.639252 -158.101792)
					(end 414.905952 -158.368492)
				)
			)
		)
	)
	(zone
		(layers "B.Cu" "In2.Cu" "In4.Cu" "In7.Cu")
		(hatch none 0.5)
		(connect_pads
			(clearance 0)
		)
		(min_thickness 0.25)
		(keepout
			(tracks not_allowed)
			(vias allowed)
			(pads allowed)
			(copperpour not_allowed)
			(footprints allowed)
		)
		(placement
			(enabled no)
			(sheetname "")
		)
		(fill yes
			(thermal_gap 0.5)
			(thermal_bridge_width 0.5)
			(island_removal_mode 0)
		)
		(polygon
			(pts
				(arc
					(start 320.41084 -273.368516)
					(mid 319.9892 -272.946876)
					(end 319.56756 -273.368516)
				)
				(arc
					(start 319.56756 -274.511516)
					(mid 319.98793 -274.933154)
					(end 320.41084 -274.514056)
				)
				(arc
					(start 320.2559 -274.514056)
					(mid 319.9892 -274.778228)
					(end 319.7225 -274.514056)
				)
				(arc
					(start 319.7225 -274.511516)
					(mid 319.9892 -274.244816)
					(end 320.2559 -274.511516)
				)
				(xy 320.41084 -274.511516) (xy 320.41084 -273.371056)
				(arc
					(start 320.2559 -273.371056)
					(mid 319.9892 -273.635228)
					(end 319.7225 -273.371056)
				)
				(arc
					(start 319.7225 -273.368516)
					(mid 319.9892 -273.101816)
					(end 320.2559 -273.368516)
				)
			)
		)
	)
	(zone
		(layers "B.Cu" "In2.Cu" "In4.Cu" "In7.Cu")
		(hatch none 0.5)
		(connect_pads
			(clearance 0)
		)
		(min_thickness 0.25)
		(keepout
			(tracks not_allowed)
			(vias allowed)
			(pads allowed)
			(copperpour not_allowed)
			(footprints allowed)
		)
		(placement
			(enabled no)
			(sheetname "")
		)
		(fill yes
			(thermal_gap 0.5)
			(thermal_bridge_width 0.5)
			(island_removal_mode 0)
		)
		(polygon
			(pts
				(arc
					(start 478.120202 -158.368492)
					(mid 477.739202 -157.987492)
					(end 477.358202 -158.368492)
				)
				(arc
					(start 477.358202 -159.511238)
					(mid 477.737805 -159.89249)
					(end 478.120202 -159.514032)
				)
				(arc
					(start 478.005902 -159.514032)
					(mid 477.739202 -159.778204)
					(end 477.472502 -159.514032)
				)
				(arc
					(start 477.472502 -159.511492)
					(mid 477.739202 -159.244792)
					(end 478.005902 -159.511492)
				)
				(xy 478.120202 -159.511492) (xy 478.120202 -158.371032)
				(arc
					(start 478.005902 -158.371032)
					(mid 477.739202 -158.635204)
					(end 477.472502 -158.371032)
				)
				(arc
					(start 477.472502 -158.368492)
					(mid 477.739202 -158.101792)
					(end 478.005902 -158.368492)
				)
			)
		)
	)
	(zone
		(layers "B.Cu" "In2.Cu" "In4.Cu" "In7.Cu")
		(hatch none 0.5)
		(connect_pads
			(clearance 0)
		)
		(min_thickness 0.25)
		(keepout
			(tracks not_allowed)
			(vias allowed)
			(pads allowed)
			(copperpour not_allowed)
			(footprints allowed)
		)
		(placement
			(enabled no)
			(sheetname "")
		)
		(fill yes
			(thermal_gap 0.5)
			(thermal_bridge_width 0.5)
			(island_removal_mode 0)
		)
		(polygon
			(pts
				(arc
					(start 478.120202 -273.368516)
					(mid 477.739202 -272.987516)
					(end 477.358202 -273.368516)
				)
				(arc
					(start 477.358202 -274.511262)
					(mid 477.737805 -274.892514)
					(end 478.120202 -274.514056)
				)
				(arc
					(start 478.005902 -274.514056)
					(mid 477.739202 -274.778228)
					(end 477.472502 -274.514056)
				)
				(arc
					(start 477.472502 -274.511516)
					(mid 477.739202 -274.244816)
					(end 478.005902 -274.511516)
				)
				(xy 478.120202 -274.511516) (xy 478.120202 -273.371056)
				(arc
					(start 478.005902 -273.371056)
					(mid 477.739202 -273.635228)
					(end 477.472502 -273.371056)
				)
				(arc
					(start 477.472502 -273.368516)
					(mid 477.739202 -273.101816)
					(end 478.005902 -273.368516)
				)
			)
		)
	)
	(zone
		(layers "B.Cu" "In2.Cu" "In4.Cu" "In7.Cu")
		(hatch none 0.5)
		(connect_pads
			(clearance 0)
		)
		(min_thickness 0.25)
		(keepout
			(tracks not_allowed)
			(vias allowed)
			(pads allowed)
			(copperpour not_allowed)
			(footprints allowed)
		)
		(placement
			(enabled no)
			(sheetname "")
		)
		(fill yes
			(thermal_gap 0.5)
			(thermal_bridge_width 0.5)
			(island_removal_mode 0)
		)
		(polygon
			(pts
				(arc
					(start 446.5701 -273.368516)
					(mid 446.1891 -272.987516)
					(end 445.8081 -273.368516)
				)
				(arc
					(start 445.8081 -274.511262)
					(mid 446.187703 -274.892514)
					(end 446.5701 -274.514056)
				)
				(arc
					(start 446.4558 -274.514056)
					(mid 446.1891 -274.778228)
					(end 445.9224 -274.514056)
				)
				(arc
					(start 445.9224 -274.511516)
					(mid 446.1891 -274.244816)
					(end 446.4558 -274.511516)
				)
				(xy 446.5701 -274.511516) (xy 446.5701 -273.371056)
				(arc
					(start 446.4558 -273.371056)
					(mid 446.1891 -273.635228)
					(end 445.9224 -273.371056)
				)
				(arc
					(start 445.9224 -273.368516)
					(mid 446.1891 -273.101816)
					(end 446.4558 -273.368516)
				)
			)
		)
	)
	(zone
		(layers "B.Cu" "In2.Cu" "In4.Cu" "In7.Cu")
		(hatch none 0.5)
		(connect_pads
			(clearance 0)
		)
		(min_thickness 0.25)
		(keepout
			(tracks not_allowed)
			(vias allowed)
			(pads allowed)
			(copperpour not_allowed)
			(footprints allowed)
		)
		(placement
			(enabled no)
			(sheetname "")
		)
		(fill yes
			(thermal_gap 0.5)
			(thermal_bridge_width 0.5)
			(island_removal_mode 0)
		)
		(polygon
			(pts
				(arc
					(start 351.920302 -273.368516)
					(mid 351.539302 -272.987516)
					(end 351.158302 -273.368516)
				)
				(arc
					(start 351.158302 -274.511262)
					(mid 351.537905 -274.892514)
					(end 351.920302 -274.514056)
				)
				(arc
					(start 351.806002 -274.514056)
					(mid 351.539302 -274.778228)
					(end 351.272602 -274.514056)
				)
				(arc
					(start 351.272602 -274.511516)
					(mid 351.539302 -274.244816)
					(end 351.806002 -274.511516)
				)
				(xy 351.920302 -274.511516) (xy 351.920302 -273.371056)
				(arc
					(start 351.806002 -273.371056)
					(mid 351.539302 -273.635228)
					(end 351.272602 -273.371056)
				)
				(arc
					(start 351.272602 -273.368516)
					(mid 351.539302 -273.101816)
					(end 351.806002 -273.368516)
				)
			)
		)
	)
	(zone
		(layers "B.Cu" "In2.Cu" "In4.Cu" "In7.Cu" "In9.Cu")
		(hatch none 0.5)
		(connect_pads
			(clearance 0)
		)
		(min_thickness 0.25)
		(keepout
			(tracks not_allowed)
			(vias allowed)
			(pads allowed)
			(copperpour not_allowed)
			(footprints allowed)
		)
		(placement
			(enabled no)
			(sheetname "")
		)
		(fill yes
			(thermal_gap 0.5)
			(thermal_bridge_width 0.5)
			(island_removal_mode 0)
		)
		(polygon
			(pts
				(arc
					(start 409.658058 -290.000436)
					(mid 404.400258 -284.742636)
					(end 399.142204 -290.000436)
				)
				(arc
					(start 399.142204 -290.000436)
					(mid 404.400258 -295.25849)
					(end 409.658058 -290.000436)
				)
			)
		)
	)
	(zone
		(layers "B.Cu" "In2.Cu" "In4.Cu" "In7.Cu" "In9.Cu")
		(hatch none 0.5)
		(connect_pads
			(clearance 0)
		)
		(min_thickness 0.25)
		(keepout
			(tracks not_allowed)
			(vias allowed)
			(pads allowed)
			(copperpour not_allowed)
			(footprints allowed)
		)
		(placement
			(enabled no)
			(sheetname "")
		)
		(fill yes
			(thermal_gap 0.5)
			(thermal_bridge_width 0.5)
			(island_removal_mode 0)
		)
		(polygon
			(pts
				(arc
					(start 281.47645 -17.200118)
					(mid 281.131922 -16.582171)
					(end 280.425144 -16.550386)
				)
				(xy 280.423874 -16.5481) (xy 278.424132 -17.548098) (xy 278.424132 -17.548352)
				(arc
					(start 278.425148 -17.550384)
					(mid 278.100282 -18.524982)
					(end 279.07488 -18.849848)
				)
				(xy 279.07615 -18.852134) (xy 280.375106 -18.202656)
				(arc
					(start 279.296114 -18.202656)
					(mid 278.750014 -18.746222)
					(end 278.203914 -18.202656)
				)
				(arc
					(start 278.203914 -18.200116)
					(mid 278.750014 -17.654016)
					(end 279.296114 -18.200116)
				)
				(xy 280.375614 -18.200116) (xy 280.375614 -18.202402) (xy 281.076146 -17.852136)
				(arc
					(start 281.074876 -17.84985)
					(mid 281.367273 -17.583101)
					(end 281.47645 -17.202658)
				)
				(arc
					(start 281.29611 -17.202658)
					(mid 280.75001 -17.746224)
					(end 280.20391 -17.202658)
				)
				(arc
					(start 280.20391 -17.200118)
					(mid 280.75001 -16.654018)
					(end 281.29611 -17.200118)
				)
			)
		)
	)
	(zone
		(layers "B.Cu" "In2.Cu" "In4.Cu" "In7.Cu" "In9.Cu")
		(hatch none 0.5)
		(connect_pads
			(clearance 0)
		)
		(min_thickness 0.25)
		(keepout
			(tracks not_allowed)
			(vias allowed)
			(pads allowed)
			(copperpour not_allowed)
			(footprints allowed)
		)
		(placement
			(enabled no)
			(sheetname "")
		)
		(fill yes
			(thermal_gap 0.5)
			(thermal_bridge_width 0.5)
			(island_removal_mode 0)
		)
		(polygon
			(pts
				(arc
					(start 283.574744 -134.850124)
					(mid 282.600146 -135.17499)
					(end 282.925012 -136.149588)
				)
				(xy 282.923742 -136.151874) (xy 284.923738 -137.151872) (xy 284.923992 -137.151618)
				(arc
					(start 284.925008 -137.149586)
					(mid 285.630696 -137.118453)
					(end 285.976314 -136.502394)
				)
				(arc
					(start 285.795974 -136.502394)
					(mid 285.249874 -137.04596)
					(end 284.703774 -136.502394)
				)
				(arc
					(start 284.703774 -136.499854)
					(mid 285.249874 -135.953754)
					(end 285.795974 -136.499854)
				)
				(arc
					(start 285.976314 -136.499854)
					(mid 285.867821 -136.117942)
					(end 285.57474 -135.850122)
				)
				(xy 285.57601 -135.847836) (xy 284.88513 -135.502396)
				(arc
					(start 283.795978 -135.502396)
					(mid 283.249878 -136.045962)
					(end 282.703778 -135.502396)
				)
				(arc
					(start 282.703778 -135.499856)
					(mid 283.249878 -134.953756)
					(end 283.795978 -135.499856)
				)
				(xy 284.88005 -135.499856) (xy 283.576014 -134.847838)
			)
		)
	)
	(zone
		(layers "B.Cu" "In2.Cu" "In4.Cu" "In7.Cu" "In9.Cu")
		(hatch none 0.5)
		(connect_pads
			(clearance 0)
		)
		(min_thickness 0.25)
		(keepout
			(tracks not_allowed)
			(vias allowed)
			(pads allowed)
			(copperpour not_allowed)
			(footprints allowed)
		)
		(placement
			(enabled no)
			(sheetname "")
		)
		(fill yes
			(thermal_gap 0.5)
			(thermal_bridge_width 0.5)
			(island_removal_mode 0)
		)
		(polygon
			(pts
				(arc
					(start 238.77651 -17.200118)
					(mid 238.431982 -16.582171)
					(end 237.725204 -16.550386)
				)
				(xy 237.723934 -16.5481) (xy 235.724192 -17.548098) (xy 235.724192 -17.548352)
				(arc
					(start 235.725208 -17.550384)
					(mid 235.400342 -18.524982)
					(end 236.37494 -18.849848)
				)
				(xy 236.37621 -18.852134) (xy 237.675166 -18.202656)
				(arc
					(start 236.596174 -18.202656)
					(mid 236.050074 -18.746222)
					(end 235.503974 -18.202656)
				)
				(arc
					(start 235.503974 -18.200116)
					(mid 236.050074 -17.654016)
					(end 236.596174 -18.200116)
				)
				(xy 237.675674 -18.200116) (xy 237.675674 -18.202402) (xy 238.376206 -17.852136)
				(arc
					(start 238.374936 -17.84985)
					(mid 238.667333 -17.583101)
					(end 238.77651 -17.202658)
				)
				(arc
					(start 238.59617 -17.202658)
					(mid 238.05007 -17.746224)
					(end 237.50397 -17.202658)
				)
				(arc
					(start 237.50397 -17.200118)
					(mid 238.05007 -16.654018)
					(end 238.59617 -17.200118)
				)
			)
		)
	)
	(zone
		(layers "B.Cu" "In2.Cu" "In4.Cu" "In7.Cu" "In9.Cu")
		(hatch none 0.5)
		(connect_pads
			(clearance 0)
		)
		(min_thickness 0.25)
		(keepout
			(tracks not_allowed)
			(vias allowed)
			(pads allowed)
			(copperpour not_allowed)
			(footprints allowed)
		)
		(placement
			(enabled no)
			(sheetname "")
		)
		(fill yes
			(thermal_gap 0.5)
			(thermal_bridge_width 0.5)
			(island_removal_mode 0)
		)
		(polygon
			(pts
				(arc
					(start 116.898674 -28.150058)
					(mid 116.350034 -27.601418)
					(end 115.801394 -28.150058)
				)
				(arc
					(start 115.801394 -29.550106)
					(mid 116.348764 -30.098745)
					(end 116.898674 -29.552646)
				)
				(arc
					(start 116.743734 -29.552646)
					(mid 116.350034 -29.943814)
					(end 115.956334 -29.552646)
				)
				(arc
					(start 115.956334 -29.550106)
					(mid 116.350034 -29.156406)
					(end 116.743734 -29.550106)
				)
				(xy 116.898674 -29.550106) (xy 116.898674 -28.152598)
				(arc
					(start 116.743734 -28.152598)
					(mid 116.350034 -28.543766)
					(end 115.956334 -28.152598)
				)
				(arc
					(start 115.956334 -28.150058)
					(mid 116.350034 -27.756358)
					(end 116.743734 -28.150058)
				)
			)
		)
	)
	(zone
		(layers "B.Cu" "In2.Cu" "In4.Cu" "In7.Cu" "In9.Cu")
		(hatch none 0.5)
		(connect_pads
			(clearance 0)
		)
		(min_thickness 0.25)
		(keepout
			(tracks not_allowed)
			(vias allowed)
			(pads allowed)
			(copperpour not_allowed)
			(footprints allowed)
		)
		(placement
			(enabled no)
			(sheetname "")
		)
		(fill yes
			(thermal_gap 0.5)
			(thermal_bridge_width 0.5)
			(island_removal_mode 0)
		)
		(polygon
			(pts
				(arc
					(start 238.78159 -113.4999)
					(mid 238.434653 -112.877632)
					(end 237.722918 -112.845596)
				)
				(arc
					(start 235.733844 -113.84026)
					(mid 235.393447 -114.82129)
					(end 236.377226 -115.154202)
				)
				(xy 237.680754 -114.502438)
				(arc
					(start 236.596174 -114.502438)
					(mid 236.050074 -115.046004)
					(end 235.503974 -114.502438)
				)
				(arc
					(start 235.503974 -114.499898)
					(mid 236.050074 -113.953798)
					(end 236.596174 -114.499898)
				)
				(xy 237.685834 -114.499898)
				(arc
					(start 238.377222 -114.154204)
					(mid 238.671681 -113.88557)
					(end 238.78159 -113.50244)
				)
				(arc
					(start 238.59617 -113.50244)
					(mid 238.05007 -114.046006)
					(end 237.50397 -113.50244)
				)
				(arc
					(start 237.50397 -113.4999)
					(mid 238.05007 -112.9538)
					(end 238.59617 -113.4999)
				)
			)
		)
	)
	(zone
		(layers "B.Cu" "In2.Cu" "In4.Cu" "In7.Cu" "In9.Cu")
		(hatch none 0.5)
		(connect_pads
			(clearance 0)
		)
		(min_thickness 0.25)
		(keepout
			(tracks not_allowed)
			(vias allowed)
			(pads allowed)
			(copperpour not_allowed)
			(footprints allowed)
		)
		(placement
			(enabled no)
			(sheetname "")
		)
		(fill yes
			(thermal_gap 0.5)
			(thermal_bridge_width 0.5)
			(island_removal_mode 0)
		)
		(polygon
			(pts
				(arc
					(start 282.83662 -263.153652)
					(mid 282.28798 -263.702292)
					(end 282.83662 -264.250932)
				)
				(arc
					(start 284.236668 -264.250932)
					(mid 284.623716 -264.091136)
					(end 284.785308 -263.704832)
				)
				(arc
					(start 284.630368 -263.704832)
					(mid 284.236668 -264.096)
					(end 283.842968 -263.704832)
				)
				(arc
					(start 283.23032 -263.704832)
					(mid 282.83662 -264.096)
					(end 282.44292 -263.704832)
				)
				(arc
					(start 282.44292 -263.702292)
					(mid 282.83662 -263.308592)
					(end 283.23032 -263.702292)
				)
				(arc
					(start 283.842968 -263.702292)
					(mid 284.236668 -263.308592)
					(end 284.630368 -263.702292)
				)
				(arc
					(start 284.785308 -263.702292)
					(mid 284.624615 -263.314345)
					(end 284.236668 -263.153652)
				)
			)
		)
	)
	(zone
		(layers "B.Cu" "In2.Cu" "In4.Cu" "In7.Cu" "In9.Cu")
		(hatch none 0.5)
		(connect_pads
			(clearance 0)
		)
		(min_thickness 0.25)
		(keepout
			(tracks not_allowed)
			(vias allowed)
			(pads allowed)
			(copperpour not_allowed)
			(footprints allowed)
		)
		(placement
			(enabled no)
			(sheetname "")
		)
		(fill yes
			(thermal_gap 0.5)
			(thermal_bridge_width 0.5)
			(island_removal_mode 0)
		)
		(polygon
			(pts
				(arc
					(start 362.89869 -28.150058)
					(mid 362.35005 -27.601418)
					(end 361.80141 -28.150058)
				)
				(arc
					(start 361.80141 -29.550106)
					(mid 362.34878 -30.098745)
					(end 362.89869 -29.552646)
				)
				(arc
					(start 362.74375 -29.552646)
					(mid 362.35005 -29.943814)
					(end 361.95635 -29.552646)
				)
				(arc
					(start 361.95635 -29.550106)
					(mid 362.35005 -29.156406)
					(end 362.74375 -29.550106)
				)
				(xy 362.89869 -29.550106) (xy 362.89869 -28.152598)
				(arc
					(start 362.74375 -28.152598)
					(mid 362.35005 -28.543766)
					(end 361.95635 -28.152598)
				)
				(arc
					(start 361.95635 -28.150058)
					(mid 362.35005 -27.756358)
					(end 362.74375 -28.150058)
				)
			)
		)
	)
	(zone
		(layers "B.Cu" "In2.Cu" "In4.Cu" "In7.Cu" "In9.Cu")
		(hatch none 0.5)
		(connect_pads
			(clearance 0)
		)
		(min_thickness 0.25)
		(keepout
			(tracks not_allowed)
			(vias allowed)
			(pads allowed)
			(copperpour not_allowed)
			(footprints allowed)
		)
		(placement
			(enabled no)
			(sheetname "")
		)
		(fill yes
			(thermal_gap 0.5)
			(thermal_bridge_width 0.5)
			(island_removal_mode 0)
		)
		(polygon
			(pts
				(arc
					(start 238.77651 -137.499852)
					(mid 238.431982 -136.881905)
					(end 237.725204 -136.85012)
				)
				(xy 237.723934 -136.847834) (xy 235.724192 -137.847832) (xy 235.724192 -137.848086)
				(arc
					(start 235.725208 -137.850118)
					(mid 235.400342 -138.824716)
					(end 236.37494 -139.149582)
				)
				(xy 236.37621 -139.151868) (xy 237.675166 -138.50239)
				(arc
					(start 236.596174 -138.50239)
					(mid 236.050074 -139.045956)
					(end 235.503974 -138.50239)
				)
				(arc
					(start 235.503974 -138.49985)
					(mid 236.050074 -137.95375)
					(end 236.596174 -138.49985)
				)
				(xy 237.675674 -138.49985) (xy 237.675674 -138.502136) (xy 238.376206 -138.15187)
				(arc
					(start 238.374936 -138.149584)
					(mid 238.667333 -137.882835)
					(end 238.77651 -137.502392)
				)
				(arc
					(start 238.59617 -137.502392)
					(mid 238.05007 -138.045958)
					(end 237.50397 -137.502392)
				)
				(arc
					(start 237.50397 -137.499852)
					(mid 238.05007 -136.953752)
					(end 238.59617 -137.499852)
				)
			)
		)
	)
	(zone
		(layers "B.Cu" "In2.Cu" "In4.Cu" "In7.Cu" "In9.Cu")
		(hatch none 0.5)
		(connect_pads
			(clearance 0)
		)
		(min_thickness 0.25)
		(keepout
			(tracks not_allowed)
			(vias allowed)
			(pads allowed)
			(copperpour not_allowed)
			(footprints allowed)
		)
		(placement
			(enabled no)
			(sheetname "")
		)
		(fill yes
			(thermal_gap 0.5)
			(thermal_bridge_width 0.5)
			(island_removal_mode 0)
		)
		(polygon
			(pts
				(arc
					(start 389.898636 -29.150056)
					(mid 389.349996 -28.601416)
					(end 388.801356 -29.150056)
				)
				(arc
					(start 388.801356 -30.550104)
					(mid 389.348726 -31.098743)
					(end 389.898636 -30.552644)
				)
				(arc
					(start 389.743696 -30.552644)
					(mid 389.349996 -30.943812)
					(end 388.956296 -30.552644)
				)
				(arc
					(start 388.956296 -30.550104)
					(mid 389.349996 -30.156404)
					(end 389.743696 -30.550104)
				)
				(xy 389.898636 -30.550104) (xy 389.898636 -29.152596)
				(arc
					(start 389.743696 -29.152596)
					(mid 389.349996 -29.543764)
					(end 388.956296 -29.152596)
				)
				(arc
					(start 388.956296 -29.150056)
					(mid 389.349996 -28.756356)
					(end 389.743696 -29.150056)
				)
			)
		)
	)
	(zone
		(layers "B.Cu" "In2.Cu" "In4.Cu" "In7.Cu" "In9.Cu")
		(hatch none 0.5)
		(connect_pads
			(clearance 0)
		)
		(min_thickness 0.25)
		(keepout
			(tracks not_allowed)
			(vias allowed)
			(pads allowed)
			(copperpour not_allowed)
			(footprints allowed)
		)
		(placement
			(enabled no)
			(sheetname "")
		)
		(fill yes
			(thermal_gap 0.5)
			(thermal_bridge_width 0.5)
			(island_removal_mode 0)
		)
		(polygon
			(pts
				(arc
					(start 134.936992 -210.799934)
					(mid 120.712992 -210.799934)
					(end 134.936992 -210.799934)
				)
			)
		)
	)
	(zone
		(layers "B.Cu" "In2.Cu" "In4.Cu" "In7.Cu" "In9.Cu")
		(hatch none 0.5)
		(connect_pads
			(clearance 0)
		)
		(min_thickness 0.25)
		(keepout
			(tracks not_allowed)
			(vias allowed)
			(pads allowed)
			(copperpour not_allowed)
			(footprints allowed)
		)
		(placement
			(enabled no)
			(sheetname "")
		)
		(fill yes
			(thermal_gap 0.5)
			(thermal_bridge_width 0.5)
			(island_removal_mode 0)
		)
		(polygon
			(pts
				(arc
					(start 283.576014 -106.847894)
					(mid 282.59786 -107.173776)
					(end 282.923742 -108.15193)
				)
				(arc
					(start 284.923738 -109.151928)
					(mid 285.632021 -109.120761)
					(end 285.978854 -108.50245)
				)
				(arc
					(start 285.795974 -108.50245)
					(mid 285.249874 -109.046016)
					(end 284.703774 -108.50245)
				)
				(arc
					(start 284.703774 -108.49991)
					(mid 285.249874 -107.95381)
					(end 285.795974 -108.49991)
				)
				(arc
					(start 285.978854 -108.49991)
					(mid 285.870011 -108.116711)
					(end 285.57601 -107.847892)
				)
				(xy 284.88513 -107.502452)
				(arc
					(start 283.795978 -107.502452)
					(mid 283.249878 -108.046018)
					(end 282.703778 -107.502452)
				)
				(arc
					(start 282.703778 -107.499912)
					(mid 283.249878 -106.953812)
					(end 283.795978 -107.499912)
				)
				(xy 284.88005 -107.499912)
			)
		)
	)
	(zone
		(layers "B.Cu" "In2.Cu" "In4.Cu" "In7.Cu" "In9.Cu")
		(hatch none 0.5)
		(connect_pads
			(clearance 0)
		)
		(min_thickness 0.25)
		(keepout
			(tracks not_allowed)
			(vias allowed)
			(pads allowed)
			(copperpour not_allowed)
			(footprints allowed)
		)
		(placement
			(enabled no)
			(sheetname "")
		)
		(fill yes
			(thermal_gap 0.5)
			(thermal_bridge_width 0.5)
			(island_removal_mode 0)
		)
		(polygon
			(pts
				(arc
					(start 281.47645 -137.499852)
					(mid 281.131922 -136.881905)
					(end 280.425144 -136.85012)
				)
				(xy 280.423874 -136.847834) (xy 278.424132 -137.847832) (xy 278.424132 -137.848086)
				(arc
					(start 278.425148 -137.850118)
					(mid 278.100282 -138.824716)
					(end 279.07488 -139.149582)
				)
				(xy 279.07615 -139.151868) (xy 280.375106 -138.50239)
				(arc
					(start 279.296114 -138.50239)
					(mid 278.750014 -139.045956)
					(end 278.203914 -138.50239)
				)
				(arc
					(start 278.203914 -138.49985)
					(mid 278.750014 -137.95375)
					(end 279.296114 -138.49985)
				)
				(xy 280.375614 -138.49985) (xy 280.375614 -138.502136) (xy 281.076146 -138.15187)
				(arc
					(start 281.074876 -138.149584)
					(mid 281.367273 -137.882835)
					(end 281.47645 -137.502392)
				)
				(arc
					(start 281.29611 -137.502392)
					(mid 280.75001 -138.045958)
					(end 280.20391 -137.502392)
				)
				(arc
					(start 280.20391 -137.499852)
					(mid 280.75001 -136.953752)
					(end 281.29611 -137.499852)
				)
			)
		)
	)
	(zone
		(layers "B.Cu" "In2.Cu" "In4.Cu" "In7.Cu" "In9.Cu")
		(hatch none 0.5)
		(connect_pads
			(clearance 0)
		)
		(min_thickness 0.25)
		(keepout
			(tracks not_allowed)
			(vias allowed)
			(pads allowed)
			(copperpour not_allowed)
			(footprints allowed)
		)
		(placement
			(enabled no)
			(sheetname "")
		)
		(fill yes
			(thermal_gap 0.5)
			(thermal_bridge_width 0.5)
			(island_removal_mode 0)
		)
		(polygon
			(pts
				(arc
					(start 432.286918 -210.799934)
					(mid 418.062918 -210.799934)
					(end 432.286918 -210.799934)
				)
			)
		)
	)
	(zone
		(layers "B.Cu" "In2.Cu" "In4.Cu" "In7.Cu" "In9.Cu")
		(hatch none 0.5)
		(connect_pads
			(clearance 0)
		)
		(min_thickness 0.25)
		(keepout
			(tracks not_allowed)
			(vias allowed)
			(pads allowed)
			(copperpour not_allowed)
			(footprints allowed)
		)
		(placement
			(enabled no)
			(sheetname "")
		)
		(fill yes
			(thermal_gap 0.5)
			(thermal_bridge_width 0.5)
			(island_removal_mode 0)
		)
		(polygon
			(pts
				(arc
					(start 143.89862 -29.150056)
					(mid 143.34998 -28.601416)
					(end 142.80134 -29.150056)
				)
				(arc
					(start 142.80134 -30.550104)
					(mid 143.34871 -31.098743)
					(end 143.89862 -30.552644)
				)
				(arc
					(start 143.74368 -30.552644)
					(mid 143.34998 -30.943812)
					(end 142.95628 -30.552644)
				)
				(arc
					(start 142.95628 -30.550104)
					(mid 143.34998 -30.156404)
					(end 143.74368 -30.550104)
				)
				(xy 143.89862 -30.550104) (xy 143.89862 -29.152596)
				(arc
					(start 143.74368 -29.152596)
					(mid 143.34998 -29.543764)
					(end 142.95628 -29.152596)
				)
				(arc
					(start 142.95628 -29.150056)
					(mid 143.34998 -28.756356)
					(end 143.74368 -29.150056)
				)
			)
		)
	)
	(zone
		(layers "B.Cu" "In2.Cu" "In4.Cu" "In7.Cu" "In9.Cu")
		(hatch none 0.5)
		(connect_pads
			(clearance 0)
		)
		(min_thickness 0.25)
		(keepout
			(tracks not_allowed)
			(vias allowed)
			(pads allowed)
			(copperpour not_allowed)
			(footprints allowed)
		)
		(placement
			(enabled no)
			(sheetname "")
		)
		(fill yes
			(thermal_gap 0.5)
			(thermal_bridge_width 0.5)
			(island_removal_mode 0)
		)
		(polygon
			(pts
				(arc
					(start 240.874804 -134.850124)
					(mid 239.900206 -135.17499)
					(end 240.225072 -136.149588)
				)
				(xy 240.223802 -136.151874) (xy 242.223798 -137.151872) (xy 242.224052 -137.151618)
				(arc
					(start 242.225068 -137.149586)
					(mid 242.930756 -137.118453)
					(end 243.276374 -136.502394)
				)
				(arc
					(start 243.096034 -136.502394)
					(mid 242.549934 -137.04596)
					(end 242.003834 -136.502394)
				)
				(arc
					(start 242.003834 -136.499854)
					(mid 242.549934 -135.953754)
					(end 243.096034 -136.499854)
				)
				(arc
					(start 243.276374 -136.499854)
					(mid 243.167881 -136.117942)
					(end 242.8748 -135.850122)
				)
				(xy 242.87607 -135.847836) (xy 242.18519 -135.502396)
				(arc
					(start 241.096038 -135.502396)
					(mid 240.549938 -136.045962)
					(end 240.003838 -135.502396)
				)
				(arc
					(start 240.003838 -135.499856)
					(mid 240.549938 -134.953756)
					(end 241.096038 -135.499856)
				)
				(xy 242.18011 -135.499856) (xy 240.876074 -134.847838)
			)
		)
	)
	(zone
		(layers "B.Cu" "In2.Cu" "In4.Cu" "In7.Cu" "In9.Cu")
		(hatch none 0.5)
		(connect_pads
			(clearance 0)
		)
		(min_thickness 0.25)
		(keepout
			(tracks not_allowed)
			(vias allowed)
			(pads allowed)
			(copperpour not_allowed)
			(footprints allowed)
		)
		(placement
			(enabled no)
			(sheetname "")
		)
		(fill yes
			(thermal_gap 0.5)
			(thermal_bridge_width 0.5)
			(island_removal_mode 0)
		)
		(polygon
			(pts
				(arc
					(start 240.874804 -106.85018)
					(mid 239.900206 -107.175046)
					(end 240.225072 -108.149644)
				)
				(xy 240.223802 -108.15193) (xy 242.223798 -109.151928) (xy 242.224052 -109.151674)
				(arc
					(start 242.225068 -109.149642)
					(mid 242.930756 -109.118509)
					(end 243.276374 -108.50245)
				)
				(arc
					(start 243.096034 -108.50245)
					(mid 242.549934 -109.046016)
					(end 242.003834 -108.50245)
				)
				(arc
					(start 242.003834 -108.49991)
					(mid 242.549934 -107.95381)
					(end 243.096034 -108.49991)
				)
				(arc
					(start 243.276374 -108.49991)
					(mid 243.167881 -108.117998)
					(end 242.8748 -107.850178)
				)
				(xy 242.87607 -107.847892) (xy 242.18519 -107.502452)
				(arc
					(start 241.096038 -107.502452)
					(mid 240.549938 -108.046018)
					(end 240.003838 -107.502452)
				)
				(arc
					(start 240.003838 -107.499912)
					(mid 240.549938 -106.953812)
					(end 241.096038 -107.499912)
				)
				(xy 242.18011 -107.499912) (xy 240.876074 -106.847894)
			)
		)
	)
	(zone
		(layers "B.Cu" "In2.Cu" "In4.Cu" "In9.Cu")
		(hatch none 0.5)
		(connect_pads
			(clearance 0)
		)
		(min_thickness 0.25)
		(keepout
			(tracks not_allowed)
			(vias allowed)
			(pads allowed)
			(copperpour not_allowed)
			(footprints allowed)
		)
		(placement
			(enabled no)
			(sheetname "")
		)
		(fill yes
			(thermal_gap 0.5)
			(thermal_bridge_width 0.5)
			(island_removal_mode 0)
		)
		(polygon
			(pts
				(arc
					(start 159.089852 -47.178468)
					(mid 158.708852 -46.797468)
					(end 158.327852 -47.178468)
				)
				(arc
					(start 158.327852 -48.321468)
					(mid 158.707582 -48.702466)
					(end 159.089852 -48.324008)
				)
				(arc
					(start 158.975552 -48.324008)
					(mid 158.708852 -48.58818)
					(end 158.442152 -48.324008)
				)
				(arc
					(start 158.442152 -48.321468)
					(mid 158.708852 -48.054768)
					(end 158.975552 -48.321468)
				)
				(xy 159.089852 -48.321468) (xy 159.089852 -47.181008)
				(arc
					(start 158.975552 -47.181008)
					(mid 158.708852 -47.44518)
					(end 158.442152 -47.181008)
				)
				(arc
					(start 158.442152 -47.178468)
					(mid 158.708852 -46.911768)
					(end 158.975552 -47.178468)
				)
			)
		)
	)
	(zone
		(layers "B.Cu" "In2.Cu" "In4.Cu" "In9.Cu")
		(hatch none 0.5)
		(connect_pads
			(clearance 0)
		)
		(min_thickness 0.25)
		(keepout
			(tracks not_allowed)
			(vias allowed)
			(pads allowed)
			(copperpour not_allowed)
			(footprints allowed)
		)
		(placement
			(enabled no)
			(sheetname "")
		)
		(fill yes
			(thermal_gap 0.5)
			(thermal_bridge_width 0.5)
			(island_removal_mode 0)
		)
		(polygon
			(pts
				(arc
					(start 319.214754 -42.246042)
					(mid 318.8335 -42.626915)
					(end 319.2145 -43.008042)
				)
				(arc
					(start 320.3575 -43.008042)
					(mid 320.626008 -42.897346)
					(end 320.7385 -42.629582)
				)
				(arc
					(start 320.6242 -42.629582)
					(mid 320.3575 -42.893754)
					(end 320.0908 -42.629582)
				)
				(arc
					(start 319.4812 -42.629582)
					(mid 319.2145 -42.893754)
					(end 318.9478 -42.629582)
				)
				(arc
					(start 318.9478 -42.627042)
					(mid 319.2145 -42.360342)
					(end 319.4812 -42.627042)
				)
				(arc
					(start 320.0908 -42.627042)
					(mid 320.3575 -42.360342)
					(end 320.6242 -42.627042)
				)
				(arc
					(start 320.7385 -42.627042)
					(mid 320.626908 -42.357634)
					(end 320.3575 -42.246042)
				)
			)
		)
	)
	(zone
		(layers "B.Cu" "In2.Cu" "In4.Cu" "In9.Cu")
		(hatch none 0.5)
		(connect_pads
			(clearance 0)
		)
		(min_thickness 0.25)
		(keepout
			(tracks not_allowed)
			(vias allowed)
			(pads allowed)
			(copperpour not_allowed)
			(footprints allowed)
		)
		(placement
			(enabled no)
			(sheetname "")
		)
		(fill yes
			(thermal_gap 0.5)
			(thermal_bridge_width 0.5)
			(island_removal_mode 0)
		)
		(polygon
			(pts
				(arc
					(start 127.53975 -277.178516)
					(mid 127.15875 -276.797516)
					(end 126.77775 -277.178516)
				)
				(arc
					(start 126.77775 -278.321516)
					(mid 127.15748 -278.702514)
					(end 127.53975 -278.324056)
				)
				(arc
					(start 127.42545 -278.324056)
					(mid 127.15875 -278.588228)
					(end 126.89205 -278.324056)
				)
				(arc
					(start 126.89205 -278.321516)
					(mid 127.15875 -278.054816)
					(end 127.42545 -278.321516)
				)
				(xy 127.53975 -278.321516) (xy 127.53975 -277.181056)
				(arc
					(start 127.42545 -277.181056)
					(mid 127.15875 -277.445228)
					(end 126.89205 -277.181056)
				)
				(arc
					(start 126.89205 -277.178516)
					(mid 127.15875 -276.911816)
					(end 127.42545 -277.178516)
				)
			)
		)
	)
	(zone
		(layers "B.Cu" "In2.Cu" "In4.Cu" "In9.Cu")
		(hatch none 0.5)
		(connect_pads
			(clearance 0)
		)
		(min_thickness 0.25)
		(keepout
			(tracks not_allowed)
			(vias allowed)
			(pads allowed)
			(copperpour not_allowed)
			(footprints allowed)
		)
		(placement
			(enabled no)
			(sheetname "")
		)
		(fill yes
			(thermal_gap 0.5)
			(thermal_bridge_width 0.5)
			(island_removal_mode 0)
		)
		(polygon
			(pts
				(arc
					(start 190.639954 -47.178468)
					(mid 190.258954 -46.797468)
					(end 189.877954 -47.178468)
				)
				(arc
					(start 189.877954 -48.321468)
					(mid 190.257684 -48.702466)
					(end 190.639954 -48.324008)
				)
				(arc
					(start 190.525654 -48.324008)
					(mid 190.258954 -48.58818)
					(end 189.992254 -48.324008)
				)
				(arc
					(start 189.992254 -48.321468)
					(mid 190.258954 -48.054768)
					(end 190.525654 -48.321468)
				)
				(xy 190.639954 -48.321468) (xy 190.639954 -47.181008)
				(arc
					(start 190.525654 -47.181008)
					(mid 190.258954 -47.44518)
					(end 189.992254 -47.181008)
				)
				(arc
					(start 189.992254 -47.178468)
					(mid 190.258954 -46.911768)
					(end 190.525654 -47.178468)
				)
			)
		)
	)
	(zone
		(layers "B.Cu" "In2.Cu" "In4.Cu" "In9.Cu")
		(hatch none 0.5)
		(connect_pads
			(clearance 0)
		)
		(min_thickness 0.25)
		(keepout
			(tracks not_allowed)
			(vias allowed)
			(pads allowed)
			(copperpour not_allowed)
			(footprints allowed)
		)
		(placement
			(enabled no)
			(sheetname "")
		)
		(fill yes
			(thermal_gap 0.5)
			(thermal_bridge_width 0.5)
			(island_removal_mode 0)
		)
		(polygon
			(pts
				(arc
					(start 95.989902 -47.178468)
					(mid 95.608902 -46.797468)
					(end 95.227902 -47.178468)
				)
				(arc
					(start 95.227902 -48.321468)
					(mid 95.607632 -48.702466)
					(end 95.989902 -48.324008)
				)
				(arc
					(start 95.875602 -48.324008)
					(mid 95.608902 -48.58818)
					(end 95.342202 -48.324008)
				)
				(arc
					(start 95.342202 -48.321468)
					(mid 95.608902 -48.054768)
					(end 95.875602 -48.321468)
				)
				(xy 95.989902 -48.321468) (xy 95.989902 -47.181008)
				(arc
					(start 95.875602 -47.181008)
					(mid 95.608902 -47.44518)
					(end 95.342202 -47.181008)
				)
				(arc
					(start 95.342202 -47.178468)
					(mid 95.608902 -46.911768)
					(end 95.875602 -47.178468)
				)
			)
		)
	)
	(zone
		(layers "B.Cu" "In2.Cu" "In4.Cu" "In9.Cu")
		(hatch none 0.5)
		(connect_pads
			(clearance 0)
		)
		(min_thickness 0.25)
		(keepout
			(tracks not_allowed)
			(vias allowed)
			(pads allowed)
			(copperpour not_allowed)
			(footprints allowed)
		)
		(placement
			(enabled no)
			(sheetname "")
		)
		(fill yes
			(thermal_gap 0.5)
			(thermal_bridge_width 0.5)
			(island_removal_mode 0)
		)
		(polygon
			(pts
				(arc
					(start 190.639954 -162.178492)
					(mid 190.258954 -161.797492)
					(end 189.877954 -162.178492)
				)
				(arc
					(start 189.877954 -163.321492)
					(mid 190.257684 -163.70249)
					(end 190.639954 -163.324032)
				)
				(arc
					(start 190.525654 -163.324032)
					(mid 190.258954 -163.588204)
					(end 189.992254 -163.324032)
				)
				(arc
					(start 189.992254 -163.321492)
					(mid 190.258954 -163.054792)
					(end 190.525654 -163.321492)
				)
				(xy 190.639954 -163.321492) (xy 190.639954 -162.181032)
				(arc
					(start 190.525654 -162.181032)
					(mid 190.258954 -162.445204)
					(end 189.992254 -162.181032)
				)
				(arc
					(start 189.992254 -162.178492)
					(mid 190.258954 -161.911792)
					(end 190.525654 -162.178492)
				)
			)
		)
	)
	(zone
		(layers "B.Cu" "In2.Cu" "In4.Cu" "In9.Cu")
		(hatch none 0.5)
		(connect_pads
			(clearance 0)
		)
		(min_thickness 0.25)
		(keepout
			(tracks not_allowed)
			(vias allowed)
			(pads allowed)
			(copperpour not_allowed)
			(footprints allowed)
		)
		(placement
			(enabled no)
			(sheetname "")
		)
		(fill yes
			(thermal_gap 0.5)
			(thermal_bridge_width 0.5)
			(island_removal_mode 0)
		)
		(polygon
			(pts
				(arc
					(start 64.4398 -162.178492)
					(mid 64.0588 -161.797492)
					(end 63.6778 -162.178492)
				)
				(arc
					(start 63.6778 -163.321492)
					(mid 64.05753 -163.70249)
					(end 64.4398 -163.324032)
				)
				(arc
					(start 64.3255 -163.324032)
					(mid 64.0588 -163.588204)
					(end 63.7921 -163.324032)
				)
				(arc
					(start 63.7921 -163.321492)
					(mid 64.0588 -163.054792)
					(end 64.3255 -163.321492)
				)
				(xy 64.4398 -163.321492) (xy 64.4398 -162.181032)
				(arc
					(start 64.3255 -162.181032)
					(mid 64.0588 -162.445204)
					(end 63.7921 -162.181032)
				)
				(arc
					(start 63.7921 -162.178492)
					(mid 64.0588 -161.911792)
					(end 64.3255 -162.178492)
				)
			)
		)
	)
	(zone
		(layers "B.Cu" "In2.Cu" "In4.Cu" "In9.Cu")
		(hatch none 0.5)
		(connect_pads
			(clearance 0)
		)
		(min_thickness 0.25)
		(keepout
			(tracks not_allowed)
			(vias allowed)
			(pads allowed)
			(copperpour not_allowed)
			(footprints allowed)
		)
		(placement
			(enabled no)
			(sheetname "")
		)
		(fill yes
			(thermal_gap 0.5)
			(thermal_bridge_width 0.5)
			(island_removal_mode 0)
		)
		(polygon
			(pts
				(arc
					(start 32.889952 -47.178468)
					(mid 32.508952 -46.797468)
					(end 32.127952 -47.178468)
				)
				(arc
					(start 32.127952 -48.321468)
					(mid 32.507682 -48.702466)
					(end 32.889952 -48.324008)
				)
				(arc
					(start 32.775652 -48.324008)
					(mid 32.508952 -48.58818)
					(end 32.242252 -48.324008)
				)
				(arc
					(start 32.242252 -48.321468)
					(mid 32.508952 -48.054768)
					(end 32.775652 -48.321468)
				)
				(xy 32.889952 -48.321468) (xy 32.889952 -47.181008)
				(arc
					(start 32.775652 -47.181008)
					(mid 32.508952 -47.44518)
					(end 32.242252 -47.181008)
				)
				(arc
					(start 32.242252 -47.178468)
					(mid 32.508952 -46.911768)
					(end 32.775652 -47.178468)
				)
			)
		)
	)
	(zone
		(layers "B.Cu" "In2.Cu" "In4.Cu" "In9.Cu")
		(hatch none 0.5)
		(connect_pads
			(clearance 0)
		)
		(min_thickness 0.25)
		(keepout
			(tracks not_allowed)
			(vias allowed)
			(pads allowed)
			(copperpour not_allowed)
			(footprints allowed)
		)
		(placement
			(enabled no)
			(sheetname "")
		)
		(fill yes
			(thermal_gap 0.5)
			(thermal_bridge_width 0.5)
			(island_removal_mode 0)
		)
		(polygon
			(pts
				(arc
					(start 64.4398 -277.178516)
					(mid 64.0588 -276.797516)
					(end 63.6778 -277.178516)
				)
				(arc
					(start 63.6778 -278.321516)
					(mid 64.05753 -278.702514)
					(end 64.4398 -278.324056)
				)
				(arc
					(start 64.3255 -278.324056)
					(mid 64.0588 -278.588228)
					(end 63.7921 -278.324056)
				)
				(arc
					(start 63.7921 -278.321516)
					(mid 64.0588 -278.054816)
					(end 64.3255 -278.321516)
				)
				(xy 64.4398 -278.321516) (xy 64.4398 -277.181056)
				(arc
					(start 64.3255 -277.181056)
					(mid 64.0588 -277.445228)
					(end 63.7921 -277.181056)
				)
				(arc
					(start 63.7921 -277.178516)
					(mid 64.0588 -276.911816)
					(end 64.3255 -277.178516)
				)
			)
		)
	)
	(zone
		(layers "B.Cu" "In2.Cu" "In4.Cu" "In9.Cu")
		(hatch none 0.5)
		(connect_pads
			(clearance 0)
		)
		(min_thickness 0.25)
		(keepout
			(tracks not_allowed)
			(vias allowed)
			(pads allowed)
			(copperpour not_allowed)
			(footprints allowed)
		)
		(placement
			(enabled no)
			(sheetname "")
		)
		(fill yes
			(thermal_gap 0.5)
			(thermal_bridge_width 0.5)
			(island_removal_mode 0)
		)
		(polygon
			(pts
				(arc
					(start 127.53975 -47.178468)
					(mid 127.15875 -46.797468)
					(end 126.77775 -47.178468)
				)
				(arc
					(start 126.77775 -48.321468)
					(mid 127.15748 -48.702466)
					(end 127.53975 -48.324008)
				)
				(arc
					(start 127.42545 -48.324008)
					(mid 127.15875 -48.58818)
					(end 126.89205 -48.324008)
				)
				(arc
					(start 126.89205 -48.321468)
					(mid 127.15875 -48.054768)
					(end 127.42545 -48.321468)
				)
				(xy 127.53975 -48.321468) (xy 127.53975 -47.181008)
				(arc
					(start 127.42545 -47.181008)
					(mid 127.15875 -47.44518)
					(end 126.89205 -47.181008)
				)
				(arc
					(start 126.89205 -47.178468)
					(mid 127.15875 -46.911768)
					(end 127.42545 -47.178468)
				)
			)
		)
	)
	(zone
		(layers "B.Cu" "In2.Cu" "In4.Cu" "In9.Cu")
		(hatch none 0.5)
		(connect_pads
			(clearance 0)
		)
		(min_thickness 0.25)
		(keepout
			(tracks not_allowed)
			(vias allowed)
			(pads allowed)
			(copperpour not_allowed)
			(footprints allowed)
		)
		(placement
			(enabled no)
			(sheetname "")
		)
		(fill yes
			(thermal_gap 0.5)
			(thermal_bridge_width 0.5)
			(island_removal_mode 0)
		)
		(polygon
			(pts
				(arc
					(start 95.989902 -162.178492)
					(mid 95.608902 -161.797492)
					(end 95.227902 -162.178492)
				)
				(arc
					(start 95.227902 -163.321492)
					(mid 95.607632 -163.70249)
					(end 95.989902 -163.324032)
				)
				(arc
					(start 95.875602 -163.324032)
					(mid 95.608902 -163.588204)
					(end 95.342202 -163.324032)
				)
				(arc
					(start 95.342202 -163.321492)
					(mid 95.608902 -163.054792)
					(end 95.875602 -163.321492)
				)
				(xy 95.989902 -163.321492) (xy 95.989902 -162.181032)
				(arc
					(start 95.875602 -162.181032)
					(mid 95.608902 -162.445204)
					(end 95.342202 -162.181032)
				)
				(arc
					(start 95.342202 -162.178492)
					(mid 95.608902 -161.911792)
					(end 95.875602 -162.178492)
				)
			)
		)
	)
	(zone
		(layers "B.Cu" "In2.Cu" "In4.Cu" "In9.Cu")
		(hatch none 0.5)
		(connect_pads
			(clearance 0)
		)
		(min_thickness 0.25)
		(keepout
			(tracks not_allowed)
			(vias allowed)
			(pads allowed)
			(copperpour not_allowed)
			(footprints allowed)
		)
		(placement
			(enabled no)
			(sheetname "")
		)
		(fill yes
			(thermal_gap 0.5)
			(thermal_bridge_width 0.5)
			(island_removal_mode 0)
		)
		(polygon
			(pts
				(arc
					(start 95.989902 -277.178516)
					(mid 95.608902 -276.797516)
					(end 95.227902 -277.178516)
				)
				(arc
					(start 95.227902 -278.321516)
					(mid 95.607632 -278.702514)
					(end 95.989902 -278.324056)
				)
				(arc
					(start 95.875602 -278.324056)
					(mid 95.608902 -278.588228)
					(end 95.342202 -278.324056)
				)
				(arc
					(start 95.342202 -278.321516)
					(mid 95.608902 -278.054816)
					(end 95.875602 -278.321516)
				)
				(xy 95.989902 -278.321516) (xy 95.989902 -277.181056)
				(arc
					(start 95.875602 -277.181056)
					(mid 95.608902 -277.445228)
					(end 95.342202 -277.181056)
				)
				(arc
					(start 95.342202 -277.178516)
					(mid 95.608902 -276.911816)
					(end 95.875602 -277.178516)
				)
			)
		)
	)
	(zone
		(layers "B.Cu" "In2.Cu" "In4.Cu" "In9.Cu")
		(hatch none 0.5)
		(connect_pads
			(clearance 0)
		)
		(min_thickness 0.25)
		(keepout
			(tracks not_allowed)
			(vias allowed)
			(pads allowed)
			(copperpour not_allowed)
			(footprints allowed)
		)
		(placement
			(enabled no)
			(sheetname "")
		)
		(fill yes
			(thermal_gap 0.5)
			(thermal_bridge_width 0.5)
			(island_removal_mode 0)
		)
		(polygon
			(pts
				(arc
					(start 350.764856 -42.240962)
					(mid 350.378522 -42.626915)
					(end 350.764602 -43.013122)
				)
				(arc
					(start 351.907602 -43.013122)
					(mid 352.179702 -42.900938)
					(end 352.293682 -42.629582)
				)
				(arc
					(start 352.174302 -42.629582)
					(mid 351.907602 -42.893754)
					(end 351.640902 -42.629582)
				)
				(arc
					(start 351.031302 -42.629582)
					(mid 350.764602 -42.893754)
					(end 350.497902 -42.629582)
				)
				(arc
					(start 350.497902 -42.627042)
					(mid 350.764602 -42.360342)
					(end 351.031302 -42.627042)
				)
				(arc
					(start 351.640902 -42.627042)
					(mid 351.907602 -42.360342)
					(end 352.174302 -42.627042)
				)
				(arc
					(start 352.293682 -42.627042)
					(mid 352.180602 -42.354042)
					(end 351.907602 -42.240962)
				)
			)
		)
	)
	(zone
		(layers "B.Cu" "In2.Cu" "In4.Cu" "In9.Cu")
		(hatch none 0.5)
		(connect_pads
			(clearance 0)
		)
		(min_thickness 0.25)
		(keepout
			(tracks not_allowed)
			(vias allowed)
			(pads allowed)
			(copperpour not_allowed)
			(footprints allowed)
		)
		(placement
			(enabled no)
			(sheetname "")
		)
		(fill yes
			(thermal_gap 0.5)
			(thermal_bridge_width 0.5)
			(island_removal_mode 0)
		)
		(polygon
			(pts
				(arc
					(start 32.889952 -162.178492)
					(mid 32.508952 -161.797492)
					(end 32.127952 -162.178492)
				)
				(arc
					(start 32.127952 -163.321492)
					(mid 32.507682 -163.70249)
					(end 32.889952 -163.324032)
				)
				(arc
					(start 32.775652 -163.324032)
					(mid 32.508952 -163.588204)
					(end 32.242252 -163.324032)
				)
				(arc
					(start 32.242252 -163.321492)
					(mid 32.508952 -163.054792)
					(end 32.775652 -163.321492)
				)
				(xy 32.889952 -163.321492) (xy 32.889952 -162.181032)
				(arc
					(start 32.775652 -162.181032)
					(mid 32.508952 -162.445204)
					(end 32.242252 -162.181032)
				)
				(arc
					(start 32.242252 -162.178492)
					(mid 32.508952 -161.911792)
					(end 32.775652 -162.178492)
				)
			)
		)
	)
	(zone
		(layers "B.Cu" "In2.Cu" "In4.Cu" "In9.Cu")
		(hatch none 0.5)
		(connect_pads
			(clearance 0)
		)
		(min_thickness 0.25)
		(keepout
			(tracks not_allowed)
			(vias allowed)
			(pads allowed)
			(copperpour not_allowed)
			(footprints allowed)
		)
		(placement
			(enabled no)
			(sheetname "")
		)
		(fill yes
			(thermal_gap 0.5)
			(thermal_bridge_width 0.5)
			(island_removal_mode 0)
		)
		(polygon
			(pts
				(arc
					(start 356.675182 -47.178468)
					(mid 356.289102 -46.792388)
					(end 355.903022 -47.178468)
				)
				(arc
					(start 355.903022 -48.321468)
					(mid 356.287832 -48.707546)
					(end 356.675182 -48.324008)
				)
				(arc
					(start 356.555802 -48.324008)
					(mid 356.289102 -48.58818)
					(end 356.022402 -48.324008)
				)
				(arc
					(start 356.022402 -48.321468)
					(mid 356.289102 -48.054768)
					(end 356.555802 -48.321468)
				)
				(xy 356.675182 -48.321468) (xy 356.675182 -47.181008)
				(arc
					(start 356.555802 -47.181008)
					(mid 356.289102 -47.44518)
					(end 356.022402 -47.181008)
				)
				(arc
					(start 356.022402 -47.178468)
					(mid 356.289102 -46.911768)
					(end 356.555802 -47.178468)
				)
			)
		)
	)
	(zone
		(layers "B.Cu" "In2.Cu" "In4.Cu" "In9.Cu")
		(hatch none 0.5)
		(connect_pads
			(clearance 0)
		)
		(min_thickness 0.25)
		(keepout
			(tracks not_allowed)
			(vias allowed)
			(pads allowed)
			(copperpour not_allowed)
			(footprints allowed)
		)
		(placement
			(enabled no)
			(sheetname "")
		)
		(fill yes
			(thermal_gap 0.5)
			(thermal_bridge_width 0.5)
			(island_removal_mode 0)
		)
		(polygon
			(pts
				(arc
					(start 32.889952 -277.178516)
					(mid 32.508952 -276.797516)
					(end 32.127952 -277.178516)
				)
				(arc
					(start 32.127952 -278.321516)
					(mid 32.507682 -278.702514)
					(end 32.889952 -278.324056)
				)
				(arc
					(start 32.775652 -278.324056)
					(mid 32.508952 -278.588228)
					(end 32.242252 -278.324056)
				)
				(arc
					(start 32.242252 -278.321516)
					(mid 32.508952 -278.054816)
					(end 32.775652 -278.321516)
				)
				(xy 32.889952 -278.321516) (xy 32.889952 -277.181056)
				(arc
					(start 32.775652 -277.181056)
					(mid 32.508952 -277.445228)
					(end 32.242252 -277.181056)
				)
				(arc
					(start 32.242252 -277.178516)
					(mid 32.508952 -276.911816)
					(end 32.775652 -277.178516)
				)
			)
		)
	)
	(zone
		(layers "B.Cu" "In2.Cu" "In4.Cu" "In9.Cu")
		(hatch none 0.5)
		(connect_pads
			(clearance 0)
		)
		(min_thickness 0.25)
		(keepout
			(tracks not_allowed)
			(vias allowed)
			(pads allowed)
			(copperpour not_allowed)
			(footprints allowed)
		)
		(placement
			(enabled no)
			(sheetname "")
		)
		(fill yes
			(thermal_gap 0.5)
			(thermal_bridge_width 0.5)
			(island_removal_mode 0)
		)
		(polygon
			(pts
				(arc
					(start 190.639954 -277.178516)
					(mid 190.258954 -276.797516)
					(end 189.877954 -277.178516)
				)
				(arc
					(start 189.877954 -278.321516)
					(mid 190.257684 -278.702514)
					(end 190.639954 -278.324056)
				)
				(arc
					(start 190.525654 -278.324056)
					(mid 190.258954 -278.588228)
					(end 189.992254 -278.324056)
				)
				(arc
					(start 189.992254 -278.321516)
					(mid 190.258954 -278.054816)
					(end 190.525654 -278.321516)
				)
				(xy 190.639954 -278.321516) (xy 190.639954 -277.181056)
				(arc
					(start 190.525654 -277.181056)
					(mid 190.258954 -277.445228)
					(end 189.992254 -277.181056)
				)
				(arc
					(start 189.992254 -277.178516)
					(mid 190.258954 -276.911816)
					(end 190.525654 -277.178516)
				)
			)
		)
	)
	(zone
		(layers "B.Cu" "In2.Cu" "In4.Cu" "In9.Cu")
		(hatch none 0.5)
		(connect_pads
			(clearance 0)
		)
		(min_thickness 0.25)
		(keepout
			(tracks not_allowed)
			(vias allowed)
			(pads allowed)
			(copperpour not_allowed)
			(footprints allowed)
		)
		(placement
			(enabled no)
			(sheetname "")
		)
		(fill yes
			(thermal_gap 0.5)
			(thermal_bridge_width 0.5)
			(island_removal_mode 0)
		)
		(polygon
			(pts
				(arc
					(start 159.089852 -162.178492)
					(mid 158.708852 -161.797492)
					(end 158.327852 -162.178492)
				)
				(arc
					(start 158.327852 -163.321492)
					(mid 158.707582 -163.70249)
					(end 159.089852 -163.324032)
				)
				(arc
					(start 158.975552 -163.324032)
					(mid 158.708852 -163.588204)
					(end 158.442152 -163.324032)
				)
				(arc
					(start 158.442152 -163.321492)
					(mid 158.708852 -163.054792)
					(end 158.975552 -163.321492)
				)
				(xy 159.089852 -163.321492) (xy 159.089852 -162.181032)
				(arc
					(start 158.975552 -162.181032)
					(mid 158.708852 -162.445204)
					(end 158.442152 -162.181032)
				)
				(arc
					(start 158.442152 -162.178492)
					(mid 158.708852 -161.911792)
					(end 158.975552 -162.178492)
				)
			)
		)
	)
	(zone
		(layers "B.Cu" "In2.Cu" "In4.Cu" "In9.Cu")
		(hatch none 0.5)
		(connect_pads
			(clearance 0)
		)
		(min_thickness 0.25)
		(keepout
			(tracks not_allowed)
			(vias allowed)
			(pads allowed)
			(copperpour not_allowed)
			(footprints allowed)
		)
		(placement
			(enabled no)
			(sheetname "")
		)
		(fill yes
			(thermal_gap 0.5)
			(thermal_bridge_width 0.5)
			(island_removal_mode 0)
		)
		(polygon
			(pts
				(arc
					(start 127.53975 -162.178492)
					(mid 127.15875 -161.797492)
					(end 126.77775 -162.178492)
				)
				(arc
					(start 126.77775 -163.321492)
					(mid 127.15748 -163.70249)
					(end 127.53975 -163.324032)
				)
				(arc
					(start 127.42545 -163.324032)
					(mid 127.15875 -163.588204)
					(end 126.89205 -163.324032)
				)
				(arc
					(start 126.89205 -163.321492)
					(mid 127.15875 -163.054792)
					(end 127.42545 -163.321492)
				)
				(xy 127.53975 -163.321492) (xy 127.53975 -162.181032)
				(arc
					(start 127.42545 -162.181032)
					(mid 127.15875 -162.445204)
					(end 126.89205 -162.181032)
				)
				(arc
					(start 126.89205 -162.178492)
					(mid 127.15875 -161.911792)
					(end 127.42545 -162.178492)
				)
			)
		)
	)
	(zone
		(layers "B.Cu" "In2.Cu" "In4.Cu" "In9.Cu")
		(hatch none 0.5)
		(connect_pads
			(clearance 0)
		)
		(min_thickness 0.25)
		(keepout
			(tracks not_allowed)
			(vias allowed)
			(pads allowed)
			(copperpour not_allowed)
			(footprints allowed)
		)
		(placement
			(enabled no)
			(sheetname "")
		)
		(fill yes
			(thermal_gap 0.5)
			(thermal_bridge_width 0.5)
			(island_removal_mode 0)
		)
		(polygon
			(pts
				(arc
					(start 159.089852 -277.178516)
					(mid 158.708852 -276.797516)
					(end 158.327852 -277.178516)
				)
				(arc
					(start 158.327852 -278.321516)
					(mid 158.707582 -278.702514)
					(end 159.089852 -278.324056)
				)
				(arc
					(start 158.975552 -278.324056)
					(mid 158.708852 -278.588228)
					(end 158.442152 -278.324056)
				)
				(arc
					(start 158.442152 -278.321516)
					(mid 158.708852 -278.054816)
					(end 158.975552 -278.321516)
				)
				(xy 159.089852 -278.321516) (xy 159.089852 -277.181056)
				(arc
					(start 158.975552 -277.181056)
					(mid 158.708852 -277.445228)
					(end 158.442152 -277.181056)
				)
				(arc
					(start 158.442152 -277.178516)
					(mid 158.708852 -276.911816)
					(end 158.975552 -277.178516)
				)
			)
		)
	)
	(zone
		(layers "B.Cu" "In2.Cu" "In4.Cu" "In9.Cu")
		(hatch none 0.5)
		(connect_pads
			(clearance 0)
		)
		(min_thickness 0.25)
		(keepout
			(tracks not_allowed)
			(vias allowed)
			(pads allowed)
			(copperpour not_allowed)
			(footprints allowed)
		)
		(placement
			(enabled no)
			(sheetname "")
		)
		(fill yes
			(thermal_gap 0.5)
			(thermal_bridge_width 0.5)
			(island_removal_mode 0)
		)
		(polygon
			(pts
				(arc
					(start 322.6816 -46.056042)
					(mid 322.3006 -46.437042)
					(end 322.6816 -46.818042)
				)
				(arc
					(start 323.824346 -46.818042)
					(mid 324.093018 -46.707436)
					(end 324.2056 -46.439582)
				)
				(arc
					(start 324.0913 -46.439582)
					(mid 323.8246 -46.703754)
					(end 323.5579 -46.439582)
				)
				(arc
					(start 322.9483 -46.439582)
					(mid 322.6816 -46.703754)
					(end 322.4149 -46.439582)
				)
				(arc
					(start 322.4149 -46.437042)
					(mid 322.6816 -46.170342)
					(end 322.9483 -46.437042)
				)
				(arc
					(start 323.5579 -46.437042)
					(mid 323.8246 -46.170342)
					(end 324.0913 -46.437042)
				)
				(arc
					(start 324.2056 -46.437042)
					(mid 324.094008 -46.167634)
					(end 323.8246 -46.056042)
				)
			)
		)
	)
	(zone
		(layers "B.Cu" "In2.Cu" "In4.Cu" "In9.Cu")
		(hatch none 0.5)
		(connect_pads
			(clearance 0)
		)
		(min_thickness 0.25)
		(keepout
			(tracks not_allowed)
			(vias allowed)
			(pads allowed)
			(copperpour not_allowed)
			(footprints allowed)
		)
		(placement
			(enabled no)
			(sheetname "")
		)
		(fill yes
			(thermal_gap 0.5)
			(thermal_bridge_width 0.5)
			(island_removal_mode 0)
		)
		(polygon
			(pts
				(arc
					(start 64.4398 -47.178468)
					(mid 64.0588 -46.797468)
					(end 63.6778 -47.178468)
				)
				(arc
					(start 63.6778 -48.321468)
					(mid 64.05753 -48.702466)
					(end 64.4398 -48.324008)
				)
				(arc
					(start 64.3255 -48.324008)
					(mid 64.0588 -48.58818)
					(end 63.7921 -48.324008)
				)
				(arc
					(start 63.7921 -48.321468)
					(mid 64.0588 -48.054768)
					(end 64.3255 -48.321468)
				)
				(xy 64.4398 -48.321468) (xy 64.4398 -47.181008)
				(arc
					(start 64.3255 -47.181008)
					(mid 64.0588 -47.44518)
					(end 63.7921 -47.181008)
				)
				(arc
					(start 63.7921 -47.178468)
					(mid 64.0588 -46.911768)
					(end 64.3255 -47.178468)
				)
			)
		)
	)
	(zone
		(layers "B.Cu" "In4.Cu" "In7.Cu")
		(hatch none 0.5)
		(connect_pads
			(clearance 0)
		)
		(min_thickness 0.25)
		(keepout
			(tracks not_allowed)
			(vias allowed)
			(pads allowed)
			(copperpour not_allowed)
			(footprints allowed)
		)
		(placement
			(enabled no)
			(sheetname "")
		)
		(fill yes
			(thermal_gap 0.5)
			(thermal_bridge_width 0.5)
			(island_removal_mode 0)
		)
		(polygon
			(pts
				(arc
					(start 409.277058 -289.999928)
					(mid 399.52295 -289.999928)
					(end 409.277058 -289.999928)
				)
			)
		)
	)
	(zone
		(layers "B.Cu" "In4.Cu" "In7.Cu")
		(hatch none 0.5)
		(connect_pads
			(clearance 0)
		)
		(min_thickness 0.25)
		(keepout
			(tracks not_allowed)
			(vias allowed)
			(pads allowed)
			(copperpour not_allowed)
			(footprints allowed)
		)
		(placement
			(enabled no)
			(sheetname "")
		)
		(fill yes
			(thermal_gap 0.5)
			(thermal_bridge_width 0.5)
			(island_removal_mode 0)
		)
		(polygon
			(pts
				(arc
					(start 472.377008 -269.999968)
					(mid 462.6229 -269.999968)
					(end 472.377008 -269.999968)
				)
			)
		)
	)
	(zone
		(layers "B.Cu" "In4.Cu" "In7.Cu")
		(hatch none 0.5)
		(connect_pads
			(clearance 0)
		)
		(min_thickness 0.25)
		(keepout
			(tracks not_allowed)
			(vias allowed)
			(pads allowed)
			(copperpour not_allowed)
			(footprints allowed)
		)
		(placement
			(enabled no)
			(sheetname "")
		)
		(fill yes
			(thermal_gap 0.5)
			(thermal_bridge_width 0.5)
			(island_removal_mode 0)
		)
		(polygon
			(pts
				(arc
					(start 346.177108 -269.999968)
					(mid 336.423 -269.999968)
					(end 346.177108 -269.999968)
				)
			)
		)
	)
	(zone
		(layers "B.Cu" "In4.Cu" "In7.Cu")
		(hatch none 0.5)
		(connect_pads
			(clearance 0)
		)
		(min_thickness 0.25)
		(keepout
			(tracks not_allowed)
			(vias allowed)
			(pads allowed)
			(copperpour not_allowed)
			(footprints allowed)
		)
		(placement
			(enabled no)
			(sheetname "")
		)
		(fill yes
			(thermal_gap 0.5)
			(thermal_bridge_width 0.5)
			(island_removal_mode 0)
		)
		(polygon
			(pts
				(arc
					(start 175.07712 -269.999968)
					(mid 165.323012 -269.999968)
					(end 175.07712 -269.999968)
				)
			)
		)
	)
	(zone
		(layers "B.Cu" "In7.Cu")
		(hatch none 0.5)
		(connect_pads
			(clearance 0)
		)
		(min_thickness 0.25)
		(keepout
			(tracks not_allowed)
			(vias allowed)
			(pads allowed)
			(copperpour not_allowed)
			(footprints allowed)
		)
		(placement
			(enabled no)
			(sheetname "")
		)
		(fill yes
			(thermal_gap 0.5)
			(thermal_bridge_width 0.5)
			(island_removal_mode 0)
		)
		(polygon
			(pts
				(arc
					(start 386.298694 -18.35023)
					(mid 385.750054 -17.80159)
					(end 385.201414 -18.35023)
				)
				(arc
					(start 385.201414 -19.750024)
					(mid 385.748784 -20.298663)
					(end 386.298694 -19.752564)
				)
				(arc
					(start 386.143754 -19.752564)
					(mid 385.750054 -20.143732)
					(end 385.356354 -19.752564)
				)
				(arc
					(start 385.356354 -19.750024)
					(mid 385.750054 -19.356324)
					(end 386.143754 -19.750024)
				)
				(xy 386.298694 -19.750024) (xy 386.298694 -18.35277)
				(arc
					(start 386.143754 -18.35277)
					(mid 385.750054 -18.743938)
					(end 385.356354 -18.35277)
				)
				(arc
					(start 385.356354 -18.35023)
					(mid 385.750054 -17.95653)
					(end 386.143754 -18.35023)
				)
			)
		)
	)
	(zone
		(layers "B.Cu" "In7.Cu")
		(hatch none 0.5)
		(connect_pads
			(clearance 0)
		)
		(min_thickness 0.25)
		(keepout
			(tracks not_allowed)
			(vias allowed)
			(pads allowed)
			(copperpour not_allowed)
			(footprints allowed)
		)
		(placement
			(enabled no)
			(sheetname "")
		)
		(fill yes
			(thermal_gap 0.5)
			(thermal_bridge_width 0.5)
			(island_removal_mode 0)
		)
		(polygon
			(pts
				(arc
					(start 142.098522 -17.349978)
					(mid 141.549882 -16.801338)
					(end 141.001242 -17.349978)
				)
				(arc
					(start 141.001242 -18.750026)
					(mid 141.548612 -19.298665)
					(end 142.098522 -18.752566)
				)
				(arc
					(start 141.943582 -18.752566)
					(mid 141.549882 -19.143734)
					(end 141.156182 -18.752566)
				)
				(arc
					(start 141.156182 -18.750026)
					(mid 141.549882 -18.356326)
					(end 141.943582 -18.750026)
				)
				(xy 142.098522 -18.750026) (xy 142.098522 -17.352518)
				(arc
					(start 141.943582 -17.352518)
					(mid 141.549882 -17.743686)
					(end 141.156182 -17.352518)
				)
				(arc
					(start 141.156182 -17.349978)
					(mid 141.549882 -16.956278)
					(end 141.943582 -17.349978)
				)
			)
		)
	)
	(zone
		(layers "B.Cu" "In7.Cu")
		(hatch none 0.5)
		(connect_pads
			(clearance 0)
		)
		(min_thickness 0.25)
		(keepout
			(tracks not_allowed)
			(vias allowed)
			(pads allowed)
			(copperpour not_allowed)
			(footprints allowed)
		)
		(placement
			(enabled no)
			(sheetname "")
		)
		(fill yes
			(thermal_gap 0.5)
			(thermal_bridge_width 0.5)
			(island_removal_mode 0)
		)
		(polygon
			(pts
				(arc
					(start 133.09854 -18.35023)
					(mid 132.5499 -17.80159)
					(end 132.00126 -18.35023)
				)
				(arc
					(start 132.00126 -19.74977)
					(mid 132.548503 -20.298662)
					(end 133.09854 -19.752564)
				)
				(arc
					(start 132.9436 -19.752564)
					(mid 132.5499 -20.143732)
					(end 132.1562 -19.752564)
				)
				(arc
					(start 132.1562 -19.750024)
					(mid 132.5499 -19.356324)
					(end 132.9436 -19.750024)
				)
				(xy 133.09854 -19.750024) (xy 133.09854 -18.35277)
				(arc
					(start 132.9436 -18.35277)
					(mid 132.5499 -18.743938)
					(end 132.1562 -18.35277)
				)
				(arc
					(start 132.1562 -18.35023)
					(mid 132.5499 -17.95653)
					(end 132.9436 -18.35023)
				)
			)
		)
	)
	(zone
		(layers "B.Cu" "In7.Cu")
		(hatch none 0.5)
		(connect_pads
			(clearance 0)
		)
		(min_thickness 0.25)
		(keepout
			(tracks not_allowed)
			(vias allowed)
			(pads allowed)
			(copperpour not_allowed)
			(footprints allowed)
		)
		(placement
			(enabled no)
			(sheetname "")
		)
		(fill yes
			(thermal_gap 0.5)
			(thermal_bridge_width 0.5)
			(island_removal_mode 0)
		)
		(polygon
			(pts
				(arc
					(start 136.698736 -18.35023)
					(mid 136.150096 -17.80159)
					(end 135.601456 -18.35023)
				)
				(arc
					(start 135.601456 -19.750024)
					(mid 136.148826 -20.298663)
					(end 136.698736 -19.752564)
				)
				(arc
					(start 136.543796 -19.752564)
					(mid 136.150096 -20.143732)
					(end 135.756396 -19.752564)
				)
				(arc
					(start 135.756396 -19.750024)
					(mid 136.150096 -19.356324)
					(end 136.543796 -19.750024)
				)
				(xy 136.698736 -19.750024) (xy 136.698736 -18.35277)
				(arc
					(start 136.543796 -18.35277)
					(mid 136.150096 -18.743938)
					(end 135.756396 -18.35277)
				)
				(arc
					(start 135.756396 -18.35023)
					(mid 136.150096 -17.95653)
					(end 136.543796 -18.35023)
				)
			)
		)
	)
	(zone
		(layers "B.Cu" "In7.Cu")
		(hatch none 0.5)
		(connect_pads
			(clearance 0)
		)
		(min_thickness 0.25)
		(keepout
			(tracks not_allowed)
			(vias allowed)
			(pads allowed)
			(copperpour not_allowed)
			(footprints allowed)
		)
		(placement
			(enabled no)
			(sheetname "")
		)
		(fill yes
			(thermal_gap 0.5)
			(thermal_bridge_width 0.5)
			(island_removal_mode 0)
		)
		(polygon
			(pts
				(arc
					(start 115.098576 -18.35023)
					(mid 114.549936 -17.80159)
					(end 114.001296 -18.35023)
				)
				(arc
					(start 114.001296 -19.750024)
					(mid 114.548666 -20.298663)
					(end 115.098576 -19.752564)
				)
				(arc
					(start 114.943636 -19.752564)
					(mid 114.549936 -20.143732)
					(end 114.156236 -19.752564)
				)
				(arc
					(start 114.156236 -19.750024)
					(mid 114.549936 -19.356324)
					(end 114.943636 -19.750024)
				)
				(xy 115.098576 -19.750024) (xy 115.098576 -18.35277)
				(arc
					(start 114.943636 -18.35277)
					(mid 114.549936 -18.743938)
					(end 114.156236 -18.35277)
				)
				(arc
					(start 114.156236 -18.35023)
					(mid 114.549936 -17.95653)
					(end 114.943636 -18.35023)
				)
			)
		)
	)
	(zone
		(layers "B.Cu" "In7.Cu")
		(hatch none 0.5)
		(connect_pads
			(clearance 0)
		)
		(min_thickness 0.25)
		(keepout
			(tracks not_allowed)
			(vias allowed)
			(pads allowed)
			(copperpour not_allowed)
			(footprints allowed)
		)
		(placement
			(enabled no)
			(sheetname "")
		)
		(fill yes
			(thermal_gap 0.5)
			(thermal_bridge_width 0.5)
			(island_removal_mode 0)
		)
		(polygon
			(pts
				(arc
					(start 111.498634 -18.35023)
					(mid 110.949994 -17.80159)
					(end 110.401354 -18.35023)
				)
				(arc
					(start 110.401354 -19.750024)
					(mid 110.948724 -20.298663)
					(end 111.498634 -19.752564)
				)
				(arc
					(start 111.343694 -19.752564)
					(mid 110.949994 -20.143732)
					(end 110.556294 -19.752564)
				)
				(arc
					(start 110.556294 -19.750024)
					(mid 110.949994 -19.356324)
					(end 111.343694 -19.750024)
				)
				(xy 111.498634 -19.750024) (xy 111.498634 -18.35277)
				(arc
					(start 111.343694 -18.35277)
					(mid 110.949994 -18.743938)
					(end 110.556294 -18.35277)
				)
				(arc
					(start 110.556294 -18.35023)
					(mid 110.949994 -17.95653)
					(end 111.343694 -18.35023)
				)
			)
		)
	)
	(zone
		(layers "B.Cu" "In7.Cu")
		(hatch none 0.5)
		(connect_pads
			(clearance 0)
		)
		(min_thickness 0.25)
		(keepout
			(tracks not_allowed)
			(vias allowed)
			(pads allowed)
			(copperpour not_allowed)
			(footprints allowed)
		)
		(placement
			(enabled no)
			(sheetname "")
		)
		(fill yes
			(thermal_gap 0.5)
			(thermal_bridge_width 0.5)
			(island_removal_mode 0)
		)
		(polygon
			(pts
				(arc
					(start 134.898638 -17.349978)
					(mid 134.349998 -16.801338)
					(end 133.801358 -17.349978)
				)
				(arc
					(start 133.801358 -18.750026)
					(mid 134.348728 -19.298665)
					(end 134.898638 -18.752566)
				)
				(arc
					(start 134.743698 -18.752566)
					(mid 134.349998 -19.143734)
					(end 133.956298 -18.752566)
				)
				(arc
					(start 133.956298 -18.750026)
					(mid 134.349998 -18.356326)
					(end 134.743698 -18.750026)
				)
				(xy 134.898638 -18.750026) (xy 134.898638 -17.352518)
				(arc
					(start 134.743698 -17.352518)
					(mid 134.349998 -17.743686)
					(end 133.956298 -17.352518)
				)
				(arc
					(start 133.956298 -17.349978)
					(mid 134.349998 -16.956278)
					(end 134.743698 -17.349978)
				)
			)
		)
	)
	(zone
		(layers "B.Cu" "In7.Cu")
		(hatch none 0.5)
		(connect_pads
			(clearance 0)
		)
		(min_thickness 0.25)
		(keepout
			(tracks not_allowed)
			(vias allowed)
			(pads allowed)
			(copperpour not_allowed)
			(footprints allowed)
		)
		(placement
			(enabled no)
			(sheetname "")
		)
		(fill yes
			(thermal_gap 0.5)
			(thermal_bridge_width 0.5)
			(island_removal_mode 0)
		)
		(polygon
			(pts
				(arc
					(start 120.498616 -17.349978)
					(mid 119.949976 -16.801338)
					(end 119.401336 -17.349978)
				)
				(arc
					(start 119.401336 -18.750026)
					(mid 119.948706 -19.298665)
					(end 120.498616 -18.752566)
				)
				(arc
					(start 120.343676 -18.752566)
					(mid 119.949976 -19.143734)
					(end 119.556276 -18.752566)
				)
				(arc
					(start 119.556276 -18.750026)
					(mid 119.949976 -18.356326)
					(end 120.343676 -18.750026)
				)
				(xy 120.498616 -18.750026) (xy 120.498616 -17.352518)
				(arc
					(start 120.343676 -17.352518)
					(mid 119.949976 -17.743686)
					(end 119.556276 -17.352518)
				)
				(arc
					(start 119.556276 -17.349978)
					(mid 119.949976 -16.956278)
					(end 120.343676 -17.349978)
				)
			)
		)
	)
	(zone
		(layers "B.Cu" "In7.Cu")
		(hatch none 0.5)
		(connect_pads
			(clearance 0)
		)
		(min_thickness 0.25)
		(keepout
			(tracks not_allowed)
			(vias allowed)
			(pads allowed)
			(copperpour not_allowed)
			(footprints allowed)
		)
		(placement
			(enabled no)
			(sheetname "")
		)
		(fill yes
			(thermal_gap 0.5)
			(thermal_bridge_width 0.5)
			(island_removal_mode 0)
		)
		(polygon
			(pts
				(arc
					(start 109.698536 -17.349978)
					(mid 109.149896 -16.801338)
					(end 108.601256 -17.349978)
				)
				(arc
					(start 108.601256 -18.750026)
					(mid 109.148626 -19.298665)
					(end 109.698536 -18.752566)
				)
				(arc
					(start 109.543596 -18.752566)
					(mid 109.149896 -19.143734)
					(end 108.756196 -18.752566)
				)
				(arc
					(start 108.756196 -18.750026)
					(mid 109.149896 -18.356326)
					(end 109.543596 -18.750026)
				)
				(xy 109.698536 -18.750026) (xy 109.698536 -17.352518)
				(arc
					(start 109.543596 -17.352518)
					(mid 109.149896 -17.743686)
					(end 108.756196 -17.352518)
				)
				(arc
					(start 108.756196 -17.349978)
					(mid 109.149896 -16.956278)
					(end 109.543596 -17.349978)
				)
			)
		)
	)
	(zone
		(layers "B.Cu" "In7.Cu")
		(hatch none 0.5)
		(connect_pads
			(clearance 0)
		)
		(min_thickness 0.25)
		(keepout
			(tracks not_allowed)
			(vias allowed)
			(pads allowed)
			(copperpour not_allowed)
			(footprints allowed)
		)
		(placement
			(enabled no)
			(sheetname "")
		)
		(fill yes
			(thermal_gap 0.5)
			(thermal_bridge_width 0.5)
			(island_removal_mode 0)
		)
		(polygon
			(pts
				(arc
					(start 384.498596 -17.349978)
					(mid 383.949956 -16.801338)
					(end 383.401316 -17.349978)
				)
				(arc
					(start 383.401316 -18.750026)
					(mid 383.948686 -19.298665)
					(end 384.498596 -18.752566)
				)
				(arc
					(start 384.343656 -18.752566)
					(mid 383.949956 -19.143734)
					(end 383.556256 -18.752566)
				)
				(arc
					(start 383.556256 -18.750026)
					(mid 383.949956 -18.356326)
					(end 384.343656 -18.750026)
				)
				(xy 384.498596 -18.750026) (xy 384.498596 -17.352518)
				(arc
					(start 384.343656 -17.352518)
					(mid 383.949956 -17.743686)
					(end 383.556256 -17.352518)
				)
				(arc
					(start 383.556256 -17.349978)
					(mid 383.949956 -16.956278)
					(end 384.343656 -17.349978)
				)
			)
		)
	)
	(zone
		(layers "B.Cu" "In7.Cu")
		(hatch none 0.5)
		(connect_pads
			(clearance 0)
		)
		(min_thickness 0.25)
		(keepout
			(tracks not_allowed)
			(vias allowed)
			(pads allowed)
			(copperpour not_allowed)
			(footprints allowed)
		)
		(placement
			(enabled no)
			(sheetname "")
		)
		(fill yes
			(thermal_gap 0.5)
			(thermal_bridge_width 0.5)
			(island_removal_mode 0)
		)
		(polygon
			(pts
				(arc
					(start 131.298696 -17.349978)
					(mid 130.750056 -16.801338)
					(end 130.201416 -17.349978)
				)
				(arc
					(start 130.201416 -18.750026)
					(mid 130.748786 -19.298665)
					(end 131.298696 -18.752566)
				)
				(arc
					(start 131.143756 -18.752566)
					(mid 130.750056 -19.143734)
					(end 130.356356 -18.752566)
				)
				(arc
					(start 130.356356 -18.750026)
					(mid 130.750056 -18.356326)
					(end 131.143756 -18.750026)
				)
				(xy 131.298696 -18.750026) (xy 131.298696 -17.352518)
				(arc
					(start 131.143756 -17.352518)
					(mid 130.750056 -17.743686)
					(end 130.356356 -17.352518)
				)
				(arc
					(start 130.356356 -17.349978)
					(mid 130.750056 -16.956278)
					(end 131.143756 -17.349978)
				)
			)
		)
	)
	(zone
		(layers "B.Cu" "In7.Cu")
		(hatch none 0.5)
		(connect_pads
			(clearance 0)
		)
		(min_thickness 0.25)
		(keepout
			(tracks not_allowed)
			(vias allowed)
			(pads allowed)
			(copperpour not_allowed)
			(footprints allowed)
		)
		(placement
			(enabled no)
			(sheetname "")
		)
		(fill yes
			(thermal_gap 0.5)
			(thermal_bridge_width 0.5)
			(island_removal_mode 0)
		)
		(polygon
			(pts
				(arc
					(start 388.098538 -17.349978)
					(mid 387.549898 -16.801338)
					(end 387.001258 -17.349978)
				)
				(arc
					(start 387.001258 -18.750026)
					(mid 387.548628 -19.298665)
					(end 388.098538 -18.752566)
				)
				(arc
					(start 387.943598 -18.752566)
					(mid 387.549898 -19.143734)
					(end 387.156198 -18.752566)
				)
				(arc
					(start 387.156198 -18.750026)
					(mid 387.549898 -18.356326)
					(end 387.943598 -18.750026)
				)
				(xy 388.098538 -18.750026) (xy 388.098538 -17.352518)
				(arc
					(start 387.943598 -17.352518)
					(mid 387.549898 -17.743686)
					(end 387.156198 -17.352518)
				)
				(arc
					(start 387.156198 -17.349978)
					(mid 387.549898 -16.956278)
					(end 387.943598 -17.349978)
				)
			)
		)
	)
	(zone
		(layers "B.Cu" "In7.Cu")
		(hatch none 0.5)
		(connect_pads
			(clearance 0)
		)
		(min_thickness 0.25)
		(keepout
			(tracks not_allowed)
			(vias allowed)
			(pads allowed)
			(copperpour not_allowed)
			(footprints allowed)
		)
		(placement
			(enabled no)
			(sheetname "")
		)
		(fill yes
			(thermal_gap 0.5)
			(thermal_bridge_width 0.5)
			(island_removal_mode 0)
		)
		(polygon
			(pts
				(arc
					(start 364.698534 -18.35023)
					(mid 364.149894 -17.80159)
					(end 363.601254 -18.35023)
				)
				(arc
					(start 363.601254 -19.750024)
					(mid 364.148624 -20.298663)
					(end 364.698534 -19.752564)
				)
				(arc
					(start 364.543594 -19.752564)
					(mid 364.149894 -20.143732)
					(end 363.756194 -19.752564)
				)
				(arc
					(start 363.756194 -19.750024)
					(mid 364.149894 -19.356324)
					(end 364.543594 -19.750024)
				)
				(xy 364.698534 -19.750024) (xy 364.698534 -18.35277)
				(arc
					(start 364.543594 -18.35277)
					(mid 364.149894 -18.743938)
					(end 363.756194 -18.35277)
				)
				(arc
					(start 363.756194 -18.35023)
					(mid 364.149894 -17.95653)
					(end 364.543594 -18.35023)
				)
			)
		)
	)
	(zone
		(layers "B.Cu" "In7.Cu")
		(hatch none 0.5)
		(connect_pads
			(clearance 0)
		)
		(min_thickness 0.25)
		(keepout
			(tracks not_allowed)
			(vias allowed)
			(pads allowed)
			(copperpour not_allowed)
			(footprints allowed)
		)
		(placement
			(enabled no)
			(sheetname "")
		)
		(fill yes
			(thermal_gap 0.5)
			(thermal_bridge_width 0.5)
			(island_removal_mode 0)
		)
		(polygon
			(pts
				(arc
					(start 118.698518 -18.35023)
					(mid 118.149878 -17.80159)
					(end 117.601238 -18.35023)
				)
				(arc
					(start 117.601238 -19.750024)
					(mid 118.148608 -20.298663)
					(end 118.698518 -19.752564)
				)
				(arc
					(start 118.543578 -19.752564)
					(mid 118.149878 -20.143732)
					(end 117.756178 -19.752564)
				)
				(arc
					(start 117.756178 -19.750024)
					(mid 118.149878 -19.356324)
					(end 118.543578 -19.750024)
				)
				(xy 118.698518 -19.750024) (xy 118.698518 -18.35277)
				(arc
					(start 118.543578 -18.35277)
					(mid 118.149878 -18.743938)
					(end 117.756178 -18.35277)
				)
				(arc
					(start 117.756178 -18.35023)
					(mid 118.149878 -17.95653)
					(end 118.543578 -18.35023)
				)
			)
		)
	)
	(zone
		(layers "B.Cu" "In7.Cu")
		(hatch none 0.5)
		(connect_pads
			(clearance 0)
		)
		(min_thickness 0.25)
		(keepout
			(tracks not_allowed)
			(vias allowed)
			(pads allowed)
			(copperpour not_allowed)
			(footprints allowed)
		)
		(placement
			(enabled no)
			(sheetname "")
		)
		(fill yes
			(thermal_gap 0.5)
			(thermal_bridge_width 0.5)
			(island_removal_mode 0)
		)
		(polygon
			(pts
				(arc
					(start 138.49858 -17.349978)
					(mid 137.94994 -16.801338)
					(end 137.4013 -17.349978)
				)
				(arc
					(start 137.4013 -18.750026)
					(mid 137.94867 -19.298665)
					(end 138.49858 -18.752566)
				)
				(arc
					(start 138.34364 -18.752566)
					(mid 137.94994 -19.143734)
					(end 137.55624 -18.752566)
				)
				(arc
					(start 137.55624 -18.750026)
					(mid 137.94994 -18.356326)
					(end 138.34364 -18.750026)
				)
				(xy 138.49858 -18.750026) (xy 138.49858 -17.352518)
				(arc
					(start 138.34364 -17.352518)
					(mid 137.94994 -17.743686)
					(end 137.55624 -17.352518)
				)
				(arc
					(start 137.55624 -17.349978)
					(mid 137.94994 -16.956278)
					(end 138.34364 -17.349978)
				)
			)
		)
	)
	(zone
		(layers "B.Cu" "In7.Cu")
		(hatch none 0.5)
		(connect_pads
			(clearance 0)
		)
		(min_thickness 0.25)
		(keepout
			(tracks not_allowed)
			(vias allowed)
			(pads allowed)
			(copperpour not_allowed)
			(footprints allowed)
		)
		(placement
			(enabled no)
			(sheetname "")
		)
		(fill yes
			(thermal_gap 0.5)
			(thermal_bridge_width 0.5)
			(island_removal_mode 0)
		)
		(polygon
			(pts
				(arc
					(start 366.498632 -17.349978)
					(mid 365.949992 -16.801338)
					(end 365.401352 -17.349978)
				)
				(arc
					(start 365.401352 -18.750026)
					(mid 365.948722 -19.298665)
					(end 366.498632 -18.752566)
				)
				(arc
					(start 366.343692 -18.752566)
					(mid 365.949992 -19.143734)
					(end 365.556292 -18.752566)
				)
				(arc
					(start 365.556292 -18.750026)
					(mid 365.949992 -18.356326)
					(end 366.343692 -18.750026)
				)
				(xy 366.498632 -18.750026) (xy 366.498632 -17.352518)
				(arc
					(start 366.343692 -17.352518)
					(mid 365.949992 -17.743686)
					(end 365.556292 -17.352518)
				)
				(arc
					(start 365.556292 -17.349978)
					(mid 365.949992 -16.956278)
					(end 366.343692 -17.349978)
				)
			)
		)
	)
	(zone
		(layers "B.Cu" "In7.Cu")
		(hatch none 0.5)
		(connect_pads
			(clearance 0)
		)
		(min_thickness 0.25)
		(keepout
			(tracks not_allowed)
			(vias allowed)
			(pads allowed)
			(copperpour not_allowed)
			(footprints allowed)
		)
		(placement
			(enabled no)
			(sheetname "")
		)
		(fill yes
			(thermal_gap 0.5)
			(thermal_bridge_width 0.5)
			(island_removal_mode 0)
		)
		(polygon
			(pts
				(arc
					(start 359.298748 -17.349978)
					(mid 358.750108 -16.801338)
					(end 358.201468 -17.349978)
				)
				(arc
					(start 358.201468 -18.750026)
					(mid 358.748838 -19.298665)
					(end 359.298748 -18.752566)
				)
				(arc
					(start 359.143808 -18.752566)
					(mid 358.750108 -19.143734)
					(end 358.356408 -18.752566)
				)
				(arc
					(start 358.356408 -18.750026)
					(mid 358.750108 -18.356326)
					(end 359.143808 -18.750026)
				)
				(xy 359.298748 -18.750026) (xy 359.298748 -17.352518)
				(arc
					(start 359.143808 -17.352518)
					(mid 358.750108 -17.743686)
					(end 358.356408 -17.352518)
				)
				(arc
					(start 358.356408 -17.349978)
					(mid 358.750108 -16.956278)
					(end 359.143808 -17.349978)
				)
			)
		)
	)
	(zone
		(layers "B.Cu" "In7.Cu")
		(hatch none 0.5)
		(connect_pads
			(clearance 0)
		)
		(min_thickness 0.25)
		(keepout
			(tracks not_allowed)
			(vias allowed)
			(pads allowed)
			(copperpour not_allowed)
			(footprints allowed)
		)
		(placement
			(enabled no)
			(sheetname "")
		)
		(fill yes
			(thermal_gap 0.5)
			(thermal_bridge_width 0.5)
			(island_removal_mode 0)
		)
		(polygon
			(pts
				(arc
					(start 368.29873 -18.35023)
					(mid 367.75009 -17.80159)
					(end 367.20145 -18.35023)
				)
				(arc
					(start 367.20145 -19.750024)
					(mid 367.74882 -20.298663)
					(end 368.29873 -19.752564)
				)
				(arc
					(start 368.14379 -19.752564)
					(mid 367.75009 -20.143732)
					(end 367.35639 -19.752564)
				)
				(arc
					(start 367.35639 -19.750024)
					(mid 367.75009 -19.356324)
					(end 368.14379 -19.750024)
				)
				(xy 368.29873 -19.750024) (xy 368.29873 -18.35277)
				(arc
					(start 368.14379 -18.35277)
					(mid 367.75009 -18.743938)
					(end 367.35639 -18.35277)
				)
				(arc
					(start 367.35639 -18.35023)
					(mid 367.75009 -17.95653)
					(end 368.14379 -18.35023)
				)
			)
		)
	)
	(zone
		(layers "B.Cu" "In7.Cu")
		(hatch none 0.5)
		(connect_pads
			(clearance 0)
		)
		(min_thickness 0.25)
		(keepout
			(tracks not_allowed)
			(vias allowed)
			(pads allowed)
			(copperpour not_allowed)
			(footprints allowed)
		)
		(placement
			(enabled no)
			(sheetname "")
		)
		(fill yes
			(thermal_gap 0.5)
			(thermal_bridge_width 0.5)
			(island_removal_mode 0)
		)
		(polygon
			(pts
				(arc
					(start 380.898654 -17.349978)
					(mid 380.350014 -16.801338)
					(end 379.801374 -17.349978)
				)
				(arc
					(start 379.801374 -18.750026)
					(mid 380.348744 -19.298665)
					(end 380.898654 -18.752566)
				)
				(arc
					(start 380.743714 -18.752566)
					(mid 380.350014 -19.143734)
					(end 379.956314 -18.752566)
				)
				(arc
					(start 379.956314 -18.750026)
					(mid 380.350014 -18.356326)
					(end 380.743714 -18.750026)
				)
				(xy 380.898654 -18.750026) (xy 380.898654 -17.352518)
				(arc
					(start 380.743714 -17.352518)
					(mid 380.350014 -17.743686)
					(end 379.956314 -17.352518)
				)
				(arc
					(start 379.956314 -17.349978)
					(mid 380.350014 -16.956278)
					(end 380.743714 -17.349978)
				)
			)
		)
	)
	(zone
		(layers "B.Cu" "In7.Cu")
		(hatch none 0.5)
		(connect_pads
			(clearance 0)
		)
		(min_thickness 0.25)
		(keepout
			(tracks not_allowed)
			(vias allowed)
			(pads allowed)
			(copperpour not_allowed)
			(footprints allowed)
		)
		(placement
			(enabled no)
			(sheetname "")
		)
		(fill yes
			(thermal_gap 0.5)
			(thermal_bridge_width 0.5)
			(island_removal_mode 0)
		)
		(polygon
			(pts
				(arc
					(start 116.898674 -17.349978)
					(mid 116.350034 -16.801338)
					(end 115.801394 -17.349978)
				)
				(arc
					(start 115.801394 -18.750026)
					(mid 116.348764 -19.298665)
					(end 116.898674 -18.752566)
				)
				(arc
					(start 116.743734 -18.752566)
					(mid 116.350034 -19.143734)
					(end 115.956334 -18.752566)
				)
				(arc
					(start 115.956334 -18.750026)
					(mid 116.350034 -18.356326)
					(end 116.743734 -18.750026)
				)
				(xy 116.898674 -18.750026) (xy 116.898674 -17.352518)
				(arc
					(start 116.743734 -17.352518)
					(mid 116.350034 -17.743686)
					(end 115.956334 -17.352518)
				)
				(arc
					(start 115.956334 -17.349978)
					(mid 116.350034 -16.956278)
					(end 116.743734 -17.349978)
				)
			)
		)
	)
	(zone
		(layers "B.Cu" "In7.Cu")
		(hatch none 0.5)
		(connect_pads
			(clearance 0)
		)
		(min_thickness 0.25)
		(keepout
			(tracks not_allowed)
			(vias allowed)
			(pads allowed)
			(copperpour not_allowed)
			(footprints allowed)
		)
		(placement
			(enabled no)
			(sheetname "")
		)
		(fill yes
			(thermal_gap 0.5)
			(thermal_bridge_width 0.5)
			(island_removal_mode 0)
		)
		(polygon
			(pts
				(arc
					(start 379.098556 -18.35023)
					(mid 378.549916 -17.80159)
					(end 378.001276 -18.35023)
				)
				(arc
					(start 378.001276 -19.750024)
					(mid 378.548646 -20.298663)
					(end 379.098556 -19.752564)
				)
				(arc
					(start 378.943616 -19.752564)
					(mid 378.549916 -20.143732)
					(end 378.156216 -19.752564)
				)
				(arc
					(start 378.156216 -19.750024)
					(mid 378.549916 -19.356324)
					(end 378.943616 -19.750024)
				)
				(xy 379.098556 -19.750024) (xy 379.098556 -18.35277)
				(arc
					(start 378.943616 -18.35277)
					(mid 378.549916 -18.743938)
					(end 378.156216 -18.35277)
				)
				(arc
					(start 378.156216 -18.35023)
					(mid 378.549916 -17.95653)
					(end 378.943616 -18.35023)
				)
			)
		)
	)
	(zone
		(layers "B.Cu" "In7.Cu")
		(hatch none 0.5)
		(connect_pads
			(clearance 0)
		)
		(min_thickness 0.25)
		(keepout
			(tracks not_allowed)
			(vias allowed)
			(pads allowed)
			(copperpour not_allowed)
			(footprints allowed)
		)
		(placement
			(enabled no)
			(sheetname "")
		)
		(fill yes
			(thermal_gap 0.5)
			(thermal_bridge_width 0.5)
			(island_removal_mode 0)
		)
		(polygon
			(pts
				(arc
					(start 389.898636 -18.35023)
					(mid 389.349996 -17.80159)
					(end 388.801356 -18.35023)
				)
				(arc
					(start 388.801356 -19.750024)
					(mid 389.348726 -20.298663)
					(end 389.898636 -19.752564)
				)
				(arc
					(start 389.743696 -19.752564)
					(mid 389.349996 -20.143732)
					(end 388.956296 -19.752564)
				)
				(arc
					(start 388.956296 -19.750024)
					(mid 389.349996 -19.356324)
					(end 389.743696 -19.750024)
				)
				(xy 389.898636 -19.750024) (xy 389.898636 -18.35277)
				(arc
					(start 389.743696 -18.35277)
					(mid 389.349996 -18.743938)
					(end 388.956296 -18.35277)
				)
				(arc
					(start 388.956296 -18.35023)
					(mid 389.349996 -17.95653)
					(end 389.743696 -18.35023)
				)
			)
		)
	)
	(zone
		(layers "B.Cu" "In7.Cu")
		(hatch none 0.5)
		(connect_pads
			(clearance 0)
		)
		(min_thickness 0.25)
		(keepout
			(tracks not_allowed)
			(vias allowed)
			(pads allowed)
			(copperpour not_allowed)
			(footprints allowed)
		)
		(placement
			(enabled no)
			(sheetname "")
		)
		(fill yes
			(thermal_gap 0.5)
			(thermal_bridge_width 0.5)
			(island_removal_mode 0)
		)
		(polygon
			(pts
				(arc
					(start 362.89869 -17.349978)
					(mid 362.35005 -16.801338)
					(end 361.80141 -17.349978)
				)
				(arc
					(start 361.80141 -18.750026)
					(mid 362.34878 -19.298665)
					(end 362.89869 -18.752566)
				)
				(arc
					(start 362.74375 -18.752566)
					(mid 362.35005 -19.143734)
					(end 361.95635 -18.752566)
				)
				(arc
					(start 361.95635 -18.750026)
					(mid 362.35005 -18.356326)
					(end 362.74375 -18.750026)
				)
				(xy 362.89869 -18.750026) (xy 362.89869 -17.352518)
				(arc
					(start 362.74375 -17.352518)
					(mid 362.35005 -17.743686)
					(end 361.95635 -17.352518)
				)
				(arc
					(start 361.95635 -17.349978)
					(mid 362.35005 -16.956278)
					(end 362.74375 -17.349978)
				)
			)
		)
	)
	(zone
		(layers "B.Cu" "In7.Cu")
		(hatch none 0.5)
		(connect_pads
			(clearance 0)
		)
		(min_thickness 0.25)
		(keepout
			(tracks not_allowed)
			(vias allowed)
			(pads allowed)
			(copperpour not_allowed)
			(footprints allowed)
		)
		(placement
			(enabled no)
			(sheetname "")
		)
		(fill yes
			(thermal_gap 0.5)
			(thermal_bridge_width 0.5)
			(island_removal_mode 0)
		)
		(polygon
			(pts
				(arc
					(start 382.698752 -18.35023)
					(mid 382.150112 -17.80159)
					(end 381.601472 -18.35023)
				)
				(arc
					(start 381.601472 -19.750024)
					(mid 382.148842 -20.298663)
					(end 382.698752 -19.752564)
				)
				(arc
					(start 382.543812 -19.752564)
					(mid 382.150112 -20.143732)
					(end 381.756412 -19.752564)
				)
				(arc
					(start 381.756412 -19.750024)
					(mid 382.150112 -19.356324)
					(end 382.543812 -19.750024)
				)
				(xy 382.698752 -19.750024) (xy 382.698752 -18.35277)
				(arc
					(start 382.543812 -18.35277)
					(mid 382.150112 -18.743938)
					(end 381.756412 -18.35277)
				)
				(arc
					(start 381.756412 -18.35023)
					(mid 382.150112 -17.95653)
					(end 382.543812 -18.35023)
				)
			)
		)
	)
	(zone
		(layers "B.Cu" "In7.Cu")
		(hatch none 0.5)
		(connect_pads
			(clearance 0)
		)
		(min_thickness 0.25)
		(keepout
			(tracks not_allowed)
			(vias allowed)
			(pads allowed)
			(copperpour not_allowed)
			(footprints allowed)
		)
		(placement
			(enabled no)
			(sheetname "")
		)
		(fill yes
			(thermal_gap 0.5)
			(thermal_bridge_width 0.5)
			(island_removal_mode 0)
		)
		(polygon
			(pts
				(arc
					(start 355.698552 -17.349978)
					(mid 355.149912 -16.801338)
					(end 354.601272 -17.349978)
				)
				(arc
					(start 354.601272 -18.750026)
					(mid 355.148642 -19.298665)
					(end 355.698552 -18.752566)
				)
				(arc
					(start 355.543612 -18.752566)
					(mid 355.149912 -19.143734)
					(end 354.756212 -18.752566)
				)
				(arc
					(start 354.756212 -18.750026)
					(mid 355.149912 -18.356326)
					(end 355.543612 -18.750026)
				)
				(xy 355.698552 -18.750026) (xy 355.698552 -17.352518)
				(arc
					(start 355.543612 -17.352518)
					(mid 355.149912 -17.743686)
					(end 354.756212 -17.352518)
				)
				(arc
					(start 354.756212 -17.349978)
					(mid 355.149912 -16.956278)
					(end 355.543612 -17.349978)
				)
			)
		)
	)
	(zone
		(layers "B.Cu" "In7.Cu")
		(hatch none 0.5)
		(connect_pads
			(clearance 0)
		)
		(min_thickness 0.25)
		(keepout
			(tracks not_allowed)
			(vias allowed)
			(pads allowed)
			(copperpour not_allowed)
			(footprints allowed)
		)
		(placement
			(enabled no)
			(sheetname "")
		)
		(fill yes
			(thermal_gap 0.5)
			(thermal_bridge_width 0.5)
			(island_removal_mode 0)
		)
		(polygon
			(pts
				(arc
					(start 140.298678 -18.35023)
					(mid 139.750038 -17.80159)
					(end 139.201398 -18.35023)
				)
				(arc
					(start 139.201398 -19.750024)
					(mid 139.748768 -20.298663)
					(end 140.298678 -19.752564)
				)
				(arc
					(start 140.143738 -19.752564)
					(mid 139.750038 -20.143732)
					(end 139.356338 -19.752564)
				)
				(arc
					(start 139.356338 -19.750024)
					(mid 139.750038 -19.356324)
					(end 140.143738 -19.750024)
				)
				(xy 140.298678 -19.750024) (xy 140.298678 -18.35277)
				(arc
					(start 140.143738 -18.35277)
					(mid 139.750038 -18.743938)
					(end 139.356338 -18.35277)
				)
				(arc
					(start 139.356338 -18.35023)
					(mid 139.750038 -17.95653)
					(end 140.143738 -18.35023)
				)
			)
		)
	)
	(zone
		(layers "B.Cu" "In7.Cu")
		(hatch none 0.5)
		(connect_pads
			(clearance 0)
		)
		(min_thickness 0.25)
		(keepout
			(tracks not_allowed)
			(vias allowed)
			(pads allowed)
			(copperpour not_allowed)
			(footprints allowed)
		)
		(placement
			(enabled no)
			(sheetname "")
		)
		(fill yes
			(thermal_gap 0.5)
			(thermal_bridge_width 0.5)
			(island_removal_mode 0)
		)
		(polygon
			(pts
				(arc
					(start 122.298714 -18.35023)
					(mid 121.750074 -17.80159)
					(end 121.201434 -18.35023)
				)
				(arc
					(start 121.201434 -19.750024)
					(mid 121.748804 -20.298663)
					(end 122.298714 -19.752564)
				)
				(arc
					(start 122.143774 -19.752564)
					(mid 121.750074 -20.143732)
					(end 121.356374 -19.752564)
				)
				(arc
					(start 121.356374 -19.750024)
					(mid 121.750074 -19.356324)
					(end 122.143774 -19.750024)
				)
				(xy 122.298714 -19.750024) (xy 122.298714 -18.35277)
				(arc
					(start 122.143774 -18.35277)
					(mid 121.750074 -18.743938)
					(end 121.356374 -18.35277)
				)
				(arc
					(start 121.356374 -18.35023)
					(mid 121.750074 -17.95653)
					(end 122.143774 -18.35023)
				)
			)
		)
	)
	(zone
		(layers "B.Cu" "In7.Cu")
		(hatch none 0.5)
		(connect_pads
			(clearance 0)
		)
		(min_thickness 0.25)
		(keepout
			(tracks not_allowed)
			(vias allowed)
			(pads allowed)
			(copperpour not_allowed)
			(footprints allowed)
		)
		(placement
			(enabled no)
			(sheetname "")
		)
		(fill yes
			(thermal_gap 0.5)
			(thermal_bridge_width 0.5)
			(island_removal_mode 0)
		)
		(polygon
			(pts
				(arc
					(start 357.49865 -18.35023)
					(mid 356.95001 -17.80159)
					(end 356.40137 -18.35023)
				)
				(arc
					(start 356.40137 -19.750024)
					(mid 356.94874 -20.298663)
					(end 357.49865 -19.752564)
				)
				(arc
					(start 357.34371 -19.752564)
					(mid 356.95001 -20.143732)
					(end 356.55631 -19.752564)
				)
				(arc
					(start 356.55631 -19.750024)
					(mid 356.95001 -19.356324)
					(end 357.34371 -19.750024)
				)
				(xy 357.49865 -19.750024) (xy 357.49865 -18.35277)
				(arc
					(start 357.34371 -18.35277)
					(mid 356.95001 -18.743938)
					(end 356.55631 -18.35277)
				)
				(arc
					(start 356.55631 -18.35023)
					(mid 356.95001 -17.95653)
					(end 357.34371 -18.35023)
				)
			)
		)
	)
	(zone
		(layers "B.Cu" "In7.Cu")
		(hatch none 0.5)
		(connect_pads
			(clearance 0)
		)
		(min_thickness 0.25)
		(keepout
			(tracks not_allowed)
			(vias allowed)
			(pads allowed)
			(copperpour not_allowed)
			(footprints allowed)
		)
		(placement
			(enabled no)
			(sheetname "")
		)
		(fill yes
			(thermal_gap 0.5)
			(thermal_bridge_width 0.5)
			(island_removal_mode 0)
		)
		(polygon
			(pts
				(arc
					(start 113.298732 -17.349978)
					(mid 112.750092 -16.801338)
					(end 112.201452 -17.349978)
				)
				(arc
					(start 112.201452 -18.750026)
					(mid 112.748822 -19.298665)
					(end 113.298732 -18.752566)
				)
				(arc
					(start 113.143792 -18.752566)
					(mid 112.750092 -19.143734)
					(end 112.356392 -18.752566)
				)
				(arc
					(start 112.356392 -18.750026)
					(mid 112.750092 -18.356326)
					(end 113.143792 -18.750026)
				)
				(xy 113.298732 -18.750026) (xy 113.298732 -17.352518)
				(arc
					(start 113.143792 -17.352518)
					(mid 112.750092 -17.743686)
					(end 112.356392 -17.352518)
				)
				(arc
					(start 112.356392 -17.349978)
					(mid 112.750092 -16.956278)
					(end 113.143792 -17.349978)
				)
			)
		)
	)
	(zone
		(layers "B.Cu" "In7.Cu")
		(hatch none 0.5)
		(connect_pads
			(clearance 0)
		)
		(min_thickness 0.25)
		(keepout
			(tracks not_allowed)
			(vias allowed)
			(pads allowed)
			(copperpour not_allowed)
			(footprints allowed)
		)
		(placement
			(enabled no)
			(sheetname "")
		)
		(fill yes
			(thermal_gap 0.5)
			(thermal_bridge_width 0.5)
			(island_removal_mode 0)
		)
		(polygon
			(pts
				(arc
					(start 143.89862 -18.35023)
					(mid 143.34998 -17.80159)
					(end 142.80134 -18.35023)
				)
				(arc
					(start 142.80134 -19.750024)
					(mid 143.34871 -20.298663)
					(end 143.89862 -19.752564)
				)
				(arc
					(start 143.74368 -19.752564)
					(mid 143.34998 -20.143732)
					(end 142.95628 -19.752564)
				)
				(arc
					(start 142.95628 -19.750024)
					(mid 143.34998 -19.356324)
					(end 143.74368 -19.750024)
				)
				(xy 143.89862 -19.750024) (xy 143.89862 -18.35277)
				(arc
					(start 143.74368 -18.35277)
					(mid 143.34998 -18.743938)
					(end 142.95628 -18.35277)
				)
				(arc
					(start 142.95628 -18.35023)
					(mid 143.34998 -17.95653)
					(end 143.74368 -18.35023)
				)
			)
		)
	)
	(zone
		(layers "B.Cu" "In7.Cu")
		(hatch none 0.5)
		(connect_pads
			(clearance 0)
		)
		(min_thickness 0.25)
		(keepout
			(tracks not_allowed)
			(vias allowed)
			(pads allowed)
			(copperpour not_allowed)
			(footprints allowed)
		)
		(placement
			(enabled no)
			(sheetname "")
		)
		(fill yes
			(thermal_gap 0.5)
			(thermal_bridge_width 0.5)
			(island_removal_mode 0)
		)
		(polygon
			(pts
				(arc
					(start 377.298712 -17.349978)
					(mid 376.750072 -16.801338)
					(end 376.201432 -17.349978)
				)
				(arc
					(start 376.201432 -18.750026)
					(mid 376.748802 -19.298665)
					(end 377.298712 -18.752566)
				)
				(arc
					(start 377.143772 -18.752566)
					(mid 376.750072 -19.143734)
					(end 376.356372 -18.752566)
				)
				(arc
					(start 376.356372 -18.750026)
					(mid 376.750072 -18.356326)
					(end 377.143772 -18.750026)
				)
				(xy 377.298712 -18.750026) (xy 377.298712 -17.352518)
				(arc
					(start 377.143772 -17.352518)
					(mid 376.750072 -17.743686)
					(end 376.356372 -17.352518)
				)
				(arc
					(start 376.356372 -17.349978)
					(mid 376.750072 -16.956278)
					(end 377.143772 -17.349978)
				)
			)
		)
	)
	(zone
		(layers "B.Cu" "In7.Cu")
		(hatch none 0.5)
		(connect_pads
			(clearance 0)
		)
		(min_thickness 0.25)
		(keepout
			(tracks not_allowed)
			(vias allowed)
			(pads allowed)
			(copperpour not_allowed)
			(footprints allowed)
		)
		(placement
			(enabled no)
			(sheetname "")
		)
		(fill yes
			(thermal_gap 0.5)
			(thermal_bridge_width 0.5)
			(island_removal_mode 0)
		)
		(polygon
			(pts
				(arc
					(start 361.098592 -18.35023)
					(mid 360.549952 -17.80159)
					(end 360.001312 -18.35023)
				)
				(arc
					(start 360.001312 -19.750024)
					(mid 360.548682 -20.298663)
					(end 361.098592 -19.752564)
				)
				(arc
					(start 360.943652 -19.752564)
					(mid 360.549952 -20.143732)
					(end 360.156252 -19.752564)
				)
				(arc
					(start 360.156252 -19.750024)
					(mid 360.549952 -19.356324)
					(end 360.943652 -19.750024)
				)
				(xy 361.098592 -19.750024) (xy 361.098592 -18.35277)
				(arc
					(start 360.943652 -18.35277)
					(mid 360.549952 -18.743938)
					(end 360.156252 -18.35277)
				)
				(arc
					(start 360.156252 -18.35023)
					(mid 360.549952 -17.95653)
					(end 360.943652 -18.35023)
				)
			)
		)
	)
	(zone
		(layer "In1.Cu")
		(hatch none 0.5)
		(connect_pads
			(clearance 0)
		)
		(min_thickness 0.25)
		(keepout
			(tracks not_allowed)
			(vias allowed)
			(pads allowed)
			(copperpour not_allowed)
			(footprints allowed)
		)
		(placement
			(enabled no)
			(sheetname "")
		)
		(fill
			(thermal_gap 0.5)
			(thermal_bridge_width 0.5)
			(island_removal_mode 0)
		)
		(polygon
			(pts
				(arc
					(start 63.606934 -273.508216)
					(mid 63.571013 -273.523095)
					(end 63.556134 -273.559016)
				)
				(arc
					(start 63.556134 -273.762216)
					(mid 63.571013 -273.798137)
					(end 63.606934 -273.813016)
				)
				(arc
					(start 64.419734 -273.813016)
					(mid 64.455655 -273.798137)
					(end 64.470534 -273.762216)
				)
				(arc
					(start 64.470534 -273.559016)
					(mid 64.455655 -273.523095)
					(end 64.419734 -273.508216)
				)
			)
		)
	)
	(zone
		(layer "In1.Cu")
		(hatch none 0.5)
		(connect_pads
			(clearance 0)
		)
		(min_thickness 0.25)
		(keepout
			(tracks not_allowed)
			(vias allowed)
			(pads allowed)
			(copperpour not_allowed)
			(footprints allowed)
		)
		(placement
			(enabled no)
			(sheetname "")
		)
		(fill
			(thermal_gap 0.5)
			(thermal_bridge_width 0.5)
			(island_removal_mode 0)
		)
		(polygon
			(pts
				(arc
					(start 415.878264 -43.508168)
					(mid 415.842343 -43.523047)
					(end 415.827464 -43.558968)
				)
				(arc
					(start 415.827464 -43.762168)
					(mid 415.842343 -43.798089)
					(end 415.878264 -43.812968)
				)
				(arc
					(start 416.691064 -43.812968)
					(mid 416.726985 -43.798089)
					(end 416.741864 -43.762168)
				)
				(arc
					(start 416.741864 -43.558968)
					(mid 416.726985 -43.523047)
					(end 416.691064 -43.508168)
				)
			)
		)
	)
	(zone
		(layer "In1.Cu")
		(hatch none 0.5)
		(connect_pads
			(clearance 0)
		)
		(min_thickness 0.25)
		(keepout
			(tracks not_allowed)
			(vias allowed)
			(pads allowed)
			(copperpour not_allowed)
			(footprints allowed)
		)
		(placement
			(enabled no)
			(sheetname "")
		)
		(fill
			(thermal_gap 0.5)
			(thermal_bridge_width 0.5)
			(island_removal_mode 0)
		)
		(polygon
			(pts
				(arc
					(start 32.057086 -273.508216)
					(mid 32.021165 -273.523095)
					(end 32.006286 -273.559016)
				)
				(arc
					(start 32.006286 -273.762216)
					(mid 32.021165 -273.798137)
					(end 32.057086 -273.813016)
				)
				(arc
					(start 32.869886 -273.813016)
					(mid 32.905807 -273.798137)
					(end 32.920686 -273.762216)
				)
				(arc
					(start 32.920686 -273.559016)
					(mid 32.905807 -273.523095)
					(end 32.869886 -273.508216)
				)
			)
		)
	)
	(zone
		(layer "In1.Cu")
		(hatch none 0.5)
		(connect_pads
			(clearance 0)
		)
		(min_thickness 0.25)
		(keepout
			(tracks not_allowed)
			(vias allowed)
			(pads allowed)
			(copperpour not_allowed)
			(footprints allowed)
		)
		(placement
			(enabled no)
			(sheetname "")
		)
		(fill
			(thermal_gap 0.5)
			(thermal_bridge_width 0.5)
			(island_removal_mode 0)
		)
		(polygon
			(pts
				(xy 326.193912 -46.810168) (xy 328.556112 -46.810168) (xy 328.556112 -48.689768) (xy 326.193912 -48.689768)
			)
		)
	)
	(zone
		(layer "In1.Cu")
		(hatch none 0.5)
		(connect_pads
			(clearance 0)
		)
		(min_thickness 0.25)
		(keepout
			(tracks not_allowed)
			(vias allowed)
			(pads allowed)
			(copperpour not_allowed)
			(footprints allowed)
		)
		(placement
			(enabled no)
			(sheetname "")
		)
		(fill
			(thermal_gap 0.5)
			(thermal_bridge_width 0.5)
			(island_removal_mode 0)
		)
		(polygon
			(pts
				(arc
					(start 189.807088 -44.066968)
					(mid 189.771167 -44.081847)
					(end 189.756288 -44.117768)
				)
				(arc
					(start 189.756288 -44.320968)
					(mid 189.771167 -44.356889)
					(end 189.807088 -44.371768)
				)
				(arc
					(start 190.619888 -44.371768)
					(mid 190.655809 -44.356889)
					(end 190.670688 -44.320968)
				)
				(arc
					(start 190.670688 -44.117768)
					(mid 190.655809 -44.081847)
					(end 190.619888 -44.066968)
				)
			)
		)
	)
	(zone
		(layer "In1.Cu")
		(hatch none 0.5)
		(connect_pads
			(clearance 0)
		)
		(min_thickness 0.25)
		(keepout
			(tracks not_allowed)
			(vias allowed)
			(pads allowed)
			(copperpour not_allowed)
			(footprints allowed)
		)
		(placement
			(enabled no)
			(sheetname "")
		)
		(fill
			(thermal_gap 0.5)
			(thermal_bridge_width 0.5)
			(island_removal_mode 0)
		)
		(polygon
			(pts
				(arc
					(start 63.606934 -44.066968)
					(mid 63.571013 -44.081847)
					(end 63.556134 -44.117768)
				)
				(arc
					(start 63.556134 -44.320968)
					(mid 63.571013 -44.356889)
					(end 63.606934 -44.371768)
				)
				(arc
					(start 64.419734 -44.371768)
					(mid 64.455655 -44.356889)
					(end 64.470534 -44.320968)
				)
				(arc
					(start 64.470534 -44.117768)
					(mid 64.455655 -44.081847)
					(end 64.419734 -44.066968)
				)
			)
		)
	)
	(zone
		(layer "In1.Cu")
		(hatch none 0.5)
		(connect_pads
			(clearance 0)
		)
		(min_thickness 0.25)
		(keepout
			(tracks not_allowed)
			(vias allowed)
			(pads allowed)
			(copperpour not_allowed)
			(footprints allowed)
		)
		(placement
			(enabled no)
			(sheetname "")
		)
		(fill
			(thermal_gap 0.5)
			(thermal_bridge_width 0.5)
			(island_removal_mode 0)
		)
		(polygon
			(pts
				(arc
					(start 478.978214 -44.066968)
					(mid 478.942293 -44.081847)
					(end 478.927414 -44.117768)
				)
				(arc
					(start 478.927414 -44.320968)
					(mid 478.942293 -44.356889)
					(end 478.978214 -44.371768)
				)
				(arc
					(start 479.791014 -44.371768)
					(mid 479.826935 -44.356889)
					(end 479.841814 -44.320968)
				)
				(arc
					(start 479.841814 -44.117768)
					(mid 479.826935 -44.081847)
					(end 479.791014 -44.066968)
				)
			)
		)
	)
	(zone
		(layer "In1.Cu")
		(hatch none 0.5)
		(connect_pads
			(clearance 0)
		)
		(min_thickness 0.25)
		(keepout
			(tracks not_allowed)
			(vias allowed)
			(pads allowed)
			(copperpour not_allowed)
			(footprints allowed)
		)
		(placement
			(enabled no)
			(sheetname "")
		)
		(fill
			(thermal_gap 0.5)
			(thermal_bridge_width 0.5)
			(island_removal_mode 0)
		)
		(polygon
			(pts
				(xy 123.493784 -161.810192) (xy 125.855984 -161.810192) (xy 125.855984 -163.689792) (xy 123.493784 -163.689792)
			)
		)
	)
	(zone
		(layer "In1.Cu")
		(hatch none 0.5)
		(connect_pads
			(clearance 0)
		)
		(min_thickness 0.25)
		(keepout
			(tracks not_allowed)
			(vias allowed)
			(pads allowed)
			(copperpour not_allowed)
			(footprints allowed)
		)
		(placement
			(enabled no)
			(sheetname "")
		)
		(fill
			(thermal_gap 0.5)
			(thermal_bridge_width 0.5)
			(island_removal_mode 0)
		)
		(polygon
			(pts
				(xy 91.943936 -158.000192) (xy 94.306136 -158.000192) (xy 94.306136 -159.879792) (xy 91.943936 -159.879792)
			)
		)
	)
	(zone
		(net "AGND_CURRENT_DPB")
		(layer "In1.Cu")
		(hatch none 0.5)
		(connect_pads
			(clearance 0.5)
		)
		(min_thickness 0.25)
		(fill yes
			(thermal_gap 0.5)
			(thermal_bridge_width 0.5)
			(island_removal_mode 0)
		)
		(polygon
			(pts
				(xy 234.278424 -378.6759) (xy 231.01935 -381.934974) (xy 231.01935 -384.615944) (xy 230.710994 -384.9243)
				(xy 226.672394 -384.9243) (xy 225.783394 -385.8133) (xy 223.141794 -385.8133) (xy 222.9485 -386.006594)
				(xy 222.9485 -389.861806) (xy 225.681794 -392.5951) (xy 228.228144 -392.5951) (xy 234.018328 -398.385284)
				(xy 247.602502 -398.385284) (xy 249.4407 -396.547086) (xy 249.4407 -388.820406) (xy 251.7013 -386.559806)
				(xy 251.7013 -381.739394) (xy 248.637806 -378.6759)
			)
		)
	)
	(zone
		(layer "In1.Cu")
		(hatch none 0.5)
		(connect_pads
			(clearance 0)
		)
		(min_thickness 0.25)
		(keepout
			(tracks not_allowed)
			(vias allowed)
			(pads allowed)
			(copperpour not_allowed)
			(footprints allowed)
		)
		(placement
			(enabled no)
			(sheetname "")
		)
		(fill
			(thermal_gap 0.5)
			(thermal_bridge_width 0.5)
			(island_removal_mode 0)
		)
		(polygon
			(pts
				(arc
					(start 384.328162 -43.508168)
					(mid 384.292241 -43.523047)
					(end 384.277362 -43.558968)
				)
				(arc
					(start 384.277362 -43.762168)
					(mid 384.292241 -43.798089)
					(end 384.328162 -43.812968)
				)
				(arc
					(start 385.140962 -43.812968)
					(mid 385.176883 -43.798089)
					(end 385.191762 -43.762168)
				)
				(arc
					(start 385.191762 -43.558968)
					(mid 385.176883 -43.523047)
					(end 385.140962 -43.508168)
				)
			)
		)
	)
	(zone
		(layer "In1.Cu")
		(hatch none 0.5)
		(connect_pads
			(clearance 0)
		)
		(min_thickness 0.25)
		(keepout
			(tracks not_allowed)
			(vias allowed)
			(pads allowed)
			(copperpour not_allowed)
			(footprints allowed)
		)
		(placement
			(enabled no)
			(sheetname "")
		)
		(fill
			(thermal_gap 0.5)
			(thermal_bridge_width 0.5)
			(island_removal_mode 0)
		)
		(polygon
			(pts
				(xy 483.943914 -161.810192) (xy 486.306114 -161.810192) (xy 486.306114 -163.689792) (xy 483.943914 -163.689792)
			)
		)
	)
	(zone
		(layer "In1.Cu")
		(hatch none 0.5)
		(connect_pads
			(clearance 0)
		)
		(min_thickness 0.25)
		(keepout
			(tracks not_allowed)
			(vias allowed)
			(pads allowed)
			(copperpour not_allowed)
			(footprints allowed)
		)
		(placement
			(enabled no)
			(sheetname "")
		)
		(fill
			(thermal_gap 0.5)
			(thermal_bridge_width 0.5)
			(island_removal_mode 0)
		)
		(polygon
			(pts
				(xy 123.493784 -46.810168) (xy 125.855984 -46.810168) (xy 125.855984 -48.689768) (xy 123.493784 -48.689768)
			)
		)
	)
	(zone
		(layer "In1.Cu")
		(hatch none 0.5)
		(connect_pads
			(clearance 0)
		)
		(min_thickness 0.25)
		(keepout
			(tracks not_allowed)
			(vias allowed)
			(pads allowed)
			(copperpour not_allowed)
			(footprints allowed)
		)
		(placement
			(enabled no)
			(sheetname "")
		)
		(fill
			(thermal_gap 0.5)
			(thermal_bridge_width 0.5)
			(island_removal_mode 0)
		)
		(polygon
			(pts
				(arc
					(start 32.057086 -44.066968)
					(mid 32.021165 -44.081847)
					(end 32.006286 -44.117768)
				)
				(arc
					(start 32.006286 -44.320968)
					(mid 32.021165 -44.356889)
					(end 32.057086 -44.371768)
				)
				(arc
					(start 32.869886 -44.371768)
					(mid 32.905807 -44.356889)
					(end 32.920686 -44.320968)
				)
				(arc
					(start 32.920686 -44.117768)
					(mid 32.905807 -44.081847)
					(end 32.869886 -44.066968)
				)
			)
		)
	)
	(zone
		(layer "In1.Cu")
		(hatch none 0.5)
		(connect_pads
			(clearance 0)
		)
		(min_thickness 0.25)
		(keepout
			(tracks not_allowed)
			(vias allowed)
			(pads allowed)
			(copperpour not_allowed)
			(footprints allowed)
		)
		(placement
			(enabled no)
			(sheetname "")
		)
		(fill
			(thermal_gap 0.5)
			(thermal_bridge_width 0.5)
			(island_removal_mode 0)
		)
		(polygon
			(pts
				(xy 389.293862 -273.000216) (xy 391.656062 -273.000216) (xy 391.656062 -274.879816) (xy 389.293862 -274.879816)
			)
		)
	)
	(zone
		(layer "In1.Cu")
		(hatch none 0.5)
		(connect_pads
			(clearance 0)
		)
		(min_thickness 0.25)
		(keepout
			(tracks not_allowed)
			(vias allowed)
			(pads allowed)
			(copperpour not_allowed)
			(footprints allowed)
		)
		(placement
			(enabled no)
			(sheetname "")
		)
		(fill
			(thermal_gap 0.5)
			(thermal_bridge_width 0.5)
			(island_removal_mode 0)
		)
		(polygon
			(pts
				(xy 28.843986 -276.810216) (xy 31.206186 -276.810216) (xy 31.206186 -278.689816) (xy 28.843986 -278.689816)
			)
		)
	)
	(zone
		(layer "In1.Cu")
		(hatch none 0.5)
		(connect_pads
			(clearance 0)
		)
		(min_thickness 0.25)
		(keepout
			(tracks not_allowed)
			(vias allowed)
			(pads allowed)
			(copperpour not_allowed)
			(footprints allowed)
		)
		(placement
			(enabled no)
			(sheetname "")
		)
		(fill
			(thermal_gap 0.5)
			(thermal_bridge_width 0.5)
			(island_removal_mode 0)
		)
		(polygon
			(pts
				(arc
					(start 415.878264 -274.067016)
					(mid 415.842343 -274.081895)
					(end 415.827464 -274.117816)
				)
				(arc
					(start 415.827464 -274.321016)
					(mid 415.842343 -274.356937)
					(end 415.878264 -274.371816)
				)
				(arc
					(start 416.691064 -274.371816)
					(mid 416.726985 -274.356937)
					(end 416.741864 -274.321016)
				)
				(arc
					(start 416.741864 -274.117816)
					(mid 416.726985 -274.081895)
					(end 416.691064 -274.067016)
				)
			)
		)
	)
	(zone
		(layer "In1.Cu")
		(hatch none 0.5)
		(connect_pads
			(clearance 0)
		)
		(min_thickness 0.25)
		(keepout
			(tracks not_allowed)
			(vias allowed)
			(pads allowed)
			(copperpour not_allowed)
			(footprints allowed)
		)
		(placement
			(enabled no)
			(sheetname "")
		)
		(fill
			(thermal_gap 0.5)
			(thermal_bridge_width 0.5)
			(island_removal_mode 0)
		)
		(polygon
			(pts
				(xy 357.744014 -43.000168) (xy 360.106214 -43.000168) (xy 360.106214 -44.879768) (xy 357.744014 -44.879768)
			)
		)
	)
	(zone
		(layer "In1.Cu")
		(hatch none 0.5)
		(connect_pads
			(clearance 0)
		)
		(min_thickness 0.25)
		(keepout
			(tracks not_allowed)
			(vias allowed)
			(pads allowed)
			(copperpour not_allowed)
			(footprints allowed)
		)
		(placement
			(enabled no)
			(sheetname "")
		)
		(fill
			(thermal_gap 0.5)
			(thermal_bridge_width 0.5)
			(island_removal_mode 0)
		)
		(polygon
			(pts
				(arc
					(start 352.778314 -158.508192)
					(mid 352.742393 -158.523071)
					(end 352.727514 -158.558992)
				)
				(arc
					(start 352.727514 -158.762192)
					(mid 352.742393 -158.798113)
					(end 352.778314 -158.812992)
				)
				(arc
					(start 353.591114 -158.812992)
					(mid 353.627035 -158.798113)
					(end 353.641914 -158.762192)
				)
				(arc
					(start 353.641914 -158.558992)
					(mid 353.627035 -158.523071)
					(end 353.591114 -158.508192)
				)
			)
		)
	)
	(zone
		(layer "In1.Cu")
		(hatch none 0.5)
		(connect_pads
			(clearance 0)
		)
		(min_thickness 0.25)
		(keepout
			(tracks not_allowed)
			(vias allowed)
			(pads allowed)
			(copperpour not_allowed)
			(footprints allowed)
		)
		(placement
			(enabled no)
			(sheetname "")
		)
		(fill
			(thermal_gap 0.5)
			(thermal_bridge_width 0.5)
			(island_removal_mode 0)
		)
		(polygon
			(pts
				(arc
					(start 352.778314 -274.067016)
					(mid 352.742393 -274.081895)
					(end 352.727514 -274.117816)
				)
				(arc
					(start 352.727514 -274.321016)
					(mid 352.742393 -274.356937)
					(end 352.778314 -274.371816)
				)
				(arc
					(start 353.591114 -274.371816)
					(mid 353.627035 -274.356937)
					(end 353.641914 -274.321016)
				)
				(arc
					(start 353.641914 -274.117816)
					(mid 353.627035 -274.081895)
					(end 353.591114 -274.067016)
				)
			)
		)
	)
	(zone
		(layer "In1.Cu")
		(hatch none 0.5)
		(connect_pads
			(clearance 0)
		)
		(min_thickness 0.25)
		(keepout
			(tracks not_allowed)
			(vias allowed)
			(pads allowed)
			(copperpour not_allowed)
			(footprints allowed)
		)
		(placement
			(enabled no)
			(sheetname "")
		)
		(fill
			(thermal_gap 0.5)
			(thermal_bridge_width 0.5)
			(island_removal_mode 0)
		)
		(polygon
			(pts
				(arc
					(start 384.328162 -158.508192)
					(mid 384.292241 -158.523071)
					(end 384.277362 -158.558992)
				)
				(arc
					(start 384.277362 -158.762192)
					(mid 384.292241 -158.798113)
					(end 384.328162 -158.812992)
				)
				(arc
					(start 385.140962 -158.812992)
					(mid 385.176883 -158.798113)
					(end 385.191762 -158.762192)
				)
				(arc
					(start 385.191762 -158.558992)
					(mid 385.176883 -158.523071)
					(end 385.140962 -158.508192)
				)
			)
		)
	)
	(zone
		(layer "In1.Cu")
		(hatch none 0.5)
		(connect_pads
			(clearance 0)
		)
		(min_thickness 0.25)
		(keepout
			(tracks not_allowed)
			(vias allowed)
			(pads allowed)
			(copperpour not_allowed)
			(footprints allowed)
		)
		(placement
			(enabled no)
			(sheetname "")
		)
		(fill
			(thermal_gap 0.5)
			(thermal_bridge_width 0.5)
			(island_removal_mode 0)
		)
		(polygon
			(pts
				(xy 60.393834 -276.810216) (xy 62.756034 -276.810216) (xy 62.756034 -278.689816) (xy 60.393834 -278.689816)
			)
		)
	)
	(zone
		(layer "In1.Cu")
		(hatch none 0.5)
		(connect_pads
			(clearance 0)
		)
		(min_thickness 0.25)
		(keepout
			(tracks not_allowed)
			(vias allowed)
			(pads allowed)
			(copperpour not_allowed)
			(footprints allowed)
		)
		(placement
			(enabled no)
			(sheetname "")
		)
		(fill
			(thermal_gap 0.5)
			(thermal_bridge_width 0.5)
			(island_removal_mode 0)
		)
		(polygon
			(pts
				(arc
					(start 63.606934 -274.067016)
					(mid 63.571013 -274.081895)
					(end 63.556134 -274.117816)
				)
				(arc
					(start 63.556134 -274.321016)
					(mid 63.571013 -274.356937)
					(end 63.606934 -274.371816)
				)
				(arc
					(start 64.419734 -274.371816)
					(mid 64.455655 -274.356937)
					(end 64.470534 -274.321016)
				)
				(arc
					(start 64.470534 -274.117816)
					(mid 64.455655 -274.081895)
					(end 64.419734 -274.067016)
				)
			)
		)
	)
	(zone
		(layer "In1.Cu")
		(hatch none 0.5)
		(connect_pads
			(clearance 0)
		)
		(min_thickness 0.25)
		(keepout
			(tracks not_allowed)
			(vias allowed)
			(pads allowed)
			(copperpour not_allowed)
			(footprints allowed)
		)
		(placement
			(enabled no)
			(sheetname "")
		)
		(fill
			(thermal_gap 0.5)
			(thermal_bridge_width 0.5)
			(island_removal_mode 0)
		)
		(polygon
			(pts
				(arc
					(start 447.428112 -44.066968)
					(mid 447.392191 -44.081847)
					(end 447.377312 -44.117768)
				)
				(arc
					(start 447.377312 -44.320968)
					(mid 447.392191 -44.356889)
					(end 447.428112 -44.371768)
				)
				(arc
					(start 448.240912 -44.371768)
					(mid 448.276833 -44.356889)
					(end 448.291712 -44.320968)
				)
				(arc
					(start 448.291712 -44.117768)
					(mid 448.276833 -44.081847)
					(end 448.240912 -44.066968)
				)
			)
		)
	)
	(zone
		(layer "In1.Cu")
		(hatch none 0.5)
		(connect_pads
			(clearance 0)
		)
		(min_thickness 0.25)
		(keepout
			(tracks not_allowed)
			(vias allowed)
			(pads allowed)
			(copperpour not_allowed)
			(footprints allowed)
		)
		(placement
			(enabled no)
			(sheetname "")
		)
		(fill
			(thermal_gap 0.5)
			(thermal_bridge_width 0.5)
			(island_removal_mode 0)
		)
		(polygon
			(pts
				(arc
					(start 478.978214 -43.508168)
					(mid 478.942293 -43.523047)
					(end 478.927414 -43.558968)
				)
				(arc
					(start 478.927414 -43.762168)
					(mid 478.942293 -43.798089)
					(end 478.978214 -43.812968)
				)
				(arc
					(start 479.791014 -43.812968)
					(mid 479.826935 -43.798089)
					(end 479.841814 -43.762168)
				)
				(arc
					(start 479.841814 -43.558968)
					(mid 479.826935 -43.523047)
					(end 479.791014 -43.508168)
				)
			)
		)
	)
	(zone
		(layer "In1.Cu")
		(hatch none 0.5)
		(connect_pads
			(clearance 0)
		)
		(min_thickness 0.25)
		(keepout
			(tracks not_allowed)
			(vias allowed)
			(pads allowed)
			(copperpour not_allowed)
			(footprints allowed)
		)
		(placement
			(enabled no)
			(sheetname "")
		)
		(fill
			(thermal_gap 0.5)
			(thermal_bridge_width 0.5)
			(island_removal_mode 0)
		)
		(polygon
			(pts
				(xy 357.744014 -46.810168) (xy 360.106214 -46.810168) (xy 360.106214 -48.689768) (xy 357.744014 -48.689768)
			)
		)
	)
	(zone
		(layer "In1.Cu")
		(hatch none 0.5)
		(connect_pads
			(clearance 0)
		)
		(min_thickness 0.25)
		(keepout
			(tracks not_allowed)
			(vias allowed)
			(pads allowed)
			(copperpour not_allowed)
			(footprints allowed)
		)
		(placement
			(enabled no)
			(sheetname "")
		)
		(fill
			(thermal_gap 0.5)
			(thermal_bridge_width 0.5)
			(island_removal_mode 0)
		)
		(polygon
			(pts
				(arc
					(start 189.807088 -273.508216)
					(mid 189.771167 -273.523095)
					(end 189.756288 -273.559016)
				)
				(arc
					(start 189.756288 -273.762216)
					(mid 189.771167 -273.798137)
					(end 189.807088 -273.813016)
				)
				(arc
					(start 190.619888 -273.813016)
					(mid 190.655809 -273.798137)
					(end 190.670688 -273.762216)
				)
				(arc
					(start 190.670688 -273.559016)
					(mid 190.655809 -273.523095)
					(end 190.619888 -273.508216)
				)
			)
		)
	)
	(zone
		(layer "In1.Cu")
		(hatch none 0.5)
		(connect_pads
			(clearance 0)
		)
		(min_thickness 0.25)
		(keepout
			(tracks not_allowed)
			(vias allowed)
			(pads allowed)
			(copperpour not_allowed)
			(footprints allowed)
		)
		(placement
			(enabled no)
			(sheetname "")
		)
		(fill
			(thermal_gap 0.5)
			(thermal_bridge_width 0.5)
			(island_removal_mode 0)
		)
		(polygon
			(pts
				(xy 91.943936 -161.810192) (xy 94.306136 -161.810192) (xy 94.306136 -163.689792) (xy 91.943936 -163.689792)
			)
		)
	)
	(zone
		(layer "In1.Cu")
		(hatch none 0.5)
		(connect_pads
			(clearance 0)
		)
		(min_thickness 0.25)
		(keepout
			(tracks not_allowed)
			(vias allowed)
			(pads allowed)
			(copperpour not_allowed)
			(footprints allowed)
		)
		(placement
			(enabled no)
			(sheetname "")
		)
		(fill
			(thermal_gap 0.5)
			(thermal_bridge_width 0.5)
			(island_removal_mode 0)
		)
		(polygon
			(pts
				(arc
					(start 415.878264 -158.508192)
					(mid 415.842343 -158.523071)
					(end 415.827464 -158.558992)
				)
				(arc
					(start 415.827464 -158.762192)
					(mid 415.842343 -158.798113)
					(end 415.878264 -158.812992)
				)
				(arc
					(start 416.691064 -158.812992)
					(mid 416.726985 -158.798113)
					(end 416.741864 -158.762192)
				)
				(arc
					(start 416.741864 -158.558992)
					(mid 416.726985 -158.523071)
					(end 416.691064 -158.508192)
				)
			)
		)
	)
	(zone
		(layer "In1.Cu")
		(hatch none 0.5)
		(connect_pads
			(clearance 0)
		)
		(min_thickness 0.25)
		(keepout
			(tracks not_allowed)
			(vias allowed)
			(pads allowed)
			(copperpour not_allowed)
			(footprints allowed)
		)
		(placement
			(enabled no)
			(sheetname "")
		)
		(fill
			(thermal_gap 0.5)
			(thermal_bridge_width 0.5)
			(island_removal_mode 0)
		)
		(polygon
			(pts
				(arc
					(start 63.606934 -158.508192)
					(mid 63.571013 -158.523071)
					(end 63.556134 -158.558992)
				)
				(arc
					(start 63.556134 -158.762192)
					(mid 63.571013 -158.798113)
					(end 63.606934 -158.812992)
				)
				(arc
					(start 64.419734 -158.812992)
					(mid 64.455655 -158.798113)
					(end 64.470534 -158.762192)
				)
				(arc
					(start 64.470534 -158.558992)
					(mid 64.455655 -158.523071)
					(end 64.419734 -158.508192)
				)
			)
		)
	)
	(zone
		(layer "In1.Cu")
		(hatch none 0.5)
		(connect_pads
			(clearance 0)
		)
		(min_thickness 0.25)
		(keepout
			(tracks not_allowed)
			(vias allowed)
			(pads allowed)
			(copperpour not_allowed)
			(footprints allowed)
		)
		(placement
			(enabled no)
			(sheetname "")
		)
		(fill
			(thermal_gap 0.5)
			(thermal_bridge_width 0.5)
			(island_removal_mode 0)
		)
		(polygon
			(pts
				(xy 60.393834 -46.810168) (xy 62.756034 -46.810168) (xy 62.756034 -48.689768) (xy 60.393834 -48.689768)
			)
		)
	)
	(zone
		(layer "In1.Cu")
		(hatch none 0.5)
		(connect_pads
			(clearance 0)
		)
		(min_thickness 0.25)
		(keepout
			(tracks not_allowed)
			(vias allowed)
			(pads allowed)
			(copperpour not_allowed)
			(footprints allowed)
		)
		(placement
			(enabled no)
			(sheetname "")
		)
		(fill
			(thermal_gap 0.5)
			(thermal_bridge_width 0.5)
			(island_removal_mode 0)
		)
		(polygon
			(pts
				(xy 91.943936 -43.000168) (xy 94.306136 -43.000168) (xy 94.306136 -44.879768) (xy 91.943936 -44.879768)
			)
		)
	)
	(zone
		(layer "In1.Cu")
		(hatch none 0.5)
		(connect_pads
			(clearance 0)
		)
		(min_thickness 0.25)
		(keepout
			(tracks not_allowed)
			(vias allowed)
			(pads allowed)
			(copperpour not_allowed)
			(footprints allowed)
		)
		(placement
			(enabled no)
			(sheetname "")
		)
		(fill
			(thermal_gap 0.5)
			(thermal_bridge_width 0.5)
			(island_removal_mode 0)
		)
		(polygon
			(pts
				(arc
					(start 321.228212 -44.066968)
					(mid 321.192291 -44.081847)
					(end 321.177412 -44.117768)
				)
				(arc
					(start 321.177412 -44.320968)
					(mid 321.192291 -44.356889)
					(end 321.228212 -44.371768)
				)
				(arc
					(start 322.041012 -44.371768)
					(mid 322.076933 -44.356889)
					(end 322.091812 -44.320968)
				)
				(arc
					(start 322.091812 -44.117768)
					(mid 322.076933 -44.081847)
					(end 322.041012 -44.066968)
				)
			)
		)
	)
	(zone
		(layer "In1.Cu")
		(hatch none 0.5)
		(connect_pads
			(clearance 0)
		)
		(min_thickness 0.25)
		(keepout
			(tracks not_allowed)
			(vias allowed)
			(pads allowed)
			(copperpour not_allowed)
			(footprints allowed)
		)
		(placement
			(enabled no)
			(sheetname "")
		)
		(fill
			(thermal_gap 0.5)
			(thermal_bridge_width 0.5)
			(island_removal_mode 0)
		)
		(polygon
			(pts
				(xy 326.193912 -276.810216) (xy 328.556112 -276.810216) (xy 328.556112 -278.689816) (xy 326.193912 -278.689816)
			)
		)
	)
	(zone
		(layer "In1.Cu")
		(hatch none 0.5)
		(connect_pads
			(clearance 0)
		)
		(min_thickness 0.25)
		(keepout
			(tracks not_allowed)
			(vias allowed)
			(pads allowed)
			(copperpour not_allowed)
			(footprints allowed)
		)
		(placement
			(enabled no)
			(sheetname "")
		)
		(fill
			(thermal_gap 0.5)
			(thermal_bridge_width 0.5)
			(island_removal_mode 0)
		)
		(polygon
			(pts
				(xy 186.593988 -43.000168) (xy 188.956188 -43.000168) (xy 188.956188 -44.879768) (xy 186.593988 -44.879768)
			)
		)
	)
	(zone
		(layer "In1.Cu")
		(hatch none 0.5)
		(connect_pads
			(clearance 0)
		)
		(min_thickness 0.25)
		(keepout
			(tracks not_allowed)
			(vias allowed)
			(pads allowed)
			(copperpour not_allowed)
			(footprints allowed)
		)
		(placement
			(enabled no)
			(sheetname "")
		)
		(fill
			(thermal_gap 0.5)
			(thermal_bridge_width 0.5)
			(island_removal_mode 0)
		)
		(polygon
			(pts
				(xy 326.193912 -161.810192) (xy 328.556112 -161.810192) (xy 328.556112 -163.689792) (xy 326.193912 -163.689792)
			)
		)
	)
	(zone
		(layer "In1.Cu")
		(hatch none 0.5)
		(connect_pads
			(clearance 0)
		)
		(min_thickness 0.25)
		(keepout
			(tracks not_allowed)
			(vias allowed)
			(pads allowed)
			(copperpour not_allowed)
			(footprints allowed)
		)
		(placement
			(enabled no)
			(sheetname "")
		)
		(fill
			(thermal_gap 0.5)
			(thermal_bridge_width 0.5)
			(island_removal_mode 0)
		)
		(polygon
			(pts
				(xy 357.744014 -276.810216) (xy 360.106214 -276.810216) (xy 360.106214 -278.689816) (xy 357.744014 -278.689816)
			)
		)
	)
	(zone
		(layer "In1.Cu")
		(hatch none 0.5)
		(connect_pads
			(clearance 0)
		)
		(min_thickness 0.25)
		(keepout
			(tracks not_allowed)
			(vias allowed)
			(pads allowed)
			(copperpour not_allowed)
			(footprints allowed)
		)
		(placement
			(enabled no)
			(sheetname "")
		)
		(fill
			(thermal_gap 0.5)
			(thermal_bridge_width 0.5)
			(island_removal_mode 0)
		)
		(polygon
			(pts
				(arc
					(start 126.706884 -43.508168)
					(mid 126.670963 -43.523047)
					(end 126.656084 -43.558968)
				)
				(arc
					(start 126.656084 -43.762168)
					(mid 126.670963 -43.798089)
					(end 126.706884 -43.812968)
				)
				(arc
					(start 127.519684 -43.812968)
					(mid 127.555605 -43.798089)
					(end 127.570484 -43.762168)
				)
				(arc
					(start 127.570484 -43.558968)
					(mid 127.555605 -43.523047)
					(end 127.519684 -43.508168)
				)
			)
		)
	)
	(zone
		(layer "In1.Cu")
		(hatch none 0.5)
		(connect_pads
			(clearance 0)
		)
		(min_thickness 0.25)
		(keepout
			(tracks not_allowed)
			(vias allowed)
			(pads allowed)
			(copperpour not_allowed)
			(footprints allowed)
		)
		(placement
			(enabled no)
			(sheetname "")
		)
		(fill
			(thermal_gap 0.5)
			(thermal_bridge_width 0.5)
			(island_removal_mode 0)
		)
		(polygon
			(pts
				(xy 326.193912 -158.000192) (xy 328.556112 -158.000192) (xy 328.556112 -159.879792) (xy 326.193912 -159.879792)
			)
		)
	)
	(zone
		(layer "In1.Cu")
		(hatch none 0.5)
		(connect_pads
			(clearance 0)
		)
		(min_thickness 0.25)
		(keepout
			(tracks not_allowed)
			(vias allowed)
			(pads allowed)
			(copperpour not_allowed)
			(footprints allowed)
		)
		(placement
			(enabled no)
			(sheetname "")
		)
		(fill
			(thermal_gap 0.5)
			(thermal_bridge_width 0.5)
			(island_removal_mode 0)
		)
		(polygon
			(pts
				(arc
					(start 95.157036 -43.508168)
					(mid 95.121115 -43.523047)
					(end 95.106236 -43.558968)
				)
				(arc
					(start 95.106236 -43.762168)
					(mid 95.121115 -43.798089)
					(end 95.157036 -43.812968)
				)
				(arc
					(start 95.969836 -43.812968)
					(mid 96.005757 -43.798089)
					(end 96.020636 -43.762168)
				)
				(arc
					(start 96.020636 -43.558968)
					(mid 96.005757 -43.523047)
					(end 95.969836 -43.508168)
				)
			)
		)
	)
	(zone
		(layer "In1.Cu")
		(hatch none 0.5)
		(connect_pads
			(clearance 0)
		)
		(min_thickness 0.25)
		(keepout
			(tracks not_allowed)
			(vias allowed)
			(pads allowed)
			(copperpour not_allowed)
			(footprints allowed)
		)
		(placement
			(enabled no)
			(sheetname "")
		)
		(fill
			(thermal_gap 0.5)
			(thermal_bridge_width 0.5)
			(island_removal_mode 0)
		)
		(polygon
			(pts
				(arc
					(start 95.157036 -158.508192)
					(mid 95.121115 -158.523071)
					(end 95.106236 -158.558992)
				)
				(arc
					(start 95.106236 -158.762192)
					(mid 95.121115 -158.798113)
					(end 95.157036 -158.812992)
				)
				(arc
					(start 95.969836 -158.812992)
					(mid 96.005757 -158.798113)
					(end 96.020636 -158.762192)
				)
				(arc
					(start 96.020636 -158.558992)
					(mid 96.005757 -158.523071)
					(end 95.969836 -158.508192)
				)
			)
		)
	)
	(zone
		(layer "In1.Cu")
		(hatch none 0.5)
		(connect_pads
			(clearance 0)
		)
		(min_thickness 0.25)
		(keepout
			(tracks not_allowed)
			(vias allowed)
			(pads allowed)
			(copperpour not_allowed)
			(footprints allowed)
		)
		(placement
			(enabled no)
			(sheetname "")
		)
		(fill
			(thermal_gap 0.5)
			(thermal_bridge_width 0.5)
			(island_removal_mode 0)
		)
		(polygon
			(pts
				(xy 483.943914 -158.000192) (xy 486.306114 -158.000192) (xy 486.306114 -159.879792) (xy 483.943914 -159.879792)
			)
		)
	)
	(zone
		(layer "In1.Cu")
		(hatch none 0.5)
		(connect_pads
			(clearance 0)
		)
		(min_thickness 0.25)
		(keepout
			(tracks not_allowed)
			(vias allowed)
			(pads allowed)
			(copperpour not_allowed)
			(footprints allowed)
		)
		(placement
			(enabled no)
			(sheetname "")
		)
		(fill
			(thermal_gap 0.5)
			(thermal_bridge_width 0.5)
			(island_removal_mode 0)
		)
		(polygon
			(pts
				(arc
					(start 32.057086 -158.508192)
					(mid 32.021165 -158.523071)
					(end 32.006286 -158.558992)
				)
				(arc
					(start 32.006286 -158.762192)
					(mid 32.021165 -158.798113)
					(end 32.057086 -158.812992)
				)
				(arc
					(start 32.869886 -158.812992)
					(mid 32.905807 -158.798113)
					(end 32.920686 -158.762192)
				)
				(arc
					(start 32.920686 -158.558992)
					(mid 32.905807 -158.523071)
					(end 32.869886 -158.508192)
				)
			)
		)
	)
	(zone
		(layer "In1.Cu")
		(hatch none 0.5)
		(connect_pads
			(clearance 0)
		)
		(min_thickness 0.25)
		(keepout
			(tracks not_allowed)
			(vias allowed)
			(pads allowed)
			(copperpour not_allowed)
			(footprints allowed)
		)
		(placement
			(enabled no)
			(sheetname "")
		)
		(fill
			(thermal_gap 0.5)
			(thermal_bridge_width 0.5)
			(island_removal_mode 0)
		)
		(polygon
			(pts
				(arc
					(start 352.778314 -44.066968)
					(mid 352.742393 -44.081847)
					(end 352.727514 -44.117768)
				)
				(arc
					(start 352.727514 -44.320968)
					(mid 352.742393 -44.356889)
					(end 352.778314 -44.371768)
				)
				(arc
					(start 353.591114 -44.371768)
					(mid 353.627035 -44.356889)
					(end 353.641914 -44.320968)
				)
				(arc
					(start 353.641914 -44.117768)
					(mid 353.627035 -44.081847)
					(end 353.591114 -44.066968)
				)
			)
		)
	)
	(zone
		(layer "In1.Cu")
		(hatch none 0.5)
		(connect_pads
			(clearance 0)
		)
		(min_thickness 0.25)
		(keepout
			(tracks not_allowed)
			(vias allowed)
			(pads allowed)
			(copperpour not_allowed)
			(footprints allowed)
		)
		(placement
			(enabled no)
			(sheetname "")
		)
		(fill
			(thermal_gap 0.5)
			(thermal_bridge_width 0.5)
			(island_removal_mode 0)
		)
		(polygon
			(pts
				(xy 155.043886 -161.810192) (xy 157.406086 -161.810192) (xy 157.406086 -163.689792) (xy 155.043886 -163.689792)
			)
		)
	)
	(zone
		(layer "In1.Cu")
		(hatch none 0.5)
		(connect_pads
			(clearance 0)
		)
		(min_thickness 0.25)
		(keepout
			(tracks not_allowed)
			(vias allowed)
			(pads allowed)
			(copperpour not_allowed)
			(footprints allowed)
		)
		(placement
			(enabled no)
			(sheetname "")
		)
		(fill
			(thermal_gap 0.5)
			(thermal_bridge_width 0.5)
			(island_removal_mode 0)
		)
		(polygon
			(pts
				(xy 389.293862 -46.810168) (xy 391.656062 -46.810168) (xy 391.656062 -48.689768) (xy 389.293862 -48.689768)
			)
		)
	)
	(zone
		(layer "In1.Cu")
		(hatch none 0.5)
		(connect_pads
			(clearance 0)
		)
		(min_thickness 0.25)
		(keepout
			(tracks not_allowed)
			(vias allowed)
			(pads allowed)
			(copperpour not_allowed)
			(footprints allowed)
		)
		(placement
			(enabled no)
			(sheetname "")
		)
		(fill
			(thermal_gap 0.5)
			(thermal_bridge_width 0.5)
			(island_removal_mode 0)
		)
		(polygon
			(pts
				(arc
					(start 321.228212 -273.508216)
					(mid 321.192291 -273.523095)
					(end 321.177412 -273.559016)
				)
				(arc
					(start 321.177412 -273.762216)
					(mid 321.192291 -273.798137)
					(end 321.228212 -273.813016)
				)
				(arc
					(start 322.041012 -273.813016)
					(mid 322.076933 -273.798137)
					(end 322.091812 -273.762216)
				)
				(arc
					(start 322.091812 -273.559016)
					(mid 322.076933 -273.523095)
					(end 322.041012 -273.508216)
				)
			)
		)
	)
	(zone
		(layer "In1.Cu")
		(hatch none 0.5)
		(connect_pads
			(clearance 0)
		)
		(min_thickness 0.25)
		(keepout
			(tracks not_allowed)
			(vias allowed)
			(pads allowed)
			(copperpour not_allowed)
			(footprints allowed)
		)
		(placement
			(enabled no)
			(sheetname "")
		)
		(fill
			(thermal_gap 0.5)
			(thermal_bridge_width 0.5)
			(island_removal_mode 0)
		)
		(polygon
			(pts
				(xy 155.043886 -158.000192) (xy 157.406086 -158.000192) (xy 157.406086 -159.879792) (xy 155.043886 -159.879792)
			)
		)
	)
	(zone
		(layer "In1.Cu")
		(hatch none 0.5)
		(connect_pads
			(clearance 0)
		)
		(min_thickness 0.25)
		(keepout
			(tracks not_allowed)
			(vias allowed)
			(pads allowed)
			(copperpour not_allowed)
			(footprints allowed)
		)
		(placement
			(enabled no)
			(sheetname "")
		)
		(fill
			(thermal_gap 0.5)
			(thermal_bridge_width 0.5)
			(island_removal_mode 0)
		)
		(polygon
			(pts
				(arc
					(start 158.256986 -44.066968)
					(mid 158.221065 -44.081847)
					(end 158.206186 -44.117768)
				)
				(arc
					(start 158.206186 -44.320968)
					(mid 158.221065 -44.356889)
					(end 158.256986 -44.371768)
				)
				(arc
					(start 159.069786 -44.371768)
					(mid 159.105707 -44.356889)
					(end 159.120586 -44.320968)
				)
				(arc
					(start 159.120586 -44.117768)
					(mid 159.105707 -44.081847)
					(end 159.069786 -44.066968)
				)
			)
		)
	)
	(zone
		(layer "In1.Cu")
		(hatch none 0.5)
		(connect_pads
			(clearance 0)
		)
		(min_thickness 0.25)
		(keepout
			(tracks not_allowed)
			(vias allowed)
			(pads allowed)
			(copperpour not_allowed)
			(footprints allowed)
		)
		(placement
			(enabled no)
			(sheetname "")
		)
		(fill
			(thermal_gap 0.5)
			(thermal_bridge_width 0.5)
			(island_removal_mode 0)
		)
		(polygon
			(pts
				(arc
					(start 415.878264 -44.066968)
					(mid 415.842343 -44.081847)
					(end 415.827464 -44.117768)
				)
				(arc
					(start 415.827464 -44.320968)
					(mid 415.842343 -44.356889)
					(end 415.878264 -44.371768)
				)
				(arc
					(start 416.691064 -44.371768)
					(mid 416.726985 -44.356889)
					(end 416.741864 -44.320968)
				)
				(arc
					(start 416.741864 -44.117768)
					(mid 416.726985 -44.081847)
					(end 416.691064 -44.066968)
				)
			)
		)
	)
	(zone
		(layer "In1.Cu")
		(hatch none 0.5)
		(connect_pads
			(clearance 0)
		)
		(min_thickness 0.25)
		(keepout
			(tracks not_allowed)
			(vias allowed)
			(pads allowed)
			(copperpour not_allowed)
			(footprints allowed)
		)
		(placement
			(enabled no)
			(sheetname "")
		)
		(fill
			(thermal_gap 0.5)
			(thermal_bridge_width 0.5)
			(island_removal_mode 0)
		)
		(polygon
			(pts
				(arc
					(start 189.807088 -43.508168)
					(mid 189.771167 -43.523047)
					(end 189.756288 -43.558968)
				)
				(arc
					(start 189.756288 -43.762168)
					(mid 189.771167 -43.798089)
					(end 189.807088 -43.812968)
				)
				(arc
					(start 190.619888 -43.812968)
					(mid 190.655809 -43.798089)
					(end 190.670688 -43.762168)
				)
				(arc
					(start 190.670688 -43.558968)
					(mid 190.655809 -43.523047)
					(end 190.619888 -43.508168)
				)
			)
		)
	)
	(zone
		(layer "In1.Cu")
		(hatch none 0.5)
		(connect_pads
			(clearance 0)
		)
		(min_thickness 0.25)
		(keepout
			(tracks not_allowed)
			(vias allowed)
			(pads allowed)
			(copperpour not_allowed)
			(footprints allowed)
		)
		(placement
			(enabled no)
			(sheetname "")
		)
		(fill
			(thermal_gap 0.5)
			(thermal_bridge_width 0.5)
			(island_removal_mode 0)
		)
		(polygon
			(pts
				(xy 452.393812 -46.810168) (xy 454.756012 -46.810168) (xy 454.756012 -48.689768) (xy 452.393812 -48.689768)
			)
		)
	)
	(zone
		(layer "In1.Cu")
		(hatch none 0.5)
		(connect_pads
			(clearance 0)
		)
		(min_thickness 0.25)
		(keepout
			(tracks not_allowed)
			(vias allowed)
			(pads allowed)
			(copperpour not_allowed)
			(footprints allowed)
		)
		(placement
			(enabled no)
			(sheetname "")
		)
		(fill
			(thermal_gap 0.5)
			(thermal_bridge_width 0.5)
			(island_removal_mode 0)
		)
		(polygon
			(pts
				(arc
					(start 415.878264 -273.508216)
					(mid 415.842343 -273.523095)
					(end 415.827464 -273.559016)
				)
				(arc
					(start 415.827464 -273.762216)
					(mid 415.842343 -273.798137)
					(end 415.878264 -273.813016)
				)
				(arc
					(start 416.691064 -273.813016)
					(mid 416.726985 -273.798137)
					(end 416.741864 -273.762216)
				)
				(arc
					(start 416.741864 -273.559016)
					(mid 416.726985 -273.523095)
					(end 416.691064 -273.508216)
				)
			)
		)
	)
	(zone
		(layer "In1.Cu")
		(hatch none 0.5)
		(connect_pads
			(clearance 0)
		)
		(min_thickness 0.25)
		(keepout
			(tracks not_allowed)
			(vias allowed)
			(pads allowed)
			(copperpour not_allowed)
			(footprints allowed)
		)
		(placement
			(enabled no)
			(sheetname "")
		)
		(fill
			(thermal_gap 0.5)
			(thermal_bridge_width 0.5)
			(island_removal_mode 0)
		)
		(polygon
			(pts
				(arc
					(start 441.078112 -158.508192)
					(mid 441.042191 -158.523071)
					(end 441.027312 -158.558992)
				)
				(arc
					(start 441.027312 -158.762192)
					(mid 441.042191 -158.798113)
					(end 441.078112 -158.812992)
				)
				(arc
					(start 441.890912 -158.812992)
					(mid 441.926833 -158.798113)
					(end 441.941712 -158.762192)
				)
				(arc
					(start 441.941712 -158.558992)
					(mid 441.926833 -158.523071)
					(end 441.890912 -158.508192)
				)
			)
		)
	)
	(zone
		(layer "In1.Cu")
		(hatch none 0.5)
		(connect_pads
			(clearance 0)
		)
		(min_thickness 0.25)
		(keepout
			(tracks not_allowed)
			(vias allowed)
			(pads allowed)
			(copperpour not_allowed)
			(footprints allowed)
		)
		(placement
			(enabled no)
			(sheetname "")
		)
		(fill
			(thermal_gap 0.5)
			(thermal_bridge_width 0.5)
			(island_removal_mode 0)
		)
		(polygon
			(pts
				(arc
					(start 415.878264 -159.066992)
					(mid 415.842343 -159.081871)
					(end 415.827464 -159.117792)
				)
				(arc
					(start 415.827464 -159.320992)
					(mid 415.842343 -159.356913)
					(end 415.878264 -159.371792)
				)
				(arc
					(start 416.691064 -159.371792)
					(mid 416.726985 -159.356913)
					(end 416.741864 -159.320992)
				)
				(arc
					(start 416.741864 -159.117792)
					(mid 416.726985 -159.081871)
					(end 416.691064 -159.066992)
				)
			)
		)
	)
	(zone
		(layer "In1.Cu")
		(hatch none 0.5)
		(connect_pads
			(clearance 0)
		)
		(min_thickness 0.25)
		(keepout
			(tracks not_allowed)
			(vias allowed)
			(pads allowed)
			(copperpour not_allowed)
			(footprints allowed)
		)
		(placement
			(enabled no)
			(sheetname "")
		)
		(fill
			(thermal_gap 0.5)
			(thermal_bridge_width 0.5)
			(island_removal_mode 0)
		)
		(polygon
			(pts
				(arc
					(start 384.328162 -273.508216)
					(mid 384.292241 -273.523095)
					(end 384.277362 -273.559016)
				)
				(arc
					(start 384.277362 -273.762216)
					(mid 384.292241 -273.798137)
					(end 384.328162 -273.813016)
				)
				(arc
					(start 385.140962 -273.813016)
					(mid 385.176883 -273.798137)
					(end 385.191762 -273.762216)
				)
				(arc
					(start 385.191762 -273.559016)
					(mid 385.176883 -273.523095)
					(end 385.140962 -273.508216)
				)
			)
		)
	)
	(zone
		(layer "In1.Cu")
		(hatch none 0.5)
		(connect_pads
			(clearance 0)
		)
		(min_thickness 0.25)
		(keepout
			(tracks not_allowed)
			(vias allowed)
			(pads allowed)
			(copperpour not_allowed)
			(footprints allowed)
		)
		(placement
			(enabled no)
			(sheetname "")
		)
		(fill
			(thermal_gap 0.5)
			(thermal_bridge_width 0.5)
			(island_removal_mode 0)
		)
		(polygon
			(pts
				(arc
					(start 352.778314 -159.066992)
					(mid 352.742393 -159.081871)
					(end 352.727514 -159.117792)
				)
				(arc
					(start 352.727514 -159.320992)
					(mid 352.742393 -159.356913)
					(end 352.778314 -159.371792)
				)
				(arc
					(start 353.591114 -159.371792)
					(mid 353.627035 -159.356913)
					(end 353.641914 -159.320992)
				)
				(arc
					(start 353.641914 -159.117792)
					(mid 353.627035 -159.081871)
					(end 353.591114 -159.066992)
				)
			)
		)
	)
	(zone
		(layer "In1.Cu")
		(hatch none 0.5)
		(connect_pads
			(clearance 0)
		)
		(min_thickness 0.25)
		(keepout
			(tracks not_allowed)
			(vias allowed)
			(pads allowed)
			(copperpour not_allowed)
			(footprints allowed)
		)
		(placement
			(enabled no)
			(sheetname "")
		)
		(fill
			(thermal_gap 0.5)
			(thermal_bridge_width 0.5)
			(island_removal_mode 0)
		)
		(polygon
			(pts
				(arc
					(start 95.157036 -44.066968)
					(mid 95.121115 -44.081847)
					(end 95.106236 -44.117768)
				)
				(arc
					(start 95.106236 -44.320968)
					(mid 95.121115 -44.356889)
					(end 95.157036 -44.371768)
				)
				(arc
					(start 95.969836 -44.371768)
					(mid 96.005757 -44.356889)
					(end 96.020636 -44.320968)
				)
				(arc
					(start 96.020636 -44.117768)
					(mid 96.005757 -44.081847)
					(end 95.969836 -44.066968)
				)
			)
		)
	)
	(zone
		(layer "In1.Cu")
		(hatch none 0.5)
		(connect_pads
			(clearance 0)
		)
		(min_thickness 0.25)
		(keepout
			(tracks not_allowed)
			(vias allowed)
			(pads allowed)
			(copperpour not_allowed)
			(footprints allowed)
		)
		(placement
			(enabled no)
			(sheetname "")
		)
		(fill
			(thermal_gap 0.5)
			(thermal_bridge_width 0.5)
			(island_removal_mode 0)
		)
		(polygon
			(pts
				(xy 123.493784 -43.000168) (xy 125.855984 -43.000168) (xy 125.855984 -44.879768) (xy 123.493784 -44.879768)
			)
		)
	)
	(zone
		(layer "In1.Cu")
		(hatch none 0.5)
		(connect_pads
			(clearance 0)
		)
		(min_thickness 0.25)
		(keepout
			(tracks not_allowed)
			(vias allowed)
			(pads allowed)
			(copperpour not_allowed)
			(footprints allowed)
		)
		(placement
			(enabled no)
			(sheetname "")
		)
		(fill
			(thermal_gap 0.5)
			(thermal_bridge_width 0.5)
			(island_removal_mode 0)
		)
		(polygon
			(pts
				(xy 285.57601 -107.847892) (xy 283.576014 -106.847894)
				(arc
					(start 283.574744 -106.85018)
					(mid 282.600146 -107.175046)
					(end 282.925012 -108.149644)
				)
				(xy 282.923742 -108.15193) (xy 284.923738 -109.151928) (xy 284.923992 -109.151674)
				(arc
					(start 284.925008 -109.149642)
					(mid 285.899606 -108.824776)
					(end 285.57474 -107.850178)
				)
			)
		)
	)
	(zone
		(layer "In1.Cu")
		(hatch none 0.5)
		(connect_pads
			(clearance 0)
		)
		(min_thickness 0.25)
		(keepout
			(tracks not_allowed)
			(vias allowed)
			(pads allowed)
			(copperpour not_allowed)
			(footprints allowed)
		)
		(placement
			(enabled no)
			(sheetname "")
		)
		(fill
			(thermal_gap 0.5)
			(thermal_bridge_width 0.5)
			(island_removal_mode 0)
		)
		(polygon
			(pts
				(xy 389.293862 -276.810216) (xy 391.656062 -276.810216) (xy 391.656062 -278.689816) (xy 389.293862 -278.689816)
			)
		)
	)
	(zone
		(layer "In1.Cu")
		(hatch none 0.5)
		(connect_pads
			(clearance 0)
		)
		(min_thickness 0.25)
		(keepout
			(tracks not_allowed)
			(vias allowed)
			(pads allowed)
			(copperpour not_allowed)
			(footprints allowed)
		)
		(placement
			(enabled no)
			(sheetname "")
		)
		(fill
			(thermal_gap 0.5)
			(thermal_bridge_width 0.5)
			(island_removal_mode 0)
		)
		(polygon
			(pts
				(xy 420.843964 -276.810216) (xy 423.206164 -276.810216) (xy 423.206164 -278.689816) (xy 420.843964 -278.689816)
			)
		)
	)
	(zone
		(layer "In1.Cu")
		(hatch none 0.5)
		(connect_pads
			(clearance 0)
		)
		(min_thickness 0.25)
		(keepout
			(tracks not_allowed)
			(vias allowed)
			(pads allowed)
			(copperpour not_allowed)
			(footprints allowed)
		)
		(placement
			(enabled no)
			(sheetname "")
		)
		(fill
			(thermal_gap 0.5)
			(thermal_bridge_width 0.5)
			(island_removal_mode 0)
		)
		(polygon
			(pts
				(xy 155.043886 -46.810168) (xy 157.406086 -46.810168) (xy 157.406086 -48.689768) (xy 155.043886 -48.689768)
			)
		)
	)
	(zone
		(layer "In1.Cu")
		(hatch none 0.5)
		(connect_pads
			(clearance 0)
		)
		(min_thickness 0.25)
		(keepout
			(tracks not_allowed)
			(vias allowed)
			(pads allowed)
			(copperpour not_allowed)
			(footprints allowed)
		)
		(placement
			(enabled no)
			(sheetname "")
		)
		(fill
			(thermal_gap 0.5)
			(thermal_bridge_width 0.5)
			(island_removal_mode 0)
		)
		(polygon
			(pts
				(xy 28.843986 -273.000216) (xy 31.206186 -273.000216) (xy 31.206186 -274.879816) (xy 28.843986 -274.879816)
			)
		)
	)
	(zone
		(layer "In1.Cu")
		(hatch none 0.5)
		(connect_pads
			(clearance 0)
		)
		(min_thickness 0.25)
		(keepout
			(tracks not_allowed)
			(vias allowed)
			(pads allowed)
			(copperpour not_allowed)
			(footprints allowed)
		)
		(placement
			(enabled no)
			(sheetname "")
		)
		(fill
			(thermal_gap 0.5)
			(thermal_bridge_width 0.5)
			(island_removal_mode 0)
		)
		(polygon
			(pts
				(arc
					(start 158.256986 -273.508216)
					(mid 158.221065 -273.523095)
					(end 158.206186 -273.559016)
				)
				(arc
					(start 158.206186 -273.762216)
					(mid 158.221065 -273.798137)
					(end 158.256986 -273.813016)
				)
				(arc
					(start 159.069786 -273.813016)
					(mid 159.105707 -273.798137)
					(end 159.120586 -273.762216)
				)
				(arc
					(start 159.120586 -273.559016)
					(mid 159.105707 -273.523095)
					(end 159.069786 -273.508216)
				)
			)
		)
	)
	(zone
		(layer "In1.Cu")
		(hatch none 0.5)
		(connect_pads
			(clearance 0)
		)
		(min_thickness 0.25)
		(keepout
			(tracks not_allowed)
			(vias allowed)
			(pads allowed)
			(copperpour not_allowed)
			(footprints allowed)
		)
		(placement
			(enabled no)
			(sheetname "")
		)
		(fill
			(thermal_gap 0.5)
			(thermal_bridge_width 0.5)
			(island_removal_mode 0)
		)
		(polygon
			(pts
				(xy 357.744014 -161.810192) (xy 360.106214 -161.810192) (xy 360.106214 -163.689792) (xy 357.744014 -163.689792)
			)
		)
	)
	(zone
		(layer "In1.Cu")
		(hatch none 0.5)
		(connect_pads
			(clearance 0)
		)
		(min_thickness 0.25)
		(keepout
			(tracks not_allowed)
			(vias allowed)
			(pads allowed)
			(copperpour not_allowed)
			(footprints allowed)
		)
		(placement
			(enabled no)
			(sheetname "")
		)
		(fill
			(thermal_gap 0.5)
			(thermal_bridge_width 0.5)
			(island_removal_mode 0)
		)
		(polygon
			(pts
				(xy 420.843964 -43.000168) (xy 423.206164 -43.000168) (xy 423.206164 -44.879768) (xy 420.843964 -44.879768)
			)
		)
	)
	(zone
		(layer "In1.Cu")
		(hatch none 0.5)
		(connect_pads
			(clearance 0)
		)
		(min_thickness 0.25)
		(keepout
			(tracks not_allowed)
			(vias allowed)
			(pads allowed)
			(copperpour not_allowed)
			(footprints allowed)
		)
		(placement
			(enabled no)
			(sheetname "")
		)
		(fill
			(thermal_gap 0.5)
			(thermal_bridge_width 0.5)
			(island_removal_mode 0)
		)
		(polygon
			(pts
				(xy 186.593988 -158.000192) (xy 188.956188 -158.000192) (xy 188.956188 -159.879792) (xy 186.593988 -159.879792)
			)
		)
	)
	(zone
		(layer "In1.Cu")
		(hatch none 0.5)
		(connect_pads
			(clearance 0)
		)
		(min_thickness 0.25)
		(keepout
			(tracks not_allowed)
			(vias allowed)
			(pads allowed)
			(copperpour not_allowed)
			(footprints allowed)
		)
		(placement
			(enabled no)
			(sheetname "")
		)
		(fill
			(thermal_gap 0.5)
			(thermal_bridge_width 0.5)
			(island_removal_mode 0)
		)
		(polygon
			(pts
				(arc
					(start 240.874804 -106.85018)
					(mid 239.900206 -107.175046)
					(end 240.225072 -108.149644)
				)
				(xy 240.223802 -108.15193) (xy 242.223798 -109.151928)
				(arc
					(start 242.225068 -109.149642)
					(mid 243.199666 -108.824776)
					(end 242.8748 -107.850178)
				)
				(xy 242.87607 -107.847892) (xy 240.876074 -106.847894) (xy 240.87582 -106.848148)
			)
		)
	)
	(zone
		(layer "In1.Cu")
		(hatch none 0.5)
		(connect_pads
			(clearance 0)
		)
		(min_thickness 0.25)
		(keepout
			(tracks not_allowed)
			(vias allowed)
			(pads allowed)
			(copperpour not_allowed)
			(footprints allowed)
		)
		(placement
			(enabled no)
			(sheetname "")
		)
		(fill
			(thermal_gap 0.5)
			(thermal_bridge_width 0.5)
			(island_removal_mode 0)
		)
		(polygon
			(pts
				(xy 483.943914 -43.000168) (xy 486.306114 -43.000168) (xy 486.306114 -44.879768) (xy 483.943914 -44.879768)
			)
		)
	)
	(zone
		(layer "In1.Cu")
		(hatch none 0.5)
		(connect_pads
			(clearance 0)
		)
		(min_thickness 0.25)
		(keepout
			(tracks not_allowed)
			(vias allowed)
			(pads allowed)
			(copperpour not_allowed)
			(footprints allowed)
		)
		(placement
			(enabled no)
			(sheetname "")
		)
		(fill
			(thermal_gap 0.5)
			(thermal_bridge_width 0.5)
			(island_removal_mode 0)
		)
		(polygon
			(pts
				(arc
					(start 447.428112 -274.067016)
					(mid 447.392191 -274.081895)
					(end 447.377312 -274.117816)
				)
				(arc
					(start 447.377312 -274.321016)
					(mid 447.392191 -274.356937)
					(end 447.428112 -274.371816)
				)
				(arc
					(start 448.240912 -274.371816)
					(mid 448.276833 -274.356937)
					(end 448.291712 -274.321016)
				)
				(arc
					(start 448.291712 -274.117816)
					(mid 448.276833 -274.081895)
					(end 448.240912 -274.067016)
				)
			)
		)
	)
	(zone
		(layer "In1.Cu")
		(hatch none 0.5)
		(connect_pads
			(clearance 0)
		)
		(min_thickness 0.25)
		(keepout
			(tracks not_allowed)
			(vias allowed)
			(pads allowed)
			(copperpour not_allowed)
			(footprints allowed)
		)
		(placement
			(enabled no)
			(sheetname "")
		)
		(fill
			(thermal_gap 0.5)
			(thermal_bridge_width 0.5)
			(island_removal_mode 0)
		)
		(polygon
			(pts
				(arc
					(start 63.606934 -159.066992)
					(mid 63.571013 -159.081871)
					(end 63.556134 -159.117792)
				)
				(arc
					(start 63.556134 -159.320992)
					(mid 63.571013 -159.356913)
					(end 63.606934 -159.371792)
				)
				(arc
					(start 64.419734 -159.371792)
					(mid 64.455655 -159.356913)
					(end 64.470534 -159.320992)
				)
				(arc
					(start 64.470534 -159.117792)
					(mid 64.455655 -159.081871)
					(end 64.419734 -159.066992)
				)
			)
		)
	)
	(zone
		(layer "In1.Cu")
		(hatch none 0.5)
		(connect_pads
			(clearance 0)
		)
		(min_thickness 0.25)
		(keepout
			(tracks not_allowed)
			(vias allowed)
			(pads allowed)
			(copperpour not_allowed)
			(footprints allowed)
		)
		(placement
			(enabled no)
			(sheetname "")
		)
		(fill
			(thermal_gap 0.5)
			(thermal_bridge_width 0.5)
			(island_removal_mode 0)
		)
		(polygon
			(pts
				(xy 357.744014 -273.000216) (xy 360.106214 -273.000216) (xy 360.106214 -274.879816) (xy 357.744014 -274.879816)
			)
		)
	)
	(zone
		(layer "In1.Cu")
		(hatch none 0.5)
		(connect_pads
			(clearance 0)
		)
		(min_thickness 0.25)
		(keepout
			(tracks not_allowed)
			(vias allowed)
			(pads allowed)
			(copperpour not_allowed)
			(footprints allowed)
		)
		(placement
			(enabled no)
			(sheetname "")
		)
		(fill
			(thermal_gap 0.5)
			(thermal_bridge_width 0.5)
			(island_removal_mode 0)
		)
		(polygon
			(pts
				(arc
					(start 447.428112 -43.508168)
					(mid 447.392191 -43.523047)
					(end 447.377312 -43.558968)
				)
				(arc
					(start 447.377312 -43.762168)
					(mid 447.392191 -43.798089)
					(end 447.428112 -43.812968)
				)
				(arc
					(start 448.240912 -43.812968)
					(mid 448.276833 -43.798089)
					(end 448.291712 -43.762168)
				)
				(arc
					(start 448.291712 -43.558968)
					(mid 448.276833 -43.523047)
					(end 448.240912 -43.508168)
				)
			)
		)
	)
	(zone
		(layer "In1.Cu")
		(hatch none 0.5)
		(connect_pads
			(clearance 0)
		)
		(min_thickness 0.25)
		(keepout
			(tracks not_allowed)
			(vias allowed)
			(pads allowed)
			(copperpour not_allowed)
			(footprints allowed)
		)
		(placement
			(enabled no)
			(sheetname "")
		)
		(fill
			(thermal_gap 0.5)
			(thermal_bridge_width 0.5)
			(island_removal_mode 0)
		)
		(polygon
			(pts
				(arc
					(start 158.256986 -274.067016)
					(mid 158.221065 -274.081895)
					(end 158.206186 -274.117816)
				)
				(arc
					(start 158.206186 -274.321016)
					(mid 158.221065 -274.356937)
					(end 158.256986 -274.371816)
				)
				(arc
					(start 159.069786 -274.371816)
					(mid 159.105707 -274.356937)
					(end 159.120586 -274.321016)
				)
				(arc
					(start 159.120586 -274.117816)
					(mid 159.105707 -274.081895)
					(end 159.069786 -274.067016)
				)
			)
		)
	)
	(zone
		(layer "In1.Cu")
		(hatch none 0.5)
		(connect_pads
			(clearance 0)
		)
		(min_thickness 0.25)
		(keepout
			(tracks not_allowed)
			(vias allowed)
			(pads allowed)
			(copperpour not_allowed)
			(footprints allowed)
		)
		(placement
			(enabled no)
			(sheetname "")
		)
		(fill
			(thermal_gap 0.5)
			(thermal_bridge_width 0.5)
			(island_removal_mode 0)
		)
		(polygon
			(pts
				(arc
					(start 447.428112 -273.508216)
					(mid 447.392191 -273.523095)
					(end 447.377312 -273.559016)
				)
				(arc
					(start 447.377312 -273.762216)
					(mid 447.392191 -273.798137)
					(end 447.428112 -273.813016)
				)
				(arc
					(start 448.240912 -273.813016)
					(mid 448.276833 -273.798137)
					(end 448.291712 -273.762216)
				)
				(arc
					(start 448.291712 -273.559016)
					(mid 448.276833 -273.523095)
					(end 448.240912 -273.508216)
				)
			)
		)
	)
	(zone
		(layer "In1.Cu")
		(hatch none 0.5)
		(connect_pads
			(clearance 0)
		)
		(min_thickness 0.25)
		(keepout
			(tracks not_allowed)
			(vias allowed)
			(pads allowed)
			(copperpour not_allowed)
			(footprints allowed)
		)
		(placement
			(enabled no)
			(sheetname "")
		)
		(fill
			(thermal_gap 0.5)
			(thermal_bridge_width 0.5)
			(island_removal_mode 0)
		)
		(polygon
			(pts
				(arc
					(start 95.157036 -273.508216)
					(mid 95.121115 -273.523095)
					(end 95.106236 -273.559016)
				)
				(arc
					(start 95.106236 -273.762216)
					(mid 95.121115 -273.798137)
					(end 95.157036 -273.813016)
				)
				(arc
					(start 95.969836 -273.813016)
					(mid 96.005757 -273.798137)
					(end 96.020636 -273.762216)
				)
				(arc
					(start 96.020636 -273.559016)
					(mid 96.005757 -273.523095)
					(end 95.969836 -273.508216)
				)
			)
		)
	)
	(zone
		(net "GND")
		(layer "In1.Cu")
		(hatch none 0.5)
		(connect_pads
			(clearance 0.5)
		)
		(min_thickness 0.25)
		(fill yes
			(thermal_gap 0.5)
			(thermal_bridge_width 0.5)
			(island_removal_mode 0)
		)
		(polygon
			(pts
				(arc
					(start 221.000066 38.037008)
					(mid 220.832494 37.967598)
					(end 220.763084 37.800026)
				)
				(arc
					(start 220.763084 2.999994)
					(mid 220.246709 1.753355)
					(end 219.00007 1.23698)
				)
				(arc
					(start 201.000106 1.23698)
					(mid 200.832534 1.16757)
					(end 200.763124 0.999998)
				)
				(arc
					(start 200.763124 0.999998)
					(mid 200.246749 -0.246641)
					(end 199.00011 -0.763016)
				)
				(arc
					(start 150.999952 -0.763016)
					(mid 150.83238 -0.832426)
					(end 150.76297 -0.999998)
				)
				(arc
					(start 150.76297 -13.999972)
					(mid 150.246595 -15.246611)
					(end 148.999956 -15.762986)
				)
				(arc
					(start 103.000048 -15.762986)
					(mid 101.753409 -15.246611)
					(end 101.237034 -13.999972)
				)
				(arc
					(start 101.237034 -0.999998)
					(mid 101.167624 -0.832426)
					(end 101.000052 -0.763016)
				)
				(arc
					(start 0.999998 -0.763016)
					(mid 0.832426 -0.832426)
					(end 0.763016 -0.999998)
				)
				(arc
					(start 0.763016 -348.199964)
					(mid 0.832426 -348.367536)
					(end 0.999998 -348.436946)
				)
				(arc
					(start 189.6999 -348.436946)
					(mid 190.946539 -348.953321)
					(end 191.462914 -350.19996)
				)
				(arc
					(start 191.462914 -372.000018)
					(mid 191.532324 -372.16759)
					(end 191.699896 -372.237)
				)
				(arc
					(start 199.00011 -372.237)
					(mid 200.246749 -372.753375)
					(end 200.763124 -374.000014)
				)
				(arc
					(start 200.763124 -420.200074)
					(mid 200.832534 -420.367646)
					(end 201.000106 -420.437056)
				)
				(arc
					(start 308.99989 -420.437056)
					(mid 309.167462 -420.367646)
					(end 309.236872 -420.200074)
				)
				(arc
					(start 309.236872 -375.000012)
					(mid 309.167462 -374.83244)
					(end 308.99989 -374.76303)
				)
				(arc
					(start 296.69994 -374.76303)
					(mid 295.453301 -374.246655)
					(end 294.936926 -373.000016)
				)
				(arc
					(start 294.936926 -350.19996)
					(mid 295.453301 -348.953321)
					(end 296.69994 -348.436946)
				)
				(arc
					(start 490.450124 -348.436946)
					(mid 490.617696 -348.367536)
					(end 490.687106 -348.199964)
				)
				(arc
					(start 490.687106 -0.999998)
					(mid 490.617696 -0.832426)
					(end 490.450124 -0.763016)
				)
				(arc
					(start 396.999968 -0.763016)
					(mid 396.832396 -0.832426)
					(end 396.762986 -0.999998)
				)
				(arc
					(start 396.762986 -13.999972)
					(mid 396.246611 -15.246611)
					(end 394.999972 -15.762986)
				)
				(arc
					(start 349.000064 -15.762986)
					(mid 347.753425 -15.246611)
					(end 347.23705 -13.999972)
				)
				(arc
					(start 347.23705 -0.999998)
					(mid 347.16764 -0.832426)
					(end 347.000068 -0.763016)
				)
				(arc
					(start 300.999906 -0.763016)
					(mid 299.753267 -0.246641)
					(end 299.236892 0.999998)
				)
				(arc
					(start 299.236892 37.800026)
					(mid 299.167482 37.967598)
					(end 298.99991 38.037008)
				)
			)
		)
		(polygon
			(pts
				(arc
					(start 223.148652 -416.799776)
					(mid 222.599885 -416.25139)
					(end 222.051372 -416.80003)
				)
				(arc
					(start 222.051372 -418.200078)
					(mid 222.600012 -418.748718)
					(end 223.148652 -418.200078)
				)
			)
		)
		(polygon
			(pts
				(arc
					(start 219.54871 -416.799776)
					(mid 218.999943 -416.25139)
					(end 218.45143 -416.80003)
				)
				(arc
					(start 218.45143 -418.200078)
					(mid 219.00007 -418.748718)
					(end 219.54871 -418.200078)
				)
			)
		)
		(polygon
			(pts
				(arc
					(start 215.948768 -416.799776)
					(mid 215.400001 -416.25139)
					(end 214.851488 -416.80003)
				)
				(arc
					(start 214.851488 -418.200078)
					(mid 215.400128 -418.748718)
					(end 215.948768 -418.200078)
				)
			)
		)
		(polygon
			(pts
				(arc
					(start 212.348826 -416.799776)
					(mid 211.800059 -416.25139)
					(end 211.251546 -416.80003)
				)
				(arc
					(start 211.251546 -418.200078)
					(mid 211.800186 -418.748718)
					(end 212.348826 -418.200078)
				)
			)
		)
		(polygon
			(pts
				(arc
					(start 221.348808 -414.199832)
					(mid 220.800041 -413.651446)
					(end 220.251528 -414.200086)
				)
				(arc
					(start 220.251528 -415.600134)
					(mid 220.800168 -416.148774)
					(end 221.348808 -415.600134)
				)
			)
		)
		(polygon
			(pts
				(arc
					(start 217.748612 -414.199832)
					(mid 217.199845 -413.651446)
					(end 216.651332 -414.200086)
				)
				(arc
					(start 216.651332 -415.600134)
					(mid 217.199972 -416.148774)
					(end 217.748612 -415.600134)
				)
			)
		)
		(polygon
			(pts
				(arc
					(start 214.14867 -414.199832)
					(mid 213.599903 -413.651446)
					(end 213.05139 -414.200086)
				)
				(arc
					(start 213.05139 -415.600134)
					(mid 213.60003 -416.148774)
					(end 214.14867 -415.600134)
				)
			)
		)
		(polygon
			(pts
				(arc
					(start 210.548728 -414.199832)
					(mid 209.999961 -413.651446)
					(end 209.451448 -414.200086)
				)
				(arc
					(start 209.451448 -415.600134)
					(mid 210.000088 -416.148774)
					(end 210.548728 -415.600134)
				)
			)
		)
		(polygon
			(pts
				(arc
					(start 210.548728 -410.59989)
					(mid 209.999961 -410.051504)
					(end 209.451448 -410.600144)
				)
				(arc
					(start 209.451448 -412.000192)
					(mid 210.000088 -412.548832)
					(end 210.548728 -412.000192)
				)
			)
		)
		(polygon
			(pts
				(arc
					(start 221.348808 -406.999948)
					(mid 220.800041 -406.451562)
					(end 220.251528 -407.000202)
				)
				(arc
					(start 220.251528 -408.399996)
					(mid 220.800168 -408.948636)
					(end 221.348808 -408.399996)
				)
			)
		)
		(polygon
			(pts
				(arc
					(start 217.748612 -406.999948)
					(mid 217.199845 -406.451562)
					(end 216.651332 -407.000202)
				)
				(arc
					(start 216.651332 -408.399996)
					(mid 217.199972 -408.948636)
					(end 217.748612 -408.399996)
				)
			)
		)
		(polygon
			(pts
				(arc
					(start 214.14867 -406.999948)
					(mid 213.599903 -406.451562)
					(end 213.05139 -407.000202)
				)
				(arc
					(start 213.05139 -408.399996)
					(mid 213.60003 -408.948636)
					(end 214.14867 -408.399996)
				)
			)
		)
		(polygon
			(pts
				(arc
					(start 210.548728 -406.999948)
					(mid 209.999961 -406.451562)
					(end 209.451448 -407.000202)
				)
				(arc
					(start 209.451448 -408.399996)
					(mid 210.000088 -408.948636)
					(end 210.548728 -408.399996)
				)
			)
		)
		(polygon
			(pts
				(arc
					(start 223.148652 -405.999696)
					(mid 222.599885 -405.45131)
					(end 222.051372 -405.99995)
				)
				(arc
					(start 222.051372 -407.399998)
					(mid 222.600012 -407.948638)
					(end 223.148652 -407.399998)
				)
			)
		)
		(polygon
			(pts
				(arc
					(start 219.54871 -405.999696)
					(mid 218.999943 -405.45131)
					(end 218.45143 -405.99995)
				)
				(arc
					(start 218.45143 -407.399998)
					(mid 219.00007 -407.948638)
					(end 219.54871 -407.399998)
				)
			)
		)
		(polygon
			(pts
				(arc
					(start 215.948768 -405.999696)
					(mid 215.400001 -405.45131)
					(end 214.851488 -405.99995)
				)
				(arc
					(start 214.851488 -407.399998)
					(mid 215.400128 -407.948638)
					(end 215.948768 -407.399998)
				)
			)
		)
		(polygon
			(pts
				(arc
					(start 212.348826 -405.999696)
					(mid 211.800059 -405.45131)
					(end 211.251546 -405.99995)
				)
				(arc
					(start 211.251546 -407.399998)
					(mid 211.800186 -407.948638)
					(end 212.348826 -407.399998)
				)
			)
		)
		(polygon
			(pts
				(xy 248.795794 -378.2949) (xy 234.120436 -378.2949) (xy 230.63835 -381.776986) (xy 230.63835 -384.457956)
				(xy 230.553006 -384.5433) (xy 226.514406 -384.5433) (xy 225.625406 -385.4323) (xy 222.983806 -385.4323)
				(xy 222.5675 -385.848606) (xy 222.5675 -390.019794) (xy 225.523806 -392.9761) (xy 228.070156 -392.9761)
				(xy 233.86034 -398.766284) (xy 247.76049 -398.766284) (xy 249.8217 -396.705074) (xy 249.8217 -388.978394)
				(xy 252.0823 -386.717794) (xy 252.0823 -381.581406)
			)
		)
		(polygon
			(pts
				(arc
					(start 273.1135 -359.885996)
					(mid 273.4945 -359.504996)
					(end 273.1135 -359.123996)
				)
				(arc
					(start 271.970246 -359.123996)
					(mid 271.5895 -359.505123)
					(end 271.9705 -359.885996)
				)
			)
		)
		(polygon
			(pts
				(arc
					(start 273.1135 -358.085898)
					(mid 273.4945 -357.704898)
					(end 273.1135 -357.323898)
				)
				(arc
					(start 271.970246 -357.323898)
					(mid 271.5895 -357.705025)
					(end 271.9705 -358.085898)
				)
			)
		)
		(polygon
			(pts
				(arc
					(start 280.636726 -358.253792)
					(mid 281.185366 -357.705152)
					(end 280.636726 -357.156512)
				)
				(arc
					(start 279.236678 -357.156512)
					(mid 278.688038 -357.705152)
					(end 279.236678 -358.253792)
				)
			)
		)
		(polygon
			(pts
				(arc
					(start 287.83661 -358.256332)
					(mid 288.38779 -357.705152)
					(end 287.83661 -357.153972)
				)
				(arc
					(start 286.436562 -357.153972)
					(mid 285.885382 -357.705152)
					(end 286.436562 -358.256332)
				)
			)
		)
		(polygon
			(pts
				(arc
					(start 273.1135 -356.286054)
					(mid 273.4945 -355.905054)
					(end 273.1135 -355.524054)
				)
				(arc
					(start 271.970246 -355.524054)
					(mid 271.5895 -355.905181)
					(end 271.9705 -356.286054)
				)
			)
		)
		(polygon
			(pts
				(arc
					(start 279.636728 -356.453694)
					(mid 280.185368 -355.905054)
					(end 279.636728 -355.356414)
				)
				(arc
					(start 278.23668 -355.356414)
					(mid 277.68804 -355.905054)
					(end 278.23668 -356.453694)
				)
			)
		)
		(polygon
			(pts
				(arc
					(start 286.836612 -356.456234)
					(mid 287.387792 -355.905054)
					(end 286.836612 -355.353874)
				)
				(arc
					(start 285.436564 -355.353874)
					(mid 284.885384 -355.905054)
					(end 285.436564 -356.456234)
				)
			)
		)
		(polygon
			(pts
				(arc
					(start 273.1135 -354.485956)
					(mid 273.4945 -354.104956)
					(end 273.1135 -353.723956)
				)
				(arc
					(start 271.970246 -353.723956)
					(mid 271.5895 -354.105083)
					(end 271.9705 -354.485956)
				)
			)
		)
		(polygon
			(pts
				(arc
					(start 280.636726 -354.65385)
					(mid 281.185366 -354.10521)
					(end 280.636726 -353.55657)
				)
				(arc
					(start 279.236678 -353.55657)
					(mid 278.688038 -354.10521)
					(end 279.236678 -354.65385)
				)
			)
		)
		(polygon
			(pts
				(arc
					(start 287.83661 -354.65639)
					(mid 288.38779 -354.10521)
					(end 287.83661 -353.55403)
				)
				(arc
					(start 286.436562 -353.55403)
					(mid 285.885382 -354.10521)
					(end 286.436562 -354.65639)
				)
			)
		)
		(polygon
			(pts
				(arc
					(start 273.1135 -352.686112)
					(mid 273.4945 -352.305112)
					(end 273.1135 -351.924112)
				)
				(arc
					(start 271.970246 -351.924112)
					(mid 271.5895 -352.305239)
					(end 271.9705 -352.686112)
				)
			)
		)
		(polygon
			(pts
				(arc
					(start 279.636728 -352.853752)
					(mid 280.185368 -352.305112)
					(end 279.636728 -351.756472)
				)
				(arc
					(start 278.23668 -351.756472)
					(mid 277.68804 -352.305112)
					(end 278.23668 -352.853752)
				)
			)
		)
		(polygon
			(pts
				(arc
					(start 286.836612 -352.856292)
					(mid 287.387792 -352.305112)
					(end 286.836612 -351.753932)
				)
				(arc
					(start 285.436564 -351.753932)
					(mid 284.885384 -352.305112)
					(end 285.436564 -352.856292)
				)
			)
		)
		(polygon
			(pts
				(arc
					(start 273.1135 -350.886014)
					(mid 273.4945 -350.505014)
					(end 273.1135 -350.124014)
				)
				(arc
					(start 271.970246 -350.124014)
					(mid 271.5895 -350.505141)
					(end 271.9705 -350.886014)
				)
			)
		)
		(polygon
			(pts
				(arc
					(start 280.636726 -351.053908)
					(mid 281.185366 -350.505268)
					(end 280.636726 -349.956628)
				)
				(arc
					(start 279.236678 -349.956628)
					(mid 278.688038 -350.505268)
					(end 279.236678 -351.053908)
				)
			)
		)
		(polygon
			(pts
				(arc
					(start 287.83661 -351.056448)
					(mid 288.38779 -350.505268)
					(end 287.83661 -349.954088)
				)
				(arc
					(start 286.436562 -349.954088)
					(mid 285.885382 -350.505268)
					(end 286.436562 -351.056448)
				)
			)
		)
		(polygon
			(pts
				(arc
					(start 279.636728 -349.25381)
					(mid 280.185368 -348.70517)
					(end 279.636728 -348.15653)
				)
				(arc
					(start 278.23668 -348.15653)
					(mid 277.68804 -348.70517)
					(end 278.23668 -349.25381)
				)
			)
		)
		(polygon
			(pts
				(arc
					(start 286.836612 -349.25635)
					(mid 287.387792 -348.70517)
					(end 286.836612 -348.15399)
				)
				(arc
					(start 285.436564 -348.15399)
					(mid 284.885384 -348.70517)
					(end 285.436564 -349.25635)
				)
			)
		)
		(polygon
			(pts
				(arc
					(start 287.83661 -347.453712)
					(mid 288.38525 -346.905072)
					(end 287.83661 -346.356432)
				)
				(arc
					(start 286.436562 -346.356432)
					(mid 285.887922 -346.905072)
					(end 286.436562 -347.453712)
				)
			)
		)
		(polygon
			(pts
				(arc
					(start 280.636726 -347.453712)
					(mid 281.185366 -346.905072)
					(end 280.636726 -346.356432)
				)
				(arc
					(start 279.236678 -346.356432)
					(mid 278.688038 -346.905072)
					(end 279.236678 -347.453712)
				)
			)
		)
		(polygon
			(pts
				(arc
					(start 286.836612 -345.653868)
					(mid 287.385252 -345.105228)
					(end 286.836612 -344.556588)
				)
				(arc
					(start 285.436564 -344.556588)
					(mid 284.887924 -345.105228)
					(end 285.436564 -345.653868)
				)
			)
		)
		(polygon
			(pts
				(arc
					(start 279.636728 -345.653868)
					(mid 280.185368 -345.105228)
					(end 279.636728 -344.556588)
				)
				(arc
					(start 278.23668 -344.556588)
					(mid 277.68804 -345.105228)
					(end 278.23668 -345.653868)
				)
			)
		)
		(polygon
			(pts
				(arc
					(start 287.83661 -343.85377)
					(mid 288.38525 -343.30513)
					(end 287.83661 -342.75649)
				)
				(arc
					(start 286.436562 -342.75649)
					(mid 285.887922 -343.30513)
					(end 286.436562 -343.85377)
				)
			)
		)
		(polygon
			(pts
				(arc
					(start 280.636726 -343.85377)
					(mid 281.185366 -343.30513)
					(end 280.636726 -342.75649)
				)
				(arc
					(start 279.236678 -342.75649)
					(mid 278.688038 -343.30513)
					(end 279.236678 -343.85377)
				)
			)
		)
		(polygon
			(pts
				(arc
					(start 286.836612 -342.053672)
					(mid 287.385252 -341.505032)
					(end 286.836612 -340.956392)
				)
				(arc
					(start 285.436564 -340.956392)
					(mid 284.887924 -341.505032)
					(end 285.436564 -342.053672)
				)
			)
		)
		(polygon
			(pts
				(arc
					(start 279.636728 -342.053672)
					(mid 280.185368 -341.505032)
					(end 279.636728 -340.956392)
				)
				(arc
					(start 278.23668 -340.956392)
					(mid 277.68804 -341.505032)
					(end 278.23668 -342.053672)
				)
			)
		)
		(polygon
			(pts
				(arc
					(start 287.83661 -340.253828)
					(mid 288.38525 -339.705188)
					(end 287.83661 -339.156548)
				)
				(arc
					(start 286.436562 -339.156548)
					(mid 285.887922 -339.705188)
					(end 286.436562 -340.253828)
				)
			)
		)
		(polygon
			(pts
				(arc
					(start 280.636726 -340.253828)
					(mid 281.185366 -339.705188)
					(end 280.636726 -339.156548)
				)
				(arc
					(start 279.236678 -339.156548)
					(mid 278.688038 -339.705188)
					(end 279.236678 -340.253828)
				)
			)
		)
		(polygon
			(pts
				(arc
					(start 273.1135 -338.28863)
					(mid 273.49704 -337.90509)
					(end 273.1135 -337.52155)
				)
				(arc
					(start 271.970246 -337.52155)
					(mid 271.58696 -337.905217)
					(end 271.9705 -338.28863)
				)
			)
		)
		(polygon
			(pts
				(arc
					(start 286.836612 -338.45373)
					(mid 287.385252 -337.90509)
					(end 286.836612 -337.35645)
				)
				(arc
					(start 285.436564 -337.35645)
					(mid 284.887924 -337.90509)
					(end 285.436564 -338.45373)
				)
			)
		)
		(polygon
			(pts
				(arc
					(start 279.636728 -338.45373)
					(mid 280.185368 -337.90509)
					(end 279.636728 -337.35645)
				)
				(arc
					(start 278.23668 -337.35645)
					(mid 277.68804 -337.90509)
					(end 278.23668 -338.45373)
				)
			)
		)
		(polygon
			(pts
				(arc
					(start 273.1135 -336.488532)
					(mid 273.49704 -336.104992)
					(end 273.1135 -335.721452)
				)
				(arc
					(start 271.970246 -335.721452)
					(mid 271.58696 -336.105119)
					(end 271.9705 -336.488532)
				)
			)
		)
		(polygon
			(pts
				(arc
					(start 280.636726 -336.653886)
					(mid 281.185366 -336.105246)
					(end 280.636726 -335.556606)
				)
				(arc
					(start 279.236678 -335.556606)
					(mid 278.688038 -336.105246)
					(end 279.236678 -336.653886)
				)
			)
		)
		(polygon
			(pts
				(arc
					(start 287.83661 -336.656426)
					(mid 288.38779 -336.105246)
					(end 287.83661 -335.554066)
				)
				(arc
					(start 286.436562 -335.554066)
					(mid 285.885382 -336.105246)
					(end 286.436562 -336.656426)
				)
			)
		)
		(polygon
			(pts
				(arc
					(start 273.1135 -334.688434)
					(mid 273.49704 -334.304894)
					(end 273.1135 -333.921354)
				)
				(arc
					(start 271.970246 -333.921354)
					(mid 271.58696 -334.305021)
					(end 271.9705 -334.688434)
				)
			)
		)
		(polygon
			(pts
				(arc
					(start 279.636728 -334.853788)
					(mid 280.185368 -334.305148)
					(end 279.636728 -333.756508)
				)
				(arc
					(start 278.23668 -333.756508)
					(mid 277.68804 -334.305148)
					(end 278.23668 -334.853788)
				)
			)
		)
		(polygon
			(pts
				(arc
					(start 286.836612 -334.856328)
					(mid 287.387792 -334.305148)
					(end 286.836612 -333.753968)
				)
				(arc
					(start 285.436564 -333.753968)
					(mid 284.885384 -334.305148)
					(end 285.436564 -334.856328)
				)
			)
		)
		(polygon
			(pts
				(arc
					(start 273.1135 -332.88859)
					(mid 273.49704 -332.50505)
					(end 273.1135 -332.12151)
				)
				(arc
					(start 271.970246 -332.12151)
					(mid 271.58696 -332.505177)
					(end 271.9705 -332.88859)
				)
			)
		)
		(polygon
			(pts
				(arc
					(start 280.636726 -333.05369)
					(mid 281.185366 -332.50505)
					(end 280.636726 -331.95641)
				)
				(arc
					(start 279.236678 -331.95641)
					(mid 278.688038 -332.50505)
					(end 279.236678 -333.05369)
				)
			)
		)
		(polygon
			(pts
				(arc
					(start 287.83661 -333.05623)
					(mid 288.38779 -332.50505)
					(end 287.83661 -331.95387)
				)
				(arc
					(start 286.436562 -331.95387)
					(mid 285.885382 -332.50505)
					(end 286.436562 -333.05623)
				)
			)
		)
		(polygon
			(pts
				(arc
					(start 273.1135 -331.088492)
					(mid 273.49704 -330.704952)
					(end 273.1135 -330.321412)
				)
				(arc
					(start 271.970246 -330.321412)
					(mid 271.58696 -330.705079)
					(end 271.9705 -331.088492)
				)
			)
		)
		(polygon
			(pts
				(arc
					(start 279.636728 -331.253846)
					(mid 280.185368 -330.705206)
					(end 279.636728 -330.156566)
				)
				(arc
					(start 278.23668 -330.156566)
					(mid 277.68804 -330.705206)
					(end 278.23668 -331.253846)
				)
			)
		)
		(polygon
			(pts
				(arc
					(start 286.836612 -331.256386)
					(mid 287.387792 -330.705206)
					(end 286.836612 -330.154026)
				)
				(arc
					(start 285.436564 -330.154026)
					(mid 284.885384 -330.705206)
					(end 285.436564 -331.256386)
				)
			)
		)
		(polygon
			(pts
				(arc
					(start 273.1135 -329.288648)
					(mid 273.49704 -328.905108)
					(end 273.1135 -328.521568)
				)
				(arc
					(start 271.970246 -328.521568)
					(mid 271.58696 -328.905235)
					(end 271.9705 -329.288648)
				)
			)
		)
		(polygon
			(pts
				(arc
					(start 280.636726 -329.453748)
					(mid 281.185366 -328.905108)
					(end 280.636726 -328.356468)
				)
				(arc
					(start 279.236678 -328.356468)
					(mid 278.688038 -328.905108)
					(end 279.236678 -329.453748)
				)
			)
		)
		(polygon
			(pts
				(arc
					(start 287.83661 -329.456288)
					(mid 288.38779 -328.905108)
					(end 287.83661 -328.353928)
				)
				(arc
					(start 286.436562 -328.353928)
					(mid 285.885382 -328.905108)
					(end 286.436562 -329.456288)
				)
			)
		)
		(polygon
			(pts
				(arc
					(start 279.636728 -327.653904)
					(mid 280.185368 -327.105264)
					(end 279.636728 -326.556624)
				)
				(arc
					(start 278.23668 -326.556624)
					(mid 277.68804 -327.105264)
					(end 278.23668 -327.653904)
				)
			)
		)
		(polygon
			(pts
				(arc
					(start 286.836612 -327.656444)
					(mid 287.387792 -327.105264)
					(end 286.836612 -326.554084)
				)
				(arc
					(start 285.436564 -326.554084)
					(mid 284.885384 -327.105264)
					(end 285.436564 -327.656444)
				)
			)
		)
		(polygon
			(pts
				(arc
					(start 287.83661 -325.853806)
					(mid 288.38525 -325.305166)
					(end 287.83661 -324.756526)
				)
				(arc
					(start 286.436562 -324.756526)
					(mid 285.887922 -325.305166)
					(end 286.436562 -325.853806)
				)
			)
		)
		(polygon
			(pts
				(arc
					(start 280.636726 -325.853806)
					(mid 281.185366 -325.305166)
					(end 280.636726 -324.756526)
				)
				(arc
					(start 279.236678 -324.756526)
					(mid 278.688038 -325.305166)
					(end 279.236678 -325.853806)
				)
			)
		)
		(polygon
			(pts
				(arc
					(start 286.836612 -324.053708)
					(mid 287.385252 -323.505068)
					(end 286.836612 -322.956428)
				)
				(arc
					(start 285.436564 -322.956428)
					(mid 284.887924 -323.505068)
					(end 285.436564 -324.053708)
				)
			)
		)
		(polygon
			(pts
				(arc
					(start 279.636728 -324.053708)
					(mid 280.185368 -323.505068)
					(end 279.636728 -322.956428)
				)
				(arc
					(start 278.23668 -322.956428)
					(mid 277.68804 -323.505068)
					(end 278.23668 -324.053708)
				)
			)
		)
		(polygon
			(pts
				(arc
					(start 287.83661 -322.253864)
					(mid 288.38525 -321.705224)
					(end 287.83661 -321.156584)
				)
				(arc
					(start 286.436562 -321.156584)
					(mid 285.887922 -321.705224)
					(end 286.436562 -322.253864)
				)
			)
		)
		(polygon
			(pts
				(arc
					(start 280.636726 -322.253864)
					(mid 281.185366 -321.705224)
					(end 280.636726 -321.156584)
				)
				(arc
					(start 279.236678 -321.156584)
					(mid 278.688038 -321.705224)
					(end 279.236678 -322.253864)
				)
			)
		)
		(polygon
			(pts
				(arc
					(start 286.836612 -320.453766)
					(mid 287.385252 -319.905126)
					(end 286.836612 -319.356486)
				)
				(arc
					(start 285.436564 -319.356486)
					(mid 284.887924 -319.905126)
					(end 285.436564 -320.453766)
				)
			)
		)
		(polygon
			(pts
				(arc
					(start 279.636728 -320.453766)
					(mid 280.185368 -319.905126)
					(end 279.636728 -319.356486)
				)
				(arc
					(start 278.23668 -319.356486)
					(mid 277.68804 -319.905126)
					(end 278.23668 -320.453766)
				)
			)
		)
		(polygon
			(pts
				(arc
					(start 287.83661 -318.653668)
					(mid 288.38525 -318.105028)
					(end 287.83661 -317.556388)
				)
				(arc
					(start 286.436562 -317.556388)
					(mid 285.887922 -318.105028)
					(end 286.436562 -318.653668)
				)
			)
		)
		(polygon
			(pts
				(arc
					(start 280.636726 -318.653668)
					(mid 281.185366 -318.105028)
					(end 280.636726 -317.556388)
				)
				(arc
					(start 279.236678 -317.556388)
					(mid 278.688038 -318.105028)
					(end 279.236678 -318.653668)
				)
			)
		)
		(polygon
			(pts
				(arc
					(start 273.1135 -316.68847)
					(mid 273.49704 -316.30493)
					(end 273.1135 -315.92139)
				)
				(arc
					(start 271.970246 -315.92139)
					(mid 271.58696 -316.305057)
					(end 271.9705 -316.68847)
				)
			)
		)
		(polygon
			(pts
				(arc
					(start 286.836612 -316.853824)
					(mid 287.385252 -316.305184)
					(end 286.836612 -315.756544)
				)
				(arc
					(start 285.436564 -315.756544)
					(mid 284.887924 -316.305184)
					(end 285.436564 -316.853824)
				)
			)
		)
		(polygon
			(pts
				(arc
					(start 279.636728 -316.853824)
					(mid 280.185368 -316.305184)
					(end 279.636728 -315.756544)
				)
				(arc
					(start 278.23668 -315.756544)
					(mid 277.68804 -316.305184)
					(end 278.23668 -316.853824)
				)
			)
		)
		(polygon
			(pts
				(arc
					(start 273.1135 -314.888626)
					(mid 273.49704 -314.505086)
					(end 273.1135 -314.121546)
				)
				(arc
					(start 271.970246 -314.121546)
					(mid 271.58696 -314.505213)
					(end 271.9705 -314.888626)
				)
			)
		)
		(polygon
			(pts
				(arc
					(start 280.636726 -315.053726)
					(mid 281.185366 -314.505086)
					(end 280.636726 -313.956446)
				)
				(arc
					(start 279.236678 -313.956446)
					(mid 278.688038 -314.505086)
					(end 279.236678 -315.053726)
				)
			)
		)
		(polygon
			(pts
				(arc
					(start 287.83661 -315.056266)
					(mid 288.38779 -314.505086)
					(end 287.83661 -313.953906)
				)
				(arc
					(start 286.436562 -313.953906)
					(mid 285.885382 -314.505086)
					(end 286.436562 -315.056266)
				)
			)
		)
		(polygon
			(pts
				(arc
					(start 273.1135 -313.088528)
					(mid 273.49704 -312.704988)
					(end 273.1135 -312.321448)
				)
				(arc
					(start 271.970246 -312.321448)
					(mid 271.58696 -312.705115)
					(end 271.9705 -313.088528)
				)
			)
		)
		(polygon
			(pts
				(arc
					(start 279.636728 -313.253882)
					(mid 280.185368 -312.705242)
					(end 279.636728 -312.156602)
				)
				(arc
					(start 278.23668 -312.156602)
					(mid 277.68804 -312.705242)
					(end 278.23668 -313.253882)
				)
			)
		)
		(polygon
			(pts
				(arc
					(start 286.836612 -313.256422)
					(mid 287.387792 -312.705242)
					(end 286.836612 -312.154062)
				)
				(arc
					(start 285.436564 -312.154062)
					(mid 284.885384 -312.705242)
					(end 285.436564 -313.256422)
				)
			)
		)
		(polygon
			(pts
				(arc
					(start 273.1135 -311.28843)
					(mid 273.49704 -310.90489)
					(end 273.1135 -310.52135)
				)
				(arc
					(start 271.970246 -310.52135)
					(mid 271.58696 -310.905017)
					(end 271.9705 -311.28843)
				)
			)
		)
		(polygon
			(pts
				(arc
					(start 280.636726 -311.453784)
					(mid 281.185366 -310.905144)
					(end 280.636726 -310.356504)
				)
				(arc
					(start 279.236678 -310.356504)
					(mid 278.688038 -310.905144)
					(end 279.236678 -311.453784)
				)
			)
		)
		(polygon
			(pts
				(arc
					(start 287.83661 -311.456324)
					(mid 288.38779 -310.905144)
					(end 287.83661 -310.353964)
				)
				(arc
					(start 286.436562 -310.353964)
					(mid 285.885382 -310.905144)
					(end 286.436562 -311.456324)
				)
			)
		)
		(polygon
			(pts
				(arc
					(start 273.1135 -309.488586)
					(mid 273.49704 -309.105046)
					(end 273.1135 -308.721506)
				)
				(arc
					(start 271.970246 -308.721506)
					(mid 271.58696 -309.105173)
					(end 271.9705 -309.488586)
				)
			)
		)
		(polygon
			(pts
				(arc
					(start 279.636728 -309.653686)
					(mid 280.185368 -309.105046)
					(end 279.636728 -308.556406)
				)
				(arc
					(start 278.23668 -308.556406)
					(mid 277.68804 -309.105046)
					(end 278.23668 -309.653686)
				)
			)
		)
		(polygon
			(pts
				(arc
					(start 286.836612 -309.656226)
					(mid 287.387792 -309.105046)
					(end 286.836612 -308.553866)
				)
				(arc
					(start 285.436564 -308.553866)
					(mid 284.885384 -309.105046)
					(end 285.436564 -309.656226)
				)
			)
		)
		(polygon
			(pts
				(arc
					(start 273.1135 -307.688488)
					(mid 273.49704 -307.304948)
					(end 273.1135 -306.921408)
				)
				(arc
					(start 271.970246 -306.921408)
					(mid 271.58696 -307.305075)
					(end 271.9705 -307.688488)
				)
			)
		)
		(polygon
			(pts
				(arc
					(start 280.636726 -307.853842)
					(mid 281.185366 -307.305202)
					(end 280.636726 -306.756562)
				)
				(arc
					(start 279.236678 -306.756562)
					(mid 278.688038 -307.305202)
					(end 279.236678 -307.853842)
				)
			)
		)
		(polygon
			(pts
				(arc
					(start 287.83661 -307.856382)
					(mid 288.38779 -307.305202)
					(end 287.83661 -306.754022)
				)
				(arc
					(start 286.436562 -306.754022)
					(mid 285.885382 -307.305202)
					(end 286.436562 -307.856382)
				)
			)
		)
		(polygon
			(pts
				(arc
					(start 279.636728 -306.053744)
					(mid 280.185368 -305.505104)
					(end 279.636728 -304.956464)
				)
				(arc
					(start 278.23668 -304.956464)
					(mid 277.68804 -305.505104)
					(end 278.23668 -306.053744)
				)
			)
		)
		(polygon
			(pts
				(arc
					(start 286.836612 -306.056284)
					(mid 287.387792 -305.505104)
					(end 286.836612 -304.953924)
				)
				(arc
					(start 285.436564 -304.953924)
					(mid 284.885384 -305.505104)
					(end 285.436564 -306.056284)
				)
			)
		)
		(polygon
			(pts
				(arc
					(start 287.83661 -304.2539)
					(mid 288.38525 -303.70526)
					(end 287.83661 -303.15662)
				)
				(arc
					(start 286.436562 -303.15662)
					(mid 285.887922 -303.70526)
					(end 286.436562 -304.2539)
				)
			)
		)
		(polygon
			(pts
				(arc
					(start 280.636726 -304.2539)
					(mid 281.185366 -303.70526)
					(end 280.636726 -303.15662)
				)
				(arc
					(start 279.236678 -303.15662)
					(mid 278.688038 -303.70526)
					(end 279.236678 -304.2539)
				)
			)
		)
		(polygon
			(pts
				(arc
					(start 286.836612 -302.453802)
					(mid 287.385252 -301.905162)
					(end 286.836612 -301.356522)
				)
				(arc
					(start 285.436564 -301.356522)
					(mid 284.887924 -301.905162)
					(end 285.436564 -302.453802)
				)
			)
		)
		(polygon
			(pts
				(arc
					(start 279.636728 -302.453802)
					(mid 280.185368 -301.905162)
					(end 279.636728 -301.356522)
				)
				(arc
					(start 278.23668 -301.356522)
					(mid 277.68804 -301.905162)
					(end 278.23668 -302.453802)
				)
			)
		)
		(polygon
			(pts
				(arc
					(start 287.83661 -300.653704)
					(mid 288.38525 -300.105064)
					(end 287.83661 -299.556424)
				)
				(arc
					(start 286.436562 -299.556424)
					(mid 285.887922 -300.105064)
					(end 286.436562 -300.653704)
				)
			)
		)
		(polygon
			(pts
				(arc
					(start 280.636726 -300.653704)
					(mid 281.185366 -300.105064)
					(end 280.636726 -299.556424)
				)
				(arc
					(start 279.236678 -299.556424)
					(mid 278.688038 -300.105064)
					(end 279.236678 -300.653704)
				)
			)
		)
		(polygon
			(pts
				(arc
					(start 286.836612 -298.85386)
					(mid 287.385252 -298.30522)
					(end 286.836612 -297.75658)
				)
				(arc
					(start 285.436564 -297.75658)
					(mid 284.887924 -298.30522)
					(end 285.436564 -298.85386)
				)
			)
		)
		(polygon
			(pts
				(arc
					(start 279.636728 -298.85386)
					(mid 280.185368 -298.30522)
					(end 279.636728 -297.75658)
				)
				(arc
					(start 278.23668 -297.75658)
					(mid 277.68804 -298.30522)
					(end 278.23668 -298.85386)
				)
			)
		)
		(polygon
			(pts
				(arc
					(start 280.636726 -297.053762)
					(mid 281.185366 -296.505122)
					(end 280.636726 -295.956482)
				)
				(arc
					(start 279.236678 -295.956482)
					(mid 278.688038 -296.505122)
					(end 279.236678 -297.053762)
				)
			)
		)
		(polygon
			(pts
				(arc
					(start 287.83661 -297.056302)
					(mid 288.38779 -296.505122)
					(end 287.83661 -295.953942)
				)
				(arc
					(start 286.436562 -295.953942)
					(mid 285.885382 -296.505122)
					(end 286.436562 -297.056302)
				)
			)
		)
		(polygon
			(pts
				(arc
					(start 279.636728 -295.253918)
					(mid 280.185368 -294.705278)
					(end 279.636728 -294.156638)
				)
				(arc
					(start 278.23668 -294.156638)
					(mid 277.68804 -294.705278)
					(end 278.23668 -295.253918)
				)
			)
		)
		(polygon
			(pts
				(arc
					(start 286.836612 -295.256458)
					(mid 287.387792 -294.705278)
					(end 286.836612 -294.154098)
				)
				(arc
					(start 285.436564 -294.154098)
					(mid 284.885384 -294.705278)
					(end 285.436564 -295.256458)
				)
			)
		)
		(polygon
			(pts
				(arc
					(start 482.870002 -277.178262)
					(mid 482.488875 -276.797516)
					(end 482.108002 -277.178516)
				)
				(arc
					(start 482.108002 -278.321516)
					(mid 482.489002 -278.702516)
					(end 482.870002 -278.321516)
				)
			)
		)
		(polygon
			(pts
				(arc
					(start 451.3199 -277.178262)
					(mid 450.938773 -276.797516)
					(end 450.5579 -277.178516)
				)
				(arc
					(start 450.5579 -278.321516)
					(mid 450.9389 -278.702516)
					(end 451.3199 -278.321516)
				)
			)
		)
		(polygon
			(pts
				(arc
					(start 419.770052 -277.178262)
					(mid 419.388925 -276.797516)
					(end 419.008052 -277.178516)
				)
				(arc
					(start 419.008052 -278.321516)
					(mid 419.389052 -278.702516)
					(end 419.770052 -278.321516)
				)
			)
		)
		(polygon
			(pts
				(arc
					(start 388.21995 -277.178262)
					(mid 387.838823 -276.797516)
					(end 387.45795 -277.178516)
				)
				(arc
					(start 387.45795 -278.321516)
					(mid 387.83895 -278.702516)
					(end 388.21995 -278.321516)
				)
			)
		)
		(polygon
			(pts
				(arc
					(start 356.670102 -277.178262)
					(mid 356.288975 -276.797516)
					(end 355.908102 -277.178516)
				)
				(arc
					(start 355.908102 -278.321516)
					(mid 356.289102 -278.702516)
					(end 356.670102 -278.321516)
				)
			)
		)
		(polygon
			(pts
				(arc
					(start 325.12 -277.178262)
					(mid 324.738873 -276.797516)
					(end 324.358 -277.178516)
				)
				(arc
					(start 324.358 -278.321516)
					(mid 324.739 -278.702516)
					(end 325.12 -278.321516)
				)
			)
		)
		(polygon
			(pts
				(arc
					(start 190.639954 -277.178262)
					(mid 190.258827 -276.797516)
					(end 189.877954 -277.178516)
				)
				(arc
					(start 189.877954 -278.321516)
					(mid 190.258954 -278.702516)
					(end 190.639954 -278.321516)
				)
			)
		)
		(polygon
			(pts
				(arc
					(start 159.089852 -277.178262)
					(mid 158.708725 -276.797516)
					(end 158.327852 -277.178516)
				)
				(arc
					(start 158.327852 -278.321516)
					(mid 158.708852 -278.702516)
					(end 159.089852 -278.321516)
				)
			)
		)
		(polygon
			(pts
				(arc
					(start 127.53975 -277.178262)
					(mid 127.158623 -276.797516)
					(end 126.77775 -277.178516)
				)
				(arc
					(start 126.77775 -278.321516)
					(mid 127.15875 -278.702516)
					(end 127.53975 -278.321516)
				)
			)
		)
		(polygon
			(pts
				(arc
					(start 95.989902 -277.178262)
					(mid 95.608775 -276.797516)
					(end 95.227902 -277.178516)
				)
				(arc
					(start 95.227902 -278.321516)
					(mid 95.608902 -278.702516)
					(end 95.989902 -278.321516)
				)
			)
		)
		(polygon
			(pts
				(arc
					(start 64.4398 -277.178262)
					(mid 64.058673 -276.797516)
					(end 63.6778 -277.178516)
				)
				(arc
					(start 63.6778 -278.321516)
					(mid 64.0588 -278.702516)
					(end 64.4398 -278.321516)
				)
			)
		)
		(polygon
			(pts
				(arc
					(start 32.889952 -277.178262)
					(mid 32.508825 -276.797516)
					(end 32.127952 -277.178516)
				)
				(arc
					(start 32.127952 -278.321516)
					(mid 32.508952 -278.702516)
					(end 32.889952 -278.321516)
				)
			)
		)
		(polygon
			(pts
				(xy 486.306114 -276.149816) (xy 483.943914 -276.149816) (xy 483.943914 -279.350216) (xy 486.306114 -279.350216)
			)
		)
		(polygon
			(pts
				(xy 454.756012 -276.149816) (xy 452.393812 -276.149816) (xy 452.393812 -279.350216) (xy 454.756012 -279.350216)
			)
		)
		(polygon
			(pts
				(xy 423.206164 -276.149816) (xy 420.843964 -276.149816) (xy 420.843964 -279.350216) (xy 423.206164 -279.350216)
			)
		)
		(polygon
			(pts
				(xy 391.656062 -276.149816) (xy 389.293862 -276.149816) (xy 389.293862 -279.350216) (xy 391.656062 -279.350216)
			)
		)
		(polygon
			(pts
				(xy 360.106214 -276.149816) (xy 357.744014 -276.149816) (xy 357.744014 -279.350216) (xy 360.106214 -279.350216)
			)
		)
		(polygon
			(pts
				(xy 328.556112 -276.149816) (xy 326.193912 -276.149816) (xy 326.193912 -279.350216) (xy 328.556112 -279.350216)
			)
		)
		(polygon
			(pts
				(xy 188.956188 -276.149816) (xy 186.593988 -276.149816) (xy 186.593988 -279.350216) (xy 188.956188 -279.350216)
			)
		)
		(polygon
			(pts
				(xy 157.406086 -276.149816) (xy 155.043886 -276.149816) (xy 155.043886 -279.350216) (xy 157.406086 -279.350216)
			)
		)
		(polygon
			(pts
				(xy 125.855984 -276.149816) (xy 123.493784 -276.149816) (xy 123.493784 -279.350216) (xy 125.855984 -279.350216)
			)
		)
		(polygon
			(pts
				(xy 94.306136 -276.149816) (xy 91.943936 -276.149816) (xy 91.943936 -279.350216) (xy 94.306136 -279.350216)
			)
		)
		(polygon
			(pts
				(xy 62.756034 -276.149816) (xy 60.393834 -276.149816) (xy 60.393834 -279.350216) (xy 62.756034 -279.350216)
			)
		)
		(polygon
			(pts
				(xy 31.206186 -276.149816) (xy 28.843986 -276.149816) (xy 28.843986 -279.350216) (xy 31.206186 -279.350216)
			)
		)
		(polygon
			(pts
				(arc
					(start 479.841814 -274.117816)
					(mid 479.826935 -274.081895)
					(end 479.791014 -274.067016)
				)
				(arc
					(start 478.978214 -274.067016)
					(mid 478.942293 -274.081895)
					(end 478.927414 -274.117816)
				)
				(arc
					(start 478.927414 -274.321016)
					(mid 478.942293 -274.356937)
					(end 478.978214 -274.371816)
				)
				(arc
					(start 479.791014 -274.371816)
					(mid 479.826935 -274.356937)
					(end 479.841814 -274.321016)
				)
			)
		)
		(polygon
			(pts
				(arc
					(start 448.291712 -274.117816)
					(mid 448.276833 -274.081895)
					(end 448.240912 -274.067016)
				)
				(arc
					(start 447.428112 -274.067016)
					(mid 447.392191 -274.081895)
					(end 447.377312 -274.117816)
				)
				(arc
					(start 447.377312 -274.321016)
					(mid 447.392191 -274.356937)
					(end 447.428112 -274.371816)
				)
				(arc
					(start 448.240912 -274.371816)
					(mid 448.276833 -274.356937)
					(end 448.291712 -274.321016)
				)
			)
		)
		(polygon
			(pts
				(arc
					(start 416.741864 -274.117816)
					(mid 416.726985 -274.081895)
					(end 416.691064 -274.067016)
				)
				(arc
					(start 415.878264 -274.067016)
					(mid 415.842343 -274.081895)
					(end 415.827464 -274.117816)
				)
				(arc
					(start 415.827464 -274.321016)
					(mid 415.842343 -274.356937)
					(end 415.878264 -274.371816)
				)
				(arc
					(start 416.691064 -274.371816)
					(mid 416.726985 -274.356937)
					(end 416.741864 -274.321016)
				)
			)
		)
		(polygon
			(pts
				(arc
					(start 385.191762 -274.117816)
					(mid 385.176883 -274.081895)
					(end 385.140962 -274.067016)
				)
				(arc
					(start 384.328162 -274.067016)
					(mid 384.292241 -274.081895)
					(end 384.277362 -274.117816)
				)
				(arc
					(start 384.277362 -274.321016)
					(mid 384.292241 -274.356937)
					(end 384.328162 -274.371816)
				)
				(arc
					(start 385.140962 -274.371816)
					(mid 385.176883 -274.356937)
					(end 385.191762 -274.321016)
				)
			)
		)
		(polygon
			(pts
				(arc
					(start 353.641914 -274.117816)
					(mid 353.627035 -274.081895)
					(end 353.591114 -274.067016)
				)
				(arc
					(start 352.778314 -274.067016)
					(mid 352.742393 -274.081895)
					(end 352.727514 -274.117816)
				)
				(arc
					(start 352.727514 -274.321016)
					(mid 352.742393 -274.356937)
					(end 352.778314 -274.371816)
				)
				(arc
					(start 353.591114 -274.371816)
					(mid 353.627035 -274.356937)
					(end 353.641914 -274.321016)
				)
			)
		)
		(polygon
			(pts
				(arc
					(start 322.091812 -274.117816)
					(mid 322.076933 -274.081895)
					(end 322.041012 -274.067016)
				)
				(arc
					(start 321.228212 -274.067016)
					(mid 321.192291 -274.081895)
					(end 321.177412 -274.117816)
				)
				(arc
					(start 321.177412 -274.321016)
					(mid 321.192291 -274.356937)
					(end 321.228212 -274.371816)
				)
				(arc
					(start 322.041012 -274.371816)
					(mid 322.076933 -274.356937)
					(end 322.091812 -274.321016)
				)
			)
		)
		(polygon
			(pts
				(arc
					(start 190.670688 -274.117816)
					(mid 190.655809 -274.081895)
					(end 190.619888 -274.067016)
				)
				(arc
					(start 189.807088 -274.067016)
					(mid 189.771167 -274.081895)
					(end 189.756288 -274.117816)
				)
				(arc
					(start 189.756288 -274.321016)
					(mid 189.771167 -274.356937)
					(end 189.807088 -274.371816)
				)
				(arc
					(start 190.619888 -274.371816)
					(mid 190.655809 -274.356937)
					(end 190.670688 -274.321016)
				)
			)
		)
		(polygon
			(pts
				(arc
					(start 159.120586 -274.117816)
					(mid 159.105707 -274.081895)
					(end 159.069786 -274.067016)
				)
				(arc
					(start 158.256986 -274.067016)
					(mid 158.221065 -274.081895)
					(end 158.206186 -274.117816)
				)
				(arc
					(start 158.206186 -274.321016)
					(mid 158.221065 -274.356937)
					(end 158.256986 -274.371816)
				)
				(arc
					(start 159.069786 -274.371816)
					(mid 159.105707 -274.356937)
					(end 159.120586 -274.321016)
				)
			)
		)
		(polygon
			(pts
				(arc
					(start 127.570484 -274.117816)
					(mid 127.555605 -274.081895)
					(end 127.519684 -274.067016)
				)
				(arc
					(start 126.706884 -274.067016)
					(mid 126.670963 -274.081895)
					(end 126.656084 -274.117816)
				)
				(arc
					(start 126.656084 -274.321016)
					(mid 126.670963 -274.356937)
					(end 126.706884 -274.371816)
				)
				(arc
					(start 127.519684 -274.371816)
					(mid 127.555605 -274.356937)
					(end 127.570484 -274.321016)
				)
			)
		)
		(polygon
			(pts
				(arc
					(start 96.020636 -274.117816)
					(mid 96.005757 -274.081895)
					(end 95.969836 -274.067016)
				)
				(arc
					(start 95.157036 -274.067016)
					(mid 95.121115 -274.081895)
					(end 95.106236 -274.117816)
				)
				(arc
					(start 95.106236 -274.321016)
					(mid 95.121115 -274.356937)
					(end 95.157036 -274.371816)
				)
				(arc
					(start 95.969836 -274.371816)
					(mid 96.005757 -274.356937)
					(end 96.020636 -274.321016)
				)
			)
		)
		(polygon
			(pts
				(arc
					(start 64.470534 -274.117816)
					(mid 64.455655 -274.081895)
					(end 64.419734 -274.067016)
				)
				(arc
					(start 63.606934 -274.067016)
					(mid 63.571013 -274.081895)
					(end 63.556134 -274.117816)
				)
				(arc
					(start 63.556134 -274.321016)
					(mid 63.571013 -274.356937)
					(end 63.606934 -274.371816)
				)
				(arc
					(start 64.419734 -274.371816)
					(mid 64.455655 -274.356937)
					(end 64.470534 -274.321016)
				)
			)
		)
		(polygon
			(pts
				(arc
					(start 32.920686 -274.117816)
					(mid 32.905807 -274.081895)
					(end 32.869886 -274.067016)
				)
				(arc
					(start 32.057086 -274.067016)
					(mid 32.021165 -274.081895)
					(end 32.006286 -274.117816)
				)
				(arc
					(start 32.006286 -274.321016)
					(mid 32.021165 -274.356937)
					(end 32.057086 -274.371816)
				)
				(arc
					(start 32.869886 -274.371816)
					(mid 32.905807 -274.356937)
					(end 32.920686 -274.321016)
				)
			)
		)
		(polygon
			(pts
				(arc
					(start 479.841814 -273.559016)
					(mid 479.826935 -273.523095)
					(end 479.791014 -273.508216)
				)
				(arc
					(start 478.978214 -273.508216)
					(mid 478.942293 -273.523095)
					(end 478.927414 -273.559016)
				)
				(arc
					(start 478.927414 -273.762216)
					(mid 478.942293 -273.798137)
					(end 478.978214 -273.813016)
				)
				(arc
					(start 479.791014 -273.813016)
					(mid 479.826935 -273.798137)
					(end 479.841814 -273.762216)
				)
			)
		)
		(polygon
			(pts
				(arc
					(start 448.291712 -273.559016)
					(mid 448.276833 -273.523095)
					(end 448.240912 -273.508216)
				)
				(arc
					(start 447.428112 -273.508216)
					(mid 447.392191 -273.523095)
					(end 447.377312 -273.559016)
				)
				(arc
					(start 447.377312 -273.762216)
					(mid 447.392191 -273.798137)
					(end 447.428112 -273.813016)
				)
				(arc
					(start 448.240912 -273.813016)
					(mid 448.276833 -273.798137)
					(end 448.291712 -273.762216)
				)
			)
		)
		(polygon
			(pts
				(arc
					(start 416.741864 -273.559016)
					(mid 416.726985 -273.523095)
					(end 416.691064 -273.508216)
				)
				(arc
					(start 415.878264 -273.508216)
					(mid 415.842343 -273.523095)
					(end 415.827464 -273.559016)
				)
				(arc
					(start 415.827464 -273.762216)
					(mid 415.842343 -273.798137)
					(end 415.878264 -273.813016)
				)
				(arc
					(start 416.691064 -273.813016)
					(mid 416.726985 -273.798137)
					(end 416.741864 -273.762216)
				)
			)
		)
		(polygon
			(pts
				(arc
					(start 385.191762 -273.559016)
					(mid 385.176883 -273.523095)
					(end 385.140962 -273.508216)
				)
				(arc
					(start 384.328162 -273.508216)
					(mid 384.292241 -273.523095)
					(end 384.277362 -273.559016)
				)
				(arc
					(start 384.277362 -273.762216)
					(mid 384.292241 -273.798137)
					(end 384.328162 -273.813016)
				)
				(arc
					(start 385.140962 -273.813016)
					(mid 385.176883 -273.798137)
					(end 385.191762 -273.762216)
				)
			)
		)
		(polygon
			(pts
				(arc
					(start 353.641914 -273.559016)
					(mid 353.627035 -273.523095)
					(end 353.591114 -273.508216)
				)
				(arc
					(start 352.778314 -273.508216)
					(mid 352.742393 -273.523095)
					(end 352.727514 -273.559016)
				)
				(arc
					(start 352.727514 -273.762216)
					(mid 352.742393 -273.798137)
					(end 352.778314 -273.813016)
				)
				(arc
					(start 353.591114 -273.813016)
					(mid 353.627035 -273.798137)
					(end 353.641914 -273.762216)
				)
			)
		)
		(polygon
			(pts
				(arc
					(start 322.091812 -273.559016)
					(mid 322.076933 -273.523095)
					(end 322.041012 -273.508216)
				)
				(arc
					(start 321.228212 -273.508216)
					(mid 321.192291 -273.523095)
					(end 321.177412 -273.559016)
				)
				(arc
					(start 321.177412 -273.762216)
					(mid 321.192291 -273.798137)
					(end 321.228212 -273.813016)
				)
				(arc
					(start 322.041012 -273.813016)
					(mid 322.076933 -273.798137)
					(end 322.091812 -273.762216)
				)
			)
		)
		(polygon
			(pts
				(arc
					(start 190.670688 -273.559016)
					(mid 190.655809 -273.523095)
					(end 190.619888 -273.508216)
				)
				(arc
					(start 189.807088 -273.508216)
					(mid 189.771167 -273.523095)
					(end 189.756288 -273.559016)
				)
				(arc
					(start 189.756288 -273.762216)
					(mid 189.771167 -273.798137)
					(end 189.807088 -273.813016)
				)
				(arc
					(start 190.619888 -273.813016)
					(mid 190.655809 -273.798137)
					(end 190.670688 -273.762216)
				)
			)
		)
		(polygon
			(pts
				(arc
					(start 159.120586 -273.559016)
					(mid 159.105707 -273.523095)
					(end 159.069786 -273.508216)
				)
				(arc
					(start 158.256986 -273.508216)
					(mid 158.221065 -273.523095)
					(end 158.206186 -273.559016)
				)
				(arc
					(start 158.206186 -273.762216)
					(mid 158.221065 -273.798137)
					(end 158.256986 -273.813016)
				)
				(arc
					(start 159.069786 -273.813016)
					(mid 159.105707 -273.798137)
					(end 159.120586 -273.762216)
				)
			)
		)
		(polygon
			(pts
				(arc
					(start 127.570484 -273.559016)
					(mid 127.555605 -273.523095)
					(end 127.519684 -273.508216)
				)
				(arc
					(start 126.706884 -273.508216)
					(mid 126.670963 -273.523095)
					(end 126.656084 -273.559016)
				)
				(arc
					(start 126.656084 -273.762216)
					(mid 126.670963 -273.798137)
					(end 126.706884 -273.813016)
				)
				(arc
					(start 127.519684 -273.813016)
					(mid 127.555605 -273.798137)
					(end 127.570484 -273.762216)
				)
			)
		)
		(polygon
			(pts
				(arc
					(start 96.020636 -273.559016)
					(mid 96.005757 -273.523095)
					(end 95.969836 -273.508216)
				)
				(arc
					(start 95.157036 -273.508216)
					(mid 95.121115 -273.523095)
					(end 95.106236 -273.559016)
				)
				(arc
					(start 95.106236 -273.762216)
					(mid 95.121115 -273.798137)
					(end 95.157036 -273.813016)
				)
				(arc
					(start 95.969836 -273.813016)
					(mid 96.005757 -273.798137)
					(end 96.020636 -273.762216)
				)
			)
		)
		(polygon
			(pts
				(arc
					(start 64.470534 -273.559016)
					(mid 64.455655 -273.523095)
					(end 64.419734 -273.508216)
				)
				(arc
					(start 63.606934 -273.508216)
					(mid 63.571013 -273.523095)
					(end 63.556134 -273.559016)
				)
				(arc
					(start 63.556134 -273.762216)
					(mid 63.571013 -273.798137)
					(end 63.606934 -273.813016)
				)
				(arc
					(start 64.419734 -273.813016)
					(mid 64.455655 -273.798137)
					(end 64.470534 -273.762216)
				)
			)
		)
		(polygon
			(pts
				(arc
					(start 32.920686 -273.559016)
					(mid 32.905807 -273.523095)
					(end 32.869886 -273.508216)
				)
				(arc
					(start 32.057086 -273.508216)
					(mid 32.021165 -273.523095)
					(end 32.006286 -273.559016)
				)
				(arc
					(start 32.006286 -273.762216)
					(mid 32.021165 -273.798137)
					(end 32.057086 -273.813016)
				)
				(arc
					(start 32.869886 -273.813016)
					(mid 32.905807 -273.798137)
					(end 32.920686 -273.762216)
				)
			)
		)
		(polygon
			(pts
				(arc
					(start 478.120202 -273.368516)
					(mid 477.739202 -272.987516)
					(end 477.358202 -273.368516)
				)
				(arc
					(start 477.358202 -274.51177)
					(mid 477.739329 -274.892516)
					(end 478.120202 -274.511516)
				)
			)
		)
		(polygon
			(pts
				(arc
					(start 446.5701 -273.368516)
					(mid 446.1891 -272.987516)
					(end 445.8081 -273.368516)
				)
				(arc
					(start 445.8081 -274.51177)
					(mid 446.189227 -274.892516)
					(end 446.5701 -274.511516)
				)
			)
		)
		(polygon
			(pts
				(arc
					(start 415.020252 -273.368516)
					(mid 414.639252 -272.987516)
					(end 414.258252 -273.368516)
				)
				(arc
					(start 414.258252 -274.51177)
					(mid 414.639379 -274.892516)
					(end 415.020252 -274.511516)
				)
			)
		)
		(polygon
			(pts
				(arc
					(start 383.47015 -273.368516)
					(mid 383.08915 -272.987516)
					(end 382.70815 -273.368516)
				)
				(arc
					(start 382.70815 -274.51177)
					(mid 383.089277 -274.892516)
					(end 383.47015 -274.511516)
				)
			)
		)
		(polygon
			(pts
				(arc
					(start 351.920302 -273.368516)
					(mid 351.539302 -272.987516)
					(end 351.158302 -273.368516)
				)
				(arc
					(start 351.158302 -274.51177)
					(mid 351.539429 -274.892516)
					(end 351.920302 -274.511516)
				)
			)
		)
		(polygon
			(pts
				(arc
					(start 320.41084 -273.368262)
					(mid 319.989073 -272.946876)
					(end 319.56756 -273.368516)
				)
				(arc
					(start 319.56756 -274.511516)
					(mid 319.9892 -274.933156)
					(end 320.41084 -274.511516)
				)
			)
		)
		(polygon
			(pts
				(xy 486.306114 -272.340578) (xy 483.943914 -272.339816) (xy 483.943914 -275.540216) (xy 486.306114 -275.540216)
			)
		)
		(polygon
			(pts
				(xy 454.756012 -272.340578) (xy 452.393812 -272.339816) (xy 452.393812 -275.540216) (xy 454.756012 -275.540216)
			)
		)
		(polygon
			(pts
				(xy 423.206164 -272.340578) (xy 420.843964 -272.339816) (xy 420.843964 -275.540216) (xy 423.206164 -275.540216)
			)
		)
		(polygon
			(pts
				(xy 391.656062 -272.340578) (xy 389.293862 -272.339816) (xy 389.293862 -275.540216) (xy 391.656062 -275.540216)
			)
		)
		(polygon
			(pts
				(xy 360.106214 -272.340578) (xy 357.744014 -272.339816) (xy 357.744014 -275.540216) (xy 360.106214 -275.540216)
			)
		)
		(polygon
			(pts
				(xy 328.556112 -272.340578) (xy 326.193912 -272.339816) (xy 326.193912 -275.540216) (xy 328.556112 -275.540216)
			)
		)
		(polygon
			(pts
				(xy 188.956188 -272.340578) (xy 186.593988 -272.339816) (xy 186.593988 -275.540216) (xy 188.956188 -275.540216)
			)
		)
		(polygon
			(pts
				(xy 157.406086 -272.340578) (xy 155.043886 -272.339816) (xy 155.043886 -275.540216) (xy 157.406086 -275.540216)
			)
		)
		(polygon
			(pts
				(xy 125.855984 -272.340578) (xy 123.493784 -272.339816) (xy 123.493784 -275.540216) (xy 125.855984 -275.540216)
			)
		)
		(polygon
			(pts
				(xy 94.306136 -272.340578) (xy 91.943936 -272.339816) (xy 91.943936 -275.540216) (xy 94.306136 -275.540216)
			)
		)
		(polygon
			(pts
				(xy 62.756034 -272.340578) (xy 60.393834 -272.339816) (xy 60.393834 -275.540216) (xy 62.756034 -275.540216)
			)
		)
		(polygon
			(pts
				(xy 31.206186 -272.340578) (xy 28.843986 -272.339816) (xy 28.843986 -275.540216) (xy 31.206186 -275.540216)
			)
		)
		(polygon
			(pts
				(arc
					(start 284.236668 -264.250932)
					(mid 284.785308 -263.702292)
					(end 284.236668 -263.153652)
				)
				(arc
					(start 282.83662 -263.153652)
					(mid 282.28798 -263.702292)
					(end 282.83662 -264.250932)
				)
			)
		)
		(polygon
			(pts
				(arc
					(start 287.83661 -264.253472)
					(mid 288.38779 -263.702292)
					(end 287.83661 -263.151112)
				)
				(arc
					(start 286.436562 -263.151112)
					(mid 285.885382 -263.702292)
					(end 286.436562 -264.253472)
				)
			)
		)
		(polygon
			(pts
				(arc
					(start 280.636726 -264.253472)
					(mid 281.187906 -263.702292)
					(end 280.636726 -263.151112)
				)
				(arc
					(start 279.236678 -263.151112)
					(mid 278.685498 -263.702292)
					(end 279.236678 -264.253472)
				)
			)
		)
		(polygon
			(pts
				(arc
					(start 286.836612 -262.453374)
					(mid 287.387792 -261.902194)
					(end 286.836612 -261.351014)
				)
				(arc
					(start 285.436564 -261.351014)
					(mid 284.885384 -261.902194)
					(end 285.436564 -262.453374)
				)
			)
		)
		(polygon
			(pts
				(arc
					(start 279.636728 -262.453374)
					(mid 280.187908 -261.902194)
					(end 279.636728 -261.351014)
				)
				(arc
					(start 278.23668 -261.351014)
					(mid 277.6855 -261.902194)
					(end 278.23668 -262.453374)
				)
			)
		)
		(polygon
			(pts
				(arc
					(start 287.83661 -260.65353)
					(mid 288.38779 -260.10235)
					(end 287.83661 -259.55117)
				)
				(arc
					(start 286.436562 -259.55117)
					(mid 285.885382 -260.10235)
					(end 286.436562 -260.65353)
				)
			)
		)
		(polygon
			(pts
				(arc
					(start 280.636726 -260.65353)
					(mid 281.187906 -260.10235)
					(end 280.636726 -259.55117)
				)
				(arc
					(start 279.236678 -259.55117)
					(mid 278.685498 -260.10235)
					(end 279.236678 -260.65353)
				)
			)
		)
		(polygon
			(pts
				(arc
					(start 286.836612 -258.853432)
					(mid 287.387792 -258.302252)
					(end 286.836612 -257.751072)
				)
				(arc
					(start 285.436564 -257.751072)
					(mid 284.885384 -258.302252)
					(end 285.436564 -258.853432)
				)
			)
		)
		(polygon
			(pts
				(arc
					(start 279.636728 -258.853432)
					(mid 280.187908 -258.302252)
					(end 279.636728 -257.751072)
				)
				(arc
					(start 278.23668 -257.751072)
					(mid 277.6855 -258.302252)
					(end 278.23668 -258.853432)
				)
			)
		)
		(polygon
			(pts
				(arc
					(start 287.83661 -257.053588)
					(mid 288.38779 -256.502408)
					(end 287.83661 -255.951228)
				)
				(arc
					(start 286.436562 -255.951228)
					(mid 285.885382 -256.502408)
					(end 286.436562 -257.053588)
				)
			)
		)
		(polygon
			(pts
				(arc
					(start 280.636726 -257.053588)
					(mid 281.187906 -256.502408)
					(end 280.636726 -255.951228)
				)
				(arc
					(start 279.236678 -255.951228)
					(mid 278.685498 -256.502408)
					(end 279.236678 -257.053588)
				)
			)
		)
		(polygon
			(pts
				(arc
					(start 286.836612 -255.25349)
					(mid 287.387792 -254.70231)
					(end 286.836612 -254.15113)
				)
				(arc
					(start 285.436564 -254.15113)
					(mid 284.885384 -254.70231)
					(end 285.436564 -255.25349)
				)
			)
		)
		(polygon
			(pts
				(arc
					(start 279.636728 -255.25349)
					(mid 280.187908 -254.70231)
					(end 279.636728 -254.15113)
				)
				(arc
					(start 278.23668 -254.15113)
					(mid 277.6855 -254.70231)
					(end 278.23668 -255.25349)
				)
			)
		)
		(polygon
			(pts
				(arc
					(start 287.83661 -253.453392)
					(mid 288.38779 -252.902212)
					(end 287.83661 -252.351032)
				)
				(arc
					(start 286.436562 -252.351032)
					(mid 285.885382 -252.902212)
					(end 286.436562 -253.453392)
				)
			)
		)
		(polygon
			(pts
				(arc
					(start 280.636726 -253.453392)
					(mid 281.187906 -252.902212)
					(end 280.636726 -252.351032)
				)
				(arc
					(start 279.236678 -252.351032)
					(mid 278.685498 -252.902212)
					(end 279.236678 -253.453392)
				)
			)
		)
		(polygon
			(pts
				(arc
					(start 286.836612 -251.653548)
					(mid 287.387792 -251.102368)
					(end 286.836612 -250.551188)
				)
				(arc
					(start 285.436564 -250.551188)
					(mid 284.885384 -251.102368)
					(end 285.436564 -251.653548)
				)
			)
		)
		(polygon
			(pts
				(arc
					(start 279.636728 -251.653548)
					(mid 280.187908 -251.102368)
					(end 279.636728 -250.551188)
				)
				(arc
					(start 278.23668 -250.551188)
					(mid 277.6855 -251.102368)
					(end 278.23668 -251.653548)
				)
			)
		)
		(polygon
			(pts
				(arc
					(start 240.871756 -178.87696)
					(mid 239.92498 -179.182145)
					(end 240.236502 -180.126894)
				)
				(arc
					(start 242.236498 -181.126892)
					(mid 243.17706 -180.813202)
					(end 242.86337 -179.87264)
				)
			)
		)
		(polygon
			(pts
				(arc
					(start 283.563314 -178.872642)
					(mid 282.622752 -179.186332)
					(end 282.936442 -180.126894)
				)
				(arc
					(start 284.928056 -181.122574)
					(mid 285.874832 -180.817389)
					(end 285.56331 -179.87264)
				)
			)
		)
		(polygon
			(pts
				(arc
					(start 281.074876 -178.149504)
					(mid 281.399742 -177.174906)
					(end 280.425144 -176.85004)
				)
				(xy 280.423874 -176.847754) (xy 278.424132 -177.847752) (xy 278.424132 -177.848006)
				(arc
					(start 278.425148 -177.850038)
					(mid 278.100282 -178.824636)
					(end 279.07488 -179.149502)
				)
				(xy 279.07615 -179.151788) (xy 281.076146 -178.15179)
			)
		)
		(polygon
			(pts
				(arc
					(start 238.374936 -178.149504)
					(mid 238.699802 -177.174906)
					(end 237.725204 -176.85004)
				)
				(xy 237.723934 -176.847754) (xy 235.724192 -177.847752) (xy 235.724192 -177.848006)
				(arc
					(start 235.725208 -177.850038)
					(mid 235.400342 -178.824636)
					(end 236.37494 -179.149502)
				)
				(xy 236.37621 -179.151788) (xy 238.376206 -178.15179)
			)
		)
		(polygon
			(pts
				(arc
					(start 240.871756 -174.876968)
					(mid 239.92498 -175.182153)
					(end 240.236502 -176.126902)
				)
				(arc
					(start 242.236498 -177.1269)
					(mid 243.17706 -176.81321)
					(end 242.86337 -175.872648)
				)
			)
		)
		(polygon
			(pts
				(arc
					(start 283.563314 -174.87265)
					(mid 282.622752 -175.18634)
					(end 282.936442 -176.126902)
				)
				(arc
					(start 284.928056 -177.122582)
					(mid 285.874832 -176.817397)
					(end 285.56331 -175.872648)
				)
			)
		)
		(polygon
			(pts
				(arc
					(start 281.074876 -174.149512)
					(mid 281.399742 -173.174914)
					(end 280.425144 -172.850048)
				)
				(xy 280.423874 -172.847762) (xy 278.424132 -173.84776) (xy 278.424132 -173.848014)
				(arc
					(start 278.425148 -173.850046)
					(mid 278.100282 -174.824644)
					(end 279.07488 -175.14951)
				)
				(xy 279.07615 -175.151796) (xy 281.076146 -174.151798)
			)
		)
		(polygon
			(pts
				(arc
					(start 238.374936 -174.149512)
					(mid 238.699802 -173.174914)
					(end 237.725204 -172.850048)
				)
				(xy 237.723934 -172.847762) (xy 235.724192 -173.84776) (xy 235.724192 -173.848014)
				(arc
					(start 235.725208 -173.850046)
					(mid 235.400342 -174.824644)
					(end 236.37494 -175.14951)
				)
				(xy 236.37621 -175.151796) (xy 238.376206 -174.151798)
			)
		)
		(polygon
			(pts
				(arc
					(start 240.871756 -170.876976)
					(mid 239.92498 -171.182161)
					(end 240.236502 -172.12691)
				)
				(arc
					(start 242.236498 -173.126908)
					(mid 243.17706 -172.813218)
					(end 242.86337 -171.872656)
				)
			)
		)
		(polygon
			(pts
				(arc
					(start 283.563314 -170.872658)
					(mid 282.622752 -171.186348)
					(end 282.936442 -172.12691)
				)
				(arc
					(start 284.928056 -173.12259)
					(mid 285.874832 -172.817405)
					(end 285.56331 -171.872656)
				)
			)
		)
		(polygon
			(pts
				(arc
					(start 281.074876 -170.14952)
					(mid 281.399742 -169.174922)
					(end 280.425144 -168.850056)
				)
				(xy 280.423874 -168.84777) (xy 278.424132 -169.847768) (xy 278.424132 -169.848022)
				(arc
					(start 278.425148 -169.850054)
					(mid 278.100282 -170.824652)
					(end 279.07488 -171.149518)
				)
				(xy 279.07615 -171.151804) (xy 281.076146 -170.151806)
			)
		)
		(polygon
			(pts
				(arc
					(start 238.374936 -170.14952)
					(mid 238.699802 -169.174922)
					(end 237.725204 -168.850056)
				)
				(xy 237.723934 -168.84777) (xy 235.724192 -169.847768) (xy 235.724192 -169.848022)
				(arc
					(start 235.725208 -169.850054)
					(mid 235.400342 -170.824652)
					(end 236.37494 -171.149518)
				)
				(xy 236.37621 -171.151804) (xy 238.376206 -170.151806)
			)
		)
		(polygon
			(pts
				(arc
					(start 240.871756 -166.876984)
					(mid 239.92498 -167.182169)
					(end 240.236502 -168.126918)
				)
				(arc
					(start 242.236498 -169.126916)
					(mid 243.17706 -168.813226)
					(end 242.86337 -167.872664)
				)
			)
		)
		(polygon
			(pts
				(arc
					(start 283.563314 -166.872666)
					(mid 282.622752 -167.186356)
					(end 282.936442 -168.126918)
				)
				(arc
					(start 284.928056 -169.122598)
					(mid 285.874832 -168.817413)
					(end 285.56331 -167.872664)
				)
			)
		)
		(polygon
			(pts
				(arc
					(start 281.074876 -166.149528)
					(mid 281.399742 -165.17493)
					(end 280.425144 -164.850064)
				)
				(xy 280.423874 -164.847778) (xy 278.424132 -165.847776) (xy 278.424132 -165.84803)
				(arc
					(start 278.425148 -165.850062)
					(mid 278.100282 -166.82466)
					(end 279.07488 -167.149526)
				)
				(xy 279.07615 -167.151812) (xy 281.076146 -166.151814)
			)
		)
		(polygon
			(pts
				(arc
					(start 238.374936 -166.149528)
					(mid 238.699802 -165.17493)
					(end 237.725204 -164.850064)
				)
				(xy 237.723934 -164.847778) (xy 235.724192 -165.847776) (xy 235.724192 -165.84803)
				(arc
					(start 235.725208 -165.850062)
					(mid 235.400342 -166.82466)
					(end 236.37494 -167.149526)
				)
				(xy 236.37621 -167.151812) (xy 238.376206 -166.151814)
			)
		)
		(polygon
			(pts
				(arc
					(start 283.563314 -162.872674)
					(mid 282.622752 -163.186364)
					(end 282.936442 -164.126926)
				)
				(arc
					(start 284.928056 -165.122606)
					(mid 285.874832 -164.817421)
					(end 285.56331 -163.872672)
				)
			)
		)
		(polygon
			(pts
				(arc
					(start 240.877344 -162.845496)
					(mid 239.895939 -163.172546)
					(end 240.222786 -164.154104)
				)
				(arc
					(start 242.222782 -165.154102)
					(mid 243.204238 -164.82695)
					(end 242.877086 -163.845494)
				)
			)
		)
		(polygon
			(pts
				(arc
					(start 482.870002 -162.178238)
					(mid 482.488875 -161.797492)
					(end 482.108002 -162.178492)
				)
				(arc
					(start 482.108002 -163.321492)
					(mid 482.489002 -163.702492)
					(end 482.870002 -163.321492)
				)
			)
		)
		(polygon
			(pts
				(arc
					(start 438.6199 -162.178238)
					(mid 438.238773 -161.797492)
					(end 437.8579 -162.178492)
				)
				(arc
					(start 437.8579 -163.321492)
					(mid 438.2389 -163.702492)
					(end 438.6199 -163.321492)
				)
			)
		)
		(polygon
			(pts
				(arc
					(start 419.770052 -162.178238)
					(mid 419.388925 -161.797492)
					(end 419.008052 -162.178492)
				)
				(arc
					(start 419.008052 -163.321492)
					(mid 419.389052 -163.702492)
					(end 419.770052 -163.321492)
				)
			)
		)
		(polygon
			(pts
				(arc
					(start 388.21995 -162.178238)
					(mid 387.838823 -161.797492)
					(end 387.45795 -162.178492)
				)
				(arc
					(start 387.45795 -163.321492)
					(mid 387.83895 -163.702492)
					(end 388.21995 -163.321492)
				)
			)
		)
		(polygon
			(pts
				(arc
					(start 356.670102 -162.178238)
					(mid 356.288975 -161.797492)
					(end 355.908102 -162.178492)
				)
				(arc
					(start 355.908102 -163.321492)
					(mid 356.289102 -163.702492)
					(end 356.670102 -163.321492)
				)
			)
		)
		(polygon
			(pts
				(arc
					(start 325.12 -162.178238)
					(mid 324.738873 -161.797492)
					(end 324.358 -162.178492)
				)
				(arc
					(start 324.358 -163.321492)
					(mid 324.739 -163.702492)
					(end 325.12 -163.321492)
				)
			)
		)
		(polygon
			(pts
				(arc
					(start 190.639954 -162.178238)
					(mid 190.258827 -161.797492)
					(end 189.877954 -162.178492)
				)
				(arc
					(start 189.877954 -163.321492)
					(mid 190.258954 -163.702492)
					(end 190.639954 -163.321492)
				)
			)
		)
		(polygon
			(pts
				(arc
					(start 159.089852 -162.178238)
					(mid 158.708725 -161.797492)
					(end 158.327852 -162.178492)
				)
				(arc
					(start 158.327852 -163.321492)
					(mid 158.708852 -163.702492)
					(end 159.089852 -163.321492)
				)
			)
		)
		(polygon
			(pts
				(arc
					(start 127.53975 -162.178238)
					(mid 127.158623 -161.797492)
					(end 126.77775 -162.178492)
				)
				(arc
					(start 126.77775 -163.321492)
					(mid 127.15875 -163.702492)
					(end 127.53975 -163.321492)
				)
			)
		)
		(polygon
			(pts
				(arc
					(start 95.989902 -162.178238)
					(mid 95.608775 -161.797492)
					(end 95.227902 -162.178492)
				)
				(arc
					(start 95.227902 -163.321492)
					(mid 95.608902 -163.702492)
					(end 95.989902 -163.321492)
				)
			)
		)
		(polygon
			(pts
				(arc
					(start 64.4398 -162.178238)
					(mid 64.058673 -161.797492)
					(end 63.6778 -162.178492)
				)
				(arc
					(start 63.6778 -163.321492)
					(mid 64.0588 -163.702492)
					(end 64.4398 -163.321492)
				)
			)
		)
		(polygon
			(pts
				(arc
					(start 32.889952 -162.178238)
					(mid 32.508825 -161.797492)
					(end 32.127952 -162.178492)
				)
				(arc
					(start 32.127952 -163.321492)
					(mid 32.508952 -163.702492)
					(end 32.889952 -163.321492)
				)
			)
		)
		(polygon
			(pts
				(xy 486.306114 -161.149792) (xy 483.943914 -161.149792) (xy 483.943914 -164.350192) (xy 486.306114 -164.350192)
			)
		)
		(polygon
			(pts
				(xy 454.756012 -161.149792) (xy 452.393812 -161.149792) (xy 452.393812 -164.350192) (xy 454.756012 -164.350192)
			)
		)
		(polygon
			(pts
				(xy 423.206164 -161.149792) (xy 420.843964 -161.149792) (xy 420.843964 -164.350192) (xy 423.206164 -164.350192)
			)
		)
		(polygon
			(pts
				(xy 391.656062 -161.149792) (xy 389.293862 -161.149792) (xy 389.293862 -164.350192) (xy 391.656062 -164.350192)
			)
		)
		(polygon
			(pts
				(xy 360.106214 -161.149792) (xy 357.744014 -161.149792) (xy 357.744014 -164.350192) (xy 360.106214 -164.350192)
			)
		)
		(polygon
			(pts
				(xy 328.556112 -161.149792) (xy 326.193912 -161.149792) (xy 326.193912 -164.350192) (xy 328.556112 -164.350192)
			)
		)
		(polygon
			(pts
				(xy 188.956188 -161.149792) (xy 186.593988 -161.149792) (xy 186.593988 -164.350192) (xy 188.956188 -164.350192)
			)
		)
		(polygon
			(pts
				(xy 157.406086 -161.149792) (xy 155.043886 -161.149792) (xy 155.043886 -164.350192) (xy 157.406086 -164.350192)
			)
		)
		(polygon
			(pts
				(xy 125.855984 -161.149792) (xy 123.493784 -161.149792) (xy 123.493784 -164.350192) (xy 125.855984 -164.350192)
			)
		)
		(polygon
			(pts
				(xy 94.306136 -161.149792) (xy 91.943936 -161.149792) (xy 91.943936 -164.350192) (xy 94.306136 -164.350192)
			)
		)
		(polygon
			(pts
				(xy 62.756034 -161.149792) (xy 60.393834 -161.149792) (xy 60.393834 -164.350192) (xy 62.756034 -164.350192)
			)
		)
		(polygon
			(pts
				(xy 31.206186 -161.149792) (xy 28.843986 -161.149792) (xy 28.843986 -164.350192) (xy 31.206186 -164.350192)
			)
		)
		(polygon
			(pts
				(arc
					(start 281.07386 -162.14725)
					(mid 281.397456 -161.175954)
					(end 280.42616 -160.852358)
				)
				(xy 278.426418 -161.852102)
				(arc
					(start 278.426418 -161.852356)
					(mid 278.102619 -162.8235)
					(end 279.073864 -163.147248)
				)
			)
		)
		(polygon
			(pts
				(arc
					(start 238.377222 -162.154108)
					(mid 238.704374 -161.172652)
					(end 237.722918 -160.8455)
				)
				(arc
					(start 235.733844 -161.840164)
					(mid 235.393447 -162.821194)
					(end 236.377226 -163.154106)
				)
			)
		)
		(polygon
			(pts
				(arc
					(start 479.841814 -159.117792)
					(mid 479.826935 -159.081871)
					(end 479.791014 -159.066992)
				)
				(arc
					(start 478.978214 -159.066992)
					(mid 478.942293 -159.081871)
					(end 478.927414 -159.117792)
				)
				(arc
					(start 478.927414 -159.320992)
					(mid 478.942293 -159.356913)
					(end 478.978214 -159.371792)
				)
				(arc
					(start 479.791014 -159.371792)
					(mid 479.826935 -159.356913)
					(end 479.841814 -159.320992)
				)
			)
		)
		(polygon
			(pts
				(arc
					(start 441.941712 -159.117792)
					(mid 441.926833 -159.081871)
					(end 441.890912 -159.066992)
				)
				(arc
					(start 441.078112 -159.066992)
					(mid 441.042191 -159.081871)
					(end 441.027312 -159.117792)
				)
				(arc
					(start 441.027312 -159.320992)
					(mid 441.042191 -159.356913)
					(end 441.078112 -159.371792)
				)
				(arc
					(start 441.890912 -159.371792)
					(mid 441.926833 -159.356913)
					(end 441.941712 -159.320992)
				)
			)
		)
		(polygon
			(pts
				(arc
					(start 416.741864 -159.117792)
					(mid 416.726985 -159.081871)
					(end 416.691064 -159.066992)
				)
				(arc
					(start 415.878264 -159.066992)
					(mid 415.842343 -159.081871)
					(end 415.827464 -159.117792)
				)
				(arc
					(start 415.827464 -159.320992)
					(mid 415.842343 -159.356913)
					(end 415.878264 -159.371792)
				)
				(arc
					(start 416.691064 -159.371792)
					(mid 416.726985 -159.356913)
					(end 416.741864 -159.320992)
				)
			)
		)
		(polygon
			(pts
				(arc
					(start 385.191762 -159.117792)
					(mid 385.176883 -159.081871)
					(end 385.140962 -159.066992)
				)
				(arc
					(start 384.328162 -159.066992)
					(mid 384.292241 -159.081871)
					(end 384.277362 -159.117792)
				)
				(arc
					(start 384.277362 -159.320992)
					(mid 384.292241 -159.356913)
					(end 384.328162 -159.371792)
				)
				(arc
					(start 385.140962 -159.371792)
					(mid 385.176883 -159.356913)
					(end 385.191762 -159.320992)
				)
			)
		)
		(polygon
			(pts
				(arc
					(start 353.641914 -159.117792)
					(mid 353.627035 -159.081871)
					(end 353.591114 -159.066992)
				)
				(arc
					(start 352.778314 -159.066992)
					(mid 352.742393 -159.081871)
					(end 352.727514 -159.117792)
				)
				(arc
					(start 352.727514 -159.320992)
					(mid 352.742393 -159.356913)
					(end 352.778314 -159.371792)
				)
				(arc
					(start 353.591114 -159.371792)
					(mid 353.627035 -159.356913)
					(end 353.641914 -159.320992)
				)
			)
		)
		(polygon
			(pts
				(arc
					(start 322.091812 -159.117792)
					(mid 322.076933 -159.081871)
					(end 322.041012 -159.066992)
				)
				(arc
					(start 321.228212 -159.066992)
					(mid 321.192291 -159.081871)
					(end 321.177412 -159.117792)
				)
				(arc
					(start 321.177412 -159.320992)
					(mid 321.192291 -159.356913)
					(end 321.228212 -159.371792)
				)
				(arc
					(start 322.041012 -159.371792)
					(mid 322.076933 -159.356913)
					(end 322.091812 -159.320992)
				)
			)
		)
		(polygon
			(pts
				(arc
					(start 190.670688 -159.117792)
					(mid 190.655809 -159.081871)
					(end 190.619888 -159.066992)
				)
				(arc
					(start 189.807088 -159.066992)
					(mid 189.771167 -159.081871)
					(end 189.756288 -159.117792)
				)
				(arc
					(start 189.756288 -159.320992)
					(mid 189.771167 -159.356913)
					(end 189.807088 -159.371792)
				)
				(arc
					(start 190.619888 -159.371792)
					(mid 190.655809 -159.356913)
					(end 190.670688 -159.320992)
				)
			)
		)
		(polygon
			(pts
				(arc
					(start 159.120586 -159.117792)
					(mid 159.105707 -159.081871)
					(end 159.069786 -159.066992)
				)
				(arc
					(start 158.256986 -159.066992)
					(mid 158.221065 -159.081871)
					(end 158.206186 -159.117792)
				)
				(arc
					(start 158.206186 -159.320992)
					(mid 158.221065 -159.356913)
					(end 158.256986 -159.371792)
				)
				(arc
					(start 159.069786 -159.371792)
					(mid 159.105707 -159.356913)
					(end 159.120586 -159.320992)
				)
			)
		)
		(polygon
			(pts
				(arc
					(start 127.570484 -159.117792)
					(mid 127.555605 -159.081871)
					(end 127.519684 -159.066992)
				)
				(arc
					(start 126.706884 -159.066992)
					(mid 126.670963 -159.081871)
					(end 126.656084 -159.117792)
				)
				(arc
					(start 126.656084 -159.320992)
					(mid 126.670963 -159.356913)
					(end 126.706884 -159.371792)
				)
				(arc
					(start 127.519684 -159.371792)
					(mid 127.555605 -159.356913)
					(end 127.570484 -159.320992)
				)
			)
		)
		(polygon
			(pts
				(arc
					(start 96.020636 -159.117792)
					(mid 96.005757 -159.081871)
					(end 95.969836 -159.066992)
				)
				(arc
					(start 95.157036 -159.066992)
					(mid 95.121115 -159.081871)
					(end 95.106236 -159.117792)
				)
				(arc
					(start 95.106236 -159.320992)
					(mid 95.121115 -159.356913)
					(end 95.157036 -159.371792)
				)
				(arc
					(start 95.969836 -159.371792)
					(mid 96.005757 -159.356913)
					(end 96.020636 -159.320992)
				)
			)
		)
		(polygon
			(pts
				(arc
					(start 64.470534 -159.117792)
					(mid 64.455655 -159.081871)
					(end 64.419734 -159.066992)
				)
				(arc
					(start 63.606934 -159.066992)
					(mid 63.571013 -159.081871)
					(end 63.556134 -159.117792)
				)
				(arc
					(start 63.556134 -159.320992)
					(mid 63.571013 -159.356913)
					(end 63.606934 -159.371792)
				)
				(arc
					(start 64.419734 -159.371792)
					(mid 64.455655 -159.356913)
					(end 64.470534 -159.320992)
				)
			)
		)
		(polygon
			(pts
				(arc
					(start 32.920686 -159.117792)
					(mid 32.905807 -159.081871)
					(end 32.869886 -159.066992)
				)
				(arc
					(start 32.057086 -159.066992)
					(mid 32.021165 -159.081871)
					(end 32.006286 -159.117792)
				)
				(arc
					(start 32.006286 -159.320992)
					(mid 32.021165 -159.356913)
					(end 32.057086 -159.371792)
				)
				(arc
					(start 32.869886 -159.371792)
					(mid 32.905807 -159.356913)
					(end 32.920686 -159.320992)
				)
			)
		)
		(polygon
			(pts
				(arc
					(start 283.571696 -158.877)
					(mid 282.62492 -159.182185)
					(end 282.936442 -160.126934)
				)
				(arc
					(start 284.936438 -161.126932)
					(mid 285.877 -160.813242)
					(end 285.56331 -159.87268)
				)
			)
		)
		(polygon
			(pts
				(arc
					(start 240.87709 -158.845504)
					(mid 239.895634 -159.172656)
					(end 240.222786 -160.154112)
				)
				(arc
					(start 242.222528 -161.15411)
					(mid 243.204289 -160.82711)
					(end 242.877086 -159.845502)
				)
			)
		)
		(polygon
			(pts
				(arc
					(start 479.841814 -158.558992)
					(mid 479.826935 -158.523071)
					(end 479.791014 -158.508192)
				)
				(arc
					(start 478.978214 -158.508192)
					(mid 478.942293 -158.523071)
					(end 478.927414 -158.558992)
				)
				(arc
					(start 478.927414 -158.762192)
					(mid 478.942293 -158.798113)
					(end 478.978214 -158.812992)
				)
				(arc
					(start 479.791014 -158.812992)
					(mid 479.826935 -158.798113)
					(end 479.841814 -158.762192)
				)
			)
		)
		(polygon
			(pts
				(arc
					(start 441.941712 -158.558992)
					(mid 441.926833 -158.523071)
					(end 441.890912 -158.508192)
				)
				(arc
					(start 441.078112 -158.508192)
					(mid 441.042191 -158.523071)
					(end 441.027312 -158.558992)
				)
				(arc
					(start 441.027312 -158.762192)
					(mid 441.042191 -158.798113)
					(end 441.078112 -158.812992)
				)
				(arc
					(start 441.890912 -158.812992)
					(mid 441.926833 -158.798113)
					(end 441.941712 -158.762192)
				)
			)
		)
		(polygon
			(pts
				(arc
					(start 416.741864 -158.558992)
					(mid 416.726985 -158.523071)
					(end 416.691064 -158.508192)
				)
				(arc
					(start 415.878264 -158.508192)
					(mid 415.842343 -158.523071)
					(end 415.827464 -158.558992)
				)
				(arc
					(start 415.827464 -158.762192)
					(mid 415.842343 -158.798113)
					(end 415.878264 -158.812992)
				)
				(arc
					(start 416.691064 -158.812992)
					(mid 416.726985 -158.798113)
					(end 416.741864 -158.762192)
				)
			)
		)
		(polygon
			(pts
				(arc
					(start 385.191762 -158.558992)
					(mid 385.176883 -158.523071)
					(end 385.140962 -158.508192)
				)
				(arc
					(start 384.328162 -158.508192)
					(mid 384.292241 -158.523071)
					(end 384.277362 -158.558992)
				)
				(arc
					(start 384.277362 -158.762192)
					(mid 384.292241 -158.798113)
					(end 384.328162 -158.812992)
				)
				(arc
					(start 385.140962 -158.812992)
					(mid 385.176883 -158.798113)
					(end 385.191762 -158.762192)
				)
			)
		)
		(polygon
			(pts
				(arc
					(start 353.641914 -158.558992)
					(mid 353.627035 -158.523071)
					(end 353.591114 -158.508192)
				)
				(arc
					(start 352.778314 -158.508192)
					(mid 352.742393 -158.523071)
					(end 352.727514 -158.558992)
				)
				(arc
					(start 352.727514 -158.762192)
					(mid 352.742393 -158.798113)
					(end 352.778314 -158.812992)
				)
				(arc
					(start 353.591114 -158.812992)
					(mid 353.627035 -158.798113)
					(end 353.641914 -158.762192)
				)
			)
		)
		(polygon
			(pts
				(arc
					(start 322.091812 -158.558992)
					(mid 322.076933 -158.523071)
					(end 322.041012 -158.508192)
				)
				(arc
					(start 321.228212 -158.508192)
					(mid 321.192291 -158.523071)
					(end 321.177412 -158.558992)
				)
				(arc
					(start 321.177412 -158.762192)
					(mid 321.192291 -158.798113)
					(end 321.228212 -158.812992)
				)
				(arc
					(start 322.041012 -158.812992)
					(mid 322.076933 -158.798113)
					(end 322.091812 -158.762192)
				)
			)
		)
		(polygon
			(pts
				(arc
					(start 190.670688 -158.558992)
					(mid 190.655809 -158.523071)
					(end 190.619888 -158.508192)
				)
				(arc
					(start 189.807088 -158.508192)
					(mid 189.771167 -158.523071)
					(end 189.756288 -158.558992)
				)
				(arc
					(start 189.756288 -158.762192)
					(mid 189.771167 -158.798113)
					(end 189.807088 -158.812992)
				)
				(arc
					(start 190.619888 -158.812992)
					(mid 190.655809 -158.798113)
					(end 190.670688 -158.762192)
				)
			)
		)
		(polygon
			(pts
				(arc
					(start 159.120586 -158.558992)
					(mid 159.105707 -158.523071)
					(end 159.069786 -158.508192)
				)
				(arc
					(start 158.256986 -158.508192)
					(mid 158.221065 -158.523071)
					(end 158.206186 -158.558992)
				)
				(arc
					(start 158.206186 -158.762192)
					(mid 158.221065 -158.798113)
					(end 158.256986 -158.812992)
				)
				(arc
					(start 159.069786 -158.812992)
					(mid 159.105707 -158.798113)
					(end 159.120586 -158.762192)
				)
			)
		)
		(polygon
			(pts
				(arc
					(start 127.570484 -158.558992)
					(mid 127.555605 -158.523071)
					(end 127.519684 -158.508192)
				)
				(arc
					(start 126.706884 -158.508192)
					(mid 126.670963 -158.523071)
					(end 126.656084 -158.558992)
				)
				(arc
					(start 126.656084 -158.762192)
					(mid 126.670963 -158.798113)
					(end 126.706884 -158.812992)
				)
				(arc
					(start 127.519684 -158.812992)
					(mid 127.555605 -158.798113)
					(end 127.570484 -158.762192)
				)
			)
		)
		(polygon
			(pts
				(arc
					(start 96.020636 -158.558992)
					(mid 96.005757 -158.523071)
					(end 95.969836 -158.508192)
				)
				(arc
					(start 95.157036 -158.508192)
					(mid 95.121115 -158.523071)
					(end 95.106236 -158.558992)
				)
				(arc
					(start 95.106236 -158.762192)
					(mid 95.121115 -158.798113)
					(end 95.157036 -158.812992)
				)
				(arc
					(start 95.969836 -158.812992)
					(mid 96.005757 -158.798113)
					(end 96.020636 -158.762192)
				)
			)
		)
		(polygon
			(pts
				(arc
					(start 64.470534 -158.558992)
					(mid 64.455655 -158.523071)
					(end 64.419734 -158.508192)
				)
				(arc
					(start 63.606934 -158.508192)
					(mid 63.571013 -158.523071)
					(end 63.556134 -158.558992)
				)
				(arc
					(start 63.556134 -158.762192)
					(mid 63.571013 -158.798113)
					(end 63.606934 -158.812992)
				)
				(arc
					(start 64.419734 -158.812992)
					(mid 64.455655 -158.798113)
					(end 64.470534 -158.762192)
				)
			)
		)
		(polygon
			(pts
				(arc
					(start 32.920686 -158.558992)
					(mid 32.905807 -158.523071)
					(end 32.869886 -158.508192)
				)
				(arc
					(start 32.057086 -158.508192)
					(mid 32.021165 -158.523071)
					(end 32.006286 -158.558992)
				)
				(arc
					(start 32.006286 -158.762192)
					(mid 32.021165 -158.798113)
					(end 32.057086 -158.812992)
				)
				(arc
					(start 32.869886 -158.812992)
					(mid 32.905807 -158.798113)
					(end 32.920686 -158.762192)
				)
			)
		)
		(polygon
			(pts
				(arc
					(start 478.120202 -158.368492)
					(mid 477.739202 -157.987492)
					(end 477.358202 -158.368492)
				)
				(arc
					(start 477.358202 -159.511746)
					(mid 477.739329 -159.892492)
					(end 478.120202 -159.511492)
				)
			)
		)
		(polygon
			(pts
				(arc
					(start 440.2201 -158.368492)
					(mid 439.8391 -157.987492)
					(end 439.4581 -158.368492)
				)
				(arc
					(start 439.4581 -159.511746)
					(mid 439.839227 -159.892492)
					(end 440.2201 -159.511492)
				)
			)
		)
		(polygon
			(pts
				(arc
					(start 415.020252 -158.368492)
					(mid 414.639252 -157.987492)
					(end 414.258252 -158.368492)
				)
				(arc
					(start 414.258252 -159.511746)
					(mid 414.639379 -159.892492)
					(end 415.020252 -159.511492)
				)
			)
		)
		(polygon
			(pts
				(arc
					(start 383.47015 -158.368492)
					(mid 383.08915 -157.987492)
					(end 382.70815 -158.368492)
				)
				(arc
					(start 382.70815 -159.511746)
					(mid 383.089277 -159.892492)
					(end 383.47015 -159.511492)
				)
			)
		)
		(polygon
			(pts
				(arc
					(start 351.920302 -158.368492)
					(mid 351.539302 -157.987492)
					(end 351.158302 -158.368492)
				)
				(arc
					(start 351.158302 -159.511746)
					(mid 351.539429 -159.892492)
					(end 351.920302 -159.511492)
				)
			)
		)
		(polygon
			(pts
				(arc
					(start 320.3702 -158.368492)
					(mid 319.9892 -157.987492)
					(end 319.6082 -158.368492)
				)
				(arc
					(start 319.6082 -159.511746)
					(mid 319.989327 -159.892492)
					(end 320.3702 -159.511492)
				)
			)
		)
		(polygon
			(pts
				(xy 486.306114 -157.340554) (xy 483.943914 -157.339792) (xy 483.943914 -160.540192) (xy 486.306114 -160.540192)
			)
		)
		(polygon
			(pts
				(xy 454.756012 -157.340554) (xy 452.393812 -157.339792) (xy 452.393812 -160.540192) (xy 454.756012 -160.540192)
			)
		)
		(polygon
			(pts
				(xy 423.206164 -157.340554) (xy 420.843964 -157.339792) (xy 420.843964 -160.540192) (xy 423.206164 -160.540192)
			)
		)
		(polygon
			(pts
				(xy 391.656062 -157.340554) (xy 389.293862 -157.339792) (xy 389.293862 -160.540192) (xy 391.656062 -160.540192)
			)
		)
		(polygon
			(pts
				(xy 360.106214 -157.340554) (xy 357.744014 -157.339792) (xy 357.744014 -160.540192) (xy 360.106214 -160.540192)
			)
		)
		(polygon
			(pts
				(xy 328.556112 -157.340554) (xy 326.193912 -157.339792) (xy 326.193912 -160.540192) (xy 328.556112 -160.540192)
			)
		)
		(polygon
			(pts
				(xy 188.956188 -157.340554) (xy 186.593988 -157.339792) (xy 186.593988 -160.540192) (xy 188.956188 -160.540192)
			)
		)
		(polygon
			(pts
				(xy 157.406086 -157.340554) (xy 155.043886 -157.339792) (xy 155.043886 -160.540192) (xy 157.406086 -160.540192)
			)
		)
		(polygon
			(pts
				(xy 125.855984 -157.340554) (xy 123.493784 -157.339792) (xy 123.493784 -160.540192) (xy 125.855984 -160.540192)
			)
		)
		(polygon
			(pts
				(xy 94.306136 -157.340554) (xy 91.943936 -157.339792) (xy 91.943936 -160.540192) (xy 94.306136 -160.540192)
			)
		)
		(polygon
			(pts
				(xy 62.756034 -157.340554) (xy 60.393834 -157.339792) (xy 60.393834 -160.540192) (xy 62.756034 -160.540192)
			)
		)
		(polygon
			(pts
				(xy 31.206186 -157.340554) (xy 28.843986 -157.339792) (xy 28.843986 -160.540192) (xy 31.206186 -160.540192)
			)
		)
		(polygon
			(pts
				(arc
					(start 281.07386 -158.147258)
					(mid 281.397456 -157.175962)
					(end 280.42616 -156.852366)
				)
				(xy 278.426418 -157.85211)
				(arc
					(start 278.426418 -157.852364)
					(mid 278.102619 -158.823508)
					(end 279.073864 -159.147256)
				)
			)
		)
		(polygon
			(pts
				(arc
					(start 238.377222 -158.154116)
					(mid 238.704374 -157.17266)
					(end 237.722918 -156.845508)
				)
				(arc
					(start 235.733844 -157.840172)
					(mid 235.393447 -158.821202)
					(end 236.377226 -159.154114)
				)
			)
		)
		(polygon
			(pts
				(arc
					(start 283.563314 -154.87269)
					(mid 282.622752 -155.18638)
					(end 282.936442 -156.126942)
				)
				(arc
					(start 284.928056 -157.122622)
					(mid 285.874832 -156.817437)
					(end 285.56331 -155.872688)
				)
			)
		)
		(polygon
			(pts
				(arc
					(start 240.87709 -154.845512)
					(mid 239.895634 -155.172664)
					(end 240.222786 -156.15412)
				)
				(arc
					(start 242.222528 -157.154118)
					(mid 243.204289 -156.827118)
					(end 242.877086 -155.84551)
				)
			)
		)
		(polygon
			(pts
				(arc
					(start 281.07386 -154.147266)
					(mid 281.397456 -153.17597)
					(end 280.42616 -152.852374)
				)
				(xy 278.426418 -153.852118)
				(arc
					(start 278.426418 -153.852372)
					(mid 278.102619 -154.823516)
					(end 279.073864 -155.147264)
				)
			)
		)
		(polygon
			(pts
				(arc
					(start 238.377222 -154.154124)
					(mid 238.704374 -153.172668)
					(end 237.722918 -152.845516)
				)
				(arc
					(start 235.733844 -153.84018)
					(mid 235.393447 -154.82121)
					(end 236.377226 -155.154122)
				)
			)
		)
		(polygon
			(pts
				(arc
					(start 283.563314 -150.872698)
					(mid 282.622752 -151.186388)
					(end 282.936442 -152.12695)
				)
				(arc
					(start 284.928056 -153.12263)
					(mid 285.874832 -152.817445)
					(end 285.56331 -151.872696)
				)
			)
		)
		(polygon
			(pts
				(arc
					(start 240.877344 -150.84552)
					(mid 239.895939 -151.17257)
					(end 240.222786 -152.154128)
				)
				(arc
					(start 242.222782 -153.154126)
					(mid 243.204238 -152.826974)
					(end 242.877086 -151.845518)
				)
			)
		)
		(polygon
			(pts
				(arc
					(start 281.07386 -150.147274)
					(mid 281.397456 -149.175978)
					(end 280.42616 -148.852382)
				)
				(xy 278.426418 -149.852126)
				(arc
					(start 278.426418 -149.85238)
					(mid 278.102619 -150.823524)
					(end 279.073864 -151.147272)
				)
			)
		)
		(polygon
			(pts
				(arc
					(start 238.377222 -150.154132)
					(mid 238.704374 -149.172676)
					(end 237.722918 -148.845524)
				)
				(arc
					(start 235.733844 -149.840188)
					(mid 235.393447 -150.821218)
					(end 236.377226 -151.15413)
				)
			)
		)
		(polygon
			(pts
				(arc
					(start 281.074876 -138.149584)
					(mid 281.399742 -137.174986)
					(end 280.425144 -136.85012)
				)
				(xy 280.423874 -136.847834) (xy 278.424132 -137.847832) (xy 278.424132 -137.848086)
				(arc
					(start 278.425148 -137.850118)
					(mid 278.100282 -138.824716)
					(end 279.07488 -139.149582)
				)
				(xy 279.07615 -139.151868) (xy 281.076146 -138.15187)
			)
		)
		(polygon
			(pts
				(arc
					(start 238.374936 -138.149584)
					(mid 238.699802 -137.174986)
					(end 237.725204 -136.85012)
				)
				(xy 237.723934 -136.847834) (xy 235.724192 -137.847832) (xy 235.724192 -137.848086)
				(arc
					(start 235.725208 -137.850118)
					(mid 235.400342 -138.824716)
					(end 236.37494 -139.149582)
				)
				(xy 236.37621 -139.151868) (xy 238.376206 -138.15187)
			)
		)
		(polygon
			(pts
				(arc
					(start 283.574744 -134.850124)
					(mid 282.600146 -135.17499)
					(end 282.925012 -136.149588)
				)
				(xy 282.923742 -136.151874) (xy 284.923738 -137.151872) (xy 284.923992 -137.151618)
				(arc
					(start 284.925008 -137.149586)
					(mid 285.899606 -136.82472)
					(end 285.57474 -135.850122)
				)
				(xy 285.57601 -135.847836) (xy 283.576014 -134.847838)
			)
		)
		(polygon
			(pts
				(arc
					(start 240.874804 -134.850124)
					(mid 239.900206 -135.17499)
					(end 240.225072 -136.149588)
				)
				(xy 240.223802 -136.151874) (xy 242.223798 -137.151872)
				(arc
					(start 242.225068 -137.149586)
					(mid 243.199666 -136.82472)
					(end 242.8748 -135.850122)
				)
				(xy 242.87607 -135.847836) (xy 240.876074 -134.847838) (xy 240.87582 -134.848092)
			)
		)
		(polygon
			(pts
				(xy 372.087394 -129.248916) (xy 359.10139 -129.248916) (xy 358.0257 -130.324606) (xy 358.0257 -146.763994)
				(xy 363.064806 -151.8031) (xy 375.973594 -151.8031) (xy 386.0419 -141.734794) (xy 386.0419 -136.014206)
				(xy 381.180594 -131.1529) (xy 373.991378 -131.1529) (xy 372.1989 -129.360422)
			)
		)
		(polygon
			(pts
				(arc
					(start 281.07386 -130.147314)
					(mid 281.397456 -129.176018)
					(end 280.42616 -128.852422)
				)
				(xy 278.426418 -129.852166)
				(arc
					(start 278.426418 -129.85242)
					(mid 278.102619 -130.823564)
					(end 279.073864 -131.147312)
				)
			)
		)
		(polygon
			(pts
				(arc
					(start 238.377222 -130.154172)
					(mid 238.704374 -129.172716)
					(end 237.722918 -128.845564)
				)
				(arc
					(start 235.733844 -129.840228)
					(mid 235.393447 -130.821258)
					(end 236.377226 -131.15417)
				)
			)
		)
		(polygon
			(pts
				(arc
					(start 283.563314 -126.872746)
					(mid 282.622752 -127.186436)
					(end 282.936442 -128.126998)
				)
				(arc
					(start 284.928056 -129.122678)
					(mid 285.874832 -128.817493)
					(end 285.56331 -127.872744)
				)
			)
		)
		(polygon
			(pts
				(arc
					(start 240.891822 -126.844552)
					(mid 239.891674 -127.163691)
					(end 240.219484 -128.161034)
				)
				(arc
					(start 242.21948 -129.161032)
					(mid 243.211096 -128.830324)
					(end 242.880388 -127.838708)
				)
			)
		)
		(polygon
			(pts
				(xy 153.164794 -126.1999) (xy 141.510512 -126.1999) (xy 137.7823 -129.928112) (xy 137.7823 -135.861806)
				(xy 137.665206 -135.9789) (xy 133.194806 -135.9789) (xy 128.9431 -140.230606) (xy 128.9431 -147.627594)
				(xy 129.479802 -148.164296) (xy 155.709874 -148.164296) (xy 160.0835 -143.79067) (xy 160.0835 -134.744206)
				(xy 157.0863 -131.747006) (xy 157.0863 -130.121406)
			)
		)
		(polygon
			(pts
				(arc
					(start 281.07386 -126.147322)
					(mid 281.397456 -125.176026)
					(end 280.42616 -124.85243)
				)
				(xy 278.426418 -125.852174)
				(arc
					(start 278.426418 -125.852428)
					(mid 278.102619 -126.823572)
					(end 279.073864 -127.14732)
				)
			)
		)
		(polygon
			(pts
				(arc
					(start 238.377222 -126.15418)
					(mid 238.704374 -125.172724)
					(end 237.722918 -124.845572)
				)
				(arc
					(start 235.733844 -125.840236)
					(mid 235.393447 -126.821266)
					(end 236.377226 -127.154178)
				)
			)
		)
		(polygon
			(pts
				(arc
					(start 283.563314 -122.872754)
					(mid 282.622752 -123.186444)
					(end 282.936442 -124.127006)
				)
				(arc
					(start 284.928056 -125.122686)
					(mid 285.874832 -124.817501)
					(end 285.56331 -123.872752)
				)
			)
		)
		(polygon
			(pts
				(arc
					(start 240.880392 -122.838718)
					(mid 239.888776 -123.169426)
					(end 240.219484 -124.161042)
				)
				(arc
					(start 242.20805 -125.155198)
					(mid 243.208198 -124.836059)
					(end 242.880388 -123.838716)
				)
			)
		)
		(polygon
			(pts
				(arc
					(start 281.07386 -122.14733)
					(mid 281.397456 -121.176034)
					(end 280.42616 -120.852438)
				)
				(xy 278.426418 -121.852182)
				(arc
					(start 278.426418 -121.852436)
					(mid 278.102619 -122.82358)
					(end 279.073864 -123.147328)
				)
			)
		)
		(polygon
			(pts
				(arc
					(start 238.3663 -122.159522)
					(mid 238.706697 -121.178492)
					(end 237.722918 -120.84558)
				)
				(arc
					(start 235.722922 -121.845578)
					(mid 235.39577 -122.827034)
					(end 236.377226 -123.154186)
				)
			)
		)
		(polygon
			(pts
				(arc
					(start 283.563314 -118.872762)
					(mid 282.622752 -119.186452)
					(end 282.936442 -120.127014)
				)
				(arc
					(start 284.928056 -121.122694)
					(mid 285.874832 -120.817509)
					(end 285.56331 -119.87276)
				)
			)
		)
		(polygon
			(pts
				(arc
					(start 240.87709 -118.845584)
					(mid 239.895634 -119.172736)
					(end 240.222786 -120.154192)
				)
				(arc
					(start 242.222528 -121.15419)
					(mid 243.204289 -120.82719)
					(end 242.877086 -119.845582)
				)
			)
		)
		(polygon
			(pts
				(arc
					(start 281.07386 -118.147338)
					(mid 281.397456 -117.176042)
					(end 280.42616 -116.852446)
				)
				(xy 278.426418 -117.85219)
				(arc
					(start 278.426418 -117.852444)
					(mid 278.102619 -118.823588)
					(end 279.073864 -119.147336)
				)
			)
		)
		(polygon
			(pts
				(arc
					(start 238.377222 -118.154196)
					(mid 238.704374 -117.17274)
					(end 237.722918 -116.845588)
				)
				(arc
					(start 235.733844 -117.840252)
					(mid 235.393447 -118.821282)
					(end 236.377226 -119.154194)
				)
			)
		)
		(polygon
			(pts
				(arc
					(start 283.563314 -114.87277)
					(mid 282.622752 -115.18646)
					(end 282.936442 -116.127022)
				)
				(arc
					(start 284.928056 -117.122702)
					(mid 285.874832 -116.817517)
					(end 285.56331 -115.872768)
				)
			)
		)
		(polygon
			(pts
				(arc
					(start 240.877344 -114.845592)
					(mid 239.895939 -115.172642)
					(end 240.222786 -116.1542)
				)
				(arc
					(start 242.222782 -117.154198)
					(mid 243.204238 -116.827046)
					(end 242.877086 -115.84559)
				)
			)
		)
		(polygon
			(pts
				(arc
					(start 281.063446 -114.127026)
					(mid 281.377136 -113.186464)
					(end 280.436574 -112.872774)
				)
				(arc
					(start 278.44496 -113.868708)
					(mid 278.120865 -114.809139)
					(end 279.06345 -115.127024)
				)
			)
		)
		(polygon
			(pts
				(arc
					(start 238.377222 -114.154204)
					(mid 238.704374 -113.172748)
					(end 237.722918 -112.845596)
				)
				(arc
					(start 235.733844 -113.84026)
					(mid 235.393447 -114.82129)
					(end 236.377226 -115.154202)
				)
			)
		)
		(polygon
			(pts
				(arc
					(start 283.574744 -106.85018)
					(mid 282.600146 -107.175046)
					(end 282.925012 -108.149644)
				)
				(xy 282.923742 -108.15193) (xy 284.923738 -109.151928) (xy 284.923992 -109.151674)
				(arc
					(start 284.925008 -109.149642)
					(mid 285.899606 -108.824776)
					(end 285.57474 -107.850178)
				)
				(xy 285.57601 -107.847892) (xy 283.576014 -106.847894)
			)
		)
		(polygon
			(pts
				(arc
					(start 240.874804 -106.85018)
					(mid 239.900206 -107.175046)
					(end 240.225072 -108.149644)
				)
				(xy 240.223802 -108.15193) (xy 242.223798 -109.151928)
				(arc
					(start 242.225068 -109.149642)
					(mid 243.199666 -108.824776)
					(end 242.8748 -107.850178)
				)
				(xy 242.87607 -107.847892) (xy 240.876074 -106.847894) (xy 240.87582 -106.848148)
			)
		)
		(polygon
			(pts
				(arc
					(start 240.871756 -82.577178)
					(mid 239.92498 -82.882363)
					(end 240.236502 -83.827112)
				)
				(arc
					(start 242.236498 -84.82711)
					(mid 243.17706 -84.51342)
					(end 242.86337 -83.572858)
				)
			)
		)
		(polygon
			(pts
				(arc
					(start 283.563314 -82.57286)
					(mid 282.622752 -82.88655)
					(end 282.936442 -83.827112)
				)
				(arc
					(start 284.928056 -84.822792)
					(mid 285.874832 -84.517607)
					(end 285.56331 -83.572858)
				)
			)
		)
		(polygon
			(pts
				(arc
					(start 281.074876 -81.849722)
					(mid 281.399742 -80.875124)
					(end 280.425144 -80.550258)
				)
				(xy 280.423874 -80.547972) (xy 278.424132 -81.54797) (xy 278.424132 -81.548224)
				(arc
					(start 278.425148 -81.550256)
					(mid 278.100282 -82.524854)
					(end 279.07488 -82.84972)
				)
				(xy 279.07615 -82.852006) (xy 281.076146 -81.852008)
			)
		)
		(polygon
			(pts
				(arc
					(start 238.374936 -81.849722)
					(mid 238.699802 -80.875124)
					(end 237.725204 -80.550258)
				)
				(xy 237.723934 -80.547972) (xy 235.724192 -81.54797) (xy 235.724192 -81.548224)
				(arc
					(start 235.725208 -81.550256)
					(mid 235.400342 -82.524854)
					(end 236.37494 -82.84972)
				)
				(xy 236.37621 -82.852006) (xy 238.376206 -81.852008)
			)
		)
		(polygon
			(pts
				(arc
					(start 283.563314 -78.572868)
					(mid 282.622752 -78.886558)
					(end 282.936442 -79.82712)
				)
				(arc
					(start 284.928056 -80.8228)
					(mid 285.874832 -80.517615)
					(end 285.56331 -79.572866)
				)
			)
		)
		(polygon
			(pts
				(arc
					(start 240.863374 -78.572868)
					(mid 239.922812 -78.886558)
					(end 240.236502 -79.82712)
				)
				(arc
					(start 242.228116 -80.8228)
					(mid 243.174892 -80.517615)
					(end 242.86337 -79.572866)
				)
			)
		)
		(polygon
			(pts
				(arc
					(start 281.074876 -77.84973)
					(mid 281.399742 -76.875132)
					(end 280.425144 -76.550266)
				)
				(xy 280.423874 -76.54798) (xy 278.424132 -77.547978) (xy 278.424132 -77.548232)
				(arc
					(start 278.425148 -77.550264)
					(mid 278.100282 -78.524862)
					(end 279.07488 -78.849728)
				)
				(xy 279.07615 -78.852014) (xy 281.076146 -77.852016)
			)
		)
		(polygon
			(pts
				(arc
					(start 238.374936 -77.84973)
					(mid 238.699802 -76.875132)
					(end 237.725204 -76.550266)
				)
				(xy 237.723934 -76.54798) (xy 235.724192 -77.547978) (xy 235.724192 -77.548232)
				(arc
					(start 235.725208 -77.550264)
					(mid 235.400342 -78.524862)
					(end 236.37494 -78.849728)
				)
				(xy 236.37621 -78.852014) (xy 238.376206 -77.852016)
			)
		)
		(polygon
			(pts
				(arc
					(start 283.563314 -74.572876)
					(mid 282.622752 -74.886566)
					(end 282.936442 -75.827128)
				)
				(arc
					(start 284.928056 -76.822808)
					(mid 285.874832 -76.517623)
					(end 285.56331 -75.572874)
				)
			)
		)
		(polygon
			(pts
				(arc
					(start 240.863374 -74.572876)
					(mid 239.922812 -74.886566)
					(end 240.236502 -75.827128)
				)
				(arc
					(start 242.228116 -76.822808)
					(mid 243.174892 -76.517623)
					(end 242.86337 -75.572874)
				)
			)
		)
		(polygon
			(pts
				(arc
					(start 281.074876 -73.849738)
					(mid 281.399742 -72.87514)
					(end 280.425144 -72.550274)
				)
				(xy 280.423874 -72.547988) (xy 278.424132 -73.547986) (xy 278.424132 -73.54824)
				(arc
					(start 278.425148 -73.550272)
					(mid 278.100282 -74.52487)
					(end 279.07488 -74.849736)
				)
				(xy 279.07615 -74.852022) (xy 281.076146 -73.852024)
			)
		)
		(polygon
			(pts
				(arc
					(start 238.374936 -73.849738)
					(mid 238.699802 -72.87514)
					(end 237.725204 -72.550274)
				)
				(xy 237.723934 -72.547988) (xy 235.724192 -73.547986) (xy 235.724192 -73.54824)
				(arc
					(start 235.725208 -73.550272)
					(mid 235.400342 -74.52487)
					(end 236.37494 -74.849736)
				)
				(xy 236.37621 -74.852022) (xy 238.376206 -73.852024)
			)
		)
		(polygon
			(pts
				(arc
					(start 283.563314 -70.572884)
					(mid 282.622752 -70.886574)
					(end 282.936442 -71.827136)
				)
				(arc
					(start 284.928056 -72.822816)
					(mid 285.874832 -72.517631)
					(end 285.56331 -71.572882)
				)
			)
		)
		(polygon
			(pts
				(arc
					(start 240.863374 -70.572884)
					(mid 239.922812 -70.886574)
					(end 240.236502 -71.827136)
				)
				(arc
					(start 242.228116 -72.822816)
					(mid 243.174892 -72.517631)
					(end 242.86337 -71.572882)
				)
			)
		)
		(polygon
			(pts
				(arc
					(start 281.074876 -69.849746)
					(mid 281.399742 -68.875148)
					(end 280.425144 -68.550282)
				)
				(xy 280.423874 -68.547996) (xy 278.424132 -69.547994) (xy 278.424132 -69.548248)
				(arc
					(start 278.425148 -69.55028)
					(mid 278.100282 -70.524878)
					(end 279.07488 -70.849744)
				)
				(xy 279.07615 -70.85203) (xy 281.076146 -69.852032)
			)
		)
		(polygon
			(pts
				(arc
					(start 238.374936 -69.849746)
					(mid 238.699802 -68.875148)
					(end 237.725204 -68.550282)
				)
				(xy 237.723934 -68.547996) (xy 235.724192 -69.547994) (xy 235.724192 -69.548248)
				(arc
					(start 235.725208 -69.55028)
					(mid 235.400342 -70.524878)
					(end 236.37494 -70.849744)
				)
				(xy 236.37621 -70.85203) (xy 238.376206 -69.852032)
			)
		)
		(polygon
			(pts
				(arc
					(start 240.871756 -66.57721)
					(mid 239.92498 -66.882395)
					(end 240.236502 -67.827144)
				)
				(arc
					(start 242.236498 -68.827142)
					(mid 243.17706 -68.513452)
					(end 242.86337 -67.57289)
				)
			)
		)
		(polygon
			(pts
				(arc
					(start 283.563314 -66.572892)
					(mid 282.622752 -66.886582)
					(end 282.936442 -67.827144)
				)
				(arc
					(start 284.928056 -68.822824)
					(mid 285.874832 -68.517639)
					(end 285.56331 -67.57289)
				)
			)
		)
		(polygon
			(pts
				(arc
					(start 281.074876 -65.849754)
					(mid 281.399742 -64.875156)
					(end 280.425144 -64.55029)
				)
				(xy 280.423874 -64.548004) (xy 278.424132 -65.548002) (xy 278.424132 -65.548256)
				(arc
					(start 278.425148 -65.550288)
					(mid 278.100282 -66.524886)
					(end 279.07488 -66.849752)
				)
				(xy 279.07615 -66.852038) (xy 281.076146 -65.85204)
			)
		)
		(polygon
			(pts
				(arc
					(start 238.374936 -65.849754)
					(mid 238.699802 -64.875156)
					(end 237.725204 -64.55029)
				)
				(xy 237.723934 -64.548004) (xy 235.723938 -65.548002)
				(arc
					(start 235.725208 -65.550288)
					(mid 235.400342 -66.524886)
					(end 236.37494 -66.849752)
				)
				(xy 236.37621 -66.852038) (xy 238.375952 -65.85204) (xy 238.375952 -65.851786)
			)
		)
		(polygon
			(pts
				(arc
					(start 240.871756 -62.577218)
					(mid 239.92498 -62.882403)
					(end 240.236502 -63.827152)
				)
				(arc
					(start 242.236498 -64.82715)
					(mid 243.17706 -64.51346)
					(end 242.86337 -63.572898)
				)
			)
		)
		(polygon
			(pts
				(arc
					(start 283.563314 -62.5729)
					(mid 282.622752 -62.88659)
					(end 282.936442 -63.827152)
				)
				(arc
					(start 284.928056 -64.822832)
					(mid 285.874832 -64.517647)
					(end 285.56331 -63.572898)
				)
			)
		)
		(polygon
			(pts
				(arc
					(start 281.074876 -61.849762)
					(mid 281.399742 -60.875164)
					(end 280.425144 -60.550298)
				)
				(xy 280.423874 -60.548012) (xy 278.424132 -61.54801) (xy 278.424132 -61.548264)
				(arc
					(start 278.425148 -61.550296)
					(mid 278.100282 -62.524894)
					(end 279.07488 -62.84976)
				)
				(xy 279.07615 -62.852046) (xy 281.076146 -61.852048)
			)
		)
		(polygon
			(pts
				(arc
					(start 238.374936 -61.849762)
					(mid 238.699802 -60.875164)
					(end 237.725204 -60.550298)
				)
				(xy 237.723934 -60.548012) (xy 235.724192 -61.54801) (xy 235.724192 -61.548264)
				(arc
					(start 235.725208 -61.550296)
					(mid 235.400342 -62.524894)
					(end 236.37494 -62.84976)
				)
				(xy 236.37621 -62.852046) (xy 238.376206 -61.852048)
			)
		)
		(polygon
			(pts
				(arc
					(start 240.871756 -58.577226)
					(mid 239.92498 -58.882411)
					(end 240.236502 -59.82716)
				)
				(arc
					(start 242.236498 -60.827158)
					(mid 243.17706 -60.513468)
					(end 242.86337 -59.572906)
				)
			)
		)
		(polygon
			(pts
				(arc
					(start 283.563314 -58.572908)
					(mid 282.622752 -58.886598)
					(end 282.936442 -59.82716)
				)
				(arc
					(start 284.928056 -60.82284)
					(mid 285.874832 -60.517655)
					(end 285.56331 -59.572906)
				)
			)
		)
		(polygon
			(pts
				(arc
					(start 281.074876 -57.84977)
					(mid 281.399742 -56.875172)
					(end 280.425144 -56.550306)
				)
				(xy 280.423874 -56.54802) (xy 278.424132 -57.548018) (xy 278.424132 -57.548272)
				(arc
					(start 278.425148 -57.550304)
					(mid 278.100282 -58.524902)
					(end 279.07488 -58.849768)
				)
				(xy 279.07615 -58.852054) (xy 281.076146 -57.852056)
			)
		)
		(polygon
			(pts
				(arc
					(start 238.374936 -57.84977)
					(mid 238.699802 -56.875172)
					(end 237.725204 -56.550306)
				)
				(xy 237.723934 -56.54802) (xy 235.724192 -57.548018) (xy 235.724192 -57.548272)
				(arc
					(start 235.725208 -57.550304)
					(mid 235.400342 -58.524902)
					(end 236.37494 -58.849768)
				)
				(xy 236.37621 -58.852054) (xy 238.376206 -57.852056)
			)
		)
		(polygon
			(pts
				(arc
					(start 240.871756 -54.577234)
					(mid 239.92498 -54.882419)
					(end 240.236502 -55.827168)
				)
				(arc
					(start 242.236498 -56.827166)
					(mid 243.17706 -56.513476)
					(end 242.86337 -55.572914)
				)
			)
		)
		(polygon
			(pts
				(arc
					(start 283.563314 -54.572916)
					(mid 282.622752 -54.886606)
					(end 282.936442 -55.827168)
				)
				(arc
					(start 284.928056 -56.822848)
					(mid 285.874832 -56.517663)
					(end 285.56331 -55.572914)
				)
			)
		)
		(polygon
			(pts
				(arc
					(start 281.074876 -53.849778)
					(mid 281.399742 -52.87518)
					(end 280.425144 -52.550314)
				)
				(xy 280.423874 -52.548028) (xy 278.424132 -53.548026) (xy 278.424132 -53.54828)
				(arc
					(start 278.425148 -53.550312)
					(mid 278.100282 -54.52491)
					(end 279.07488 -54.849776)
				)
				(xy 279.07615 -54.852062) (xy 281.076146 -53.852064)
			)
		)
		(polygon
			(pts
				(arc
					(start 238.374936 -53.849778)
					(mid 238.699802 -52.87518)
					(end 237.725204 -52.550314)
				)
				(xy 237.723934 -52.548028) (xy 235.724192 -53.548026) (xy 235.724192 -53.54828)
				(arc
					(start 235.725208 -53.550312)
					(mid 235.400342 -54.52491)
					(end 236.37494 -54.849776)
				)
				(xy 236.37621 -54.852062) (xy 238.376206 -53.852064)
			)
		)
		(polygon
			(pts
				(arc
					(start 283.563314 -50.572924)
					(mid 282.622752 -50.886614)
					(end 282.936442 -51.827176)
				)
				(arc
					(start 284.928056 -52.822856)
					(mid 285.874832 -52.517671)
					(end 285.56331 -51.572922)
				)
			)
		)
		(polygon
			(pts
				(arc
					(start 240.863374 -50.572924)
					(mid 239.922812 -50.886614)
					(end 240.236502 -51.827176)
				)
				(arc
					(start 242.228116 -52.822856)
					(mid 243.174892 -52.517671)
					(end 242.86337 -51.572922)
				)
			)
		)
		(polygon
			(pts
				(arc
					(start 281.074876 -49.849786)
					(mid 281.399742 -48.875188)
					(end 280.425144 -48.550322)
				)
				(xy 280.423874 -48.548036) (xy 278.424132 -49.548034) (xy 278.424132 -49.548288)
				(arc
					(start 278.425148 -49.55032)
					(mid 278.100282 -50.524918)
					(end 279.07488 -50.849784)
				)
				(xy 279.07615 -50.85207) (xy 281.076146 -49.852072)
			)
		)
		(polygon
			(pts
				(arc
					(start 238.374936 -49.849786)
					(mid 238.699802 -48.875188)
					(end 237.725204 -48.550322)
				)
				(xy 237.723934 -48.548036) (xy 235.724192 -49.548034) (xy 235.724192 -49.548288)
				(arc
					(start 235.725208 -49.55032)
					(mid 235.400342 -50.524918)
					(end 236.37494 -50.849784)
				)
				(xy 236.37621 -50.85207) (xy 238.376206 -49.852072)
			)
		)
		(polygon
			(pts
				(arc
					(start 482.870002 -47.178214)
					(mid 482.488875 -46.797468)
					(end 482.108002 -47.178468)
				)
				(arc
					(start 482.108002 -48.321468)
					(mid 482.489002 -48.702468)
					(end 482.870002 -48.321468)
				)
			)
		)
		(polygon
			(pts
				(arc
					(start 451.3199 -47.178214)
					(mid 450.938773 -46.797468)
					(end 450.5579 -47.178468)
				)
				(arc
					(start 450.5579 -48.321468)
					(mid 450.9389 -48.702468)
					(end 451.3199 -48.321468)
				)
			)
		)
		(polygon
			(pts
				(arc
					(start 419.770052 -47.178214)
					(mid 419.388925 -46.797468)
					(end 419.008052 -47.178468)
				)
				(arc
					(start 419.008052 -48.321468)
					(mid 419.389052 -48.702468)
					(end 419.770052 -48.321468)
				)
			)
		)
		(polygon
			(pts
				(arc
					(start 388.21995 -47.178214)
					(mid 387.838823 -46.797468)
					(end 387.45795 -47.178468)
				)
				(arc
					(start 387.45795 -48.321468)
					(mid 387.83895 -48.702468)
					(end 388.21995 -48.321468)
				)
			)
		)
		(polygon
			(pts
				(arc
					(start 190.639954 -47.178214)
					(mid 190.258827 -46.797468)
					(end 189.877954 -47.178468)
				)
				(arc
					(start 189.877954 -48.321468)
					(mid 190.258954 -48.702468)
					(end 190.639954 -48.321468)
				)
			)
		)
		(polygon
			(pts
				(arc
					(start 159.089852 -47.178214)
					(mid 158.708725 -46.797468)
					(end 158.327852 -47.178468)
				)
				(arc
					(start 158.327852 -48.321468)
					(mid 158.708852 -48.702468)
					(end 159.089852 -48.321468)
				)
			)
		)
		(polygon
			(pts
				(arc
					(start 127.53975 -47.178214)
					(mid 127.158623 -46.797468)
					(end 126.77775 -47.178468)
				)
				(arc
					(start 126.77775 -48.321468)
					(mid 127.15875 -48.702468)
					(end 127.53975 -48.321468)
				)
			)
		)
		(polygon
			(pts
				(arc
					(start 95.989902 -47.178214)
					(mid 95.608775 -46.797468)
					(end 95.227902 -47.178468)
				)
				(arc
					(start 95.227902 -48.321468)
					(mid 95.608902 -48.702468)
					(end 95.989902 -48.321468)
				)
			)
		)
		(polygon
			(pts
				(arc
					(start 64.4398 -47.178214)
					(mid 64.058673 -46.797468)
					(end 63.6778 -47.178468)
				)
				(arc
					(start 63.6778 -48.321468)
					(mid 64.0588 -48.702468)
					(end 64.4398 -48.321468)
				)
			)
		)
		(polygon
			(pts
				(arc
					(start 32.889952 -47.178214)
					(mid 32.508825 -46.797468)
					(end 32.127952 -47.178468)
				)
				(arc
					(start 32.127952 -48.321468)
					(mid 32.508952 -48.702468)
					(end 32.889952 -48.321468)
				)
			)
		)
		(polygon
			(pts
				(arc
					(start 356.675182 -47.178214)
					(mid 356.288975 -46.792388)
					(end 355.903022 -47.178468)
				)
				(arc
					(start 355.903022 -48.321468)
					(mid 356.289102 -48.707548)
					(end 356.675182 -48.321468)
				)
			)
		)
		(polygon
			(pts
				(arc
					(start 240.871756 -46.57725)
					(mid 239.92498 -46.882435)
					(end 240.236502 -47.827184)
				)
				(arc
					(start 242.236498 -48.827182)
					(mid 243.17706 -48.513492)
					(end 242.86337 -47.57293)
				)
			)
		)
		(polygon
			(pts
				(arc
					(start 283.563314 -46.572932)
					(mid 282.622752 -46.886622)
					(end 282.936442 -47.827184)
				)
				(arc
					(start 284.928056 -48.822864)
					(mid 285.874832 -48.517679)
					(end 285.56331 -47.57293)
				)
			)
		)
		(polygon
			(pts
				(xy 486.306114 -46.149768) (xy 483.943914 -46.149768) (xy 483.943914 -49.350168) (xy 486.306114 -49.350168)
			)
		)
		(polygon
			(pts
				(xy 454.756012 -46.149768) (xy 452.393812 -46.149768) (xy 452.393812 -49.350168) (xy 454.756012 -49.350168)
			)
		)
		(polygon
			(pts
				(xy 423.206164 -46.149768) (xy 420.843964 -46.149768) (xy 420.843964 -49.350168) (xy 423.206164 -49.350168)
			)
		)
		(polygon
			(pts
				(xy 391.656062 -46.149768) (xy 389.293862 -46.149768) (xy 389.293862 -49.350168) (xy 391.656062 -49.350168)
			)
		)
		(polygon
			(pts
				(xy 360.106214 -46.149768) (xy 357.744014 -46.149768) (xy 357.744014 -49.350168) (xy 360.106214 -49.350168)
			)
		)
		(polygon
			(pts
				(xy 328.556112 -46.149768) (xy 326.193912 -46.149768) (xy 326.193912 -49.350168) (xy 328.556112 -49.350168)
			)
		)
		(polygon
			(pts
				(xy 188.956188 -46.149768) (xy 186.593988 -46.149768) (xy 186.593988 -49.350168) (xy 188.956188 -49.350168)
			)
		)
		(polygon
			(pts
				(xy 157.406086 -46.149768) (xy 155.043886 -46.149768) (xy 155.043886 -49.350168) (xy 157.406086 -49.350168)
			)
		)
		(polygon
			(pts
				(xy 125.855984 -46.149768) (xy 123.493784 -46.149768) (xy 123.493784 -49.350168) (xy 125.855984 -49.350168)
			)
		)
		(polygon
			(pts
				(xy 94.306136 -46.149768) (xy 91.943936 -46.149768) (xy 91.943936 -49.350168) (xy 94.306136 -49.350168)
			)
		)
		(polygon
			(pts
				(xy 62.756034 -46.149768) (xy 60.393834 -46.149768) (xy 60.393834 -49.350168) (xy 62.756034 -49.350168)
			)
		)
		(polygon
			(pts
				(xy 31.206186 -46.149768) (xy 28.843986 -46.149768) (xy 28.843986 -49.350168) (xy 31.206186 -49.350168)
			)
		)
		(polygon
			(pts
				(arc
					(start 323.824854 -46.818042)
					(mid 324.2056 -46.436915)
					(end 323.8246 -46.056042)
				)
				(arc
					(start 322.6816 -46.056042)
					(mid 322.3006 -46.437042)
					(end 322.6816 -46.818042)
				)
			)
		)
		(polygon
			(pts
				(arc
					(start 383.908554 -46.5328)
					(mid 384.2893 -46.151673)
					(end 383.9083 -45.7708)
				)
				(arc
					(start 382.7653 -45.7708)
					(mid 382.3843 -46.1518)
					(end 382.7653 -46.5328)
				)
			)
		)
		(polygon
			(pts
				(arc
					(start 281.074876 -45.849794)
					(mid 281.399742 -44.875196)
					(end 280.425144 -44.55033)
				)
				(xy 280.423874 -44.548044) (xy 278.424132 -45.548042) (xy 278.424132 -45.548296)
				(arc
					(start 278.425148 -45.550328)
					(mid 278.100282 -46.524926)
					(end 279.07488 -46.849792)
				)
				(xy 279.07615 -46.852078) (xy 281.076146 -45.85208)
			)
		)
		(polygon
			(pts
				(arc
					(start 238.374936 -45.849794)
					(mid 238.699802 -44.875196)
					(end 237.725204 -44.55033)
				)
				(xy 237.723934 -44.548044) (xy 235.724192 -45.548042) (xy 235.724192 -45.548296)
				(arc
					(start 235.725208 -45.550328)
					(mid 235.400342 -46.524926)
					(end 236.37494 -46.849792)
				)
				(xy 236.37621 -46.852078) (xy 238.376206 -45.85208)
			)
		)
		(polygon
			(pts
				(arc
					(start 479.841814 -44.117768)
					(mid 479.826935 -44.081847)
					(end 479.791014 -44.066968)
				)
				(arc
					(start 478.978214 -44.066968)
					(mid 478.942293 -44.081847)
					(end 478.927414 -44.117768)
				)
				(arc
					(start 478.927414 -44.320968)
					(mid 478.942293 -44.356889)
					(end 478.978214 -44.371768)
				)
				(arc
					(start 479.791014 -44.371768)
					(mid 479.826935 -44.356889)
					(end 479.841814 -44.320968)
				)
			)
		)
		(polygon
			(pts
				(arc
					(start 448.291712 -44.117768)
					(mid 448.276833 -44.081847)
					(end 448.240912 -44.066968)
				)
				(arc
					(start 447.428112 -44.066968)
					(mid 447.392191 -44.081847)
					(end 447.377312 -44.117768)
				)
				(arc
					(start 447.377312 -44.320968)
					(mid 447.392191 -44.356889)
					(end 447.428112 -44.371768)
				)
				(arc
					(start 448.240912 -44.371768)
					(mid 448.276833 -44.356889)
					(end 448.291712 -44.320968)
				)
			)
		)
		(polygon
			(pts
				(arc
					(start 416.741864 -44.117768)
					(mid 416.726985 -44.081847)
					(end 416.691064 -44.066968)
				)
				(arc
					(start 415.878264 -44.066968)
					(mid 415.842343 -44.081847)
					(end 415.827464 -44.117768)
				)
				(arc
					(start 415.827464 -44.320968)
					(mid 415.842343 -44.356889)
					(end 415.878264 -44.371768)
				)
				(arc
					(start 416.691064 -44.371768)
					(mid 416.726985 -44.356889)
					(end 416.741864 -44.320968)
				)
			)
		)
		(polygon
			(pts
				(arc
					(start 385.191762 -44.117768)
					(mid 385.176883 -44.081847)
					(end 385.140962 -44.066968)
				)
				(arc
					(start 384.328162 -44.066968)
					(mid 384.292241 -44.081847)
					(end 384.277362 -44.117768)
				)
				(arc
					(start 384.277362 -44.320968)
					(mid 384.292241 -44.356889)
					(end 384.328162 -44.371768)
				)
				(arc
					(start 385.140962 -44.371768)
					(mid 385.176883 -44.356889)
					(end 385.191762 -44.320968)
				)
			)
		)
		(polygon
			(pts
				(arc
					(start 353.641914 -44.117768)
					(mid 353.627035 -44.081847)
					(end 353.591114 -44.066968)
				)
				(arc
					(start 352.778314 -44.066968)
					(mid 352.742393 -44.081847)
					(end 352.727514 -44.117768)
				)
				(arc
					(start 352.727514 -44.320968)
					(mid 352.742393 -44.356889)
					(end 352.778314 -44.371768)
				)
				(arc
					(start 353.591114 -44.371768)
					(mid 353.627035 -44.356889)
					(end 353.641914 -44.320968)
				)
			)
		)
		(polygon
			(pts
				(arc
					(start 322.091812 -44.117768)
					(mid 322.076933 -44.081847)
					(end 322.041012 -44.066968)
				)
				(arc
					(start 321.228212 -44.066968)
					(mid 321.192291 -44.081847)
					(end 321.177412 -44.117768)
				)
				(arc
					(start 321.177412 -44.320968)
					(mid 321.192291 -44.356889)
					(end 321.228212 -44.371768)
				)
				(arc
					(start 322.041012 -44.371768)
					(mid 322.076933 -44.356889)
					(end 322.091812 -44.320968)
				)
			)
		)
		(polygon
			(pts
				(arc
					(start 190.670688 -44.117768)
					(mid 190.655809 -44.081847)
					(end 190.619888 -44.066968)
				)
				(arc
					(start 189.807088 -44.066968)
					(mid 189.771167 -44.081847)
					(end 189.756288 -44.117768)
				)
				(arc
					(start 189.756288 -44.320968)
					(mid 189.771167 -44.356889)
					(end 189.807088 -44.371768)
				)
				(arc
					(start 190.619888 -44.371768)
					(mid 190.655809 -44.356889)
					(end 190.670688 -44.320968)
				)
			)
		)
		(polygon
			(pts
				(arc
					(start 159.120586 -44.117768)
					(mid 159.105707 -44.081847)
					(end 159.069786 -44.066968)
				)
				(arc
					(start 158.256986 -44.066968)
					(mid 158.221065 -44.081847)
					(end 158.206186 -44.117768)
				)
				(arc
					(start 158.206186 -44.320968)
					(mid 158.221065 -44.356889)
					(end 158.256986 -44.371768)
				)
				(arc
					(start 159.069786 -44.371768)
					(mid 159.105707 -44.356889)
					(end 159.120586 -44.320968)
				)
			)
		)
		(polygon
			(pts
				(arc
					(start 127.570484 -44.117768)
					(mid 127.555605 -44.081847)
					(end 127.519684 -44.066968)
				)
				(arc
					(start 126.706884 -44.066968)
					(mid 126.670963 -44.081847)
					(end 126.656084 -44.117768)
				)
				(arc
					(start 126.656084 -44.320968)
					(mid 126.670963 -44.356889)
					(end 126.706884 -44.371768)
				)
				(arc
					(start 127.519684 -44.371768)
					(mid 127.555605 -44.356889)
					(end 127.570484 -44.320968)
				)
			)
		)
		(polygon
			(pts
				(arc
					(start 96.020636 -44.117768)
					(mid 96.005757 -44.081847)
					(end 95.969836 -44.066968)
				)
				(arc
					(start 95.157036 -44.066968)
					(mid 95.121115 -44.081847)
					(end 95.106236 -44.117768)
				)
				(arc
					(start 95.106236 -44.320968)
					(mid 95.121115 -44.356889)
					(end 95.157036 -44.371768)
				)
				(arc
					(start 95.969836 -44.371768)
					(mid 96.005757 -44.356889)
					(end 96.020636 -44.320968)
				)
			)
		)
		(polygon
			(pts
				(arc
					(start 64.470534 -44.117768)
					(mid 64.455655 -44.081847)
					(end 64.419734 -44.066968)
				)
				(arc
					(start 63.606934 -44.066968)
					(mid 63.571013 -44.081847)
					(end 63.556134 -44.117768)
				)
				(arc
					(start 63.556134 -44.320968)
					(mid 63.571013 -44.356889)
					(end 63.606934 -44.371768)
				)
				(arc
					(start 64.419734 -44.371768)
					(mid 64.455655 -44.356889)
					(end 64.470534 -44.320968)
				)
			)
		)
		(polygon
			(pts
				(arc
					(start 32.920686 -44.117768)
					(mid 32.905807 -44.081847)
					(end 32.869886 -44.066968)
				)
				(arc
					(start 32.057086 -44.066968)
					(mid 32.021165 -44.081847)
					(end 32.006286 -44.117768)
				)
				(arc
					(start 32.006286 -44.320968)
					(mid 32.021165 -44.356889)
					(end 32.057086 -44.371768)
				)
				(arc
					(start 32.869886 -44.371768)
					(mid 32.905807 -44.356889)
					(end 32.920686 -44.320968)
				)
			)
		)
		(polygon
			(pts
				(arc
					(start 479.841814 -43.558968)
					(mid 479.826935 -43.523047)
					(end 479.791014 -43.508168)
				)
				(arc
					(start 478.978214 -43.508168)
					(mid 478.942293 -43.523047)
					(end 478.927414 -43.558968)
				)
				(arc
					(start 478.927414 -43.762168)
					(mid 478.942293 -43.798089)
					(end 478.978214 -43.812968)
				)
				(arc
					(start 479.791014 -43.812968)
					(mid 479.826935 -43.798089)
					(end 479.841814 -43.762168)
				)
			)
		)
		(polygon
			(pts
				(arc
					(start 448.291712 -43.558968)
					(mid 448.276833 -43.523047)
					(end 448.240912 -43.508168)
				)
				(arc
					(start 447.428112 -43.508168)
					(mid 447.392191 -43.523047)
					(end 447.377312 -43.558968)
				)
				(arc
					(start 447.377312 -43.762168)
					(mid 447.392191 -43.798089)
					(end 447.428112 -43.812968)
				)
				(arc
					(start 448.240912 -43.812968)
					(mid 448.276833 -43.798089)
					(end 448.291712 -43.762168)
				)
			)
		)
		(polygon
			(pts
				(arc
					(start 416.741864 -43.558968)
					(mid 416.726985 -43.523047)
					(end 416.691064 -43.508168)
				)
				(arc
					(start 415.878264 -43.508168)
					(mid 415.842343 -43.523047)
					(end 415.827464 -43.558968)
				)
				(arc
					(start 415.827464 -43.762168)
					(mid 415.842343 -43.798089)
					(end 415.878264 -43.812968)
				)
				(arc
					(start 416.691064 -43.812968)
					(mid 416.726985 -43.798089)
					(end 416.741864 -43.762168)
				)
			)
		)
		(polygon
			(pts
				(arc
					(start 385.191762 -43.558968)
					(mid 385.176883 -43.523047)
					(end 385.140962 -43.508168)
				)
				(arc
					(start 384.328162 -43.508168)
					(mid 384.292241 -43.523047)
					(end 384.277362 -43.558968)
				)
				(arc
					(start 384.277362 -43.762168)
					(mid 384.292241 -43.798089)
					(end 384.328162 -43.812968)
				)
				(arc
					(start 385.140962 -43.812968)
					(mid 385.176883 -43.798089)
					(end 385.191762 -43.762168)
				)
			)
		)
		(polygon
			(pts
				(arc
					(start 353.641914 -43.558968)
					(mid 353.627035 -43.523047)
					(end 353.591114 -43.508168)
				)
				(arc
					(start 352.778314 -43.508168)
					(mid 352.742393 -43.523047)
					(end 352.727514 -43.558968)
				)
				(arc
					(start 352.727514 -43.762168)
					(mid 352.742393 -43.798089)
					(end 352.778314 -43.812968)
				)
				(arc
					(start 353.591114 -43.812968)
					(mid 353.627035 -43.798089)
					(end 353.641914 -43.762168)
				)
			)
		)
		(polygon
			(pts
				(arc
					(start 322.091812 -43.558968)
					(mid 322.076933 -43.523047)
					(end 322.041012 -43.508168)
				)
				(arc
					(start 321.228212 -43.508168)
					(mid 321.192291 -43.523047)
					(end 321.177412 -43.558968)
				)
				(arc
					(start 321.177412 -43.762168)
					(mid 321.192291 -43.798089)
					(end 321.228212 -43.812968)
				)
				(arc
					(start 322.041012 -43.812968)
					(mid 322.076933 -43.798089)
					(end 322.091812 -43.762168)
				)
			)
		)
		(polygon
			(pts
				(arc
					(start 190.670688 -43.558968)
					(mid 190.655809 -43.523047)
					(end 190.619888 -43.508168)
				)
				(arc
					(start 189.807088 -43.508168)
					(mid 189.771167 -43.523047)
					(end 189.756288 -43.558968)
				)
				(arc
					(start 189.756288 -43.762168)
					(mid 189.771167 -43.798089)
					(end 189.807088 -43.812968)
				)
				(arc
					(start 190.619888 -43.812968)
					(mid 190.655809 -43.798089)
					(end 190.670688 -43.762168)
				)
			)
		)
		(polygon
			(pts
				(arc
					(start 159.120586 -43.558968)
					(mid 159.105707 -43.523047)
					(end 159.069786 -43.508168)
				)
				(arc
					(start 158.256986 -43.508168)
					(mid 158.221065 -43.523047)
					(end 158.206186 -43.558968)
				)
				(arc
					(start 158.206186 -43.762168)
					(mid 158.221065 -43.798089)
					(end 158.256986 -43.812968)
				)
				(arc
					(start 159.069786 -43.812968)
					(mid 159.105707 -43.798089)
					(end 159.120586 -43.762168)
				)
			)
		)
		(polygon
			(pts
				(arc
					(start 127.570484 -43.558968)
					(mid 127.555605 -43.523047)
					(end 127.519684 -43.508168)
				)
				(arc
					(start 126.706884 -43.508168)
					(mid 126.670963 -43.523047)
					(end 126.656084 -43.558968)
				)
				(arc
					(start 126.656084 -43.762168)
					(mid 126.670963 -43.798089)
					(end 126.706884 -43.812968)
				)
				(arc
					(start 127.519684 -43.812968)
					(mid 127.555605 -43.798089)
					(end 127.570484 -43.762168)
				)
			)
		)
		(polygon
			(pts
				(arc
					(start 96.020636 -43.558968)
					(mid 96.005757 -43.523047)
					(end 95.969836 -43.508168)
				)
				(arc
					(start 95.157036 -43.508168)
					(mid 95.121115 -43.523047)
					(end 95.106236 -43.558968)
				)
				(arc
					(start 95.106236 -43.762168)
					(mid 95.121115 -43.798089)
					(end 95.157036 -43.812968)
				)
				(arc
					(start 95.969836 -43.812968)
					(mid 96.005757 -43.798089)
					(end 96.020636 -43.762168)
				)
			)
		)
		(polygon
			(pts
				(arc
					(start 64.470534 -43.558968)
					(mid 64.455655 -43.523047)
					(end 64.419734 -43.508168)
				)
				(arc
					(start 63.606934 -43.508168)
					(mid 63.571013 -43.523047)
					(end 63.556134 -43.558968)
				)
				(arc
					(start 63.556134 -43.762168)
					(mid 63.571013 -43.798089)
					(end 63.606934 -43.812968)
				)
				(arc
					(start 64.419734 -43.812968)
					(mid 64.455655 -43.798089)
					(end 64.470534 -43.762168)
				)
			)
		)
		(polygon
			(pts
				(arc
					(start 32.920686 -43.558968)
					(mid 32.905807 -43.523047)
					(end 32.869886 -43.508168)
				)
				(arc
					(start 32.057086 -43.508168)
					(mid 32.021165 -43.523047)
					(end 32.006286 -43.558968)
				)
				(arc
					(start 32.006286 -43.762168)
					(mid 32.021165 -43.798089)
					(end 32.057086 -43.812968)
				)
				(arc
					(start 32.869886 -43.812968)
					(mid 32.905807 -43.798089)
					(end 32.920686 -43.762168)
				)
			)
		)
		(polygon
			(pts
				(arc
					(start 478.120202 -43.368468)
					(mid 477.739202 -42.987468)
					(end 477.358202 -43.368468)
				)
				(arc
					(start 477.358202 -44.511722)
					(mid 477.739329 -44.892468)
					(end 478.120202 -44.511468)
				)
			)
		)
		(polygon
			(pts
				(arc
					(start 446.5701 -43.368468)
					(mid 446.1891 -42.987468)
					(end 445.8081 -43.368468)
				)
				(arc
					(start 445.8081 -44.511722)
					(mid 446.189227 -44.892468)
					(end 446.5701 -44.511468)
				)
			)
		)
		(polygon
			(pts
				(arc
					(start 415.020252 -43.368468)
					(mid 414.639252 -42.987468)
					(end 414.258252 -43.368468)
				)
				(arc
					(start 414.258252 -44.511722)
					(mid 414.639379 -44.892468)
					(end 415.020252 -44.511468)
				)
			)
		)
		(polygon
			(pts
				(arc
					(start 240.871756 -42.577258)
					(mid 239.92498 -42.882443)
					(end 240.236502 -43.827192)
				)
				(arc
					(start 242.236498 -44.82719)
					(mid 243.17706 -44.5135)
					(end 242.86337 -43.572938)
				)
			)
		)
		(polygon
			(pts
				(arc
					(start 283.563314 -42.57294)
					(mid 282.622752 -42.88663)
					(end 282.936442 -43.827192)
				)
				(arc
					(start 284.928056 -44.822872)
					(mid 285.874832 -44.517687)
					(end 285.56331 -43.572938)
				)
			)
		)
		(polygon
			(pts
				(xy 486.306114 -42.34053) (xy 483.943914 -42.339768) (xy 483.943914 -45.540168) (xy 486.306114 -45.540168)
			)
		)
		(polygon
			(pts
				(xy 454.756012 -42.34053) (xy 452.393812 -42.339768) (xy 452.393812 -45.540168) (xy 454.756012 -45.540168)
			)
		)
		(polygon
			(pts
				(xy 423.206164 -42.34053) (xy 420.843964 -42.339768) (xy 420.843964 -45.540168) (xy 423.206164 -45.540168)
			)
		)
		(polygon
			(pts
				(xy 391.656062 -42.34053) (xy 389.293862 -42.339768) (xy 389.293862 -45.540168) (xy 391.656062 -45.540168)
			)
		)
		(polygon
			(pts
				(xy 360.106214 -42.34053) (xy 357.744014 -42.339768) (xy 357.744014 -45.540168) (xy 360.106214 -45.540168)
			)
		)
		(polygon
			(pts
				(xy 328.556112 -42.34053) (xy 326.193912 -42.339768) (xy 326.193912 -45.540168) (xy 328.556112 -45.540168)
			)
		)
		(polygon
			(pts
				(xy 188.956188 -42.34053) (xy 186.593988 -42.339768) (xy 186.593988 -45.540168) (xy 188.956188 -45.540168)
			)
		)
		(polygon
			(pts
				(xy 157.406086 -42.34053) (xy 155.043886 -42.339768) (xy 155.043886 -45.540168) (xy 157.406086 -45.540168)
			)
		)
		(polygon
			(pts
				(xy 125.855984 -42.34053) (xy 123.493784 -42.339768) (xy 123.493784 -45.540168) (xy 125.855984 -45.540168)
			)
		)
		(polygon
			(pts
				(xy 94.306136 -42.34053) (xy 91.943936 -42.339768) (xy 91.943936 -45.540168) (xy 94.306136 -45.540168)
			)
		)
		(polygon
			(pts
				(xy 62.756034 -42.34053) (xy 60.393834 -42.339768) (xy 60.393834 -45.540168) (xy 62.756034 -45.540168)
			)
		)
		(polygon
			(pts
				(xy 31.206186 -42.34053) (xy 28.843986 -42.339768) (xy 28.843986 -45.540168) (xy 31.206186 -45.540168)
			)
		)
		(polygon
			(pts
				(arc
					(start 320.3575 -43.008042)
					(mid 320.7385 -42.627042)
					(end 320.3575 -42.246042)
				)
				(arc
					(start 319.214246 -42.246042)
					(mid 318.8335 -42.627169)
					(end 319.2145 -43.008042)
				)
			)
		)
		(polygon
			(pts
				(arc
					(start 351.907602 -43.013122)
					(mid 352.293682 -42.627042)
					(end 351.907602 -42.240962)
				)
				(arc
					(start 350.764348 -42.240962)
					(mid 350.378522 -42.627169)
					(end 350.764602 -43.013122)
				)
			)
		)
		(polygon
			(pts
				(arc
					(start 281.074876 -41.849802)
					(mid 281.399742 -40.875204)
					(end 280.425144 -40.550338)
				)
				(xy 280.423874 -40.548052) (xy 278.424132 -41.54805) (xy 278.424132 -41.548304)
				(arc
					(start 278.425148 -41.550336)
					(mid 278.100282 -42.524934)
					(end 279.07488 -42.8498)
				)
				(xy 279.07615 -42.852086) (xy 281.076146 -41.852088)
			)
		)
		(polygon
			(pts
				(arc
					(start 238.374936 -41.849802)
					(mid 238.699802 -40.875204)
					(end 237.725204 -40.550338)
				)
				(xy 237.723934 -40.548052) (xy 235.724192 -41.54805) (xy 235.724192 -41.548304)
				(arc
					(start 235.725208 -41.550336)
					(mid 235.400342 -42.524934)
					(end 236.37494 -42.8498)
				)
				(xy 236.37621 -42.852086) (xy 238.376206 -41.852088)
			)
		)
		(polygon
			(pts
				(arc
					(start 240.871756 -38.577266)
					(mid 239.92498 -38.882451)
					(end 240.236502 -39.8272)
				)
				(arc
					(start 242.236498 -40.827198)
					(mid 243.17706 -40.513508)
					(end 242.86337 -39.572946)
				)
			)
		)
		(polygon
			(pts
				(arc
					(start 283.563314 -38.572948)
					(mid 282.622752 -38.886638)
					(end 282.936442 -39.8272)
				)
				(arc
					(start 284.928056 -40.82288)
					(mid 285.874832 -40.517695)
					(end 285.56331 -39.572946)
				)
			)
		)
		(polygon
			(pts
				(arc
					(start 281.074876 -37.84981)
					(mid 281.399742 -36.875212)
					(end 280.425144 -36.550346)
				)
				(xy 280.423874 -36.54806) (xy 278.424132 -37.548058) (xy 278.424132 -37.548312)
				(arc
					(start 278.425148 -37.550344)
					(mid 278.100282 -38.524942)
					(end 279.07488 -38.849808)
				)
				(xy 279.07615 -38.852094) (xy 281.076146 -37.852096)
			)
		)
		(polygon
			(pts
				(arc
					(start 238.374936 -37.84981)
					(mid 238.699802 -36.875212)
					(end 237.725204 -36.550346)
				)
				(xy 237.723934 -36.54806) (xy 235.724192 -37.548058) (xy 235.724192 -37.548312)
				(arc
					(start 235.725208 -37.550344)
					(mid 235.400342 -38.524942)
					(end 236.37494 -38.849808)
				)
				(xy 236.37621 -38.852094) (xy 238.376206 -37.852096)
			)
		)
		(polygon
			(pts
				(arc
					(start 240.876074 -34.548064)
					(mid 239.89792 -34.873946)
					(end 240.223802 -35.8521)
				)
				(arc
					(start 242.223798 -36.852098)
					(mid 243.201952 -36.526216)
					(end 242.87607 -35.548062)
				)
			)
		)
		(polygon
			(pts
				(arc
					(start 283.57703 -34.545778)
					(mid 282.595574 -34.87293)
					(end 282.922726 -35.854386)
				)
				(arc
					(start 284.922468 -36.854384)
					(mid 285.904229 -36.527384)
					(end 285.577026 -35.545776)
				)
			)
		)
		(polygon
			(pts
				(arc
					(start 143.89862 -29.149802)
					(mid 143.349853 -28.601416)
					(end 142.80134 -29.150056)
				)
				(arc
					(start 142.80134 -30.550104)
					(mid 143.34998 -31.098744)
					(end 143.89862 -30.550104)
				)
			)
		)
		(polygon
			(pts
				(arc
					(start 136.698736 -29.149802)
					(mid 136.149969 -28.601416)
					(end 135.601456 -29.150056)
				)
				(arc
					(start 135.601456 -30.550104)
					(mid 136.150096 -31.098744)
					(end 136.698736 -30.550104)
				)
			)
		)
		(polygon
			(pts
				(arc
					(start 389.898636 -29.149802)
					(mid 389.349869 -28.601416)
					(end 388.801356 -29.150056)
				)
				(arc
					(start 388.801356 -30.550104)
					(mid 389.349996 -31.098744)
					(end 389.898636 -30.550104)
				)
			)
		)
		(polygon
			(pts
				(arc
					(start 368.30127 -29.150056)
					(mid 367.75009 -28.598876)
					(end 367.19891 -29.150056)
				)
				(arc
					(start 367.19891 -30.550358)
					(mid 367.750217 -31.101284)
					(end 368.30127 -30.550104)
				)
			)
		)
		(polygon
			(pts
				(arc
					(start 122.301254 -29.150056)
					(mid 121.750074 -28.598876)
					(end 121.198894 -29.150056)
				)
				(arc
					(start 121.198894 -30.550358)
					(mid 121.750201 -31.101284)
					(end 122.301254 -30.550104)
				)
			)
		)
		(polygon
			(pts
				(arc
					(start 382.701292 -29.149802)
					(mid 382.149985 -28.598876)
					(end 381.598932 -29.150056)
				)
				(arc
					(start 381.598932 -30.550104)
					(mid 382.150112 -31.101284)
					(end 382.701292 -30.550104)
				)
			)
		)
		(polygon
			(pts
				(arc
					(start 362.89869 -28.149804)
					(mid 362.349923 -27.601418)
					(end 361.80141 -28.150058)
				)
				(arc
					(start 361.80141 -29.550106)
					(mid 362.35005 -30.098746)
					(end 362.89869 -29.550106)
				)
			)
		)
		(polygon
			(pts
				(arc
					(start 116.898674 -28.149804)
					(mid 116.349907 -27.601418)
					(end 115.801394 -28.150058)
				)
				(arc
					(start 115.801394 -29.550106)
					(mid 116.350034 -30.098746)
					(end 116.898674 -29.550106)
				)
			)
		)
		(polygon
			(pts
				(arc
					(start 389.898636 -21.949918)
					(mid 389.349869 -21.401532)
					(end 388.801356 -21.950172)
				)
				(arc
					(start 388.801356 -23.35022)
					(mid 389.349996 -23.89886)
					(end 389.898636 -23.35022)
				)
			)
		)
		(polygon
			(pts
				(arc
					(start 386.298694 -21.949918)
					(mid 385.749927 -21.401532)
					(end 385.201414 -21.950172)
				)
				(arc
					(start 385.201414 -23.35022)
					(mid 385.750054 -23.89886)
					(end 386.298694 -23.35022)
				)
			)
		)
		(polygon
			(pts
				(arc
					(start 382.698752 -21.949918)
					(mid 382.149985 -21.401532)
					(end 381.601472 -21.950172)
				)
				(arc
					(start 381.601472 -23.35022)
					(mid 382.150112 -23.89886)
					(end 382.698752 -23.35022)
				)
			)
		)
		(polygon
			(pts
				(arc
					(start 379.098556 -21.949918)
					(mid 378.549789 -21.401532)
					(end 378.001276 -21.950172)
				)
				(arc
					(start 378.001276 -23.35022)
					(mid 378.549916 -23.89886)
					(end 379.098556 -23.35022)
				)
			)
		)
		(polygon
			(pts
				(arc
					(start 368.29873 -21.949918)
					(mid 367.749963 -21.401532)
					(end 367.20145 -21.950172)
				)
				(arc
					(start 367.20145 -23.35022)
					(mid 367.75009 -23.89886)
					(end 368.29873 -23.35022)
				)
			)
		)
		(polygon
			(pts
				(arc
					(start 364.698534 -21.949918)
					(mid 364.149767 -21.401532)
					(end 363.601254 -21.950172)
				)
				(arc
					(start 363.601254 -23.35022)
					(mid 364.149894 -23.89886)
					(end 364.698534 -23.35022)
				)
			)
		)
		(polygon
			(pts
				(arc
					(start 361.098592 -21.949918)
					(mid 360.549825 -21.401532)
					(end 360.001312 -21.950172)
				)
				(arc
					(start 360.001312 -23.35022)
					(mid 360.549952 -23.89886)
					(end 361.098592 -23.35022)
				)
			)
		)
		(polygon
			(pts
				(arc
					(start 357.49865 -21.949918)
					(mid 356.949883 -21.401532)
					(end 356.40137 -21.950172)
				)
				(arc
					(start 356.40137 -23.35022)
					(mid 356.95001 -23.89886)
					(end 357.49865 -23.35022)
				)
			)
		)
		(polygon
			(pts
				(arc
					(start 143.89862 -21.949918)
					(mid 143.349853 -21.401532)
					(end 142.80134 -21.950172)
				)
				(arc
					(start 142.80134 -23.35022)
					(mid 143.34998 -23.89886)
					(end 143.89862 -23.35022)
				)
			)
		)
		(polygon
			(pts
				(arc
					(start 140.298678 -21.949918)
					(mid 139.749911 -21.401532)
					(end 139.201398 -21.950172)
				)
				(arc
					(start 139.201398 -23.35022)
					(mid 139.750038 -23.89886)
					(end 140.298678 -23.35022)
				)
			)
		)
		(polygon
			(pts
				(arc
					(start 136.698736 -21.949918)
					(mid 136.149969 -21.401532)
					(end 135.601456 -21.950172)
				)
				(arc
					(start 135.601456 -23.35022)
					(mid 136.150096 -23.89886)
					(end 136.698736 -23.35022)
				)
			)
		)
		(polygon
			(pts
				(arc
					(start 133.09854 -21.949918)
					(mid 132.549773 -21.401532)
					(end 132.00126 -21.950172)
				)
				(arc
					(start 132.00126 -23.35022)
					(mid 132.5499 -23.89886)
					(end 133.09854 -23.35022)
				)
			)
		)
		(polygon
			(pts
				(arc
					(start 122.298714 -21.949918)
					(mid 121.749947 -21.401532)
					(end 121.201434 -21.950172)
				)
				(arc
					(start 121.201434 -23.35022)
					(mid 121.750074 -23.89886)
					(end 122.298714 -23.35022)
				)
			)
		)
		(polygon
			(pts
				(arc
					(start 118.698518 -21.949918)
					(mid 118.149751 -21.401532)
					(end 117.601238 -21.950172)
				)
				(arc
					(start 117.601238 -23.35022)
					(mid 118.149878 -23.89886)
					(end 118.698518 -23.35022)
				)
			)
		)
		(polygon
			(pts
				(arc
					(start 115.098576 -21.949918)
					(mid 114.549809 -21.401532)
					(end 114.001296 -21.950172)
				)
				(arc
					(start 114.001296 -23.35022)
					(mid 114.549936 -23.89886)
					(end 115.098576 -23.35022)
				)
			)
		)
		(polygon
			(pts
				(arc
					(start 111.498634 -21.949918)
					(mid 110.949867 -21.401532)
					(end 110.401354 -21.950172)
				)
				(arc
					(start 110.401354 -23.35022)
					(mid 110.949994 -23.89886)
					(end 111.498634 -23.35022)
				)
			)
		)
		(polygon
			(pts
				(arc
					(start 388.098538 -20.94992)
					(mid 387.549771 -20.401534)
					(end 387.001258 -20.950174)
				)
				(arc
					(start 387.001258 -22.350222)
					(mid 387.549898 -22.898862)
					(end 388.098538 -22.350222)
				)
			)
		)
		(polygon
			(pts
				(arc
					(start 384.498596 -20.94992)
					(mid 383.949829 -20.401534)
					(end 383.401316 -20.950174)
				)
				(arc
					(start 383.401316 -22.350222)
					(mid 383.949956 -22.898862)
					(end 384.498596 -22.350222)
				)
			)
		)
		(polygon
			(pts
				(arc
					(start 380.898654 -20.94992)
					(mid 380.349887 -20.401534)
					(end 379.801374 -20.950174)
				)
				(arc
					(start 379.801374 -22.350222)
					(mid 380.350014 -22.898862)
					(end 380.898654 -22.350222)
				)
			)
		)
		(polygon
			(pts
				(arc
					(start 377.298712 -20.94992)
					(mid 376.749945 -20.401534)
					(end 376.201432 -20.950174)
				)
				(arc
					(start 376.201432 -22.350222)
					(mid 376.750072 -22.898862)
					(end 377.298712 -22.350222)
				)
			)
		)
		(polygon
			(pts
				(arc
					(start 366.498632 -20.94992)
					(mid 365.949865 -20.401534)
					(end 365.401352 -20.950174)
				)
				(arc
					(start 365.401352 -22.350222)
					(mid 365.949992 -22.898862)
					(end 366.498632 -22.350222)
				)
			)
		)
		(polygon
			(pts
				(arc
					(start 362.89869 -20.94992)
					(mid 362.349923 -20.401534)
					(end 361.80141 -20.950174)
				)
				(arc
					(start 361.80141 -22.350222)
					(mid 362.35005 -22.898862)
					(end 362.89869 -22.350222)
				)
			)
		)
		(polygon
			(pts
				(arc
					(start 359.298748 -20.94992)
					(mid 358.749981 -20.401534)
					(end 358.201468 -20.950174)
				)
				(arc
					(start 358.201468 -22.350222)
					(mid 358.750108 -22.898862)
					(end 359.298748 -22.350222)
				)
			)
		)
		(polygon
			(pts
				(arc
					(start 355.698552 -20.94992)
					(mid 355.149785 -20.401534)
					(end 354.601272 -20.950174)
				)
				(arc
					(start 354.601272 -22.350222)
					(mid 355.149912 -22.898862)
					(end 355.698552 -22.350222)
				)
			)
		)
		(polygon
			(pts
				(arc
					(start 142.098522 -20.94992)
					(mid 141.549755 -20.401534)
					(end 141.001242 -20.950174)
				)
				(arc
					(start 141.001242 -22.350222)
					(mid 141.549882 -22.898862)
					(end 142.098522 -22.350222)
				)
			)
		)
		(polygon
			(pts
				(arc
					(start 138.49858 -20.94992)
					(mid 137.949813 -20.401534)
					(end 137.4013 -20.950174)
				)
				(arc
					(start 137.4013 -22.350222)
					(mid 137.94994 -22.898862)
					(end 138.49858 -22.350222)
				)
			)
		)
		(polygon
			(pts
				(arc
					(start 134.898638 -20.94992)
					(mid 134.349871 -20.401534)
					(end 133.801358 -20.950174)
				)
				(arc
					(start 133.801358 -22.350222)
					(mid 134.349998 -22.898862)
					(end 134.898638 -22.350222)
				)
			)
		)
		(polygon
			(pts
				(arc
					(start 131.298696 -20.94992)
					(mid 130.749929 -20.401534)
					(end 130.201416 -20.950174)
				)
				(arc
					(start 130.201416 -22.350222)
					(mid 130.750056 -22.898862)
					(end 131.298696 -22.350222)
				)
			)
		)
		(polygon
			(pts
				(arc
					(start 120.498616 -20.94992)
					(mid 119.949849 -20.401534)
					(end 119.401336 -20.950174)
				)
				(arc
					(start 119.401336 -22.350222)
					(mid 119.949976 -22.898862)
					(end 120.498616 -22.350222)
				)
			)
		)
		(polygon
			(pts
				(arc
					(start 116.898674 -20.94992)
					(mid 116.349907 -20.401534)
					(end 115.801394 -20.950174)
				)
				(arc
					(start 115.801394 -22.350222)
					(mid 116.350034 -22.898862)
					(end 116.898674 -22.350222)
				)
			)
		)
		(polygon
			(pts
				(arc
					(start 113.298732 -20.94992)
					(mid 112.749965 -20.401534)
					(end 112.201452 -20.950174)
				)
				(arc
					(start 112.201452 -22.350222)
					(mid 112.750092 -22.898862)
					(end 113.298732 -22.350222)
				)
			)
		)
		(polygon
			(pts
				(arc
					(start 109.698536 -20.94992)
					(mid 109.149769 -20.401534)
					(end 108.601256 -20.950174)
				)
				(arc
					(start 108.601256 -22.350222)
					(mid 109.149896 -22.898862)
					(end 109.698536 -22.350222)
				)
			)
		)
		(polygon
			(pts
				(arc
					(start 133.09854 -18.35023)
					(mid 132.5499 -17.80159)
					(end 132.00126 -18.35023)
				)
				(arc
					(start 132.00126 -19.750278)
					(mid 132.550027 -20.298664)
					(end 133.09854 -19.750024)
				)
			)
		)
		(polygon
			(pts
				(arc
					(start 389.898636 -18.349976)
					(mid 389.349869 -17.80159)
					(end 388.801356 -18.35023)
				)
				(arc
					(start 388.801356 -19.750024)
					(mid 389.349996 -20.298664)
					(end 389.898636 -19.750024)
				)
			)
		)
		(polygon
			(pts
				(arc
					(start 386.298694 -18.349976)
					(mid 385.749927 -17.80159)
					(end 385.201414 -18.35023)
				)
				(arc
					(start 385.201414 -19.750024)
					(mid 385.750054 -20.298664)
					(end 386.298694 -19.750024)
				)
			)
		)
		(polygon
			(pts
				(arc
					(start 382.698752 -18.349976)
					(mid 382.149985 -17.80159)
					(end 381.601472 -18.35023)
				)
				(arc
					(start 381.601472 -19.750024)
					(mid 382.150112 -20.298664)
					(end 382.698752 -19.750024)
				)
			)
		)
		(polygon
			(pts
				(arc
					(start 379.098556 -18.349976)
					(mid 378.549789 -17.80159)
					(end 378.001276 -18.35023)
				)
				(arc
					(start 378.001276 -19.750024)
					(mid 378.549916 -20.298664)
					(end 379.098556 -19.750024)
				)
			)
		)
		(polygon
			(pts
				(arc
					(start 368.29873 -18.349976)
					(mid 367.749963 -17.80159)
					(end 367.20145 -18.35023)
				)
				(arc
					(start 367.20145 -19.750024)
					(mid 367.75009 -20.298664)
					(end 368.29873 -19.750024)
				)
			)
		)
		(polygon
			(pts
				(arc
					(start 364.698534 -18.349976)
					(mid 364.149767 -17.80159)
					(end 363.601254 -18.35023)
				)
				(arc
					(start 363.601254 -19.750024)
					(mid 364.149894 -20.298664)
					(end 364.698534 -19.750024)
				)
			)
		)
		(polygon
			(pts
				(arc
					(start 361.098592 -18.349976)
					(mid 360.549825 -17.80159)
					(end 360.001312 -18.35023)
				)
				(arc
					(start 360.001312 -19.750024)
					(mid 360.549952 -20.298664)
					(end 361.098592 -19.750024)
				)
			)
		)
		(polygon
			(pts
				(arc
					(start 357.49865 -18.349976)
					(mid 356.949883 -17.80159)
					(end 356.40137 -18.35023)
				)
				(arc
					(start 356.40137 -19.750024)
					(mid 356.95001 -20.298664)
					(end 357.49865 -19.750024)
				)
			)
		)
		(polygon
			(pts
				(arc
					(start 143.89862 -18.349976)
					(mid 143.349853 -17.80159)
					(end 142.80134 -18.35023)
				)
				(arc
					(start 142.80134 -19.750024)
					(mid 143.34998 -20.298664)
					(end 143.89862 -19.750024)
				)
			)
		)
		(polygon
			(pts
				(arc
					(start 140.298678 -18.349976)
					(mid 139.749911 -17.80159)
					(end 139.201398 -18.35023)
				)
				(arc
					(start 139.201398 -19.750024)
					(mid 139.750038 -20.298664)
					(end 140.298678 -19.750024)
				)
			)
		)
		(polygon
			(pts
				(arc
					(start 136.698736 -18.349976)
					(mid 136.149969 -17.80159)
					(end 135.601456 -18.35023)
				)
				(arc
					(start 135.601456 -19.750024)
					(mid 136.150096 -20.298664)
					(end 136.698736 -19.750024)
				)
			)
		)
		(polygon
			(pts
				(arc
					(start 122.298714 -18.349976)
					(mid 121.749947 -17.80159)
					(end 121.201434 -18.35023)
				)
				(arc
					(start 121.201434 -19.750024)
					(mid 121.750074 -20.298664)
					(end 122.298714 -19.750024)
				)
			)
		)
		(polygon
			(pts
				(arc
					(start 118.698518 -18.349976)
					(mid 118.149751 -17.80159)
					(end 117.601238 -18.35023)
				)
				(arc
					(start 117.601238 -19.750024)
					(mid 118.149878 -20.298664)
					(end 118.698518 -19.750024)
				)
			)
		)
		(polygon
			(pts
				(arc
					(start 115.098576 -18.349976)
					(mid 114.549809 -17.80159)
					(end 114.001296 -18.35023)
				)
				(arc
					(start 114.001296 -19.750024)
					(mid 114.549936 -20.298664)
					(end 115.098576 -19.750024)
				)
			)
		)
		(polygon
			(pts
				(arc
					(start 111.498634 -18.349976)
					(mid 110.949867 -17.80159)
					(end 110.401354 -18.35023)
				)
				(arc
					(start 110.401354 -19.750024)
					(mid 110.949994 -20.298664)
					(end 111.498634 -19.750024)
				)
			)
		)
		(polygon
			(pts
				(arc
					(start 388.098538 -17.349724)
					(mid 387.549771 -16.801338)
					(end 387.001258 -17.349978)
				)
				(arc
					(start 387.001258 -18.750026)
					(mid 387.549898 -19.298666)
					(end 388.098538 -18.750026)
				)
			)
		)
		(polygon
			(pts
				(arc
					(start 384.498596 -17.349724)
					(mid 383.949829 -16.801338)
					(end 383.401316 -17.349978)
				)
				(arc
					(start 383.401316 -18.750026)
					(mid 383.949956 -19.298666)
					(end 384.498596 -18.750026)
				)
			)
		)
		(polygon
			(pts
				(arc
					(start 380.898654 -17.349724)
					(mid 380.349887 -16.801338)
					(end 379.801374 -17.349978)
				)
				(arc
					(start 379.801374 -18.750026)
					(mid 380.350014 -19.298666)
					(end 380.898654 -18.750026)
				)
			)
		)
		(polygon
			(pts
				(arc
					(start 377.298712 -17.349724)
					(mid 376.749945 -16.801338)
					(end 376.201432 -17.349978)
				)
				(arc
					(start 376.201432 -18.750026)
					(mid 376.750072 -19.298666)
					(end 377.298712 -18.750026)
				)
			)
		)
		(polygon
			(pts
				(arc
					(start 366.498632 -17.349724)
					(mid 365.949865 -16.801338)
					(end 365.401352 -17.349978)
				)
				(arc
					(start 365.401352 -18.750026)
					(mid 365.949992 -19.298666)
					(end 366.498632 -18.750026)
				)
			)
		)
		(polygon
			(pts
				(arc
					(start 362.89869 -17.349724)
					(mid 362.349923 -16.801338)
					(end 361.80141 -17.349978)
				)
				(arc
					(start 361.80141 -18.750026)
					(mid 362.35005 -19.298666)
					(end 362.89869 -18.750026)
				)
			)
		)
		(polygon
			(pts
				(arc
					(start 359.298748 -17.349724)
					(mid 358.749981 -16.801338)
					(end 358.201468 -17.349978)
				)
				(arc
					(start 358.201468 -18.750026)
					(mid 358.750108 -19.298666)
					(end 359.298748 -18.750026)
				)
			)
		)
		(polygon
			(pts
				(arc
					(start 355.698552 -17.349724)
					(mid 355.149785 -16.801338)
					(end 354.601272 -17.349978)
				)
				(arc
					(start 354.601272 -18.750026)
					(mid 355.149912 -19.298666)
					(end 355.698552 -18.750026)
				)
			)
		)
		(polygon
			(pts
				(arc
					(start 142.098522 -17.349724)
					(mid 141.549755 -16.801338)
					(end 141.001242 -17.349978)
				)
				(arc
					(start 141.001242 -18.750026)
					(mid 141.549882 -19.298666)
					(end 142.098522 -18.750026)
				)
			)
		)
		(polygon
			(pts
				(arc
					(start 138.49858 -17.349724)
					(mid 137.949813 -16.801338)
					(end 137.4013 -17.349978)
				)
				(arc
					(start 137.4013 -18.750026)
					(mid 137.94994 -19.298666)
					(end 138.49858 -18.750026)
				)
			)
		)
		(polygon
			(pts
				(arc
					(start 134.898638 -17.349724)
					(mid 134.349871 -16.801338)
					(end 133.801358 -17.349978)
				)
				(arc
					(start 133.801358 -18.750026)
					(mid 134.349998 -19.298666)
					(end 134.898638 -18.750026)
				)
			)
		)
		(polygon
			(pts
				(arc
					(start 131.298696 -17.349724)
					(mid 130.749929 -16.801338)
					(end 130.201416 -17.349978)
				)
				(arc
					(start 130.201416 -18.750026)
					(mid 130.750056 -19.298666)
					(end 131.298696 -18.750026)
				)
			)
		)
		(polygon
			(pts
				(arc
					(start 120.498616 -17.349724)
					(mid 119.949849 -16.801338)
					(end 119.401336 -17.349978)
				)
				(arc
					(start 119.401336 -18.750026)
					(mid 119.949976 -19.298666)
					(end 120.498616 -18.750026)
				)
			)
		)
		(polygon
			(pts
				(arc
					(start 116.898674 -17.349724)
					(mid 116.349907 -16.801338)
					(end 115.801394 -17.349978)
				)
				(arc
					(start 115.801394 -18.750026)
					(mid 116.350034 -19.298666)
					(end 116.898674 -18.750026)
				)
			)
		)
		(polygon
			(pts
				(arc
					(start 113.298732 -17.349724)
					(mid 112.749965 -16.801338)
					(end 112.201452 -17.349978)
				)
				(arc
					(start 112.201452 -18.750026)
					(mid 112.750092 -19.298666)
					(end 113.298732 -18.750026)
				)
			)
		)
		(polygon
			(pts
				(arc
					(start 109.698536 -17.349724)
					(mid 109.149769 -16.801338)
					(end 108.601256 -17.349978)
				)
				(arc
					(start 108.601256 -18.750026)
					(mid 109.149896 -19.298666)
					(end 109.698536 -18.750026)
				)
			)
		)
		(polygon
			(pts
				(arc
					(start 281.074876 -17.84985)
					(mid 281.399742 -16.875252)
					(end 280.425144 -16.550386)
				)
				(xy 280.423874 -16.5481) (xy 278.424132 -17.548098) (xy 278.424132 -17.548352)
				(arc
					(start 278.425148 -17.550384)
					(mid 278.100282 -18.524982)
					(end 279.07488 -18.849848)
				)
				(xy 279.07615 -18.852134) (xy 281.076146 -17.852136)
			)
		)
		(polygon
			(pts
				(arc
					(start 238.374936 -17.84985)
					(mid 238.699802 -16.875252)
					(end 237.725204 -16.550386)
				)
				(xy 237.723934 -16.5481) (xy 235.724192 -17.548098) (xy 235.724192 -17.548352)
				(arc
					(start 235.725208 -17.550384)
					(mid 235.400342 -18.524982)
					(end 236.37494 -18.849848)
				)
				(xy 236.37621 -18.852134) (xy 238.376206 -17.852136)
			)
		)
		(polygon
			(pts
				(arc
					(start 281.077162 -11.854434)
					(mid 281.404314 -10.872978)
					(end 280.422858 -10.545826)
				)
				(arc
					(start 278.433784 -11.54049)
					(mid 278.037097 -12.362161)
					(end 278.750268 -12.931394)
				)
				(arc
					(start 278.750268 -12.931394)
					(mid 278.918191 -12.911919)
					(end 279.077166 -12.854432)
				)
			)
		)
		(polygon
			(pts
				(arc
					(start 238.377222 -11.854434)
					(mid 238.704374 -10.872978)
					(end 237.722918 -10.545826)
				)
				(arc
					(start 235.733844 -11.54049)
					(mid 235.393447 -12.52152)
					(end 236.377226 -12.854432)
				)
			)
		)
	)
	(zone
		(layer "In1.Cu")
		(hatch none 0.5)
		(connect_pads
			(clearance 0)
		)
		(min_thickness 0.25)
		(keepout
			(tracks not_allowed)
			(vias allowed)
			(pads allowed)
			(copperpour not_allowed)
			(footprints allowed)
		)
		(placement
			(enabled no)
			(sheetname "")
		)
		(fill
			(thermal_gap 0.5)
			(thermal_bridge_width 0.5)
			(island_removal_mode 0)
		)
		(polygon
			(pts
				(arc
					(start 126.706884 -44.066968)
					(mid 126.670963 -44.081847)
					(end 126.656084 -44.117768)
				)
				(arc
					(start 126.656084 -44.320968)
					(mid 126.670963 -44.356889)
					(end 126.706884 -44.371768)
				)
				(arc
					(start 127.519684 -44.371768)
					(mid 127.555605 -44.356889)
					(end 127.570484 -44.320968)
				)
				(arc
					(start 127.570484 -44.117768)
					(mid 127.555605 -44.081847)
					(end 127.519684 -44.066968)
				)
			)
		)
	)
	(zone
		(layer "In1.Cu")
		(hatch none 0.5)
		(connect_pads
			(clearance 0)
		)
		(min_thickness 0.25)
		(keepout
			(tracks not_allowed)
			(vias allowed)
			(pads allowed)
			(copperpour not_allowed)
			(footprints allowed)
		)
		(placement
			(enabled no)
			(sheetname "")
		)
		(fill
			(thermal_gap 0.5)
			(thermal_bridge_width 0.5)
			(island_removal_mode 0)
		)
		(polygon
			(pts
				(xy 326.193912 -273.000216) (xy 328.556112 -273.000216) (xy 328.556112 -274.879816) (xy 326.193912 -274.879816)
			)
		)
	)
	(zone
		(layer "In1.Cu")
		(hatch none 0.5)
		(connect_pads
			(clearance 0)
		)
		(min_thickness 0.25)
		(keepout
			(tracks not_allowed)
			(vias allowed)
			(pads allowed)
			(copperpour not_allowed)
			(footprints allowed)
		)
		(placement
			(enabled no)
			(sheetname "")
		)
		(fill
			(thermal_gap 0.5)
			(thermal_bridge_width 0.5)
			(island_removal_mode 0)
		)
		(polygon
			(pts
				(arc
					(start 32.057086 -159.066992)
					(mid 32.021165 -159.081871)
					(end 32.006286 -159.117792)
				)
				(arc
					(start 32.006286 -159.320992)
					(mid 32.021165 -159.356913)
					(end 32.057086 -159.371792)
				)
				(arc
					(start 32.869886 -159.371792)
					(mid 32.905807 -159.356913)
					(end 32.920686 -159.320992)
				)
				(arc
					(start 32.920686 -159.117792)
					(mid 32.905807 -159.081871)
					(end 32.869886 -159.066992)
				)
			)
		)
	)
	(zone
		(layer "In1.Cu")
		(hatch none 0.5)
		(connect_pads
			(clearance 0)
		)
		(min_thickness 0.25)
		(keepout
			(tracks not_allowed)
			(vias allowed)
			(pads allowed)
			(copperpour not_allowed)
			(footprints allowed)
		)
		(placement
			(enabled no)
			(sheetname "")
		)
		(fill
			(thermal_gap 0.5)
			(thermal_bridge_width 0.5)
			(island_removal_mode 0)
		)
		(polygon
			(pts
				(xy 155.043886 -273.000216) (xy 157.406086 -273.000216) (xy 157.406086 -274.879816) (xy 155.043886 -274.879816)
			)
		)
	)
	(zone
		(layer "In1.Cu")
		(hatch none 0.5)
		(connect_pads
			(clearance 0)
		)
		(min_thickness 0.25)
		(keepout
			(tracks not_allowed)
			(vias allowed)
			(pads allowed)
			(copperpour not_allowed)
			(footprints allowed)
		)
		(placement
			(enabled no)
			(sheetname "")
		)
		(fill
			(thermal_gap 0.5)
			(thermal_bridge_width 0.5)
			(island_removal_mode 0)
		)
		(polygon
			(pts
				(arc
					(start 478.978214 -158.508192)
					(mid 478.942293 -158.523071)
					(end 478.927414 -158.558992)
				)
				(arc
					(start 478.927414 -158.762192)
					(mid 478.942293 -158.798113)
					(end 478.978214 -158.812992)
				)
				(arc
					(start 479.791014 -158.812992)
					(mid 479.826935 -158.798113)
					(end 479.841814 -158.762192)
				)
				(arc
					(start 479.841814 -158.558992)
					(mid 479.826935 -158.523071)
					(end 479.791014 -158.508192)
				)
			)
		)
	)
	(zone
		(layer "In1.Cu")
		(hatch none 0.5)
		(connect_pads
			(clearance 0)
		)
		(min_thickness 0.25)
		(keepout
			(tracks not_allowed)
			(vias allowed)
			(pads allowed)
			(copperpour not_allowed)
			(footprints allowed)
		)
		(placement
			(enabled no)
			(sheetname "")
		)
		(fill
			(thermal_gap 0.5)
			(thermal_bridge_width 0.5)
			(island_removal_mode 0)
		)
		(polygon
			(pts
				(xy 389.293862 -158.000192) (xy 391.656062 -158.000192) (xy 391.656062 -159.879792) (xy 389.293862 -159.879792)
			)
		)
	)
	(zone
		(layer "In1.Cu")
		(hatch none 0.5)
		(connect_pads
			(clearance 0)
		)
		(min_thickness 0.25)
		(keepout
			(tracks not_allowed)
			(vias allowed)
			(pads allowed)
			(copperpour not_allowed)
			(footprints allowed)
		)
		(placement
			(enabled no)
			(sheetname "")
		)
		(fill
			(thermal_gap 0.5)
			(thermal_bridge_width 0.5)
			(island_removal_mode 0)
		)
		(polygon
			(pts
				(xy 123.493784 -276.810216) (xy 125.855984 -276.810216) (xy 125.855984 -278.689816) (xy 123.493784 -278.689816)
			)
		)
	)
	(zone
		(layer "In1.Cu")
		(hatch none 0.5)
		(connect_pads
			(clearance 0)
		)
		(min_thickness 0.25)
		(keepout
			(tracks not_allowed)
			(vias allowed)
			(pads allowed)
			(copperpour not_allowed)
			(footprints allowed)
		)
		(placement
			(enabled no)
			(sheetname "")
		)
		(fill
			(thermal_gap 0.5)
			(thermal_bridge_width 0.5)
			(island_removal_mode 0)
		)
		(polygon
			(pts
				(xy 326.193912 -43.000168) (xy 328.556112 -43.000168) (xy 328.556112 -44.879768) (xy 326.193912 -44.879768)
			)
		)
	)
	(zone
		(layer "In1.Cu")
		(hatch none 0.5)
		(connect_pads
			(clearance 0)
		)
		(min_thickness 0.25)
		(keepout
			(tracks not_allowed)
			(vias allowed)
			(pads allowed)
			(copperpour not_allowed)
			(footprints allowed)
		)
		(placement
			(enabled no)
			(sheetname "")
		)
		(fill
			(thermal_gap 0.5)
			(thermal_bridge_width 0.5)
			(island_removal_mode 0)
		)
		(polygon
			(pts
				(xy 420.843964 -273.000216) (xy 423.206164 -273.000216) (xy 423.206164 -274.879816) (xy 420.843964 -274.879816)
			)
		)
	)
	(zone
		(layer "In1.Cu")
		(hatch none 0.5)
		(connect_pads
			(clearance 0)
		)
		(min_thickness 0.25)
		(keepout
			(tracks not_allowed)
			(vias allowed)
			(pads allowed)
			(copperpour not_allowed)
			(footprints allowed)
		)
		(placement
			(enabled no)
			(sheetname "")
		)
		(fill
			(thermal_gap 0.5)
			(thermal_bridge_width 0.5)
			(island_removal_mode 0)
		)
		(polygon
			(pts
				(xy 452.393812 -276.810216) (xy 454.756012 -276.810216) (xy 454.756012 -278.689816) (xy 452.393812 -278.689816)
			)
		)
	)
	(zone
		(layer "In1.Cu")
		(hatch none 0.5)
		(connect_pads
			(clearance 0)
		)
		(min_thickness 0.25)
		(keepout
			(tracks not_allowed)
			(vias allowed)
			(pads allowed)
			(copperpour not_allowed)
			(footprints allowed)
		)
		(placement
			(enabled no)
			(sheetname "")
		)
		(fill
			(thermal_gap 0.5)
			(thermal_bridge_width 0.5)
			(island_removal_mode 0)
		)
		(polygon
			(pts
				(arc
					(start 321.228212 -43.508168)
					(mid 321.192291 -43.523047)
					(end 321.177412 -43.558968)
				)
				(arc
					(start 321.177412 -43.762168)
					(mid 321.192291 -43.798089)
					(end 321.228212 -43.812968)
				)
				(arc
					(start 322.041012 -43.812968)
					(mid 322.076933 -43.798089)
					(end 322.091812 -43.762168)
				)
				(arc
					(start 322.091812 -43.558968)
					(mid 322.076933 -43.523047)
					(end 322.041012 -43.508168)
				)
			)
		)
	)
	(zone
		(layer "In1.Cu")
		(hatch none 0.5)
		(connect_pads
			(clearance 0)
		)
		(min_thickness 0.25)
		(keepout
			(tracks not_allowed)
			(vias allowed)
			(pads allowed)
			(copperpour not_allowed)
			(footprints allowed)
		)
		(placement
			(enabled no)
			(sheetname "")
		)
		(fill
			(thermal_gap 0.5)
			(thermal_bridge_width 0.5)
			(island_removal_mode 0)
		)
		(polygon
			(pts
				(arc
					(start 478.978214 -273.508216)
					(mid 478.942293 -273.523095)
					(end 478.927414 -273.559016)
				)
				(arc
					(start 478.927414 -273.762216)
					(mid 478.942293 -273.798137)
					(end 478.978214 -273.813016)
				)
				(arc
					(start 479.791014 -273.813016)
					(mid 479.826935 -273.798137)
					(end 479.841814 -273.762216)
				)
				(arc
					(start 479.841814 -273.559016)
					(mid 479.826935 -273.523095)
					(end 479.791014 -273.508216)
				)
			)
		)
	)
	(zone
		(layer "In1.Cu")
		(hatch none 0.5)
		(connect_pads
			(clearance 0)
		)
		(min_thickness 0.25)
		(keepout
			(tracks not_allowed)
			(vias allowed)
			(pads allowed)
			(copperpour not_allowed)
			(footprints allowed)
		)
		(placement
			(enabled no)
			(sheetname "")
		)
		(fill
			(thermal_gap 0.5)
			(thermal_bridge_width 0.5)
			(island_removal_mode 0)
		)
		(polygon
			(pts
				(xy 28.843986 -161.810192) (xy 31.206186 -161.810192) (xy 31.206186 -163.689792) (xy 28.843986 -163.689792)
			)
		)
	)
	(zone
		(layer "In1.Cu")
		(hatch none 0.5)
		(connect_pads
			(clearance 0)
		)
		(min_thickness 0.25)
		(keepout
			(tracks not_allowed)
			(vias allowed)
			(pads allowed)
			(copperpour not_allowed)
			(footprints allowed)
		)
		(placement
			(enabled no)
			(sheetname "")
		)
		(fill
			(thermal_gap 0.5)
			(thermal_bridge_width 0.5)
			(island_removal_mode 0)
		)
		(polygon
			(pts
				(xy 28.843986 -158.000192) (xy 31.206186 -158.000192) (xy 31.206186 -159.879792) (xy 28.843986 -159.879792)
			)
		)
	)
	(zone
		(layer "In1.Cu")
		(hatch none 0.5)
		(connect_pads
			(clearance 0)
		)
		(min_thickness 0.25)
		(keepout
			(tracks not_allowed)
			(vias allowed)
			(pads allowed)
			(copperpour not_allowed)
			(footprints allowed)
		)
		(placement
			(enabled no)
			(sheetname "")
		)
		(fill
			(thermal_gap 0.5)
			(thermal_bridge_width 0.5)
			(island_removal_mode 0)
		)
		(polygon
			(pts
				(arc
					(start 95.157036 -274.067016)
					(mid 95.121115 -274.081895)
					(end 95.106236 -274.117816)
				)
				(arc
					(start 95.106236 -274.321016)
					(mid 95.121115 -274.356937)
					(end 95.157036 -274.371816)
				)
				(arc
					(start 95.969836 -274.371816)
					(mid 96.005757 -274.356937)
					(end 96.020636 -274.321016)
				)
				(arc
					(start 96.020636 -274.117816)
					(mid 96.005757 -274.081895)
					(end 95.969836 -274.067016)
				)
			)
		)
	)
	(zone
		(layer "In1.Cu")
		(hatch none 0.5)
		(connect_pads
			(clearance 0)
		)
		(min_thickness 0.25)
		(keepout
			(tracks not_allowed)
			(vias allowed)
			(pads allowed)
			(copperpour not_allowed)
			(footprints allowed)
		)
		(placement
			(enabled no)
			(sheetname "")
		)
		(fill
			(thermal_gap 0.5)
			(thermal_bridge_width 0.5)
			(island_removal_mode 0)
		)
		(polygon
			(pts
				(arc
					(start 189.807088 -158.508192)
					(mid 189.771167 -158.523071)
					(end 189.756288 -158.558992)
				)
				(arc
					(start 189.756288 -158.762192)
					(mid 189.771167 -158.798113)
					(end 189.807088 -158.812992)
				)
				(arc
					(start 190.619888 -158.812992)
					(mid 190.655809 -158.798113)
					(end 190.670688 -158.762192)
				)
				(arc
					(start 190.670688 -158.558992)
					(mid 190.655809 -158.523071)
					(end 190.619888 -158.508192)
				)
			)
		)
	)
	(zone
		(layer "In1.Cu")
		(hatch none 0.5)
		(connect_pads
			(clearance 0)
		)
		(min_thickness 0.25)
		(keepout
			(tracks not_allowed)
			(vias allowed)
			(pads allowed)
			(copperpour not_allowed)
			(footprints allowed)
		)
		(placement
			(enabled no)
			(sheetname "")
		)
		(fill
			(thermal_gap 0.5)
			(thermal_bridge_width 0.5)
			(island_removal_mode 0)
		)
		(polygon
			(pts
				(arc
					(start 189.807088 -274.067016)
					(mid 189.771167 -274.081895)
					(end 189.756288 -274.117816)
				)
				(arc
					(start 189.756288 -274.321016)
					(mid 189.771167 -274.356937)
					(end 189.807088 -274.371816)
				)
				(arc
					(start 190.619888 -274.371816)
					(mid 190.655809 -274.356937)
					(end 190.670688 -274.321016)
				)
				(arc
					(start 190.670688 -274.117816)
					(mid 190.655809 -274.081895)
					(end 190.619888 -274.067016)
				)
			)
		)
	)
	(zone
		(layer "In1.Cu")
		(hatch none 0.5)
		(connect_pads
			(clearance 0)
		)
		(min_thickness 0.25)
		(keepout
			(tracks not_allowed)
			(vias allowed)
			(pads allowed)
			(copperpour not_allowed)
			(footprints allowed)
		)
		(placement
			(enabled no)
			(sheetname "")
		)
		(fill
			(thermal_gap 0.5)
			(thermal_bridge_width 0.5)
			(island_removal_mode 0)
		)
		(polygon
			(pts
				(xy 60.393834 -273.000216) (xy 62.756034 -273.000216) (xy 62.756034 -274.879816) (xy 60.393834 -274.879816)
			)
		)
	)
	(zone
		(layer "In1.Cu")
		(hatch none 0.5)
		(connect_pads
			(clearance 0)
		)
		(min_thickness 0.25)
		(keepout
			(tracks not_allowed)
			(vias allowed)
			(pads allowed)
			(copperpour not_allowed)
			(footprints allowed)
		)
		(placement
			(enabled no)
			(sheetname "")
		)
		(fill
			(thermal_gap 0.5)
			(thermal_bridge_width 0.5)
			(island_removal_mode 0)
		)
		(polygon
			(pts
				(arc
					(start 126.706884 -158.508192)
					(mid 126.670963 -158.523071)
					(end 126.656084 -158.558992)
				)
				(arc
					(start 126.656084 -158.762192)
					(mid 126.670963 -158.798113)
					(end 126.706884 -158.812992)
				)
				(arc
					(start 127.519684 -158.812992)
					(mid 127.555605 -158.798113)
					(end 127.570484 -158.762192)
				)
				(arc
					(start 127.570484 -158.558992)
					(mid 127.555605 -158.523071)
					(end 127.519684 -158.508192)
				)
			)
		)
	)
	(zone
		(layer "In1.Cu")
		(hatch none 0.5)
		(connect_pads
			(clearance 0)
		)
		(min_thickness 0.25)
		(keepout
			(tracks not_allowed)
			(vias allowed)
			(pads allowed)
			(copperpour not_allowed)
			(footprints allowed)
		)
		(placement
			(enabled no)
			(sheetname "")
		)
		(fill
			(thermal_gap 0.5)
			(thermal_bridge_width 0.5)
			(island_removal_mode 0)
		)
		(polygon
			(pts
				(arc
					(start 441.078112 -159.066992)
					(mid 441.042191 -159.081871)
					(end 441.027312 -159.117792)
				)
				(arc
					(start 441.027312 -159.320992)
					(mid 441.042191 -159.356913)
					(end 441.078112 -159.371792)
				)
				(arc
					(start 441.890912 -159.371792)
					(mid 441.926833 -159.356913)
					(end 441.941712 -159.320992)
				)
				(arc
					(start 441.941712 -159.117792)
					(mid 441.926833 -159.081871)
					(end 441.890912 -159.066992)
				)
			)
		)
	)
	(zone
		(layer "In1.Cu")
		(hatch none 0.5)
		(connect_pads
			(clearance 0)
		)
		(min_thickness 0.25)
		(keepout
			(tracks not_allowed)
			(vias allowed)
			(pads allowed)
			(copperpour not_allowed)
			(footprints allowed)
		)
		(placement
			(enabled no)
			(sheetname "")
		)
		(fill
			(thermal_gap 0.5)
			(thermal_bridge_width 0.5)
			(island_removal_mode 0)
		)
		(polygon
			(pts
				(xy 389.293862 -43.000168) (xy 391.656062 -43.000168) (xy 391.656062 -44.879768) (xy 389.293862 -44.879768)
			)
		)
	)
	(zone
		(layer "In1.Cu")
		(hatch none 0.5)
		(connect_pads
			(clearance 0)
		)
		(min_thickness 0.25)
		(keepout
			(tracks not_allowed)
			(vias allowed)
			(pads allowed)
			(copperpour not_allowed)
			(footprints allowed)
		)
		(placement
			(enabled no)
			(sheetname "")
		)
		(fill
			(thermal_gap 0.5)
			(thermal_bridge_width 0.5)
			(island_removal_mode 0)
		)
		(polygon
			(pts
				(arc
					(start 321.228212 -274.067016)
					(mid 321.192291 -274.081895)
					(end 321.177412 -274.117816)
				)
				(arc
					(start 321.177412 -274.321016)
					(mid 321.192291 -274.356937)
					(end 321.228212 -274.371816)
				)
				(arc
					(start 322.041012 -274.371816)
					(mid 322.076933 -274.356937)
					(end 322.091812 -274.321016)
				)
				(arc
					(start 322.091812 -274.117816)
					(mid 322.076933 -274.081895)
					(end 322.041012 -274.067016)
				)
			)
		)
	)
	(zone
		(layer "In1.Cu")
		(hatch none 0.5)
		(connect_pads
			(clearance 0)
		)
		(min_thickness 0.25)
		(keepout
			(tracks not_allowed)
			(vias allowed)
			(pads allowed)
			(copperpour not_allowed)
			(footprints allowed)
		)
		(placement
			(enabled no)
			(sheetname "")
		)
		(fill
			(thermal_gap 0.5)
			(thermal_bridge_width 0.5)
			(island_removal_mode 0)
		)
		(polygon
			(pts
				(xy 186.593988 -273.000216) (xy 188.956188 -273.000216) (xy 188.956188 -274.879816) (xy 186.593988 -274.879816)
			)
		)
	)
	(zone
		(layer "In1.Cu")
		(hatch none 0.5)
		(connect_pads
			(clearance 0)
		)
		(min_thickness 0.25)
		(keepout
			(tracks not_allowed)
			(vias allowed)
			(pads allowed)
			(copperpour not_allowed)
			(footprints allowed)
		)
		(placement
			(enabled no)
			(sheetname "")
		)
		(fill
			(thermal_gap 0.5)
			(thermal_bridge_width 0.5)
			(island_removal_mode 0)
		)
		(polygon
			(pts
				(xy 155.043886 -276.810216) (xy 157.406086 -276.810216) (xy 157.406086 -278.689816) (xy 155.043886 -278.689816)
			)
		)
	)
	(zone
		(layer "In1.Cu")
		(hatch none 0.5)
		(connect_pads
			(clearance 0)
		)
		(min_thickness 0.25)
		(keepout
			(tracks not_allowed)
			(vias allowed)
			(pads allowed)
			(copperpour not_allowed)
			(footprints allowed)
		)
		(placement
			(enabled no)
			(sheetname "")
		)
		(fill
			(thermal_gap 0.5)
			(thermal_bridge_width 0.5)
			(island_removal_mode 0)
		)
		(polygon
			(pts
				(xy 60.393834 -158.000192) (xy 62.756034 -158.000192) (xy 62.756034 -159.879792) (xy 60.393834 -159.879792)
			)
		)
	)
	(zone
		(layer "In1.Cu")
		(hatch none 0.5)
		(connect_pads
			(clearance 0)
		)
		(min_thickness 0.25)
		(keepout
			(tracks not_allowed)
			(vias allowed)
			(pads allowed)
			(copperpour not_allowed)
			(footprints allowed)
		)
		(placement
			(enabled no)
			(sheetname "")
		)
		(fill
			(thermal_gap 0.5)
			(thermal_bridge_width 0.5)
			(island_removal_mode 0)
		)
		(polygon
			(pts
				(arc
					(start 478.978214 -159.066992)
					(mid 478.942293 -159.081871)
					(end 478.927414 -159.117792)
				)
				(arc
					(start 478.927414 -159.320992)
					(mid 478.942293 -159.356913)
					(end 478.978214 -159.371792)
				)
				(arc
					(start 479.791014 -159.371792)
					(mid 479.826935 -159.356913)
					(end 479.841814 -159.320992)
				)
				(arc
					(start 479.841814 -159.117792)
					(mid 479.826935 -159.081871)
					(end 479.791014 -159.066992)
				)
			)
		)
	)
	(zone
		(layer "In1.Cu")
		(hatch none 0.5)
		(connect_pads
			(clearance 0)
		)
		(min_thickness 0.25)
		(keepout
			(tracks not_allowed)
			(vias allowed)
			(pads allowed)
			(copperpour not_allowed)
			(footprints allowed)
		)
		(placement
			(enabled no)
			(sheetname "")
		)
		(fill
			(thermal_gap 0.5)
			(thermal_bridge_width 0.5)
			(island_removal_mode 0)
		)
		(polygon
			(pts
				(arc
					(start 189.807088 -159.066992)
					(mid 189.771167 -159.081871)
					(end 189.756288 -159.117792)
				)
				(arc
					(start 189.756288 -159.320992)
					(mid 189.771167 -159.356913)
					(end 189.807088 -159.371792)
				)
				(arc
					(start 190.619888 -159.371792)
					(mid 190.655809 -159.356913)
					(end 190.670688 -159.320992)
				)
				(arc
					(start 190.670688 -159.117792)
					(mid 190.655809 -159.081871)
					(end 190.619888 -159.066992)
				)
			)
		)
	)
	(zone
		(layer "In1.Cu")
		(hatch none 0.5)
		(connect_pads
			(clearance 0)
		)
		(min_thickness 0.25)
		(keepout
			(tracks not_allowed)
			(vias allowed)
			(pads allowed)
			(copperpour not_allowed)
			(footprints allowed)
		)
		(placement
			(enabled no)
			(sheetname "")
		)
		(fill
			(thermal_gap 0.5)
			(thermal_bridge_width 0.5)
			(island_removal_mode 0)
		)
		(polygon
			(pts
				(xy 91.943936 -46.810168) (xy 94.306136 -46.810168) (xy 94.306136 -48.689768) (xy 91.943936 -48.689768)
			)
		)
	)
	(zone
		(layer "In1.Cu")
		(hatch none 0.5)
		(connect_pads
			(clearance 0)
		)
		(min_thickness 0.25)
		(keepout
			(tracks not_allowed)
			(vias allowed)
			(pads allowed)
			(copperpour not_allowed)
			(footprints allowed)
		)
		(placement
			(enabled no)
			(sheetname "")
		)
		(fill
			(thermal_gap 0.5)
			(thermal_bridge_width 0.5)
			(island_removal_mode 0)
		)
		(polygon
			(pts
				(xy 155.043886 -43.000168) (xy 157.406086 -43.000168) (xy 157.406086 -44.879768) (xy 155.043886 -44.879768)
			)
		)
	)
	(zone
		(layer "In1.Cu")
		(hatch none 0.5)
		(connect_pads
			(clearance 0)
		)
		(min_thickness 0.25)
		(keepout
			(tracks not_allowed)
			(vias allowed)
			(pads allowed)
			(copperpour not_allowed)
			(footprints allowed)
		)
		(placement
			(enabled no)
			(sheetname "")
		)
		(fill
			(thermal_gap 0.5)
			(thermal_bridge_width 0.5)
			(island_removal_mode 0)
		)
		(polygon
			(pts
				(arc
					(start 478.978214 -274.067016)
					(mid 478.942293 -274.081895)
					(end 478.927414 -274.117816)
				)
				(arc
					(start 478.927414 -274.321016)
					(mid 478.942293 -274.356937)
					(end 478.978214 -274.371816)
				)
				(arc
					(start 479.791014 -274.371816)
					(mid 479.826935 -274.356937)
					(end 479.841814 -274.321016)
				)
				(arc
					(start 479.841814 -274.117816)
					(mid 479.826935 -274.081895)
					(end 479.791014 -274.067016)
				)
			)
		)
	)
	(zone
		(layer "In1.Cu")
		(hatch none 0.5)
		(connect_pads
			(clearance 0)
		)
		(min_thickness 0.25)
		(keepout
			(tracks not_allowed)
			(vias allowed)
			(pads allowed)
			(copperpour not_allowed)
			(footprints allowed)
		)
		(placement
			(enabled no)
			(sheetname "")
		)
		(fill
			(thermal_gap 0.5)
			(thermal_bridge_width 0.5)
			(island_removal_mode 0)
		)
		(polygon
			(pts
				(xy 420.843964 -158.000192) (xy 423.206164 -158.000192) (xy 423.206164 -159.879792) (xy 420.843964 -159.879792)
			)
		)
	)
	(zone
		(layer "In1.Cu")
		(hatch none 0.5)
		(connect_pads
			(clearance 0)
		)
		(min_thickness 0.25)
		(keepout
			(tracks not_allowed)
			(vias allowed)
			(pads allowed)
			(copperpour not_allowed)
			(footprints allowed)
		)
		(placement
			(enabled no)
			(sheetname "")
		)
		(fill
			(thermal_gap 0.5)
			(thermal_bridge_width 0.5)
			(island_removal_mode 0)
		)
		(polygon
			(pts
				(xy 91.943936 -276.810216) (xy 94.306136 -276.810216) (xy 94.306136 -278.689816) (xy 91.943936 -278.689816)
			)
		)
	)
	(zone
		(layer "In1.Cu")
		(hatch none 0.5)
		(connect_pads
			(clearance 0)
		)
		(min_thickness 0.25)
		(keepout
			(tracks not_allowed)
			(vias allowed)
			(pads allowed)
			(copperpour not_allowed)
			(footprints allowed)
		)
		(placement
			(enabled no)
			(sheetname "")
		)
		(fill
			(thermal_gap 0.5)
			(thermal_bridge_width 0.5)
			(island_removal_mode 0)
		)
		(polygon
			(pts
				(xy 452.393812 -161.810192) (xy 454.756012 -161.810192) (xy 454.756012 -163.689792) (xy 452.393812 -163.689792)
			)
		)
	)
	(zone
		(layer "In1.Cu")
		(hatch none 0.5)
		(connect_pads
			(clearance 0)
		)
		(min_thickness 0.25)
		(keepout
			(tracks not_allowed)
			(vias allowed)
			(pads allowed)
			(copperpour not_allowed)
			(footprints allowed)
		)
		(placement
			(enabled no)
			(sheetname "")
		)
		(fill
			(thermal_gap 0.5)
			(thermal_bridge_width 0.5)
			(island_removal_mode 0)
		)
		(polygon
			(pts
				(xy 60.393834 -43.000168) (xy 62.756034 -43.000168) (xy 62.756034 -44.879768) (xy 60.393834 -44.879768)
			)
		)
	)
	(zone
		(layer "In1.Cu")
		(hatch none 0.5)
		(connect_pads
			(clearance 0)
		)
		(min_thickness 0.25)
		(keepout
			(tracks not_allowed)
			(vias allowed)
			(pads allowed)
			(copperpour not_allowed)
			(footprints allowed)
		)
		(placement
			(enabled no)
			(sheetname "")
		)
		(fill
			(thermal_gap 0.5)
			(thermal_bridge_width 0.5)
			(island_removal_mode 0)
		)
		(polygon
			(pts
				(arc
					(start 126.706884 -159.066992)
					(mid 126.670963 -159.081871)
					(end 126.656084 -159.117792)
				)
				(arc
					(start 126.656084 -159.320992)
					(mid 126.670963 -159.356913)
					(end 126.706884 -159.371792)
				)
				(arc
					(start 127.519684 -159.371792)
					(mid 127.555605 -159.356913)
					(end 127.570484 -159.320992)
				)
				(arc
					(start 127.570484 -159.117792)
					(mid 127.555605 -159.081871)
					(end 127.519684 -159.066992)
				)
			)
		)
	)
	(zone
		(layer "In1.Cu")
		(hatch none 0.5)
		(connect_pads
			(clearance 0)
		)
		(min_thickness 0.25)
		(keepout
			(tracks not_allowed)
			(vias allowed)
			(pads allowed)
			(copperpour not_allowed)
			(footprints allowed)
		)
		(placement
			(enabled no)
			(sheetname "")
		)
		(fill
			(thermal_gap 0.5)
			(thermal_bridge_width 0.5)
			(island_removal_mode 0)
		)
		(polygon
			(pts
				(arc
					(start 158.256986 -43.508168)
					(mid 158.221065 -43.523047)
					(end 158.206186 -43.558968)
				)
				(arc
					(start 158.206186 -43.762168)
					(mid 158.221065 -43.798089)
					(end 158.256986 -43.812968)
				)
				(arc
					(start 159.069786 -43.812968)
					(mid 159.105707 -43.798089)
					(end 159.120586 -43.762168)
				)
				(arc
					(start 159.120586 -43.558968)
					(mid 159.105707 -43.523047)
					(end 159.069786 -43.508168)
				)
			)
		)
	)
	(zone
		(layer "In1.Cu")
		(hatch none 0.5)
		(connect_pads
			(clearance 0)
		)
		(min_thickness 0.25)
		(keepout
			(tracks not_allowed)
			(vias allowed)
			(pads allowed)
			(copperpour not_allowed)
			(footprints allowed)
		)
		(placement
			(enabled no)
			(sheetname "")
		)
		(fill
			(thermal_gap 0.5)
			(thermal_bridge_width 0.5)
			(island_removal_mode 0)
		)
		(polygon
			(pts
				(arc
					(start 384.328162 -274.067016)
					(mid 384.292241 -274.081895)
					(end 384.277362 -274.117816)
				)
				(arc
					(start 384.277362 -274.321016)
					(mid 384.292241 -274.356937)
					(end 384.328162 -274.371816)
				)
				(arc
					(start 385.140962 -274.371816)
					(mid 385.176883 -274.356937)
					(end 385.191762 -274.321016)
				)
				(arc
					(start 385.191762 -274.117816)
					(mid 385.176883 -274.081895)
					(end 385.140962 -274.067016)
				)
			)
		)
	)
	(zone
		(layer "In1.Cu")
		(hatch none 0.5)
		(connect_pads
			(clearance 0)
		)
		(min_thickness 0.25)
		(keepout
			(tracks not_allowed)
			(vias allowed)
			(pads allowed)
			(copperpour not_allowed)
			(footprints allowed)
		)
		(placement
			(enabled no)
			(sheetname "")
		)
		(fill
			(thermal_gap 0.5)
			(thermal_bridge_width 0.5)
			(island_removal_mode 0)
		)
		(polygon
			(pts
				(arc
					(start 321.228212 -159.066992)
					(mid 321.192291 -159.081871)
					(end 321.177412 -159.117792)
				)
				(arc
					(start 321.177412 -159.320992)
					(mid 321.192291 -159.356913)
					(end 321.228212 -159.371792)
				)
				(arc
					(start 322.041012 -159.371792)
					(mid 322.076933 -159.356913)
					(end 322.091812 -159.320992)
				)
				(arc
					(start 322.091812 -159.117792)
					(mid 322.076933 -159.081871)
					(end 322.041012 -159.066992)
				)
			)
		)
	)
	(zone
		(layer "In1.Cu")
		(hatch none 0.5)
		(connect_pads
			(clearance 0)
		)
		(min_thickness 0.25)
		(keepout
			(tracks not_allowed)
			(vias allowed)
			(pads allowed)
			(copperpour not_allowed)
			(footprints allowed)
		)
		(placement
			(enabled no)
			(sheetname "")
		)
		(fill
			(thermal_gap 0.5)
			(thermal_bridge_width 0.5)
			(island_removal_mode 0)
		)
		(polygon
			(pts
				(xy 123.493784 -158.000192) (xy 125.855984 -158.000192) (xy 125.855984 -159.879792) (xy 123.493784 -159.879792)
			)
		)
	)
	(zone
		(layer "In1.Cu")
		(hatch none 0.5)
		(connect_pads
			(clearance 0)
		)
		(min_thickness 0.25)
		(keepout
			(tracks not_allowed)
			(vias allowed)
			(pads allowed)
			(copperpour not_allowed)
			(footprints allowed)
		)
		(placement
			(enabled no)
			(sheetname "")
		)
		(fill
			(thermal_gap 0.5)
			(thermal_bridge_width 0.5)
			(island_removal_mode 0)
		)
		(polygon
			(pts
				(xy 123.493784 -273.000216) (xy 125.855984 -273.000216) (xy 125.855984 -274.879816) (xy 123.493784 -274.879816)
			)
		)
	)
	(zone
		(layer "In1.Cu")
		(hatch none 0.5)
		(connect_pads
			(clearance 0)
		)
		(min_thickness 0.25)
		(keepout
			(tracks not_allowed)
			(vias allowed)
			(pads allowed)
			(copperpour not_allowed)
			(footprints allowed)
		)
		(placement
			(enabled no)
			(sheetname "")
		)
		(fill
			(thermal_gap 0.5)
			(thermal_bridge_width 0.5)
			(island_removal_mode 0)
		)
		(polygon
			(pts
				(xy 420.843964 -46.810168) (xy 423.206164 -46.810168) (xy 423.206164 -48.689768) (xy 420.843964 -48.689768)
			)
		)
	)
	(zone
		(layer "In1.Cu")
		(hatch none 0.5)
		(connect_pads
			(clearance 0)
		)
		(min_thickness 0.25)
		(keepout
			(tracks not_allowed)
			(vias allowed)
			(pads allowed)
			(copperpour not_allowed)
			(footprints allowed)
		)
		(placement
			(enabled no)
			(sheetname "")
		)
		(fill
			(thermal_gap 0.5)
			(thermal_bridge_width 0.5)
			(island_removal_mode 0)
		)
		(polygon
			(pts
				(xy 420.843964 -161.810192) (xy 423.206164 -161.810192) (xy 423.206164 -163.689792) (xy 420.843964 -163.689792)
			)
		)
	)
	(zone
		(layer "In1.Cu")
		(hatch none 0.5)
		(connect_pads
			(clearance 0)
		)
		(min_thickness 0.25)
		(keepout
			(tracks not_allowed)
			(vias allowed)
			(pads allowed)
			(copperpour not_allowed)
			(footprints allowed)
		)
		(placement
			(enabled no)
			(sheetname "")
		)
		(fill
			(thermal_gap 0.5)
			(thermal_bridge_width 0.5)
			(island_removal_mode 0)
		)
		(polygon
			(pts
				(arc
					(start 384.328162 -44.066968)
					(mid 384.292241 -44.081847)
					(end 384.277362 -44.117768)
				)
				(arc
					(start 384.277362 -44.320968)
					(mid 384.292241 -44.356889)
					(end 384.328162 -44.371768)
				)
				(arc
					(start 385.140962 -44.371768)
					(mid 385.176883 -44.356889)
					(end 385.191762 -44.320968)
				)
				(arc
					(start 385.191762 -44.117768)
					(mid 385.176883 -44.081847)
					(end 385.140962 -44.066968)
				)
			)
		)
	)
	(zone
		(layer "In1.Cu")
		(hatch none 0.5)
		(connect_pads
			(clearance 0)
		)
		(min_thickness 0.25)
		(keepout
			(tracks not_allowed)
			(vias allowed)
			(pads allowed)
			(copperpour not_allowed)
			(footprints allowed)
		)
		(placement
			(enabled no)
			(sheetname "")
		)
		(fill
			(thermal_gap 0.5)
			(thermal_bridge_width 0.5)
			(island_removal_mode 0)
		)
		(polygon
			(pts
				(xy 28.843986 -43.000168) (xy 31.206186 -43.000168) (xy 31.206186 -44.879768) (xy 28.843986 -44.879768)
			)
		)
	)
	(zone
		(layer "In1.Cu")
		(hatch none 0.5)
		(connect_pads
			(clearance 0)
		)
		(min_thickness 0.25)
		(keepout
			(tracks not_allowed)
			(vias allowed)
			(pads allowed)
			(copperpour not_allowed)
			(footprints allowed)
		)
		(placement
			(enabled no)
			(sheetname "")
		)
		(fill
			(thermal_gap 0.5)
			(thermal_bridge_width 0.5)
			(island_removal_mode 0)
		)
		(polygon
			(pts
				(xy 452.393812 -158.000192) (xy 454.756012 -158.000192) (xy 454.756012 -159.879792) (xy 452.393812 -159.879792)
			)
		)
	)
	(zone
		(layer "In1.Cu")
		(hatch none 0.5)
		(connect_pads
			(clearance 0)
		)
		(min_thickness 0.25)
		(keepout
			(tracks not_allowed)
			(vias allowed)
			(pads allowed)
			(copperpour not_allowed)
			(footprints allowed)
		)
		(placement
			(enabled no)
			(sheetname "")
		)
		(fill
			(thermal_gap 0.5)
			(thermal_bridge_width 0.5)
			(island_removal_mode 0)
		)
		(polygon
			(pts
				(xy 452.393812 -273.000216) (xy 454.756012 -273.000216) (xy 454.756012 -274.879816) (xy 452.393812 -274.879816)
			)
		)
	)
	(zone
		(layer "In1.Cu")
		(hatch none 0.5)
		(connect_pads
			(clearance 0)
		)
		(min_thickness 0.25)
		(keepout
			(tracks not_allowed)
			(vias allowed)
			(pads allowed)
			(copperpour not_allowed)
			(footprints allowed)
		)
		(placement
			(enabled no)
			(sheetname "")
		)
		(fill
			(thermal_gap 0.5)
			(thermal_bridge_width 0.5)
			(island_removal_mode 0)
		)
		(polygon
			(pts
				(xy 483.943914 -276.810216) (xy 486.306114 -276.810216) (xy 486.306114 -278.689816) (xy 483.943914 -278.689816)
			)
		)
	)
	(zone
		(layer "In1.Cu")
		(hatch none 0.5)
		(connect_pads
			(clearance 0)
		)
		(min_thickness 0.25)
		(keepout
			(tracks not_allowed)
			(vias allowed)
			(pads allowed)
			(copperpour not_allowed)
			(footprints allowed)
		)
		(placement
			(enabled no)
			(sheetname "")
		)
		(fill
			(thermal_gap 0.5)
			(thermal_bridge_width 0.5)
			(island_removal_mode 0)
		)
		(polygon
			(pts
				(xy 60.393834 -161.810192) (xy 62.756034 -161.810192) (xy 62.756034 -163.689792) (xy 60.393834 -163.689792)
			)
		)
	)
	(zone
		(layer "In1.Cu")
		(hatch none 0.5)
		(connect_pads
			(clearance 0)
		)
		(min_thickness 0.25)
		(keepout
			(tracks not_allowed)
			(vias allowed)
			(pads allowed)
			(copperpour not_allowed)
			(footprints allowed)
		)
		(placement
			(enabled no)
			(sheetname "")
		)
		(fill
			(thermal_gap 0.5)
			(thermal_bridge_width 0.5)
			(island_removal_mode 0)
		)
		(polygon
			(pts
				(xy 28.843986 -46.810168) (xy 31.206186 -46.810168) (xy 31.206186 -48.689768) (xy 28.843986 -48.689768)
			)
		)
	)
	(zone
		(layer "In1.Cu")
		(hatch none 0.5)
		(connect_pads
			(clearance 0)
		)
		(min_thickness 0.25)
		(keepout
			(tracks not_allowed)
			(vias allowed)
			(pads allowed)
			(copperpour not_allowed)
			(footprints allowed)
		)
		(placement
			(enabled no)
			(sheetname "")
		)
		(fill
			(thermal_gap 0.5)
			(thermal_bridge_width 0.5)
			(island_removal_mode 0)
		)
		(polygon
			(pts
				(arc
					(start 126.706884 -273.508216)
					(mid 126.670963 -273.523095)
					(end 126.656084 -273.559016)
				)
				(arc
					(start 126.656084 -273.762216)
					(mid 126.670963 -273.798137)
					(end 126.706884 -273.813016)
				)
				(arc
					(start 127.519684 -273.813016)
					(mid 127.555605 -273.798137)
					(end 127.570484 -273.762216)
				)
				(arc
					(start 127.570484 -273.559016)
					(mid 127.555605 -273.523095)
					(end 127.519684 -273.508216)
				)
			)
		)
	)
	(zone
		(layer "In1.Cu")
		(hatch none 0.5)
		(connect_pads
			(clearance 0)
		)
		(min_thickness 0.25)
		(keepout
			(tracks not_allowed)
			(vias allowed)
			(pads allowed)
			(copperpour not_allowed)
			(footprints allowed)
		)
		(placement
			(enabled no)
			(sheetname "")
		)
		(fill
			(thermal_gap 0.5)
			(thermal_bridge_width 0.5)
			(island_removal_mode 0)
		)
		(polygon
			(pts
				(xy 357.744014 -158.000192) (xy 360.106214 -158.000192) (xy 360.106214 -159.879792) (xy 357.744014 -159.879792)
			)
		)
	)
	(zone
		(layer "In1.Cu")
		(hatch none 0.5)
		(connect_pads
			(clearance 0)
		)
		(min_thickness 0.25)
		(keepout
			(tracks not_allowed)
			(vias allowed)
			(pads allowed)
			(copperpour not_allowed)
			(footprints allowed)
		)
		(placement
			(enabled no)
			(sheetname "")
		)
		(fill
			(thermal_gap 0.5)
			(thermal_bridge_width 0.5)
			(island_removal_mode 0)
		)
		(polygon
			(pts
				(xy 483.943914 -46.810168) (xy 486.306114 -46.810168) (xy 486.306114 -48.689768) (xy 483.943914 -48.689768)
			)
		)
	)
	(zone
		(layer "In1.Cu")
		(hatch none 0.5)
		(connect_pads
			(clearance 0)
		)
		(min_thickness 0.25)
		(keepout
			(tracks not_allowed)
			(vias allowed)
			(pads allowed)
			(copperpour not_allowed)
			(footprints allowed)
		)
		(placement
			(enabled no)
			(sheetname "")
		)
		(fill
			(thermal_gap 0.5)
			(thermal_bridge_width 0.5)
			(island_removal_mode 0)
		)
		(polygon
			(pts
				(arc
					(start 384.328162 -159.066992)
					(mid 384.292241 -159.081871)
					(end 384.277362 -159.117792)
				)
				(arc
					(start 384.277362 -159.320992)
					(mid 384.292241 -159.356913)
					(end 384.328162 -159.371792)
				)
				(arc
					(start 385.140962 -159.371792)
					(mid 385.176883 -159.356913)
					(end 385.191762 -159.320992)
				)
				(arc
					(start 385.191762 -159.117792)
					(mid 385.176883 -159.081871)
					(end 385.140962 -159.066992)
				)
			)
		)
	)
	(zone
		(net "AGND_CURRENT_MONOB")
		(layer "In1.Cu")
		(hatch none 0.5)
		(connect_pads
			(clearance 0.5)
		)
		(min_thickness 0.25)
		(fill yes
			(thermal_gap 0.5)
			(thermal_bridge_width 0.5)
			(island_removal_mode 0)
		)
		(polygon
			(pts
				(xy 359.259378 -129.629916) (xy 358.4067 -130.482594) (xy 358.4067 -146.606006) (xy 363.222794 -151.4221)
				(xy 375.815606 -151.4221) (xy 385.6609 -141.576806) (xy 385.6609 -136.172194) (xy 381.022606 -131.5339)
				(xy 373.83339 -131.5339) (xy 371.929406 -129.629916)
			)
		)
	)
	(zone
		(layer "In1.Cu")
		(hatch none 0.5)
		(connect_pads
			(clearance 0)
		)
		(min_thickness 0.25)
		(keepout
			(tracks not_allowed)
			(vias allowed)
			(pads allowed)
			(copperpour not_allowed)
			(footprints allowed)
		)
		(placement
			(enabled no)
			(sheetname "")
		)
		(fill
			(thermal_gap 0.5)
			(thermal_bridge_width 0.5)
			(island_removal_mode 0)
		)
		(polygon
			(pts
				(xy 483.943914 -273.000216) (xy 486.306114 -273.000216) (xy 486.306114 -274.879816) (xy 483.943914 -274.879816)
			)
		)
	)
	(zone
		(layer "In1.Cu")
		(hatch none 0.5)
		(connect_pads
			(clearance 0)
		)
		(min_thickness 0.25)
		(keepout
			(tracks not_allowed)
			(vias allowed)
			(pads allowed)
			(copperpour not_allowed)
			(footprints allowed)
		)
		(placement
			(enabled no)
			(sheetname "")
		)
		(fill
			(thermal_gap 0.5)
			(thermal_bridge_width 0.5)
			(island_removal_mode 0)
		)
		(polygon
			(pts
				(xy 452.393812 -43.000168) (xy 454.756012 -43.000168) (xy 454.756012 -44.879768) (xy 452.393812 -44.879768)
			)
		)
	)
	(zone
		(layer "In1.Cu")
		(hatch none 0.5)
		(connect_pads
			(clearance 0)
		)
		(min_thickness 0.25)
		(keepout
			(tracks not_allowed)
			(vias allowed)
			(pads allowed)
			(copperpour not_allowed)
			(footprints allowed)
		)
		(placement
			(enabled no)
			(sheetname "")
		)
		(fill
			(thermal_gap 0.5)
			(thermal_bridge_width 0.5)
			(island_removal_mode 0)
		)
		(polygon
			(pts
				(arc
					(start 95.157036 -159.066992)
					(mid 95.121115 -159.081871)
					(end 95.106236 -159.117792)
				)
				(arc
					(start 95.106236 -159.320992)
					(mid 95.121115 -159.356913)
					(end 95.157036 -159.371792)
				)
				(arc
					(start 95.969836 -159.371792)
					(mid 96.005757 -159.356913)
					(end 96.020636 -159.320992)
				)
				(arc
					(start 96.020636 -159.117792)
					(mid 96.005757 -159.081871)
					(end 95.969836 -159.066992)
				)
			)
		)
	)
	(zone
		(layer "In1.Cu")
		(hatch none 0.5)
		(connect_pads
			(clearance 0)
		)
		(min_thickness 0.25)
		(keepout
			(tracks not_allowed)
			(vias allowed)
			(pads allowed)
			(copperpour not_allowed)
			(footprints allowed)
		)
		(placement
			(enabled no)
			(sheetname "")
		)
		(fill
			(thermal_gap 0.5)
			(thermal_bridge_width 0.5)
			(island_removal_mode 0)
		)
		(polygon
			(pts
				(xy 389.293862 -161.810192) (xy 391.656062 -161.810192) (xy 391.656062 -163.689792) (xy 389.293862 -163.689792)
			)
		)
	)
	(zone
		(layer "In1.Cu")
		(hatch none 0.5)
		(connect_pads
			(clearance 0)
		)
		(min_thickness 0.25)
		(keepout
			(tracks not_allowed)
			(vias allowed)
			(pads allowed)
			(copperpour not_allowed)
			(footprints allowed)
		)
		(placement
			(enabled no)
			(sheetname "")
		)
		(fill
			(thermal_gap 0.5)
			(thermal_bridge_width 0.5)
			(island_removal_mode 0)
		)
		(polygon
			(pts
				(arc
					(start 240.874804 -134.850124)
					(mid 239.900206 -135.17499)
					(end 240.225072 -136.149588)
				)
				(xy 240.223802 -136.151874) (xy 242.223798 -137.151872)
				(arc
					(start 242.225068 -137.149586)
					(mid 243.199666 -136.82472)
					(end 242.8748 -135.850122)
				)
				(xy 242.87607 -135.847836) (xy 240.876074 -134.847838) (xy 240.87582 -134.848092)
			)
		)
	)
	(zone
		(layer "In1.Cu")
		(hatch none 0.5)
		(connect_pads
			(clearance 0)
		)
		(min_thickness 0.25)
		(keepout
			(tracks not_allowed)
			(vias allowed)
			(pads allowed)
			(copperpour not_allowed)
			(footprints allowed)
		)
		(placement
			(enabled no)
			(sheetname "")
		)
		(fill
			(thermal_gap 0.5)
			(thermal_bridge_width 0.5)
			(island_removal_mode 0)
		)
		(polygon
			(pts
				(arc
					(start 321.228212 -158.508192)
					(mid 321.192291 -158.523071)
					(end 321.177412 -158.558992)
				)
				(arc
					(start 321.177412 -158.762192)
					(mid 321.192291 -158.798113)
					(end 321.228212 -158.812992)
				)
				(arc
					(start 322.041012 -158.812992)
					(mid 322.076933 -158.798113)
					(end 322.091812 -158.762192)
				)
				(arc
					(start 322.091812 -158.558992)
					(mid 322.076933 -158.523071)
					(end 322.041012 -158.508192)
				)
			)
		)
	)
	(zone
		(layer "In1.Cu")
		(hatch none 0.5)
		(connect_pads
			(clearance 0)
		)
		(min_thickness 0.25)
		(keepout
			(tracks not_allowed)
			(vias allowed)
			(pads allowed)
			(copperpour not_allowed)
			(footprints allowed)
		)
		(placement
			(enabled no)
			(sheetname "")
		)
		(fill
			(thermal_gap 0.5)
			(thermal_bridge_width 0.5)
			(island_removal_mode 0)
		)
		(polygon
			(pts
				(arc
					(start 352.778314 -273.508216)
					(mid 352.742393 -273.523095)
					(end 352.727514 -273.559016)
				)
				(arc
					(start 352.727514 -273.762216)
					(mid 352.742393 -273.798137)
					(end 352.778314 -273.813016)
				)
				(arc
					(start 353.591114 -273.813016)
					(mid 353.627035 -273.798137)
					(end 353.641914 -273.762216)
				)
				(arc
					(start 353.641914 -273.559016)
					(mid 353.627035 -273.523095)
					(end 353.591114 -273.508216)
				)
			)
		)
	)
	(zone
		(layer "In1.Cu")
		(hatch none 0.5)
		(connect_pads
			(clearance 0)
		)
		(min_thickness 0.25)
		(keepout
			(tracks not_allowed)
			(vias allowed)
			(pads allowed)
			(copperpour not_allowed)
			(footprints allowed)
		)
		(placement
			(enabled no)
			(sheetname "")
		)
		(fill
			(thermal_gap 0.5)
			(thermal_bridge_width 0.5)
			(island_removal_mode 0)
		)
		(polygon
			(pts
				(xy 186.593988 -161.810192) (xy 188.956188 -161.810192) (xy 188.956188 -163.689792) (xy 186.593988 -163.689792)
			)
		)
	)
	(zone
		(layer "In1.Cu")
		(hatch none 0.5)
		(connect_pads
			(clearance 0)
		)
		(min_thickness 0.25)
		(keepout
			(tracks not_allowed)
			(vias allowed)
			(pads allowed)
			(copperpour not_allowed)
			(footprints allowed)
		)
		(placement
			(enabled no)
			(sheetname "")
		)
		(fill
			(thermal_gap 0.5)
			(thermal_bridge_width 0.5)
			(island_removal_mode 0)
		)
		(polygon
			(pts
				(arc
					(start 352.778314 -43.508168)
					(mid 352.742393 -43.523047)
					(end 352.727514 -43.558968)
				)
				(arc
					(start 352.727514 -43.762168)
					(mid 352.742393 -43.798089)
					(end 352.778314 -43.812968)
				)
				(arc
					(start 353.591114 -43.812968)
					(mid 353.627035 -43.798089)
					(end 353.641914 -43.762168)
				)
				(arc
					(start 353.641914 -43.558968)
					(mid 353.627035 -43.523047)
					(end 353.591114 -43.508168)
				)
			)
		)
	)
	(zone
		(layer "In1.Cu")
		(hatch none 0.5)
		(connect_pads
			(clearance 0)
		)
		(min_thickness 0.25)
		(keepout
			(tracks not_allowed)
			(vias allowed)
			(pads allowed)
			(copperpour not_allowed)
			(footprints allowed)
		)
		(placement
			(enabled no)
			(sheetname "")
		)
		(fill
			(thermal_gap 0.5)
			(thermal_bridge_width 0.5)
			(island_removal_mode 0)
		)
		(polygon
			(pts
				(arc
					(start 126.706884 -274.067016)
					(mid 126.670963 -274.081895)
					(end 126.656084 -274.117816)
				)
				(arc
					(start 126.656084 -274.321016)
					(mid 126.670963 -274.356937)
					(end 126.706884 -274.371816)
				)
				(arc
					(start 127.519684 -274.371816)
					(mid 127.555605 -274.356937)
					(end 127.570484 -274.321016)
				)
				(arc
					(start 127.570484 -274.117816)
					(mid 127.555605 -274.081895)
					(end 127.519684 -274.067016)
				)
			)
		)
	)
	(zone
		(layer "In1.Cu")
		(hatch none 0.5)
		(connect_pads
			(clearance 0)
		)
		(min_thickness 0.25)
		(keepout
			(tracks not_allowed)
			(vias allowed)
			(pads allowed)
			(copperpour not_allowed)
			(footprints allowed)
		)
		(placement
			(enabled no)
			(sheetname "")
		)
		(fill
			(thermal_gap 0.5)
			(thermal_bridge_width 0.5)
			(island_removal_mode 0)
		)
		(polygon
			(pts
				(arc
					(start 158.256986 -159.066992)
					(mid 158.221065 -159.081871)
					(end 158.206186 -159.117792)
				)
				(arc
					(start 158.206186 -159.320992)
					(mid 158.221065 -159.356913)
					(end 158.256986 -159.371792)
				)
				(arc
					(start 159.069786 -159.371792)
					(mid 159.105707 -159.356913)
					(end 159.120586 -159.320992)
				)
				(arc
					(start 159.120586 -159.117792)
					(mid 159.105707 -159.081871)
					(end 159.069786 -159.066992)
				)
			)
		)
	)
	(zone
		(layer "In1.Cu")
		(hatch none 0.5)
		(connect_pads
			(clearance 0)
		)
		(min_thickness 0.25)
		(keepout
			(tracks not_allowed)
			(vias allowed)
			(pads allowed)
			(copperpour not_allowed)
			(footprints allowed)
		)
		(placement
			(enabled no)
			(sheetname "")
		)
		(fill
			(thermal_gap 0.5)
			(thermal_bridge_width 0.5)
			(island_removal_mode 0)
		)
		(polygon
			(pts
				(arc
					(start 32.057086 -43.508168)
					(mid 32.021165 -43.523047)
					(end 32.006286 -43.558968)
				)
				(arc
					(start 32.006286 -43.762168)
					(mid 32.021165 -43.798089)
					(end 32.057086 -43.812968)
				)
				(arc
					(start 32.869886 -43.812968)
					(mid 32.905807 -43.798089)
					(end 32.920686 -43.762168)
				)
				(arc
					(start 32.920686 -43.558968)
					(mid 32.905807 -43.523047)
					(end 32.869886 -43.508168)
				)
			)
		)
	)
	(zone
		(net "AGND_CURRENT_MONOA")
		(layer "In1.Cu")
		(hatch none 0.5)
		(connect_pads
			(clearance 0.5)
		)
		(min_thickness 0.25)
		(fill yes
			(thermal_gap 0.5)
			(thermal_bridge_width 0.5)
			(island_removal_mode 0)
		)
		(polygon
			(pts
				(xy 141.6685 -126.5809) (xy 138.1633 -130.0861) (xy 138.1633 -136.019794) (xy 137.823194 -136.3599)
				(xy 133.352794 -136.3599) (xy 129.3241 -140.388594) (xy 129.3241 -147.469606) (xy 129.63779 -147.783296)
				(xy 155.551886 -147.783296) (xy 159.7025 -143.632682) (xy 159.7025 -134.902194) (xy 156.7053 -131.904994)
				(xy 156.7053 -130.279394) (xy 153.006806 -126.5809)
			)
		)
	)
	(zone
		(layer "In1.Cu")
		(hatch none 0.5)
		(connect_pads
			(clearance 0)
		)
		(min_thickness 0.25)
		(keepout
			(tracks not_allowed)
			(vias allowed)
			(pads allowed)
			(copperpour not_allowed)
			(footprints allowed)
		)
		(placement
			(enabled no)
			(sheetname "")
		)
		(fill
			(thermal_gap 0.5)
			(thermal_bridge_width 0.5)
			(island_removal_mode 0)
		)
		(polygon
			(pts
				(xy 186.593988 -276.810216) (xy 188.956188 -276.810216) (xy 188.956188 -278.689816) (xy 186.593988 -278.689816)
			)
		)
	)
	(zone
		(layer "In1.Cu")
		(hatch none 0.5)
		(connect_pads
			(clearance 0)
		)
		(min_thickness 0.25)
		(keepout
			(tracks not_allowed)
			(vias allowed)
			(pads allowed)
			(copperpour not_allowed)
			(footprints allowed)
		)
		(placement
			(enabled no)
			(sheetname "")
		)
		(fill
			(thermal_gap 0.5)
			(thermal_bridge_width 0.5)
			(island_removal_mode 0)
		)
		(polygon
			(pts
				(xy 186.593988 -46.810168) (xy 188.956188 -46.810168) (xy 188.956188 -48.689768) (xy 186.593988 -48.689768)
			)
		)
	)
	(zone
		(layer "In1.Cu")
		(hatch none 0.5)
		(connect_pads
			(clearance 0)
		)
		(min_thickness 0.25)
		(keepout
			(tracks not_allowed)
			(vias allowed)
			(pads allowed)
			(copperpour not_allowed)
			(footprints allowed)
		)
		(placement
			(enabled no)
			(sheetname "")
		)
		(fill
			(thermal_gap 0.5)
			(thermal_bridge_width 0.5)
			(island_removal_mode 0)
		)
		(polygon
			(pts
				(xy 91.943936 -273.000216) (xy 94.306136 -273.000216) (xy 94.306136 -274.879816) (xy 91.943936 -274.879816)
			)
		)
	)
	(zone
		(layer "In1.Cu")
		(hatch none 0.5)
		(connect_pads
			(clearance 0)
		)
		(min_thickness 0.25)
		(keepout
			(tracks not_allowed)
			(vias allowed)
			(pads allowed)
			(copperpour not_allowed)
			(footprints allowed)
		)
		(placement
			(enabled no)
			(sheetname "")
		)
		(fill
			(thermal_gap 0.5)
			(thermal_bridge_width 0.5)
			(island_removal_mode 0)
		)
		(polygon
			(pts
				(arc
					(start 32.057086 -274.067016)
					(mid 32.021165 -274.081895)
					(end 32.006286 -274.117816)
				)
				(arc
					(start 32.006286 -274.321016)
					(mid 32.021165 -274.356937)
					(end 32.057086 -274.371816)
				)
				(arc
					(start 32.869886 -274.371816)
					(mid 32.905807 -274.356937)
					(end 32.920686 -274.321016)
				)
				(arc
					(start 32.920686 -274.117816)
					(mid 32.905807 -274.081895)
					(end 32.869886 -274.067016)
				)
			)
		)
	)
	(zone
		(layer "In1.Cu")
		(hatch none 0.5)
		(connect_pads
			(clearance 0)
		)
		(min_thickness 0.25)
		(keepout
			(tracks not_allowed)
			(vias allowed)
			(pads allowed)
			(copperpour not_allowed)
			(footprints allowed)
		)
		(placement
			(enabled no)
			(sheetname "")
		)
		(fill
			(thermal_gap 0.5)
			(thermal_bridge_width 0.5)
			(island_removal_mode 0)
		)
		(polygon
			(pts
				(arc
					(start 63.606934 -43.508168)
					(mid 63.571013 -43.523047)
					(end 63.556134 -43.558968)
				)
				(arc
					(start 63.556134 -43.762168)
					(mid 63.571013 -43.798089)
					(end 63.606934 -43.812968)
				)
				(arc
					(start 64.419734 -43.812968)
					(mid 64.455655 -43.798089)
					(end 64.470534 -43.762168)
				)
				(arc
					(start 64.470534 -43.558968)
					(mid 64.455655 -43.523047)
					(end 64.419734 -43.508168)
				)
			)
		)
	)
	(zone
		(layer "In1.Cu")
		(hatch none 0.5)
		(connect_pads
			(clearance 0)
		)
		(min_thickness 0.25)
		(keepout
			(tracks not_allowed)
			(vias allowed)
			(pads allowed)
			(copperpour not_allowed)
			(footprints allowed)
		)
		(placement
			(enabled no)
			(sheetname "")
		)
		(fill
			(thermal_gap 0.5)
			(thermal_bridge_width 0.5)
			(island_removal_mode 0)
		)
		(polygon
			(pts
				(arc
					(start 158.256986 -158.508192)
					(mid 158.221065 -158.523071)
					(end 158.206186 -158.558992)
				)
				(arc
					(start 158.206186 -158.762192)
					(mid 158.221065 -158.798113)
					(end 158.256986 -158.812992)
				)
				(arc
					(start 159.069786 -158.812992)
					(mid 159.105707 -158.798113)
					(end 159.120586 -158.762192)
				)
				(arc
					(start 159.120586 -158.558992)
					(mid 159.105707 -158.523071)
					(end 159.069786 -158.508192)
				)
			)
		)
	)
	(zone
		(layers "In1.Cu" "In2.Cu")
		(hatch none 0.5)
		(connect_pads
			(clearance 0)
		)
		(min_thickness 0.25)
		(keepout
			(tracks not_allowed)
			(vias allowed)
			(pads allowed)
			(copperpour not_allowed)
			(footprints allowed)
		)
		(placement
			(enabled no)
			(sheetname "")
		)
		(fill yes
			(thermal_gap 0.5)
			(thermal_bridge_width 0.5)
			(island_removal_mode 0)
		)
		(polygon
			(pts
				(xy 389.293862 -161.149792) (xy 391.656062 -161.149792) (xy 391.656062 -164.350192) (xy 389.293862 -164.350192)
			)
		)
	)
	(zone
		(layers "In1.Cu" "In2.Cu")
		(hatch none 0.5)
		(connect_pads
			(clearance 0)
		)
		(min_thickness 0.25)
		(keepout
			(tracks not_allowed)
			(vias allowed)
			(pads allowed)
			(copperpour not_allowed)
			(footprints allowed)
		)
		(placement
			(enabled no)
			(sheetname "")
		)
		(fill yes
			(thermal_gap 0.5)
			(thermal_bridge_width 0.5)
			(island_removal_mode 0)
		)
		(polygon
			(pts
				(xy 186.593988 -157.339792) (xy 188.956188 -157.340554) (xy 188.956188 -160.540192) (xy 186.593988 -160.540192)
			)
		)
	)
	(zone
		(layers "In1.Cu" "In2.Cu")
		(hatch none 0.5)
		(connect_pads
			(clearance 0)
		)
		(min_thickness 0.25)
		(keepout
			(tracks not_allowed)
			(vias allowed)
			(pads allowed)
			(copperpour not_allowed)
			(footprints allowed)
		)
		(placement
			(enabled no)
			(sheetname "")
		)
		(fill yes
			(thermal_gap 0.5)
			(thermal_bridge_width 0.5)
			(island_removal_mode 0)
		)
		(polygon
			(pts
				(xy 60.393834 -276.149816) (xy 62.756034 -276.149816) (xy 62.756034 -279.350216) (xy 60.393834 -279.350216)
			)
		)
	)
	(zone
		(layers "In1.Cu" "In2.Cu")
		(hatch none 0.5)
		(connect_pads
			(clearance 0)
		)
		(min_thickness 0.25)
		(keepout
			(tracks not_allowed)
			(vias allowed)
			(pads allowed)
			(copperpour not_allowed)
			(footprints allowed)
		)
		(placement
			(enabled no)
			(sheetname "")
		)
		(fill yes
			(thermal_gap 0.5)
			(thermal_bridge_width 0.5)
			(island_removal_mode 0)
		)
		(polygon
			(pts
				(xy 326.193912 -42.339768) (xy 328.556112 -42.34053) (xy 328.556112 -45.540168) (xy 326.193912 -45.540168)
			)
		)
	)
	(zone
		(layers "In1.Cu" "In2.Cu")
		(hatch none 0.5)
		(connect_pads
			(clearance 0)
		)
		(min_thickness 0.25)
		(keepout
			(tracks not_allowed)
			(vias allowed)
			(pads allowed)
			(copperpour not_allowed)
			(footprints allowed)
		)
		(placement
			(enabled no)
			(sheetname "")
		)
		(fill yes
			(thermal_gap 0.5)
			(thermal_bridge_width 0.5)
			(island_removal_mode 0)
		)
		(polygon
			(pts
				(xy 483.943914 -276.149816) (xy 486.306114 -276.149816) (xy 486.306114 -279.350216) (xy 483.943914 -279.350216)
			)
		)
	)
	(zone
		(layers "In1.Cu" "In2.Cu")
		(hatch none 0.5)
		(connect_pads
			(clearance 0)
		)
		(min_thickness 0.25)
		(keepout
			(tracks not_allowed)
			(vias allowed)
			(pads allowed)
			(copperpour not_allowed)
			(footprints allowed)
		)
		(placement
			(enabled no)
			(sheetname "")
		)
		(fill yes
			(thermal_gap 0.5)
			(thermal_bridge_width 0.5)
			(island_removal_mode 0)
		)
		(polygon
			(pts
				(xy 483.943914 -157.339792) (xy 486.306114 -157.340554) (xy 486.306114 -160.540192) (xy 483.943914 -160.540192)
			)
		)
	)
	(zone
		(layers "In1.Cu" "In2.Cu")
		(hatch none 0.5)
		(connect_pads
			(clearance 0)
		)
		(min_thickness 0.25)
		(keepout
			(tracks not_allowed)
			(vias allowed)
			(pads allowed)
			(copperpour not_allowed)
			(footprints allowed)
		)
		(placement
			(enabled no)
			(sheetname "")
		)
		(fill yes
			(thermal_gap 0.5)
			(thermal_bridge_width 0.5)
			(island_removal_mode 0)
		)
		(polygon
			(pts
				(xy 186.593988 -272.339816) (xy 188.956188 -272.340578) (xy 188.956188 -275.540216) (xy 186.593988 -275.540216)
			)
		)
	)
	(zone
		(layers "In1.Cu" "In2.Cu")
		(hatch none 0.5)
		(connect_pads
			(clearance 0)
		)
		(min_thickness 0.25)
		(keepout
			(tracks not_allowed)
			(vias allowed)
			(pads allowed)
			(copperpour not_allowed)
			(footprints allowed)
		)
		(placement
			(enabled no)
			(sheetname "")
		)
		(fill yes
			(thermal_gap 0.5)
			(thermal_bridge_width 0.5)
			(island_removal_mode 0)
		)
		(polygon
			(pts
				(xy 123.493784 -42.339768) (xy 125.855984 -42.34053) (xy 125.855984 -45.540168) (xy 123.493784 -45.540168)
			)
		)
	)
	(zone
		(layers "In1.Cu" "In2.Cu")
		(hatch none 0.5)
		(connect_pads
			(clearance 0)
		)
		(min_thickness 0.25)
		(keepout
			(tracks not_allowed)
			(vias allowed)
			(pads allowed)
			(copperpour not_allowed)
			(footprints allowed)
		)
		(placement
			(enabled no)
			(sheetname "")
		)
		(fill yes
			(thermal_gap 0.5)
			(thermal_bridge_width 0.5)
			(island_removal_mode 0)
		)
		(polygon
			(pts
				(xy 357.744014 -42.339768) (xy 360.106214 -42.34053) (xy 360.106214 -45.540168) (xy 357.744014 -45.540168)
			)
		)
	)
	(zone
		(layers "In1.Cu" "In2.Cu")
		(hatch none 0.5)
		(connect_pads
			(clearance 0)
		)
		(min_thickness 0.25)
		(keepout
			(tracks not_allowed)
			(vias allowed)
			(pads allowed)
			(copperpour not_allowed)
			(footprints allowed)
		)
		(placement
			(enabled no)
			(sheetname "")
		)
		(fill yes
			(thermal_gap 0.5)
			(thermal_bridge_width 0.5)
			(island_removal_mode 0)
		)
		(polygon
			(pts
				(xy 155.043886 -161.149792) (xy 157.406086 -161.149792) (xy 157.406086 -164.350192) (xy 155.043886 -164.350192)
			)
		)
	)
	(zone
		(layers "In1.Cu" "In2.Cu")
		(hatch none 0.5)
		(connect_pads
			(clearance 0)
		)
		(min_thickness 0.25)
		(keepout
			(tracks not_allowed)
			(vias allowed)
			(pads allowed)
			(copperpour not_allowed)
			(footprints allowed)
		)
		(placement
			(enabled no)
			(sheetname "")
		)
		(fill yes
			(thermal_gap 0.5)
			(thermal_bridge_width 0.5)
			(island_removal_mode 0)
		)
		(polygon
			(pts
				(xy 123.493784 -161.149792) (xy 125.855984 -161.149792) (xy 125.855984 -164.350192) (xy 123.493784 -164.350192)
			)
		)
	)
	(zone
		(layers "In1.Cu" "In2.Cu")
		(hatch none 0.5)
		(connect_pads
			(clearance 0)
		)
		(min_thickness 0.25)
		(keepout
			(tracks not_allowed)
			(vias allowed)
			(pads allowed)
			(copperpour not_allowed)
			(footprints allowed)
		)
		(placement
			(enabled no)
			(sheetname "")
		)
		(fill yes
			(thermal_gap 0.5)
			(thermal_bridge_width 0.5)
			(island_removal_mode 0)
		)
		(polygon
			(pts
				(xy 452.393812 -46.149768) (xy 454.756012 -46.149768) (xy 454.756012 -49.350168) (xy 452.393812 -49.350168)
			)
		)
	)
	(zone
		(layers "In1.Cu" "In2.Cu")
		(hatch none 0.5)
		(connect_pads
			(clearance 0)
		)
		(min_thickness 0.25)
		(keepout
			(tracks not_allowed)
			(vias allowed)
			(pads allowed)
			(copperpour not_allowed)
			(footprints allowed)
		)
		(placement
			(enabled no)
			(sheetname "")
		)
		(fill yes
			(thermal_gap 0.5)
			(thermal_bridge_width 0.5)
			(island_removal_mode 0)
		)
		(polygon
			(pts
				(xy 452.393812 -157.339792) (xy 454.756012 -157.340554) (xy 454.756012 -160.540192) (xy 452.393812 -160.540192)
			)
		)
	)
	(zone
		(layers "In1.Cu" "In2.Cu")
		(hatch none 0.5)
		(connect_pads
			(clearance 0)
		)
		(min_thickness 0.25)
		(keepout
			(tracks not_allowed)
			(vias allowed)
			(pads allowed)
			(copperpour not_allowed)
			(footprints allowed)
		)
		(placement
			(enabled no)
			(sheetname "")
		)
		(fill yes
			(thermal_gap 0.5)
			(thermal_bridge_width 0.5)
			(island_removal_mode 0)
		)
		(polygon
			(pts
				(xy 60.393834 -46.149768) (xy 62.756034 -46.149768) (xy 62.756034 -49.350168) (xy 60.393834 -49.350168)
			)
		)
	)
	(zone
		(layers "In1.Cu" "In2.Cu")
		(hatch none 0.5)
		(connect_pads
			(clearance 0)
		)
		(min_thickness 0.25)
		(keepout
			(tracks not_allowed)
			(vias allowed)
			(pads allowed)
			(copperpour not_allowed)
			(footprints allowed)
		)
		(placement
			(enabled no)
			(sheetname "")
		)
		(fill yes
			(thermal_gap 0.5)
			(thermal_bridge_width 0.5)
			(island_removal_mode 0)
		)
		(polygon
			(pts
				(xy 123.493784 -272.339816) (xy 125.855984 -272.340578) (xy 125.855984 -275.540216) (xy 123.493784 -275.540216)
			)
		)
	)
	(zone
		(layers "In1.Cu" "In2.Cu")
		(hatch none 0.5)
		(connect_pads
			(clearance 0)
		)
		(min_thickness 0.25)
		(keepout
			(tracks not_allowed)
			(vias allowed)
			(pads allowed)
			(copperpour not_allowed)
			(footprints allowed)
		)
		(placement
			(enabled no)
			(sheetname "")
		)
		(fill yes
			(thermal_gap 0.5)
			(thermal_bridge_width 0.5)
			(island_removal_mode 0)
		)
		(polygon
			(pts
				(xy 420.843964 -161.149792) (xy 423.206164 -161.149792) (xy 423.206164 -164.350192) (xy 420.843964 -164.350192)
			)
		)
	)
	(zone
		(layers "In1.Cu" "In2.Cu")
		(hatch none 0.5)
		(connect_pads
			(clearance 0)
		)
		(min_thickness 0.25)
		(keepout
			(tracks not_allowed)
			(vias allowed)
			(pads allowed)
			(copperpour not_allowed)
			(footprints allowed)
		)
		(placement
			(enabled no)
			(sheetname "")
		)
		(fill yes
			(thermal_gap 0.5)
			(thermal_bridge_width 0.5)
			(island_removal_mode 0)
		)
		(polygon
			(pts
				(xy 389.293862 -157.339792) (xy 391.656062 -157.340554) (xy 391.656062 -160.540192) (xy 389.293862 -160.540192)
			)
		)
	)
	(zone
		(layers "In1.Cu" "In2.Cu")
		(hatch none 0.5)
		(connect_pads
			(clearance 0)
		)
		(min_thickness 0.25)
		(keepout
			(tracks not_allowed)
			(vias allowed)
			(pads allowed)
			(copperpour not_allowed)
			(footprints allowed)
		)
		(placement
			(enabled no)
			(sheetname "")
		)
		(fill yes
			(thermal_gap 0.5)
			(thermal_bridge_width 0.5)
			(island_removal_mode 0)
		)
		(polygon
			(pts
				(xy 326.193912 -276.149816) (xy 328.556112 -276.149816) (xy 328.556112 -279.350216) (xy 326.193912 -279.350216)
			)
		)
	)
	(zone
		(layers "In1.Cu" "In2.Cu")
		(hatch none 0.5)
		(connect_pads
			(clearance 0)
		)
		(min_thickness 0.25)
		(keepout
			(tracks not_allowed)
			(vias allowed)
			(pads allowed)
			(copperpour not_allowed)
			(footprints allowed)
		)
		(placement
			(enabled no)
			(sheetname "")
		)
		(fill yes
			(thermal_gap 0.5)
			(thermal_bridge_width 0.5)
			(island_removal_mode 0)
		)
		(polygon
			(pts
				(xy 389.293862 -42.339768) (xy 391.656062 -42.34053) (xy 391.656062 -45.540168) (xy 389.293862 -45.540168)
			)
		)
	)
	(zone
		(layers "In1.Cu" "In2.Cu")
		(hatch none 0.5)
		(connect_pads
			(clearance 0)
		)
		(min_thickness 0.25)
		(keepout
			(tracks not_allowed)
			(vias allowed)
			(pads allowed)
			(copperpour not_allowed)
			(footprints allowed)
		)
		(placement
			(enabled no)
			(sheetname "")
		)
		(fill yes
			(thermal_gap 0.5)
			(thermal_bridge_width 0.5)
			(island_removal_mode 0)
		)
		(polygon
			(pts
				(xy 452.393812 -272.339816) (xy 454.756012 -272.340578) (xy 454.756012 -275.540216) (xy 452.393812 -275.540216)
			)
		)
	)
	(zone
		(layers "In1.Cu" "In2.Cu")
		(hatch none 0.5)
		(connect_pads
			(clearance 0)
		)
		(min_thickness 0.25)
		(keepout
			(tracks not_allowed)
			(vias allowed)
			(pads allowed)
			(copperpour not_allowed)
			(footprints allowed)
		)
		(placement
			(enabled no)
			(sheetname "")
		)
		(fill yes
			(thermal_gap 0.5)
			(thermal_bridge_width 0.5)
			(island_removal_mode 0)
		)
		(polygon
			(pts
				(xy 483.943914 -42.339768) (xy 486.306114 -42.34053) (xy 486.306114 -45.540168) (xy 483.943914 -45.540168)
			)
		)
	)
	(zone
		(layers "In1.Cu" "In2.Cu")
		(hatch none 0.5)
		(connect_pads
			(clearance 0)
		)
		(min_thickness 0.25)
		(keepout
			(tracks not_allowed)
			(vias allowed)
			(pads allowed)
			(copperpour not_allowed)
			(footprints allowed)
		)
		(placement
			(enabled no)
			(sheetname "")
		)
		(fill yes
			(thermal_gap 0.5)
			(thermal_bridge_width 0.5)
			(island_removal_mode 0)
		)
		(polygon
			(pts
				(xy 91.943936 -161.149792) (xy 94.306136 -161.149792) (xy 94.306136 -164.350192) (xy 91.943936 -164.350192)
			)
		)
	)
	(zone
		(layers "In1.Cu" "In2.Cu")
		(hatch none 0.5)
		(connect_pads
			(clearance 0)
		)
		(min_thickness 0.25)
		(keepout
			(tracks not_allowed)
			(vias allowed)
			(pads allowed)
			(copperpour not_allowed)
			(footprints allowed)
		)
		(placement
			(enabled no)
			(sheetname "")
		)
		(fill yes
			(thermal_gap 0.5)
			(thermal_bridge_width 0.5)
			(island_removal_mode 0)
		)
		(polygon
			(pts
				(xy 483.943914 -161.149792) (xy 486.306114 -161.149792) (xy 486.306114 -164.350192) (xy 483.943914 -164.350192)
			)
		)
	)
	(zone
		(layers "In1.Cu" "In2.Cu")
		(hatch none 0.5)
		(connect_pads
			(clearance 0)
		)
		(min_thickness 0.25)
		(keepout
			(tracks not_allowed)
			(vias allowed)
			(pads allowed)
			(copperpour not_allowed)
			(footprints allowed)
		)
		(placement
			(enabled no)
			(sheetname "")
		)
		(fill yes
			(thermal_gap 0.5)
			(thermal_bridge_width 0.5)
			(island_removal_mode 0)
		)
		(polygon
			(pts
				(xy 91.943936 -272.339816) (xy 94.306136 -272.340578) (xy 94.306136 -275.540216) (xy 91.943936 -275.540216)
			)
		)
	)
	(zone
		(layers "In1.Cu" "In2.Cu")
		(hatch none 0.5)
		(connect_pads
			(clearance 0)
		)
		(min_thickness 0.25)
		(keepout
			(tracks not_allowed)
			(vias allowed)
			(pads allowed)
			(copperpour not_allowed)
			(footprints allowed)
		)
		(placement
			(enabled no)
			(sheetname "")
		)
		(fill yes
			(thermal_gap 0.5)
			(thermal_bridge_width 0.5)
			(island_removal_mode 0)
		)
		(polygon
			(pts
				(xy 357.744014 -272.339816) (xy 360.106214 -272.340578) (xy 360.106214 -275.540216) (xy 357.744014 -275.540216)
			)
		)
	)
	(zone
		(layers "In1.Cu" "In2.Cu")
		(hatch none 0.5)
		(connect_pads
			(clearance 0)
		)
		(min_thickness 0.25)
		(keepout
			(tracks not_allowed)
			(vias allowed)
			(pads allowed)
			(copperpour not_allowed)
			(footprints allowed)
		)
		(placement
			(enabled no)
			(sheetname "")
		)
		(fill yes
			(thermal_gap 0.5)
			(thermal_bridge_width 0.5)
			(island_removal_mode 0)
		)
		(polygon
			(pts
				(xy 357.744014 -157.339792) (xy 360.106214 -157.340554) (xy 360.106214 -160.540192) (xy 357.744014 -160.540192)
			)
		)
	)
	(zone
		(layers "In1.Cu" "In2.Cu")
		(hatch none 0.5)
		(connect_pads
			(clearance 0)
		)
		(min_thickness 0.25)
		(keepout
			(tracks not_allowed)
			(vias allowed)
			(pads allowed)
			(copperpour not_allowed)
			(footprints allowed)
		)
		(placement
			(enabled no)
			(sheetname "")
		)
		(fill yes
			(thermal_gap 0.5)
			(thermal_bridge_width 0.5)
			(island_removal_mode 0)
		)
		(polygon
			(pts
				(xy 389.293862 -46.149768) (xy 391.656062 -46.149768) (xy 391.656062 -49.350168) (xy 389.293862 -49.350168)
			)
		)
	)
	(zone
		(layers "In1.Cu" "In2.Cu")
		(hatch none 0.5)
		(connect_pads
			(clearance 0)
		)
		(min_thickness 0.25)
		(keepout
			(tracks not_allowed)
			(vias allowed)
			(pads allowed)
			(copperpour not_allowed)
			(footprints allowed)
		)
		(placement
			(enabled no)
			(sheetname "")
		)
		(fill yes
			(thermal_gap 0.5)
			(thermal_bridge_width 0.5)
			(island_removal_mode 0)
		)
		(polygon
			(pts
				(xy 389.293862 -272.339816) (xy 391.656062 -272.340578) (xy 391.656062 -275.540216) (xy 389.293862 -275.540216)
			)
		)
	)
	(zone
		(layers "In1.Cu" "In2.Cu")
		(hatch none 0.5)
		(connect_pads
			(clearance 0)
		)
		(min_thickness 0.25)
		(keepout
			(tracks not_allowed)
			(vias allowed)
			(pads allowed)
			(copperpour not_allowed)
			(footprints allowed)
		)
		(placement
			(enabled no)
			(sheetname "")
		)
		(fill yes
			(thermal_gap 0.5)
			(thermal_bridge_width 0.5)
			(island_removal_mode 0)
		)
		(polygon
			(pts
				(xy 28.843986 -161.149792) (xy 31.206186 -161.149792) (xy 31.206186 -164.350192) (xy 28.843986 -164.350192)
			)
		)
	)
	(zone
		(layers "In1.Cu" "In2.Cu")
		(hatch none 0.5)
		(connect_pads
			(clearance 0)
		)
		(min_thickness 0.25)
		(keepout
			(tracks not_allowed)
			(vias allowed)
			(pads allowed)
			(copperpour not_allowed)
			(footprints allowed)
		)
		(placement
			(enabled no)
			(sheetname "")
		)
		(fill yes
			(thermal_gap 0.5)
			(thermal_bridge_width 0.5)
			(island_removal_mode 0)
		)
		(polygon
			(pts
				(xy 155.043886 -42.339768) (xy 157.406086 -42.34053) (xy 157.406086 -45.540168) (xy 155.043886 -45.540168)
			)
		)
	)
	(zone
		(layers "In1.Cu" "In2.Cu")
		(hatch none 0.5)
		(connect_pads
			(clearance 0)
		)
		(min_thickness 0.25)
		(keepout
			(tracks not_allowed)
			(vias allowed)
			(pads allowed)
			(copperpour not_allowed)
			(footprints allowed)
		)
		(placement
			(enabled no)
			(sheetname "")
		)
		(fill yes
			(thermal_gap 0.5)
			(thermal_bridge_width 0.5)
			(island_removal_mode 0)
		)
		(polygon
			(pts
				(xy 28.843986 -42.339768) (xy 31.206186 -42.34053) (xy 31.206186 -45.540168) (xy 28.843986 -45.540168)
			)
		)
	)
	(zone
		(layers "In1.Cu" "In2.Cu")
		(hatch none 0.5)
		(connect_pads
			(clearance 0)
		)
		(min_thickness 0.25)
		(keepout
			(tracks not_allowed)
			(vias allowed)
			(pads allowed)
			(copperpour not_allowed)
			(footprints allowed)
		)
		(placement
			(enabled no)
			(sheetname "")
		)
		(fill yes
			(thermal_gap 0.5)
			(thermal_bridge_width 0.5)
			(island_removal_mode 0)
		)
		(polygon
			(pts
				(xy 123.493784 -46.149768) (xy 125.855984 -46.149768) (xy 125.855984 -49.350168) (xy 123.493784 -49.350168)
			)
		)
	)
	(zone
		(layers "In1.Cu" "In2.Cu")
		(hatch none 0.5)
		(connect_pads
			(clearance 0)
		)
		(min_thickness 0.25)
		(keepout
			(tracks not_allowed)
			(vias allowed)
			(pads allowed)
			(copperpour not_allowed)
			(footprints allowed)
		)
		(placement
			(enabled no)
			(sheetname "")
		)
		(fill yes
			(thermal_gap 0.5)
			(thermal_bridge_width 0.5)
			(island_removal_mode 0)
		)
		(polygon
			(pts
				(xy 326.193912 -272.339816) (xy 328.556112 -272.340578) (xy 328.556112 -275.540216) (xy 326.193912 -275.540216)
			)
		)
	)
	(zone
		(layers "In1.Cu" "In2.Cu")
		(hatch none 0.5)
		(connect_pads
			(clearance 0)
		)
		(min_thickness 0.25)
		(keepout
			(tracks not_allowed)
			(vias allowed)
			(pads allowed)
			(copperpour not_allowed)
			(footprints allowed)
		)
		(placement
			(enabled no)
			(sheetname "")
		)
		(fill yes
			(thermal_gap 0.5)
			(thermal_bridge_width 0.5)
			(island_removal_mode 0)
		)
		(polygon
			(pts
				(xy 357.744014 -46.149768) (xy 360.106214 -46.149768) (xy 360.106214 -49.350168) (xy 357.744014 -49.350168)
			)
		)
	)
	(zone
		(layers "In1.Cu" "In2.Cu")
		(hatch none 0.5)
		(connect_pads
			(clearance 0)
		)
		(min_thickness 0.25)
		(keepout
			(tracks not_allowed)
			(vias allowed)
			(pads allowed)
			(copperpour not_allowed)
			(footprints allowed)
		)
		(placement
			(enabled no)
			(sheetname "")
		)
		(fill yes
			(thermal_gap 0.5)
			(thermal_bridge_width 0.5)
			(island_removal_mode 0)
		)
		(polygon
			(pts
				(xy 326.193912 -157.339792) (xy 328.556112 -157.340554) (xy 328.556112 -160.540192) (xy 326.193912 -160.540192)
			)
		)
	)
	(zone
		(layers "In1.Cu" "In2.Cu")
		(hatch none 0.5)
		(connect_pads
			(clearance 0)
		)
		(min_thickness 0.25)
		(keepout
			(tracks not_allowed)
			(vias allowed)
			(pads allowed)
			(copperpour not_allowed)
			(footprints allowed)
		)
		(placement
			(enabled no)
			(sheetname "")
		)
		(fill yes
			(thermal_gap 0.5)
			(thermal_bridge_width 0.5)
			(island_removal_mode 0)
		)
		(polygon
			(pts
				(xy 186.593988 -276.149816) (xy 188.956188 -276.149816) (xy 188.956188 -279.350216) (xy 186.593988 -279.350216)
			)
		)
	)
	(zone
		(layers "In1.Cu" "In2.Cu")
		(hatch none 0.5)
		(connect_pads
			(clearance 0)
		)
		(min_thickness 0.25)
		(keepout
			(tracks not_allowed)
			(vias allowed)
			(pads allowed)
			(copperpour not_allowed)
			(footprints allowed)
		)
		(placement
			(enabled no)
			(sheetname "")
		)
		(fill yes
			(thermal_gap 0.5)
			(thermal_bridge_width 0.5)
			(island_removal_mode 0)
		)
		(polygon
			(pts
				(xy 452.393812 -42.339768) (xy 454.756012 -42.34053) (xy 454.756012 -45.540168) (xy 452.393812 -45.540168)
			)
		)
	)
	(zone
		(layers "In1.Cu" "In2.Cu")
		(hatch none 0.5)
		(connect_pads
			(clearance 0)
		)
		(min_thickness 0.25)
		(keepout
			(tracks not_allowed)
			(vias allowed)
			(pads allowed)
			(copperpour not_allowed)
			(footprints allowed)
		)
		(placement
			(enabled no)
			(sheetname "")
		)
		(fill yes
			(thermal_gap 0.5)
			(thermal_bridge_width 0.5)
			(island_removal_mode 0)
		)
		(polygon
			(pts
				(xy 60.393834 -161.149792) (xy 62.756034 -161.149792) (xy 62.756034 -164.350192) (xy 60.393834 -164.350192)
			)
		)
	)
	(zone
		(layers "In1.Cu" "In2.Cu")
		(hatch none 0.5)
		(connect_pads
			(clearance 0)
		)
		(min_thickness 0.25)
		(keepout
			(tracks not_allowed)
			(vias allowed)
			(pads allowed)
			(copperpour not_allowed)
			(footprints allowed)
		)
		(placement
			(enabled no)
			(sheetname "")
		)
		(fill yes
			(thermal_gap 0.5)
			(thermal_bridge_width 0.5)
			(island_removal_mode 0)
		)
		(polygon
			(pts
				(xy 28.843986 -272.339816) (xy 31.206186 -272.340578) (xy 31.206186 -275.540216) (xy 28.843986 -275.540216)
			)
		)
	)
	(zone
		(layers "In1.Cu" "In2.Cu")
		(hatch none 0.5)
		(connect_pads
			(clearance 0)
		)
		(min_thickness 0.25)
		(keepout
			(tracks not_allowed)
			(vias allowed)
			(pads allowed)
			(copperpour not_allowed)
			(footprints allowed)
		)
		(placement
			(enabled no)
			(sheetname "")
		)
		(fill yes
			(thermal_gap 0.5)
			(thermal_bridge_width 0.5)
			(island_removal_mode 0)
		)
		(polygon
			(pts
				(xy 452.393812 -276.149816) (xy 454.756012 -276.149816) (xy 454.756012 -279.350216) (xy 452.393812 -279.350216)
			)
		)
	)
	(zone
		(layers "In1.Cu" "In2.Cu")
		(hatch none 0.5)
		(connect_pads
			(clearance 0)
		)
		(min_thickness 0.25)
		(keepout
			(tracks not_allowed)
			(vias allowed)
			(pads allowed)
			(copperpour not_allowed)
			(footprints allowed)
		)
		(placement
			(enabled no)
			(sheetname "")
		)
		(fill yes
			(thermal_gap 0.5)
			(thermal_bridge_width 0.5)
			(island_removal_mode 0)
		)
		(polygon
			(pts
				(xy 326.193912 -161.149792) (xy 328.556112 -161.149792) (xy 328.556112 -164.350192) (xy 326.193912 -164.350192)
			)
		)
	)
	(zone
		(layers "In1.Cu" "In2.Cu")
		(hatch none 0.5)
		(connect_pads
			(clearance 0)
		)
		(min_thickness 0.25)
		(keepout
			(tracks not_allowed)
			(vias allowed)
			(pads allowed)
			(copperpour not_allowed)
			(footprints allowed)
		)
		(placement
			(enabled no)
			(sheetname "")
		)
		(fill yes
			(thermal_gap 0.5)
			(thermal_bridge_width 0.5)
			(island_removal_mode 0)
		)
		(polygon
			(pts
				(xy 60.393834 -157.339792) (xy 62.756034 -157.340554) (xy 62.756034 -160.540192) (xy 60.393834 -160.540192)
			)
		)
	)
	(zone
		(layers "In1.Cu" "In2.Cu")
		(hatch none 0.5)
		(connect_pads
			(clearance 0)
		)
		(min_thickness 0.25)
		(keepout
			(tracks not_allowed)
			(vias allowed)
			(pads allowed)
			(copperpour not_allowed)
			(footprints allowed)
		)
		(placement
			(enabled no)
			(sheetname "")
		)
		(fill yes
			(thermal_gap 0.5)
			(thermal_bridge_width 0.5)
			(island_removal_mode 0)
		)
		(polygon
			(pts
				(xy 91.943936 -157.339792) (xy 94.306136 -157.340554) (xy 94.306136 -160.540192) (xy 91.943936 -160.540192)
			)
		)
	)
	(zone
		(layers "In1.Cu" "In2.Cu")
		(hatch none 0.5)
		(connect_pads
			(clearance 0)
		)
		(min_thickness 0.25)
		(keepout
			(tracks not_allowed)
			(vias allowed)
			(pads allowed)
			(copperpour not_allowed)
			(footprints allowed)
		)
		(placement
			(enabled no)
			(sheetname "")
		)
		(fill yes
			(thermal_gap 0.5)
			(thermal_bridge_width 0.5)
			(island_removal_mode 0)
		)
		(polygon
			(pts
				(xy 155.043886 -276.149816) (xy 157.406086 -276.149816) (xy 157.406086 -279.350216) (xy 155.043886 -279.350216)
			)
		)
	)
	(zone
		(layers "In1.Cu" "In2.Cu")
		(hatch none 0.5)
		(connect_pads
			(clearance 0)
		)
		(min_thickness 0.25)
		(keepout
			(tracks not_allowed)
			(vias allowed)
			(pads allowed)
			(copperpour not_allowed)
			(footprints allowed)
		)
		(placement
			(enabled no)
			(sheetname "")
		)
		(fill yes
			(thermal_gap 0.5)
			(thermal_bridge_width 0.5)
			(island_removal_mode 0)
		)
		(polygon
			(pts
				(xy 91.943936 -42.339768) (xy 94.306136 -42.34053) (xy 94.306136 -45.540168) (xy 91.943936 -45.540168)
			)
		)
	)
	(zone
		(layers "In1.Cu" "In2.Cu")
		(hatch none 0.5)
		(connect_pads
			(clearance 0)
		)
		(min_thickness 0.25)
		(keepout
			(tracks not_allowed)
			(vias allowed)
			(pads allowed)
			(copperpour not_allowed)
			(footprints allowed)
		)
		(placement
			(enabled no)
			(sheetname "")
		)
		(fill yes
			(thermal_gap 0.5)
			(thermal_bridge_width 0.5)
			(island_removal_mode 0)
		)
		(polygon
			(pts
				(xy 186.593988 -42.339768) (xy 188.956188 -42.34053) (xy 188.956188 -45.540168) (xy 186.593988 -45.540168)
			)
		)
	)
	(zone
		(layers "In1.Cu" "In2.Cu")
		(hatch none 0.5)
		(connect_pads
			(clearance 0)
		)
		(min_thickness 0.25)
		(keepout
			(tracks not_allowed)
			(vias allowed)
			(pads allowed)
			(copperpour not_allowed)
			(footprints allowed)
		)
		(placement
			(enabled no)
			(sheetname "")
		)
		(fill yes
			(thermal_gap 0.5)
			(thermal_bridge_width 0.5)
			(island_removal_mode 0)
		)
		(polygon
			(pts
				(xy 420.843964 -42.339768) (xy 423.206164 -42.34053) (xy 423.206164 -45.540168) (xy 420.843964 -45.540168)
			)
		)
	)
	(zone
		(layers "In1.Cu" "In2.Cu")
		(hatch none 0.5)
		(connect_pads
			(clearance 0)
		)
		(min_thickness 0.25)
		(keepout
			(tracks not_allowed)
			(vias allowed)
			(pads allowed)
			(copperpour not_allowed)
			(footprints allowed)
		)
		(placement
			(enabled no)
			(sheetname "")
		)
		(fill yes
			(thermal_gap 0.5)
			(thermal_bridge_width 0.5)
			(island_removal_mode 0)
		)
		(polygon
			(pts
				(xy 123.493784 -276.149816) (xy 125.855984 -276.149816) (xy 125.855984 -279.350216) (xy 123.493784 -279.350216)
			)
		)
	)
	(zone
		(layers "In1.Cu" "In2.Cu")
		(hatch none 0.5)
		(connect_pads
			(clearance 0)
		)
		(min_thickness 0.25)
		(keepout
			(tracks not_allowed)
			(vias allowed)
			(pads allowed)
			(copperpour not_allowed)
			(footprints allowed)
		)
		(placement
			(enabled no)
			(sheetname "")
		)
		(fill yes
			(thermal_gap 0.5)
			(thermal_bridge_width 0.5)
			(island_removal_mode 0)
		)
		(polygon
			(pts
				(xy 91.943936 -276.149816) (xy 94.306136 -276.149816) (xy 94.306136 -279.350216) (xy 91.943936 -279.350216)
			)
		)
	)
	(zone
		(layers "In1.Cu" "In2.Cu")
		(hatch none 0.5)
		(connect_pads
			(clearance 0)
		)
		(min_thickness 0.25)
		(keepout
			(tracks not_allowed)
			(vias allowed)
			(pads allowed)
			(copperpour not_allowed)
			(footprints allowed)
		)
		(placement
			(enabled no)
			(sheetname "")
		)
		(fill yes
			(thermal_gap 0.5)
			(thermal_bridge_width 0.5)
			(island_removal_mode 0)
		)
		(polygon
			(pts
				(xy 357.744014 -276.149816) (xy 360.106214 -276.149816) (xy 360.106214 -279.350216) (xy 357.744014 -279.350216)
			)
		)
	)
	(zone
		(layers "In1.Cu" "In2.Cu")
		(hatch none 0.5)
		(connect_pads
			(clearance 0)
		)
		(min_thickness 0.25)
		(keepout
			(tracks not_allowed)
			(vias allowed)
			(pads allowed)
			(copperpour not_allowed)
			(footprints allowed)
		)
		(placement
			(enabled no)
			(sheetname "")
		)
		(fill yes
			(thermal_gap 0.5)
			(thermal_bridge_width 0.5)
			(island_removal_mode 0)
		)
		(polygon
			(pts
				(xy 155.043886 -272.339816) (xy 157.406086 -272.340578) (xy 157.406086 -275.540216) (xy 155.043886 -275.540216)
			)
		)
	)
	(zone
		(layers "In1.Cu" "In2.Cu")
		(hatch none 0.5)
		(connect_pads
			(clearance 0)
		)
		(min_thickness 0.25)
		(keepout
			(tracks not_allowed)
			(vias allowed)
			(pads allowed)
			(copperpour not_allowed)
			(footprints allowed)
		)
		(placement
			(enabled no)
			(sheetname "")
		)
		(fill yes
			(thermal_gap 0.5)
			(thermal_bridge_width 0.5)
			(island_removal_mode 0)
		)
		(polygon
			(pts
				(xy 389.293862 -276.149816) (xy 391.656062 -276.149816) (xy 391.656062 -279.350216) (xy 389.293862 -279.350216)
			)
		)
	)
	(zone
		(layers "In1.Cu" "In2.Cu")
		(hatch none 0.5)
		(connect_pads
			(clearance 0)
		)
		(min_thickness 0.25)
		(keepout
			(tracks not_allowed)
			(vias allowed)
			(pads allowed)
			(copperpour not_allowed)
			(footprints allowed)
		)
		(placement
			(enabled no)
			(sheetname "")
		)
		(fill yes
			(thermal_gap 0.5)
			(thermal_bridge_width 0.5)
			(island_removal_mode 0)
		)
		(polygon
			(pts
				(xy 28.843986 -46.149768) (xy 31.206186 -46.149768) (xy 31.206186 -49.350168) (xy 28.843986 -49.350168)
			)
		)
	)
	(zone
		(layers "In1.Cu" "In2.Cu")
		(hatch none 0.5)
		(connect_pads
			(clearance 0)
		)
		(min_thickness 0.25)
		(keepout
			(tracks not_allowed)
			(vias allowed)
			(pads allowed)
			(copperpour not_allowed)
			(footprints allowed)
		)
		(placement
			(enabled no)
			(sheetname "")
		)
		(fill yes
			(thermal_gap 0.5)
			(thermal_bridge_width 0.5)
			(island_removal_mode 0)
		)
		(polygon
			(pts
				(xy 420.843964 -272.339816) (xy 423.206164 -272.340578) (xy 423.206164 -275.540216) (xy 420.843964 -275.540216)
			)
		)
	)
	(zone
		(layers "In1.Cu" "In2.Cu")
		(hatch none 0.5)
		(connect_pads
			(clearance 0)
		)
		(min_thickness 0.25)
		(keepout
			(tracks not_allowed)
			(vias allowed)
			(pads allowed)
			(copperpour not_allowed)
			(footprints allowed)
		)
		(placement
			(enabled no)
			(sheetname "")
		)
		(fill yes
			(thermal_gap 0.5)
			(thermal_bridge_width 0.5)
			(island_removal_mode 0)
		)
		(polygon
			(pts
				(xy 28.843986 -276.149816) (xy 31.206186 -276.149816) (xy 31.206186 -279.350216) (xy 28.843986 -279.350216)
			)
		)
	)
	(zone
		(layers "In1.Cu" "In2.Cu")
		(hatch none 0.5)
		(connect_pads
			(clearance 0)
		)
		(min_thickness 0.25)
		(keepout
			(tracks not_allowed)
			(vias allowed)
			(pads allowed)
			(copperpour not_allowed)
			(footprints allowed)
		)
		(placement
			(enabled no)
			(sheetname "")
		)
		(fill yes
			(thermal_gap 0.5)
			(thermal_bridge_width 0.5)
			(island_removal_mode 0)
		)
		(polygon
			(pts
				(xy 420.843964 -276.149816) (xy 423.206164 -276.149816) (xy 423.206164 -279.350216) (xy 420.843964 -279.350216)
			)
		)
	)
	(zone
		(layers "In1.Cu" "In2.Cu")
		(hatch none 0.5)
		(connect_pads
			(clearance 0)
		)
		(min_thickness 0.25)
		(keepout
			(tracks not_allowed)
			(vias allowed)
			(pads allowed)
			(copperpour not_allowed)
			(footprints allowed)
		)
		(placement
			(enabled no)
			(sheetname "")
		)
		(fill yes
			(thermal_gap 0.5)
			(thermal_bridge_width 0.5)
			(island_removal_mode 0)
		)
		(polygon
			(pts
				(xy 123.493784 -157.339792) (xy 125.855984 -157.340554) (xy 125.855984 -160.540192) (xy 123.493784 -160.540192)
			)
		)
	)
	(zone
		(layers "In1.Cu" "In2.Cu")
		(hatch none 0.5)
		(connect_pads
			(clearance 0)
		)
		(min_thickness 0.25)
		(keepout
			(tracks not_allowed)
			(vias allowed)
			(pads allowed)
			(copperpour not_allowed)
			(footprints allowed)
		)
		(placement
			(enabled no)
			(sheetname "")
		)
		(fill yes
			(thermal_gap 0.5)
			(thermal_bridge_width 0.5)
			(island_removal_mode 0)
		)
		(polygon
			(pts
				(xy 186.593988 -161.149792) (xy 188.956188 -161.149792) (xy 188.956188 -164.350192) (xy 186.593988 -164.350192)
			)
		)
	)
	(zone
		(layers "In1.Cu" "In2.Cu")
		(hatch none 0.5)
		(connect_pads
			(clearance 0)
		)
		(min_thickness 0.25)
		(keepout
			(tracks not_allowed)
			(vias allowed)
			(pads allowed)
			(copperpour not_allowed)
			(footprints allowed)
		)
		(placement
			(enabled no)
			(sheetname "")
		)
		(fill yes
			(thermal_gap 0.5)
			(thermal_bridge_width 0.5)
			(island_removal_mode 0)
		)
		(polygon
			(pts
				(xy 186.593988 -46.149768) (xy 188.956188 -46.149768) (xy 188.956188 -49.350168) (xy 186.593988 -49.350168)
			)
		)
	)
	(zone
		(layers "In1.Cu" "In2.Cu")
		(hatch none 0.5)
		(connect_pads
			(clearance 0)
		)
		(min_thickness 0.25)
		(keepout
			(tracks not_allowed)
			(vias allowed)
			(pads allowed)
			(copperpour not_allowed)
			(footprints allowed)
		)
		(placement
			(enabled no)
			(sheetname "")
		)
		(fill yes
			(thermal_gap 0.5)
			(thermal_bridge_width 0.5)
			(island_removal_mode 0)
		)
		(polygon
			(pts
				(xy 452.393812 -161.149792) (xy 454.756012 -161.149792) (xy 454.756012 -164.350192) (xy 452.393812 -164.350192)
			)
		)
	)
	(zone
		(layers "In1.Cu" "In2.Cu")
		(hatch none 0.5)
		(connect_pads
			(clearance 0)
		)
		(min_thickness 0.25)
		(keepout
			(tracks not_allowed)
			(vias allowed)
			(pads allowed)
			(copperpour not_allowed)
			(footprints allowed)
		)
		(placement
			(enabled no)
			(sheetname "")
		)
		(fill yes
			(thermal_gap 0.5)
			(thermal_bridge_width 0.5)
			(island_removal_mode 0)
		)
		(polygon
			(pts
				(xy 155.043886 -46.149768) (xy 157.406086 -46.149768) (xy 157.406086 -49.350168) (xy 155.043886 -49.350168)
			)
		)
	)
	(zone
		(layers "In1.Cu" "In2.Cu")
		(hatch none 0.5)
		(connect_pads
			(clearance 0)
		)
		(min_thickness 0.25)
		(keepout
			(tracks not_allowed)
			(vias allowed)
			(pads allowed)
			(copperpour not_allowed)
			(footprints allowed)
		)
		(placement
			(enabled no)
			(sheetname "")
		)
		(fill yes
			(thermal_gap 0.5)
			(thermal_bridge_width 0.5)
			(island_removal_mode 0)
		)
		(polygon
			(pts
				(xy 155.043886 -157.339792) (xy 157.406086 -157.340554) (xy 157.406086 -160.540192) (xy 155.043886 -160.540192)
			)
		)
	)
	(zone
		(layers "In1.Cu" "In2.Cu")
		(hatch none 0.5)
		(connect_pads
			(clearance 0)
		)
		(min_thickness 0.25)
		(keepout
			(tracks not_allowed)
			(vias allowed)
			(pads allowed)
			(copperpour not_allowed)
			(footprints allowed)
		)
		(placement
			(enabled no)
			(sheetname "")
		)
		(fill yes
			(thermal_gap 0.5)
			(thermal_bridge_width 0.5)
			(island_removal_mode 0)
		)
		(polygon
			(pts
				(xy 28.843986 -157.339792) (xy 31.206186 -157.340554) (xy 31.206186 -160.540192) (xy 28.843986 -160.540192)
			)
		)
	)
	(zone
		(layers "In1.Cu" "In2.Cu")
		(hatch none 0.5)
		(connect_pads
			(clearance 0)
		)
		(min_thickness 0.25)
		(keepout
			(tracks not_allowed)
			(vias allowed)
			(pads allowed)
			(copperpour not_allowed)
			(footprints allowed)
		)
		(placement
			(enabled no)
			(sheetname "")
		)
		(fill yes
			(thermal_gap 0.5)
			(thermal_bridge_width 0.5)
			(island_removal_mode 0)
		)
		(polygon
			(pts
				(xy 483.943914 -272.339816) (xy 486.306114 -272.340578) (xy 486.306114 -275.540216) (xy 483.943914 -275.540216)
			)
		)
	)
	(zone
		(layers "In1.Cu" "In2.Cu")
		(hatch none 0.5)
		(connect_pads
			(clearance 0)
		)
		(min_thickness 0.25)
		(keepout
			(tracks not_allowed)
			(vias allowed)
			(pads allowed)
			(copperpour not_allowed)
			(footprints allowed)
		)
		(placement
			(enabled no)
			(sheetname "")
		)
		(fill yes
			(thermal_gap 0.5)
			(thermal_bridge_width 0.5)
			(island_removal_mode 0)
		)
		(polygon
			(pts
				(xy 420.843964 -157.339792) (xy 423.206164 -157.340554) (xy 423.206164 -160.540192) (xy 420.843964 -160.540192)
			)
		)
	)
	(zone
		(layers "In1.Cu" "In2.Cu")
		(hatch none 0.5)
		(connect_pads
			(clearance 0)
		)
		(min_thickness 0.25)
		(keepout
			(tracks not_allowed)
			(vias allowed)
			(pads allowed)
			(copperpour not_allowed)
			(footprints allowed)
		)
		(placement
			(enabled no)
			(sheetname "")
		)
		(fill yes
			(thermal_gap 0.5)
			(thermal_bridge_width 0.5)
			(island_removal_mode 0)
		)
		(polygon
			(pts
				(xy 60.393834 -42.339768) (xy 62.756034 -42.34053) (xy 62.756034 -45.540168) (xy 60.393834 -45.540168)
			)
		)
	)
	(zone
		(layers "In1.Cu" "In2.Cu")
		(hatch none 0.5)
		(connect_pads
			(clearance 0)
		)
		(min_thickness 0.25)
		(keepout
			(tracks not_allowed)
			(vias allowed)
			(pads allowed)
			(copperpour not_allowed)
			(footprints allowed)
		)
		(placement
			(enabled no)
			(sheetname "")
		)
		(fill yes
			(thermal_gap 0.5)
			(thermal_bridge_width 0.5)
			(island_removal_mode 0)
		)
		(polygon
			(pts
				(xy 91.943936 -46.149768) (xy 94.306136 -46.149768) (xy 94.306136 -49.350168) (xy 91.943936 -49.350168)
			)
		)
	)
	(zone
		(layers "In1.Cu" "In2.Cu")
		(hatch none 0.5)
		(connect_pads
			(clearance 0)
		)
		(min_thickness 0.25)
		(keepout
			(tracks not_allowed)
			(vias allowed)
			(pads allowed)
			(copperpour not_allowed)
			(footprints allowed)
		)
		(placement
			(enabled no)
			(sheetname "")
		)
		(fill yes
			(thermal_gap 0.5)
			(thermal_bridge_width 0.5)
			(island_removal_mode 0)
		)
		(polygon
			(pts
				(xy 483.943914 -46.149768) (xy 486.306114 -46.149768) (xy 486.306114 -49.350168) (xy 483.943914 -49.350168)
			)
		)
	)
	(zone
		(layers "In1.Cu" "In2.Cu")
		(hatch none 0.5)
		(connect_pads
			(clearance 0)
		)
		(min_thickness 0.25)
		(keepout
			(tracks not_allowed)
			(vias allowed)
			(pads allowed)
			(copperpour not_allowed)
			(footprints allowed)
		)
		(placement
			(enabled no)
			(sheetname "")
		)
		(fill yes
			(thermal_gap 0.5)
			(thermal_bridge_width 0.5)
			(island_removal_mode 0)
		)
		(polygon
			(pts
				(xy 420.843964 -46.149768) (xy 423.206164 -46.149768) (xy 423.206164 -49.350168) (xy 420.843964 -49.350168)
			)
		)
	)
	(zone
		(layers "In1.Cu" "In2.Cu")
		(hatch none 0.5)
		(connect_pads
			(clearance 0)
		)
		(min_thickness 0.25)
		(keepout
			(tracks not_allowed)
			(vias allowed)
			(pads allowed)
			(copperpour not_allowed)
			(footprints allowed)
		)
		(placement
			(enabled no)
			(sheetname "")
		)
		(fill yes
			(thermal_gap 0.5)
			(thermal_bridge_width 0.5)
			(island_removal_mode 0)
		)
		(polygon
			(pts
				(xy 60.393834 -272.339816) (xy 62.756034 -272.340578) (xy 62.756034 -275.540216) (xy 60.393834 -275.540216)
			)
		)
	)
	(zone
		(layers "In1.Cu" "In2.Cu")
		(hatch none 0.5)
		(connect_pads
			(clearance 0)
		)
		(min_thickness 0.25)
		(keepout
			(tracks not_allowed)
			(vias allowed)
			(pads allowed)
			(copperpour not_allowed)
			(footprints allowed)
		)
		(placement
			(enabled no)
			(sheetname "")
		)
		(fill yes
			(thermal_gap 0.5)
			(thermal_bridge_width 0.5)
			(island_removal_mode 0)
		)
		(polygon
			(pts
				(xy 357.744014 -161.149792) (xy 360.106214 -161.149792) (xy 360.106214 -164.350192) (xy 357.744014 -164.350192)
			)
		)
	)
	(zone
		(layers "In1.Cu" "In2.Cu")
		(hatch none 0.5)
		(connect_pads
			(clearance 0)
		)
		(min_thickness 0.25)
		(keepout
			(tracks not_allowed)
			(vias allowed)
			(pads allowed)
			(copperpour not_allowed)
			(footprints allowed)
		)
		(placement
			(enabled no)
			(sheetname "")
		)
		(fill yes
			(thermal_gap 0.5)
			(thermal_bridge_width 0.5)
			(island_removal_mode 0)
		)
		(polygon
			(pts
				(xy 326.193912 -46.149768) (xy 328.556112 -46.149768) (xy 328.556112 -49.350168) (xy 326.193912 -49.350168)
			)
		)
	)
	(zone
		(layers "In1.Cu" "In3.Cu" "In5.Cu" "In6.Cu" "In8.Cu" "In10.Cu")
		(hatch none 0.5)
		(connect_pads
			(clearance 0)
		)
		(min_thickness 0.25)
		(keepout
			(tracks not_allowed)
			(vias allowed)
			(pads allowed)
			(copperpour not_allowed)
			(footprints allowed)
		)
		(placement
			(enabled no)
			(sheetname "")
		)
		(fill yes
			(thermal_gap 0.5)
			(thermal_bridge_width 0.5)
			(island_removal_mode 0)
		)
		(polygon
			(pts
				(arc
					(start 482.870002 -162.178746)
					(mid 482.489129 -161.797492)
					(end 482.108002 -162.178492)
				)
				(arc
					(start 482.108002 -163.321492)
					(mid 482.489002 -163.702492)
					(end 482.870002 -163.321492)
				)
			)
		)
	)
	(zone
		(layers "In1.Cu" "In3.Cu" "In5.Cu" "In6.Cu" "In8.Cu" "In10.Cu")
		(hatch none 0.5)
		(connect_pads
			(clearance 0)
		)
		(min_thickness 0.25)
		(keepout
			(tracks not_allowed)
			(vias allowed)
			(pads allowed)
			(copperpour not_allowed)
			(footprints allowed)
		)
		(placement
			(enabled no)
			(sheetname "")
		)
		(fill yes
			(thermal_gap 0.5)
			(thermal_bridge_width 0.5)
			(island_removal_mode 0)
		)
		(polygon
			(pts
				(arc
					(start 359.298748 -20.950428)
					(mid 358.750235 -20.401534)
					(end 358.201468 -20.950174)
				)
				(arc
					(start 358.201468 -22.350222)
					(mid 358.750108 -22.898862)
					(end 359.298748 -22.350222)
				)
			)
		)
	)
	(zone
		(layers "In1.Cu" "In3.Cu" "In5.Cu" "In6.Cu" "In8.Cu" "In10.Cu")
		(hatch none 0.5)
		(connect_pads
			(clearance 0)
		)
		(min_thickness 0.25)
		(keepout
			(tracks not_allowed)
			(vias allowed)
			(pads allowed)
			(copperpour not_allowed)
			(footprints allowed)
		)
		(placement
			(enabled no)
			(sheetname "")
		)
		(fill yes
			(thermal_gap 0.5)
			(thermal_bridge_width 0.5)
			(island_removal_mode 0)
		)
		(polygon
			(pts
				(arc
					(start 279.236678 -295.956482)
					(mid 278.688038 -296.505122)
					(end 279.236678 -297.053762)
				)
				(arc
					(start 280.636726 -297.053762)
					(mid 281.185366 -296.505122)
					(end 280.636726 -295.956482)
				)
				(xy 279.236932 -295.956482)
			)
		)
	)
	(zone
		(layers "In1.Cu" "In3.Cu" "In5.Cu" "In6.Cu" "In8.Cu" "In10.Cu")
		(hatch none 0.5)
		(connect_pads
			(clearance 0)
		)
		(min_thickness 0.25)
		(keepout
			(tracks not_allowed)
			(vias allowed)
			(pads allowed)
			(copperpour not_allowed)
			(footprints allowed)
		)
		(placement
			(enabled no)
			(sheetname "")
		)
		(fill yes
			(thermal_gap 0.5)
			(thermal_bridge_width 0.5)
			(island_removal_mode 0)
		)
		(polygon
			(pts
				(arc
					(start 281.074876 -138.149584)
					(mid 281.399742 -137.174986)
					(end 280.425144 -136.85012)
				)
				(xy 280.423874 -136.847834) (xy 278.424132 -137.847832) (xy 278.424132 -137.848086)
				(arc
					(start 278.425148 -137.850118)
					(mid 278.100282 -138.824716)
					(end 279.07488 -139.149582)
				)
				(xy 279.07615 -139.151868) (xy 281.076146 -138.15187)
			)
		)
	)
	(zone
		(layers "In1.Cu" "In3.Cu" "In5.Cu" "In6.Cu" "In8.Cu" "In10.Cu")
		(hatch none 0.5)
		(connect_pads
			(clearance 0)
		)
		(min_thickness 0.25)
		(keepout
			(tracks not_allowed)
			(vias allowed)
			(pads allowed)
			(copperpour not_allowed)
			(footprints allowed)
		)
		(placement
			(enabled no)
			(sheetname "")
		)
		(fill yes
			(thermal_gap 0.5)
			(thermal_bridge_width 0.5)
			(island_removal_mode 0)
		)
		(polygon
			(pts
				(arc
					(start 278.44496 -113.868708)
					(mid 278.120865 -114.809139)
					(end 279.06345 -115.127024)
				)
				(arc
					(start 281.063446 -114.127026)
					(mid 281.377136 -113.186464)
					(end 280.436574 -112.872774)
				)
			)
		)
	)
	(zone
		(layers "In1.Cu" "In3.Cu" "In5.Cu" "In6.Cu" "In8.Cu" "In10.Cu")
		(hatch none 0.5)
		(connect_pads
			(clearance 0)
		)
		(min_thickness 0.25)
		(keepout
			(tracks not_allowed)
			(vias allowed)
			(pads allowed)
			(copperpour not_allowed)
			(footprints allowed)
		)
		(placement
			(enabled no)
			(sheetname "")
		)
		(fill yes
			(thermal_gap 0.5)
			(thermal_bridge_width 0.5)
			(island_removal_mode 0)
		)
		(polygon
			(pts
				(arc
					(start 238.377222 -130.154172)
					(mid 238.704374 -129.172716)
					(end 237.722918 -128.845564)
				)
				(arc
					(start 235.733844 -129.840228)
					(mid 235.393447 -130.821258)
					(end 236.377226 -131.15417)
				)
			)
		)
	)
	(zone
		(layers "In1.Cu" "In3.Cu" "In5.Cu" "In6.Cu" "In8.Cu" "In10.Cu")
		(hatch none 0.5)
		(connect_pads
			(clearance 0)
		)
		(min_thickness 0.25)
		(keepout
			(tracks not_allowed)
			(vias allowed)
			(pads allowed)
			(copperpour not_allowed)
			(footprints allowed)
		)
		(placement
			(enabled no)
			(sheetname "")
		)
		(fill yes
			(thermal_gap 0.5)
			(thermal_bridge_width 0.5)
			(island_removal_mode 0)
		)
		(polygon
			(pts
				(arc
					(start 357.49865 -21.950426)
					(mid 356.950137 -21.401532)
					(end 356.40137 -21.950172)
				)
				(arc
					(start 356.40137 -23.35022)
					(mid 356.95001 -23.89886)
					(end 357.49865 -23.35022)
				)
			)
		)
	)
	(zone
		(layers "In1.Cu" "In3.Cu" "In5.Cu" "In6.Cu" "In8.Cu" "In10.Cu")
		(hatch none 0.5)
		(connect_pads
			(clearance 0)
		)
		(min_thickness 0.25)
		(keepout
			(tracks not_allowed)
			(vias allowed)
			(pads allowed)
			(copperpour not_allowed)
			(footprints allowed)
		)
		(placement
			(enabled no)
			(sheetname "")
		)
		(fill yes
			(thermal_gap 0.5)
			(thermal_bridge_width 0.5)
			(island_removal_mode 0)
		)
		(polygon
			(pts
				(xy 279.07615 -38.852094) (xy 281.076146 -37.852096)
				(arc
					(start 281.074876 -37.84981)
					(mid 281.399742 -36.875212)
					(end 280.425144 -36.550346)
				)
				(xy 280.423874 -36.54806) (xy 278.424132 -37.548058) (xy 278.424132 -37.548312)
				(arc
					(start 278.425148 -37.550344)
					(mid 278.100282 -38.524942)
					(end 279.07488 -38.849808)
				)
			)
		)
	)
	(zone
		(layers "In1.Cu" "In3.Cu" "In5.Cu" "In6.Cu" "In8.Cu" "In10.Cu")
		(hatch none 0.5)
		(connect_pads
			(clearance 0)
		)
		(min_thickness 0.25)
		(keepout
			(tracks not_allowed)
			(vias allowed)
			(pads allowed)
			(copperpour not_allowed)
			(footprints allowed)
		)
		(placement
			(enabled no)
			(sheetname "")
		)
		(fill yes
			(thermal_gap 0.5)
			(thermal_bridge_width 0.5)
			(island_removal_mode 0)
		)
		(polygon
			(pts
				(arc
					(start 281.07386 -118.147338)
					(mid 281.397456 -117.176042)
					(end 280.42616 -116.852446)
				)
				(xy 278.426418 -117.85219)
				(arc
					(start 278.426418 -117.852444)
					(mid 278.102619 -118.823588)
					(end 279.073864 -119.147336)
				)
			)
		)
	)
	(zone
		(layers "In1.Cu" "In3.Cu" "In5.Cu" "In6.Cu" "In8.Cu" "In10.Cu")
		(hatch none 0.5)
		(connect_pads
			(clearance 0)
		)
		(min_thickness 0.25)
		(keepout
			(tracks not_allowed)
			(vias allowed)
			(pads allowed)
			(copperpour not_allowed)
			(footprints allowed)
		)
		(placement
			(enabled no)
			(sheetname "")
		)
		(fill yes
			(thermal_gap 0.5)
			(thermal_bridge_width 0.5)
			(island_removal_mode 0)
		)
		(polygon
			(pts
				(arc
					(start 109.698536 -20.950428)
					(mid 109.150023 -20.401534)
					(end 108.601256 -20.950174)
				)
				(arc
					(start 108.601256 -22.350222)
					(mid 109.149896 -22.898862)
					(end 109.698536 -22.350222)
				)
			)
		)
	)
	(zone
		(layers "In1.Cu" "In3.Cu" "In5.Cu" "In6.Cu" "In8.Cu" "In10.Cu")
		(hatch none 0.5)
		(connect_pads
			(clearance 0)
		)
		(min_thickness 0.25)
		(keepout
			(tracks not_allowed)
			(vias allowed)
			(pads allowed)
			(copperpour not_allowed)
			(footprints allowed)
		)
		(placement
			(enabled no)
			(sheetname "")
		)
		(fill yes
			(thermal_gap 0.5)
			(thermal_bridge_width 0.5)
			(island_removal_mode 0)
		)
		(polygon
			(pts
				(arc
					(start 238.374936 -81.849722)
					(mid 238.699802 -80.875124)
					(end 237.725204 -80.550258)
				)
				(xy 237.723934 -80.547972) (xy 235.724192 -81.54797) (xy 235.724192 -81.548224)
				(arc
					(start 235.725208 -81.550256)
					(mid 235.400342 -82.524854)
					(end 236.37494 -82.84972)
				)
				(xy 236.37621 -82.852006) (xy 238.376206 -81.852008)
			)
		)
	)
	(zone
		(layers "In1.Cu" "In3.Cu" "In5.Cu" "In6.Cu" "In8.Cu" "In10.Cu")
		(hatch none 0.5)
		(connect_pads
			(clearance 0)
		)
		(min_thickness 0.25)
		(keepout
			(tracks not_allowed)
			(vias allowed)
			(pads allowed)
			(copperpour not_allowed)
			(footprints allowed)
		)
		(placement
			(enabled no)
			(sheetname "")
		)
		(fill yes
			(thermal_gap 0.5)
			(thermal_bridge_width 0.5)
			(island_removal_mode 0)
		)
		(polygon
			(pts
				(arc
					(start 240.87709 -158.845504)
					(mid 239.895634 -159.172656)
					(end 240.222786 -160.154112)
				)
				(arc
					(start 242.222528 -161.15411)
					(mid 243.204289 -160.82711)
					(end 242.877086 -159.845502)
				)
			)
		)
	)
	(zone
		(layers "In1.Cu" "In3.Cu" "In5.Cu" "In6.Cu" "In8.Cu" "In10.Cu")
		(hatch none 0.5)
		(connect_pads
			(clearance 0)
		)
		(min_thickness 0.25)
		(keepout
			(tracks not_allowed)
			(vias allowed)
			(pads allowed)
			(copperpour not_allowed)
			(footprints allowed)
		)
		(placement
			(enabled no)
			(sheetname "")
		)
		(fill yes
			(thermal_gap 0.5)
			(thermal_bridge_width 0.5)
			(island_removal_mode 0)
		)
		(polygon
			(pts
				(arc
					(start 278.23668 -304.956464)
					(mid 277.68804 -305.505104)
					(end 278.23668 -306.053744)
				)
				(arc
					(start 279.636728 -306.053744)
					(mid 280.185368 -305.505104)
					(end 279.636728 -304.956464)
				)
				(xy 278.236934 -304.956464)
			)
		)
	)
	(zone
		(layers "In1.Cu" "In3.Cu" "In5.Cu" "In6.Cu" "In8.Cu" "In10.Cu")
		(hatch none 0.5)
		(connect_pads
			(clearance 0)
		)
		(min_thickness 0.25)
		(keepout
			(tracks not_allowed)
			(vias allowed)
			(pads allowed)
			(copperpour not_allowed)
			(footprints allowed)
		)
		(placement
			(enabled no)
			(sheetname "")
		)
		(fill yes
			(thermal_gap 0.5)
			(thermal_bridge_width 0.5)
			(island_removal_mode 0)
		)
		(polygon
			(pts
				(arc
					(start 271.970754 -357.323898)
					(mid 271.5895 -357.704771)
					(end 271.9705 -358.085898)
				)
				(arc
					(start 273.1135 -358.085898)
					(mid 273.4945 -357.704898)
					(end 273.1135 -357.323898)
				)
			)
		)
	)
	(zone
		(layers "In1.Cu" "In3.Cu" "In5.Cu" "In6.Cu" "In8.Cu" "In10.Cu")
		(hatch none 0.5)
		(connect_pads
			(clearance 0)
		)
		(min_thickness 0.25)
		(keepout
			(tracks not_allowed)
			(vias allowed)
			(pads allowed)
			(copperpour not_allowed)
			(footprints allowed)
		)
		(placement
			(enabled no)
			(sheetname "")
		)
		(fill yes
			(thermal_gap 0.5)
			(thermal_bridge_width 0.5)
			(island_removal_mode 0)
		)
		(polygon
			(pts
				(arc
					(start 478.120202 -273.368516)
					(mid 477.739202 -272.987516)
					(end 477.358202 -273.368516)
				)
				(arc
					(start 477.358202 -274.511262)
					(mid 477.739075 -274.892516)
					(end 478.120202 -274.511516)
				)
			)
		)
	)
	(zone
		(layers "In1.Cu" "In3.Cu" "In5.Cu" "In6.Cu" "In8.Cu" "In10.Cu")
		(hatch none 0.5)
		(connect_pads
			(clearance 0)
		)
		(min_thickness 0.25)
		(keepout
			(tracks not_allowed)
			(vias allowed)
			(pads allowed)
			(copperpour not_allowed)
			(footprints allowed)
		)
		(placement
			(enabled no)
			(sheetname "")
		)
		(fill yes
			(thermal_gap 0.5)
			(thermal_bridge_width 0.5)
			(island_removal_mode 0)
		)
		(polygon
			(pts
				(arc
					(start 281.07386 -162.14725)
					(mid 281.397456 -161.175954)
					(end 280.42616 -160.852358)
				)
				(xy 278.426418 -161.852102)
				(arc
					(start 278.426418 -161.852356)
					(mid 278.102619 -162.8235)
					(end 279.073864 -163.147248)
				)
			)
		)
	)
	(zone
		(layers "In1.Cu" "In3.Cu" "In5.Cu" "In6.Cu" "In8.Cu" "In10.Cu")
		(hatch none 0.5)
		(connect_pads
			(clearance 0)
		)
		(min_thickness 0.25)
		(keepout
			(tracks not_allowed)
			(vias allowed)
			(pads allowed)
			(copperpour not_allowed)
			(footprints allowed)
		)
		(placement
			(enabled no)
			(sheetname "")
		)
		(fill yes
			(thermal_gap 0.5)
			(thermal_bridge_width 0.5)
			(island_removal_mode 0)
		)
		(polygon
			(pts
				(arc
					(start 242.236498 -48.827182)
					(mid 243.17706 -48.513492)
					(end 242.86337 -47.57293)
				)
				(arc
					(start 240.871756 -46.57725)
					(mid 239.92498 -46.882435)
					(end 240.236502 -47.827184)
				)
			)
		)
	)
	(zone
		(layers "In1.Cu" "In3.Cu" "In5.Cu" "In6.Cu" "In8.Cu" "In10.Cu")
		(hatch none 0.5)
		(connect_pads
			(clearance 0)
		)
		(min_thickness 0.25)
		(keepout
			(tracks not_allowed)
			(vias allowed)
			(pads allowed)
			(copperpour not_allowed)
			(footprints allowed)
		)
		(placement
			(enabled no)
			(sheetname "")
		)
		(fill yes
			(thermal_gap 0.5)
			(thermal_bridge_width 0.5)
			(island_removal_mode 0)
		)
		(polygon
			(pts
				(arc
					(start 278.23668 -344.556588)
					(mid 277.68804 -345.105228)
					(end 278.23668 -345.653868)
				)
				(arc
					(start 279.636728 -345.653868)
					(mid 280.185368 -345.105228)
					(end 279.636728 -344.556588)
				)
				(xy 278.236934 -344.556588)
			)
		)
	)
	(zone
		(layers "In1.Cu" "In3.Cu" "In5.Cu" "In6.Cu" "In8.Cu" "In10.Cu")
		(hatch none 0.5)
		(connect_pads
			(clearance 0)
		)
		(min_thickness 0.25)
		(keepout
			(tracks not_allowed)
			(vias allowed)
			(pads allowed)
			(copperpour not_allowed)
			(footprints allowed)
		)
		(placement
			(enabled no)
			(sheetname "")
		)
		(fill yes
			(thermal_gap 0.5)
			(thermal_bridge_width 0.5)
			(island_removal_mode 0)
		)
		(polygon
			(pts
				(xy 279.07615 -66.852038) (xy 281.076146 -65.85204)
				(arc
					(start 281.074876 -65.849754)
					(mid 281.399742 -64.875156)
					(end 280.425144 -64.55029)
				)
				(xy 280.423874 -64.548004) (xy 278.424132 -65.548002) (xy 278.424132 -65.548256)
				(arc
					(start 278.425148 -65.550288)
					(mid 278.100282 -66.524886)
					(end 279.07488 -66.849752)
				)
			)
		)
	)
	(zone
		(layers "In1.Cu" "In3.Cu" "In5.Cu" "In6.Cu" "In8.Cu" "In10.Cu")
		(hatch none 0.5)
		(connect_pads
			(clearance 0)
		)
		(min_thickness 0.25)
		(keepout
			(tracks not_allowed)
			(vias allowed)
			(pads allowed)
			(copperpour not_allowed)
			(footprints allowed)
		)
		(placement
			(enabled no)
			(sheetname "")
		)
		(fill yes
			(thermal_gap 0.5)
			(thermal_bridge_width 0.5)
			(island_removal_mode 0)
		)
		(polygon
			(pts
				(arc
					(start 240.87709 -118.845584)
					(mid 239.895634 -119.172736)
					(end 240.222786 -120.154192)
				)
				(arc
					(start 242.222528 -121.15419)
					(mid 243.204289 -120.82719)
					(end 242.877086 -119.845582)
				)
			)
		)
	)
	(zone
		(layers "In1.Cu" "In3.Cu" "In5.Cu" "In6.Cu" "In8.Cu" "In10.Cu")
		(hatch none 0.5)
		(connect_pads
			(clearance 0)
		)
		(min_thickness 0.25)
		(keepout
			(tracks not_allowed)
			(vias allowed)
			(pads allowed)
			(copperpour not_allowed)
			(footprints allowed)
		)
		(placement
			(enabled no)
			(sheetname "")
		)
		(fill yes
			(thermal_gap 0.5)
			(thermal_bridge_width 0.5)
			(island_removal_mode 0)
		)
		(polygon
			(pts
				(arc
					(start 384.498596 -20.950428)
					(mid 383.950083 -20.401534)
					(end 383.401316 -20.950174)
				)
				(arc
					(start 383.401316 -22.350222)
					(mid 383.949956 -22.898862)
					(end 384.498596 -22.350222)
				)
			)
		)
	)
	(zone
		(layers "In1.Cu" "In3.Cu" "In5.Cu" "In6.Cu" "In8.Cu" "In10.Cu")
		(hatch none 0.5)
		(connect_pads
			(clearance 0)
		)
		(min_thickness 0.25)
		(keepout
			(tracks not_allowed)
			(vias allowed)
			(pads allowed)
			(copperpour not_allowed)
			(footprints allowed)
		)
		(placement
			(enabled no)
			(sheetname "")
		)
		(fill yes
			(thermal_gap 0.5)
			(thermal_bridge_width 0.5)
			(island_removal_mode 0)
		)
		(polygon
			(pts
				(xy 279.07615 -58.852054) (xy 281.076146 -57.852056)
				(arc
					(start 281.074876 -57.84977)
					(mid 281.399742 -56.875172)
					(end 280.425144 -56.550306)
				)
				(xy 280.423874 -56.54802) (xy 278.424132 -57.548018) (xy 278.424132 -57.548272)
				(arc
					(start 278.425148 -57.550304)
					(mid 278.100282 -58.524902)
					(end 279.07488 -58.849768)
				)
			)
		)
	)
	(zone
		(layers "In1.Cu" "In3.Cu" "In5.Cu" "In6.Cu" "In8.Cu" "In10.Cu")
		(hatch none 0.5)
		(connect_pads
			(clearance 0)
		)
		(min_thickness 0.25)
		(keepout
			(tracks not_allowed)
			(vias allowed)
			(pads allowed)
			(copperpour not_allowed)
			(footprints allowed)
		)
		(placement
			(enabled no)
			(sheetname "")
		)
		(fill yes
			(thermal_gap 0.5)
			(thermal_bridge_width 0.5)
			(island_removal_mode 0)
		)
		(polygon
			(pts
				(arc
					(start 271.970754 -314.121546)
					(mid 271.58696 -314.504959)
					(end 271.9705 -314.888626)
				)
				(arc
					(start 273.1135 -314.888626)
					(mid 273.49704 -314.505086)
					(end 273.1135 -314.121546)
				)
			)
		)
	)
	(zone
		(layers "In1.Cu" "In3.Cu" "In5.Cu" "In6.Cu" "In8.Cu" "In10.Cu")
		(hatch none 0.5)
		(connect_pads
			(clearance 0)
		)
		(min_thickness 0.25)
		(keepout
			(tracks not_allowed)
			(vias allowed)
			(pads allowed)
			(copperpour not_allowed)
			(footprints allowed)
		)
		(placement
			(enabled no)
			(sheetname "")
		)
		(fill yes
			(thermal_gap 0.5)
			(thermal_bridge_width 0.5)
			(island_removal_mode 0)
		)
		(polygon
			(pts
				(arc
					(start 286.436562 -313.953906)
					(mid 285.885382 -314.505086)
					(end 286.436562 -315.056266)
				)
				(arc
					(start 287.83661 -315.056266)
					(mid 288.38779 -314.505086)
					(end 287.83661 -313.953906)
				)
				(xy 286.436816 -313.953906)
			)
		)
	)
	(zone
		(layers "In1.Cu" "In3.Cu" "In5.Cu" "In6.Cu" "In8.Cu" "In10.Cu")
		(hatch none 0.5)
		(connect_pads
			(clearance 0)
		)
		(min_thickness 0.25)
		(keepout
			(tracks not_allowed)
			(vias allowed)
			(pads allowed)
			(copperpour not_allowed)
			(footprints allowed)
		)
		(placement
			(enabled no)
			(sheetname "")
		)
		(fill yes
			(thermal_gap 0.5)
			(thermal_bridge_width 0.5)
			(island_removal_mode 0)
		)
		(polygon
			(pts
				(arc
					(start 281.07386 -122.14733)
					(mid 281.397456 -121.176034)
					(end 280.42616 -120.852438)
				)
				(xy 278.426418 -121.852182)
				(arc
					(start 278.426418 -121.852436)
					(mid 278.102619 -122.82358)
					(end 279.073864 -123.147328)
				)
			)
		)
	)
	(zone
		(layers "In1.Cu" "In3.Cu" "In5.Cu" "In6.Cu" "In8.Cu" "In10.Cu")
		(hatch none 0.5)
		(connect_pads
			(clearance 0)
		)
		(min_thickness 0.25)
		(keepout
			(tracks not_allowed)
			(vias allowed)
			(pads allowed)
			(copperpour not_allowed)
			(footprints allowed)
		)
		(placement
			(enabled no)
			(sheetname "")
		)
		(fill yes
			(thermal_gap 0.5)
			(thermal_bridge_width 0.5)
			(island_removal_mode 0)
		)
		(polygon
			(pts
				(arc
					(start 285.436564 -348.15399)
					(mid 284.885384 -348.70517)
					(end 285.436564 -349.25635)
				)
				(arc
					(start 286.836612 -349.25635)
					(mid 287.387792 -348.70517)
					(end 286.836612 -348.15399)
				)
				(xy 285.436818 -348.15399)
			)
		)
	)
	(zone
		(layers "In1.Cu" "In3.Cu" "In5.Cu" "In6.Cu" "In8.Cu" "In10.Cu")
		(hatch none 0.5)
		(connect_pads
			(clearance 0)
		)
		(min_thickness 0.25)
		(keepout
			(tracks not_allowed)
			(vias allowed)
			(pads allowed)
			(copperpour not_allowed)
			(footprints allowed)
		)
		(placement
			(enabled no)
			(sheetname "")
		)
		(fill yes
			(thermal_gap 0.5)
			(thermal_bridge_width 0.5)
			(island_removal_mode 0)
		)
		(polygon
			(pts
				(arc
					(start 279.236678 -331.95641)
					(mid 278.688038 -332.50505)
					(end 279.236678 -333.05369)
				)
				(arc
					(start 280.636726 -333.05369)
					(mid 281.185366 -332.50505)
					(end 280.636726 -331.95641)
				)
				(xy 279.236932 -331.95641)
			)
		)
	)
	(zone
		(layers "In1.Cu" "In3.Cu" "In5.Cu" "In6.Cu" "In8.Cu" "In10.Cu")
		(hatch none 0.5)
		(connect_pads
			(clearance 0)
		)
		(min_thickness 0.25)
		(keepout
			(tracks not_allowed)
			(vias allowed)
			(pads allowed)
			(copperpour not_allowed)
			(footprints allowed)
		)
		(placement
			(enabled no)
			(sheetname "")
		)
		(fill yes
			(thermal_gap 0.5)
			(thermal_bridge_width 0.5)
			(island_removal_mode 0)
		)
		(polygon
			(pts
				(arc
					(start 286.436562 -252.351032)
					(mid 285.885382 -252.902212)
					(end 286.436562 -253.453392)
				)
				(arc
					(start 287.83661 -253.453392)
					(mid 288.38779 -252.902212)
					(end 287.83661 -252.351032)
				)
				(xy 286.436816 -252.351032)
			)
		)
	)
	(zone
		(layers "In1.Cu" "In3.Cu" "In5.Cu" "In6.Cu" "In8.Cu" "In10.Cu")
		(hatch none 0.5)
		(connect_pads
			(clearance 0)
		)
		(min_thickness 0.25)
		(keepout
			(tracks not_allowed)
			(vias allowed)
			(pads allowed)
			(copperpour not_allowed)
			(footprints allowed)
		)
		(placement
			(enabled no)
			(sheetname "")
		)
		(fill yes
			(thermal_gap 0.5)
			(thermal_bridge_width 0.5)
			(island_removal_mode 0)
		)
		(polygon
			(pts
				(arc
					(start 210.548728 -407.000456)
					(mid 210.000215 -406.451562)
					(end 209.451448 -407.000202)
				)
				(arc
					(start 209.451448 -408.399996)
					(mid 210.000088 -408.948636)
					(end 210.548728 -408.399996)
				)
			)
		)
	)
	(zone
		(layers "In1.Cu" "In3.Cu" "In5.Cu" "In6.Cu" "In8.Cu" "In10.Cu")
		(hatch none 0.5)
		(connect_pads
			(clearance 0)
		)
		(min_thickness 0.25)
		(keepout
			(tracks not_allowed)
			(vias allowed)
			(pads allowed)
			(copperpour not_allowed)
			(footprints allowed)
		)
		(placement
			(enabled no)
			(sheetname "")
		)
		(fill yes
			(thermal_gap 0.5)
			(thermal_bridge_width 0.5)
			(island_removal_mode 0)
		)
		(polygon
			(pts
				(arc
					(start 118.698518 -21.950426)
					(mid 118.150005 -21.401532)
					(end 117.601238 -21.950172)
				)
				(arc
					(start 117.601238 -23.35022)
					(mid 118.149878 -23.89886)
					(end 118.698518 -23.35022)
				)
			)
		)
	)
	(zone
		(layers "In1.Cu" "In3.Cu" "In5.Cu" "In6.Cu" "In8.Cu" "In10.Cu")
		(hatch none 0.5)
		(connect_pads
			(clearance 0)
		)
		(min_thickness 0.25)
		(keepout
			(tracks not_allowed)
			(vias allowed)
			(pads allowed)
			(copperpour not_allowed)
			(footprints allowed)
		)
		(placement
			(enabled no)
			(sheetname "")
		)
		(fill yes
			(thermal_gap 0.5)
			(thermal_bridge_width 0.5)
			(island_removal_mode 0)
		)
		(polygon
			(pts
				(arc
					(start 286.436562 -263.151112)
					(mid 285.885382 -263.702292)
					(end 286.436562 -264.253472)
				)
				(arc
					(start 287.83661 -264.253472)
					(mid 288.38779 -263.702292)
					(end 287.83661 -263.151112)
				)
				(xy 286.436816 -263.151112)
			)
		)
	)
	(zone
		(layers "In1.Cu" "In3.Cu" "In5.Cu" "In6.Cu" "In8.Cu" "In10.Cu")
		(hatch none 0.5)
		(connect_pads
			(clearance 0)
		)
		(min_thickness 0.25)
		(keepout
			(tracks not_allowed)
			(vias allowed)
			(pads allowed)
			(copperpour not_allowed)
			(footprints allowed)
		)
		(placement
			(enabled no)
			(sheetname "")
		)
		(fill yes
			(thermal_gap 0.5)
			(thermal_bridge_width 0.5)
			(island_removal_mode 0)
		)
		(polygon
			(pts
				(arc
					(start 133.09854 -21.950426)
					(mid 132.550027 -21.401532)
					(end 132.00126 -21.950172)
				)
				(arc
					(start 132.00126 -23.35022)
					(mid 132.5499 -23.89886)
					(end 133.09854 -23.35022)
				)
			)
		)
	)
	(zone
		(layers "In1.Cu" "In3.Cu" "In5.Cu" "In6.Cu" "In8.Cu" "In10.Cu")
		(hatch none 0.5)
		(connect_pads
			(clearance 0)
		)
		(min_thickness 0.25)
		(keepout
			(tracks not_allowed)
			(vias allowed)
			(pads allowed)
			(copperpour not_allowed)
			(footprints allowed)
		)
		(placement
			(enabled no)
			(sheetname "")
		)
		(fill yes
			(thermal_gap 0.5)
			(thermal_bridge_width 0.5)
			(island_removal_mode 0)
		)
		(polygon
			(pts
				(arc
					(start 368.29873 -21.950426)
					(mid 367.750217 -21.401532)
					(end 367.20145 -21.950172)
				)
				(arc
					(start 367.20145 -23.35022)
					(mid 367.75009 -23.89886)
					(end 368.29873 -23.35022)
				)
			)
		)
	)
	(zone
		(layers "In1.Cu" "In3.Cu" "In5.Cu" "In6.Cu" "In8.Cu" "In10.Cu")
		(hatch none 0.5)
		(connect_pads
			(clearance 0)
		)
		(min_thickness 0.25)
		(keepout
			(tracks not_allowed)
			(vias allowed)
			(pads allowed)
			(copperpour not_allowed)
			(footprints allowed)
		)
		(placement
			(enabled no)
			(sheetname "")
		)
		(fill yes
			(thermal_gap 0.5)
			(thermal_bridge_width 0.5)
			(island_removal_mode 0)
		)
		(polygon
			(pts
				(arc
					(start 140.298678 -21.950426)
					(mid 139.750165 -21.401532)
					(end 139.201398 -21.950172)
				)
				(arc
					(start 139.201398 -23.35022)
					(mid 139.750038 -23.89886)
					(end 140.298678 -23.35022)
				)
			)
		)
	)
	(zone
		(layers "In1.Cu" "In3.Cu" "In5.Cu" "In6.Cu" "In8.Cu" "In10.Cu")
		(hatch none 0.5)
		(connect_pads
			(clearance 0)
		)
		(min_thickness 0.25)
		(keepout
			(tracks not_allowed)
			(vias allowed)
			(pads allowed)
			(copperpour not_allowed)
			(footprints allowed)
		)
		(placement
			(enabled no)
			(sheetname "")
		)
		(fill yes
			(thermal_gap 0.5)
			(thermal_bridge_width 0.5)
			(island_removal_mode 0)
		)
		(polygon
			(pts
				(arc
					(start 116.898674 -20.950428)
					(mid 116.350161 -20.401534)
					(end 115.801394 -20.950174)
				)
				(arc
					(start 115.801394 -22.350222)
					(mid 116.350034 -22.898862)
					(end 116.898674 -22.350222)
				)
			)
		)
	)
	(zone
		(layers "In1.Cu" "In3.Cu" "In5.Cu" "In6.Cu" "In8.Cu" "In10.Cu")
		(hatch none 0.5)
		(connect_pads
			(clearance 0)
		)
		(min_thickness 0.25)
		(keepout
			(tracks not_allowed)
			(vias allowed)
			(pads allowed)
			(copperpour not_allowed)
			(footprints allowed)
		)
		(placement
			(enabled no)
			(sheetname "")
		)
		(fill yes
			(thermal_gap 0.5)
			(thermal_bridge_width 0.5)
			(island_removal_mode 0)
		)
		(polygon
			(pts
				(arc
					(start 283.563314 -174.87265)
					(mid 282.622752 -175.18634)
					(end 282.936442 -176.126902)
				)
				(arc
					(start 284.928056 -177.122582)
					(mid 285.874832 -176.817397)
					(end 285.56331 -175.872648)
				)
			)
		)
	)
	(zone
		(layers "In1.Cu" "In3.Cu" "In5.Cu" "In6.Cu" "In8.Cu" "In10.Cu")
		(hatch none 0.5)
		(connect_pads
			(clearance 0)
		)
		(min_thickness 0.25)
		(keepout
			(tracks not_allowed)
			(vias allowed)
			(pads allowed)
			(copperpour not_allowed)
			(footprints allowed)
		)
		(placement
			(enabled no)
			(sheetname "")
		)
		(fill yes
			(thermal_gap 0.5)
			(thermal_bridge_width 0.5)
			(island_removal_mode 0)
		)
		(polygon
			(pts
				(arc
					(start 285.436564 -254.15113)
					(mid 284.885384 -254.70231)
					(end 285.436564 -255.25349)
				)
				(arc
					(start 286.836612 -255.25349)
					(mid 287.387792 -254.70231)
					(end 286.836612 -254.15113)
				)
				(xy 285.436818 -254.15113)
			)
		)
	)
	(zone
		(layers "In1.Cu" "In3.Cu" "In5.Cu" "In6.Cu" "In8.Cu" "In10.Cu")
		(hatch none 0.5)
		(connect_pads
			(clearance 0)
		)
		(min_thickness 0.25)
		(keepout
			(tracks not_allowed)
			(vias allowed)
			(pads allowed)
			(copperpour not_allowed)
			(footprints allowed)
		)
		(placement
			(enabled no)
			(sheetname "")
		)
		(fill yes
			(thermal_gap 0.5)
			(thermal_bridge_width 0.5)
			(island_removal_mode 0)
		)
		(polygon
			(pts
				(arc
					(start 283.563314 -54.572916)
					(mid 282.622752 -54.886606)
					(end 282.936442 -55.827168)
				)
				(arc
					(start 284.928056 -56.822848)
					(mid 285.874832 -56.517663)
					(end 285.56331 -55.572914)
				)
			)
		)
	)
	(zone
		(layers "In1.Cu" "In3.Cu" "In5.Cu" "In6.Cu" "In8.Cu" "In10.Cu")
		(hatch none 0.5)
		(connect_pads
			(clearance 0)
		)
		(min_thickness 0.25)
		(keepout
			(tracks not_allowed)
			(vias allowed)
			(pads allowed)
			(copperpour not_allowed)
			(footprints allowed)
		)
		(placement
			(enabled no)
			(sheetname "")
		)
		(fill yes
			(thermal_gap 0.5)
			(thermal_bridge_width 0.5)
			(island_removal_mode 0)
		)
		(polygon
			(pts
				(arc
					(start 285.436564 -326.554084)
					(mid 284.885384 -327.105264)
					(end 285.436564 -327.656444)
				)
				(arc
					(start 286.836612 -327.656444)
					(mid 287.387792 -327.105264)
					(end 286.836612 -326.554084)
				)
				(xy 285.436818 -326.554084)
			)
		)
	)
	(zone
		(layers "In1.Cu" "In3.Cu" "In5.Cu" "In6.Cu" "In8.Cu" "In10.Cu")
		(hatch none 0.5)
		(connect_pads
			(clearance 0)
		)
		(min_thickness 0.25)
		(keepout
			(tracks not_allowed)
			(vias allowed)
			(pads allowed)
			(copperpour not_allowed)
			(footprints allowed)
		)
		(placement
			(enabled no)
			(sheetname "")
		)
		(fill yes
			(thermal_gap 0.5)
			(thermal_bridge_width 0.5)
			(island_removal_mode 0)
		)
		(polygon
			(pts
				(arc
					(start 279.236678 -346.356432)
					(mid 278.688038 -346.905072)
					(end 279.236678 -347.453712)
				)
				(arc
					(start 280.636726 -347.453712)
					(mid 281.185366 -346.905072)
					(end 280.636726 -346.356432)
				)
				(xy 279.236932 -346.356432)
			)
		)
	)
	(zone
		(layers "In1.Cu" "In3.Cu" "In5.Cu" "In6.Cu" "In8.Cu" "In10.Cu")
		(hatch none 0.5)
		(connect_pads
			(clearance 0)
		)
		(min_thickness 0.25)
		(keepout
			(tracks not_allowed)
			(vias allowed)
			(pads allowed)
			(copperpour not_allowed)
			(footprints allowed)
		)
		(placement
			(enabled no)
			(sheetname "")
		)
		(fill yes
			(thermal_gap 0.5)
			(thermal_bridge_width 0.5)
			(island_removal_mode 0)
		)
		(polygon
			(pts
				(arc
					(start 134.898638 -20.950428)
					(mid 134.350125 -20.401534)
					(end 133.801358 -20.950174)
				)
				(arc
					(start 133.801358 -22.350222)
					(mid 134.349998 -22.898862)
					(end 134.898638 -22.350222)
				)
			)
		)
	)
	(zone
		(layers "In1.Cu" "In3.Cu" "In5.Cu" "In6.Cu" "In8.Cu" "In10.Cu")
		(hatch none 0.5)
		(connect_pads
			(clearance 0)
		)
		(min_thickness 0.25)
		(keepout
			(tracks not_allowed)
			(vias allowed)
			(pads allowed)
			(copperpour not_allowed)
			(footprints allowed)
		)
		(placement
			(enabled no)
			(sheetname "")
		)
		(fill yes
			(thermal_gap 0.5)
			(thermal_bridge_width 0.5)
			(island_removal_mode 0)
		)
		(polygon
			(pts
				(arc
					(start 361.098592 -18.350484)
					(mid 360.550079 -17.80159)
					(end 360.001312 -18.35023)
				)
				(arc
					(start 360.001312 -19.750024)
					(mid 360.549952 -20.298664)
					(end 361.098592 -19.750024)
				)
			)
		)
	)
	(zone
		(layers "In1.Cu" "In3.Cu" "In5.Cu" "In6.Cu" "In8.Cu" "In10.Cu")
		(hatch none 0.5)
		(connect_pads
			(clearance 0)
		)
		(min_thickness 0.25)
		(keepout
			(tracks not_allowed)
			(vias allowed)
			(pads allowed)
			(copperpour not_allowed)
			(footprints allowed)
		)
		(placement
			(enabled no)
			(sheetname "")
		)
		(fill yes
			(thermal_gap 0.5)
			(thermal_bridge_width 0.5)
			(island_removal_mode 0)
		)
		(polygon
			(pts
				(arc
					(start 278.23668 -333.756508)
					(mid 277.68804 -334.305148)
					(end 278.23668 -334.853788)
				)
				(arc
					(start 279.636728 -334.853788)
					(mid 280.185368 -334.305148)
					(end 279.636728 -333.756508)
				)
				(xy 278.236934 -333.756508)
			)
		)
	)
	(zone
		(layers "In1.Cu" "In3.Cu" "In5.Cu" "In6.Cu" "In8.Cu" "In10.Cu")
		(hatch none 0.5)
		(connect_pads
			(clearance 0)
		)
		(min_thickness 0.25)
		(keepout
			(tracks not_allowed)
			(vias allowed)
			(pads allowed)
			(copperpour not_allowed)
			(footprints allowed)
		)
		(placement
			(enabled no)
			(sheetname "")
		)
		(fill yes
			(thermal_gap 0.5)
			(thermal_bridge_width 0.5)
			(island_removal_mode 0)
		)
		(polygon
			(pts
				(arc
					(start 214.14867 -414.20034)
					(mid 213.600157 -413.651446)
					(end 213.05139 -414.200086)
				)
				(arc
					(start 213.05139 -415.600134)
					(mid 213.60003 -416.148774)
					(end 214.14867 -415.600134)
				)
			)
		)
	)
	(zone
		(layers "In1.Cu" "In3.Cu" "In5.Cu" "In6.Cu" "In8.Cu" "In10.Cu")
		(hatch none 0.5)
		(connect_pads
			(clearance 0)
		)
		(min_thickness 0.25)
		(keepout
			(tracks not_allowed)
			(vias allowed)
			(pads allowed)
			(copperpour not_allowed)
			(footprints allowed)
		)
		(placement
			(enabled no)
			(sheetname "")
		)
		(fill yes
			(thermal_gap 0.5)
			(thermal_bridge_width 0.5)
			(island_removal_mode 0)
		)
		(polygon
			(pts
				(arc
					(start 283.563314 -178.872642)
					(mid 282.622752 -179.186332)
					(end 282.936442 -180.126894)
				)
				(arc
					(start 284.928056 -181.122574)
					(mid 285.874832 -180.817389)
					(end 285.56331 -179.87264)
				)
			)
		)
	)
	(zone
		(layers "In1.Cu" "In3.Cu" "In5.Cu" "In6.Cu" "In8.Cu" "In10.Cu")
		(hatch none 0.5)
		(connect_pads
			(clearance 0)
		)
		(min_thickness 0.25)
		(keepout
			(tracks not_allowed)
			(vias allowed)
			(pads allowed)
			(copperpour not_allowed)
			(footprints allowed)
		)
		(placement
			(enabled no)
			(sheetname "")
		)
		(fill yes
			(thermal_gap 0.5)
			(thermal_bridge_width 0.5)
			(island_removal_mode 0)
		)
		(polygon
			(pts
				(arc
					(start 238.374936 -53.849778)
					(mid 238.699802 -52.87518)
					(end 237.725204 -52.550314)
				)
				(xy 237.723934 -52.548028) (xy 235.724192 -53.548026) (xy 235.724192 -53.54828)
				(arc
					(start 235.725208 -53.550312)
					(mid 235.400342 -54.52491)
					(end 236.37494 -54.849776)
				)
				(xy 236.37621 -54.852062) (xy 238.376206 -53.852064)
			)
		)
	)
	(zone
		(layers "In1.Cu" "In3.Cu" "In5.Cu" "In6.Cu" "In8.Cu" "In10.Cu")
		(hatch none 0.5)
		(connect_pads
			(clearance 0)
		)
		(min_thickness 0.25)
		(keepout
			(tracks not_allowed)
			(vias allowed)
			(pads allowed)
			(copperpour not_allowed)
			(footprints allowed)
		)
		(placement
			(enabled no)
			(sheetname "")
		)
		(fill yes
			(thermal_gap 0.5)
			(thermal_bridge_width 0.5)
			(island_removal_mode 0)
		)
		(polygon
			(pts
				(arc
					(start 319.214754 -42.246042)
					(mid 318.8335 -42.626915)
					(end 319.2145 -43.008042)
				)
				(arc
					(start 320.3575 -43.008042)
					(mid 320.7385 -42.627042)
					(end 320.3575 -42.246042)
				)
			)
		)
	)
	(zone
		(layers "In1.Cu" "In3.Cu" "In5.Cu" "In6.Cu" "In8.Cu" "In10.Cu")
		(hatch none 0.5)
		(connect_pads
			(clearance 0)
		)
		(min_thickness 0.25)
		(keepout
			(tracks not_allowed)
			(vias allowed)
			(pads allowed)
			(copperpour not_allowed)
			(footprints allowed)
		)
		(placement
			(enabled no)
			(sheetname "")
		)
		(fill yes
			(thermal_gap 0.5)
			(thermal_bridge_width 0.5)
			(island_removal_mode 0)
		)
		(polygon
			(pts
				(arc
					(start 217.748612 -407.000456)
					(mid 217.200099 -406.451562)
					(end 216.651332 -407.000202)
				)
				(arc
					(start 216.651332 -408.399996)
					(mid 217.199972 -408.948636)
					(end 217.748612 -408.399996)
				)
			)
		)
	)
	(zone
		(layers "In1.Cu" "In3.Cu" "In5.Cu" "In6.Cu" "In8.Cu" "In10.Cu")
		(hatch none 0.5)
		(connect_pads
			(clearance 0)
		)
		(min_thickness 0.25)
		(keepout
			(tracks not_allowed)
			(vias allowed)
			(pads allowed)
			(copperpour not_allowed)
			(footprints allowed)
		)
		(placement
			(enabled no)
			(sheetname "")
		)
		(fill yes
			(thermal_gap 0.5)
			(thermal_bridge_width 0.5)
			(island_removal_mode 0)
		)
		(polygon
			(pts
				(arc
					(start 32.889952 -47.178722)
					(mid 32.509079 -46.797468)
					(end 32.127952 -47.178468)
				)
				(arc
					(start 32.127952 -48.321468)
					(mid 32.508952 -48.702468)
					(end 32.889952 -48.321468)
				)
			)
		)
	)
	(zone
		(layers "In1.Cu" "In3.Cu" "In5.Cu" "In6.Cu" "In8.Cu" "In10.Cu")
		(hatch none 0.5)
		(connect_pads
			(clearance 0)
		)
		(min_thickness 0.25)
		(keepout
			(tracks not_allowed)
			(vias allowed)
			(pads allowed)
			(copperpour not_allowed)
			(footprints allowed)
		)
		(placement
			(enabled no)
			(sheetname "")
		)
		(fill yes
			(thermal_gap 0.5)
			(thermal_bridge_width 0.5)
			(island_removal_mode 0)
		)
		(polygon
			(pts
				(arc
					(start 122.298714 -18.350484)
					(mid 121.750201 -17.80159)
					(end 121.201434 -18.35023)
				)
				(arc
					(start 121.201434 -19.750024)
					(mid 121.750074 -20.298664)
					(end 122.298714 -19.750024)
				)
			)
		)
	)
	(zone
		(layers "In1.Cu" "In3.Cu" "In5.Cu" "In6.Cu" "In8.Cu" "In10.Cu")
		(hatch none 0.5)
		(connect_pads
			(clearance 0)
		)
		(min_thickness 0.25)
		(keepout
			(tracks not_allowed)
			(vias allowed)
			(pads allowed)
			(copperpour not_allowed)
			(footprints allowed)
		)
		(placement
			(enabled no)
			(sheetname "")
		)
		(fill yes
			(thermal_gap 0.5)
			(thermal_bridge_width 0.5)
			(island_removal_mode 0)
		)
		(polygon
			(pts
				(arc
					(start 242.222782 -153.154126)
					(mid 243.204238 -152.826974)
					(end 242.877086 -151.845518)
				)
				(arc
					(start 240.877344 -150.84552)
					(mid 239.895939 -151.17257)
					(end 240.222786 -152.154128)
				)
			)
		)
	)
	(zone
		(layers "In1.Cu" "In3.Cu" "In5.Cu" "In6.Cu" "In8.Cu" "In10.Cu")
		(hatch none 0.5)
		(connect_pads
			(clearance 0)
		)
		(min_thickness 0.25)
		(keepout
			(tracks not_allowed)
			(vias allowed)
			(pads allowed)
			(copperpour not_allowed)
			(footprints allowed)
		)
		(placement
			(enabled no)
			(sheetname "")
		)
		(fill yes
			(thermal_gap 0.5)
			(thermal_bridge_width 0.5)
			(island_removal_mode 0)
		)
		(polygon
			(pts
				(arc
					(start 283.563314 -58.572908)
					(mid 282.622752 -58.886598)
					(end 282.936442 -59.82716)
				)
				(arc
					(start 284.928056 -60.82284)
					(mid 285.874832 -60.517655)
					(end 285.56331 -59.572906)
				)
			)
		)
	)
	(zone
		(layers "In1.Cu" "In3.Cu" "In5.Cu" "In6.Cu" "In8.Cu" "In10.Cu")
		(hatch none 0.5)
		(connect_pads
			(clearance 0)
		)
		(min_thickness 0.25)
		(keepout
			(tracks not_allowed)
			(vias allowed)
			(pads allowed)
			(copperpour not_allowed)
			(footprints allowed)
		)
		(placement
			(enabled no)
			(sheetname "")
		)
		(fill yes
			(thermal_gap 0.5)
			(thermal_bridge_width 0.5)
			(island_removal_mode 0)
		)
		(polygon
			(pts
				(arc
					(start 279.236678 -328.356468)
					(mid 278.688038 -328.905108)
					(end 279.236678 -329.453748)
				)
				(arc
					(start 280.636726 -329.453748)
					(mid 281.185366 -328.905108)
					(end 280.636726 -328.356468)
				)
				(xy 279.236932 -328.356468)
			)
		)
	)
	(zone
		(layers "In1.Cu" "In3.Cu" "In5.Cu" "In6.Cu" "In8.Cu" "In10.Cu")
		(hatch none 0.5)
		(connect_pads
			(clearance 0)
		)
		(min_thickness 0.25)
		(keepout
			(tracks not_allowed)
			(vias allowed)
			(pads allowed)
			(copperpour not_allowed)
			(footprints allowed)
		)
		(placement
			(enabled no)
			(sheetname "")
		)
		(fill yes
			(thermal_gap 0.5)
			(thermal_bridge_width 0.5)
			(island_removal_mode 0)
		)
		(polygon
			(pts
				(arc
					(start 380.898654 -20.950428)
					(mid 380.350141 -20.401534)
					(end 379.801374 -20.950174)
				)
				(arc
					(start 379.801374 -22.350222)
					(mid 380.350014 -22.898862)
					(end 380.898654 -22.350222)
				)
			)
		)
	)
	(zone
		(layers "In1.Cu" "In3.Cu" "In5.Cu" "In6.Cu" "In8.Cu" "In10.Cu")
		(hatch none 0.5)
		(connect_pads
			(clearance 0)
		)
		(min_thickness 0.25)
		(keepout
			(tracks not_allowed)
			(vias allowed)
			(pads allowed)
			(copperpour not_allowed)
			(footprints allowed)
		)
		(placement
			(enabled no)
			(sheetname "")
		)
		(fill yes
			(thermal_gap 0.5)
			(thermal_bridge_width 0.5)
			(island_removal_mode 0)
		)
		(polygon
			(pts
				(arc
					(start 451.3199 -277.17877)
					(mid 450.939027 -276.797516)
					(end 450.5579 -277.178516)
				)
				(arc
					(start 450.5579 -278.321516)
					(mid 450.9389 -278.702516)
					(end 451.3199 -278.321516)
				)
			)
		)
	)
	(zone
		(layers "In1.Cu" "In3.Cu" "In5.Cu" "In6.Cu" "In8.Cu" "In10.Cu")
		(hatch none 0.5)
		(connect_pads
			(clearance 0)
		)
		(min_thickness 0.25)
		(keepout
			(tracks not_allowed)
			(vias allowed)
			(pads allowed)
			(copperpour not_allowed)
			(footprints allowed)
		)
		(placement
			(enabled no)
			(sheetname "")
		)
		(fill yes
			(thermal_gap 0.5)
			(thermal_bridge_width 0.5)
			(island_removal_mode 0)
		)
		(polygon
			(pts
				(arc
					(start 283.563314 -50.572924)
					(mid 282.622752 -50.886614)
					(end 282.936442 -51.827176)
				)
				(arc
					(start 284.928056 -52.822856)
					(mid 285.874832 -52.517671)
					(end 285.56331 -51.572922)
				)
			)
		)
	)
	(zone
		(layers "In1.Cu" "In3.Cu" "In5.Cu" "In6.Cu" "In8.Cu" "In10.Cu")
		(hatch none 0.5)
		(connect_pads
			(clearance 0)
		)
		(min_thickness 0.25)
		(keepout
			(tracks not_allowed)
			(vias allowed)
			(pads allowed)
			(copperpour not_allowed)
			(footprints allowed)
		)
		(placement
			(enabled no)
			(sheetname "")
		)
		(fill yes
			(thermal_gap 0.5)
			(thermal_bridge_width 0.5)
			(island_removal_mode 0)
		)
		(polygon
			(pts
				(arc
					(start 115.098576 -21.950426)
					(mid 114.550063 -21.401532)
					(end 114.001296 -21.950172)
				)
				(arc
					(start 114.001296 -23.35022)
					(mid 114.549936 -23.89886)
					(end 115.098576 -23.35022)
				)
			)
		)
	)
	(zone
		(layers "In1.Cu" "In3.Cu" "In5.Cu" "In6.Cu" "In8.Cu" "In10.Cu")
		(hatch none 0.5)
		(connect_pads
			(clearance 0)
		)
		(min_thickness 0.25)
		(keepout
			(tracks not_allowed)
			(vias allowed)
			(pads allowed)
			(copperpour not_allowed)
			(footprints allowed)
		)
		(placement
			(enabled no)
			(sheetname "")
		)
		(fill yes
			(thermal_gap 0.5)
			(thermal_bridge_width 0.5)
			(island_removal_mode 0)
		)
		(polygon
			(pts
				(arc
					(start 482.870002 -47.178722)
					(mid 482.489129 -46.797468)
					(end 482.108002 -47.178468)
				)
				(arc
					(start 482.108002 -48.321468)
					(mid 482.489002 -48.702468)
					(end 482.870002 -48.321468)
				)
			)
		)
	)
	(zone
		(layers "In1.Cu" "In3.Cu" "In5.Cu" "In6.Cu" "In8.Cu" "In10.Cu")
		(hatch none 0.5)
		(connect_pads
			(clearance 0)
		)
		(min_thickness 0.25)
		(keepout
			(tracks not_allowed)
			(vias allowed)
			(pads allowed)
			(copperpour not_allowed)
			(footprints allowed)
		)
		(placement
			(enabled no)
			(sheetname "")
		)
		(fill yes
			(thermal_gap 0.5)
			(thermal_bridge_width 0.5)
			(island_removal_mode 0)
		)
		(polygon
			(pts
				(arc
					(start 351.920302 -273.368516)
					(mid 351.539302 -272.987516)
					(end 351.158302 -273.368516)
				)
				(arc
					(start 351.158302 -274.511262)
					(mid 351.539175 -274.892516)
					(end 351.920302 -274.511516)
				)
			)
		)
	)
	(zone
		(layers "In1.Cu" "In3.Cu" "In5.Cu" "In6.Cu" "In8.Cu" "In10.Cu")
		(hatch none 0.5)
		(connect_pads
			(clearance 0)
		)
		(min_thickness 0.25)
		(keepout
			(tracks not_allowed)
			(vias allowed)
			(pads allowed)
			(copperpour not_allowed)
			(footprints allowed)
		)
		(placement
			(enabled no)
			(sheetname "")
		)
		(fill yes
			(thermal_gap 0.5)
			(thermal_bridge_width 0.5)
			(island_removal_mode 0)
		)
		(polygon
			(pts
				(xy 236.37621 -66.852038) (xy 238.375952 -65.85204) (xy 238.375952 -65.851786)
				(arc
					(start 238.374936 -65.849754)
					(mid 238.699802 -64.875156)
					(end 237.725204 -64.55029)
				)
				(xy 237.723934 -64.548004) (xy 235.723938 -65.548002)
				(arc
					(start 235.725208 -65.550288)
					(mid 235.400342 -66.524886)
					(end 236.37494 -66.849752)
				)
			)
		)
	)
	(zone
		(layers "In1.Cu" "In3.Cu" "In5.Cu" "In6.Cu" "In8.Cu" "In10.Cu")
		(hatch none 0.5)
		(connect_pads
			(clearance 0)
		)
		(min_thickness 0.25)
		(keepout
			(tracks not_allowed)
			(vias allowed)
			(pads allowed)
			(copperpour not_allowed)
			(footprints allowed)
		)
		(placement
			(enabled no)
			(sheetname "")
		)
		(fill yes
			(thermal_gap 0.5)
			(thermal_bridge_width 0.5)
			(island_removal_mode 0)
		)
		(polygon
			(pts
				(arc
					(start 351.920302 -158.368492)
					(mid 351.539302 -157.987492)
					(end 351.158302 -158.368492)
				)
				(arc
					(start 351.158302 -159.511238)
					(mid 351.539175 -159.892492)
					(end 351.920302 -159.511492)
				)
			)
		)
	)
	(zone
		(layers "In1.Cu" "In3.Cu" "In5.Cu" "In6.Cu" "In8.Cu" "In10.Cu")
		(hatch none 0.5)
		(connect_pads
			(clearance 0)
		)
		(min_thickness 0.25)
		(keepout
			(tracks not_allowed)
			(vias allowed)
			(pads allowed)
			(copperpour not_allowed)
			(footprints allowed)
		)
		(placement
			(enabled no)
			(sheetname "")
		)
		(fill yes
			(thermal_gap 0.5)
			(thermal_bridge_width 0.5)
			(island_removal_mode 0)
		)
		(polygon
			(pts
				(arc
					(start 215.948768 -406.000204)
					(mid 215.400255 -405.45131)
					(end 214.851488 -405.99995)
				)
				(arc
					(start 214.851488 -407.399998)
					(mid 215.400128 -407.948638)
					(end 215.948768 -407.399998)
				)
			)
		)
	)
	(zone
		(layers "In1.Cu" "In3.Cu" "In5.Cu" "In6.Cu" "In8.Cu" "In10.Cu")
		(hatch none 0.5)
		(connect_pads
			(clearance 0)
		)
		(min_thickness 0.25)
		(keepout
			(tracks not_allowed)
			(vias allowed)
			(pads allowed)
			(copperpour not_allowed)
			(footprints allowed)
		)
		(placement
			(enabled no)
			(sheetname "")
		)
		(fill yes
			(thermal_gap 0.5)
			(thermal_bridge_width 0.5)
			(island_removal_mode 0)
		)
		(polygon
			(pts
				(arc
					(start 242.222782 -117.154198)
					(mid 243.204238 -116.827046)
					(end 242.877086 -115.84559)
				)
				(arc
					(start 240.877344 -114.845592)
					(mid 239.895939 -115.172642)
					(end 240.222786 -116.1542)
				)
			)
		)
	)
	(zone
		(layers "In1.Cu" "In3.Cu" "In5.Cu" "In6.Cu" "In8.Cu" "In10.Cu")
		(hatch none 0.5)
		(connect_pads
			(clearance 0)
		)
		(min_thickness 0.25)
		(keepout
			(tracks not_allowed)
			(vias allowed)
			(pads allowed)
			(copperpour not_allowed)
			(footprints allowed)
		)
		(placement
			(enabled no)
			(sheetname "")
		)
		(fill yes
			(thermal_gap 0.5)
			(thermal_bridge_width 0.5)
			(island_removal_mode 0)
		)
		(polygon
			(pts
				(arc
					(start 320.41084 -273.36877)
					(mid 319.989327 -272.946876)
					(end 319.56756 -273.368516)
				)
				(arc
					(start 319.56756 -274.511516)
					(mid 319.9892 -274.933156)
					(end 320.41084 -274.511516)
				)
			)
		)
	)
	(zone
		(layers "In1.Cu" "In3.Cu" "In5.Cu" "In6.Cu" "In8.Cu" "In10.Cu")
		(hatch none 0.5)
		(connect_pads
			(clearance 0)
		)
		(min_thickness 0.25)
		(keepout
			(tracks not_allowed)
			(vias allowed)
			(pads allowed)
			(copperpour not_allowed)
			(footprints allowed)
		)
		(placement
			(enabled no)
			(sheetname "")
		)
		(fill yes
			(thermal_gap 0.5)
			(thermal_bridge_width 0.5)
			(island_removal_mode 0)
		)
		(polygon
			(pts
				(arc
					(start 278.23668 -337.35645)
					(mid 277.68804 -337.90509)
					(end 278.23668 -338.45373)
				)
				(arc
					(start 279.636728 -338.45373)
					(mid 280.185368 -337.90509)
					(end 279.636728 -337.35645)
				)
				(xy 278.236934 -337.35645)
			)
		)
	)
	(zone
		(layers "In1.Cu" "In3.Cu" "In5.Cu" "In6.Cu" "In8.Cu" "In10.Cu")
		(hatch none 0.5)
		(connect_pads
			(clearance 0)
		)
		(min_thickness 0.25)
		(keepout
			(tracks not_allowed)
			(vias allowed)
			(pads allowed)
			(copperpour not_allowed)
			(footprints allowed)
		)
		(placement
			(enabled no)
			(sheetname "")
		)
		(fill yes
			(thermal_gap 0.5)
			(thermal_bridge_width 0.5)
			(island_removal_mode 0)
		)
		(polygon
			(pts
				(arc
					(start 283.563314 -62.5729)
					(mid 282.622752 -62.88659)
					(end 282.936442 -63.827152)
				)
				(arc
					(start 284.928056 -64.822832)
					(mid 285.874832 -64.517647)
					(end 285.56331 -63.572898)
				)
			)
		)
	)
	(zone
		(layers "In1.Cu" "In3.Cu" "In5.Cu" "In6.Cu" "In8.Cu" "In10.Cu")
		(hatch none 0.5)
		(connect_pads
			(clearance 0)
		)
		(min_thickness 0.25)
		(keepout
			(tracks not_allowed)
			(vias allowed)
			(pads allowed)
			(copperpour not_allowed)
			(footprints allowed)
		)
		(placement
			(enabled no)
			(sheetname "")
		)
		(fill yes
			(thermal_gap 0.5)
			(thermal_bridge_width 0.5)
			(island_removal_mode 0)
		)
		(polygon
			(pts
				(arc
					(start 278.23668 -261.351014)
					(mid 277.6855 -261.902194)
					(end 278.23668 -262.453374)
				)
				(arc
					(start 279.636728 -262.453374)
					(mid 280.187908 -261.902194)
					(end 279.636728 -261.351014)
				)
				(xy 278.236934 -261.351014)
			)
		)
	)
	(zone
		(layers "In1.Cu" "In3.Cu" "In5.Cu" "In6.Cu" "In8.Cu" "In10.Cu")
		(hatch none 0.5)
		(connect_pads
			(clearance 0)
		)
		(min_thickness 0.25)
		(keepout
			(tracks not_allowed)
			(vias allowed)
			(pads allowed)
			(copperpour not_allowed)
			(footprints allowed)
		)
		(placement
			(enabled no)
			(sheetname "")
		)
		(fill yes
			(thermal_gap 0.5)
			(thermal_bridge_width 0.5)
			(island_removal_mode 0)
		)
		(polygon
			(pts
				(arc
					(start 286.436562 -335.554066)
					(mid 285.885382 -336.105246)
					(end 286.436562 -336.656426)
				)
				(arc
					(start 287.83661 -336.656426)
					(mid 288.38779 -336.105246)
					(end 287.83661 -335.554066)
				)
				(xy 286.436816 -335.554066)
			)
		)
	)
	(zone
		(layers "In1.Cu" "In3.Cu" "In5.Cu" "In6.Cu" "In8.Cu" "In10.Cu")
		(hatch none 0.5)
		(connect_pads
			(clearance 0)
		)
		(min_thickness 0.25)
		(keepout
			(tracks not_allowed)
			(vias allowed)
			(pads allowed)
			(copperpour not_allowed)
			(footprints allowed)
		)
		(placement
			(enabled no)
			(sheetname "")
		)
		(fill yes
			(thermal_gap 0.5)
			(thermal_bridge_width 0.5)
			(island_removal_mode 0)
		)
		(polygon
			(pts
				(arc
					(start 212.348826 -406.000204)
					(mid 211.800313 -405.45131)
					(end 211.251546 -405.99995)
				)
				(arc
					(start 211.251546 -407.399998)
					(mid 211.800186 -407.948638)
					(end 212.348826 -407.399998)
				)
			)
		)
	)
	(zone
		(layers "In1.Cu" "In3.Cu" "In5.Cu" "In6.Cu" "In8.Cu" "In10.Cu")
		(hatch none 0.5)
		(connect_pads
			(clearance 0)
		)
		(min_thickness 0.25)
		(keepout
			(tracks not_allowed)
			(vias allowed)
			(pads allowed)
			(copperpour not_allowed)
			(footprints allowed)
		)
		(placement
			(enabled no)
			(sheetname "")
		)
		(fill yes
			(thermal_gap 0.5)
			(thermal_bridge_width 0.5)
			(island_removal_mode 0)
		)
		(polygon
			(pts
				(arc
					(start 240.863374 -70.572884)
					(mid 239.922812 -70.886574)
					(end 240.236502 -71.827136)
				)
				(arc
					(start 242.228116 -72.822816)
					(mid 243.174892 -72.517631)
					(end 242.86337 -71.572882)
				)
			)
		)
	)
	(zone
		(layers "In1.Cu" "In3.Cu" "In5.Cu" "In6.Cu" "In8.Cu" "In10.Cu")
		(hatch none 0.5)
		(connect_pads
			(clearance 0)
		)
		(min_thickness 0.25)
		(keepout
			(tracks not_allowed)
			(vias allowed)
			(pads allowed)
			(copperpour not_allowed)
			(footprints allowed)
		)
		(placement
			(enabled no)
			(sheetname "")
		)
		(fill yes
			(thermal_gap 0.5)
			(thermal_bridge_width 0.5)
			(island_removal_mode 0)
		)
		(polygon
			(pts
				(arc
					(start 235.722922 -121.845578)
					(mid 235.39577 -122.827034)
					(end 236.377226 -123.154186)
				)
				(arc
					(start 238.3663 -122.159522)
					(mid 238.706697 -121.178492)
					(end 237.722918 -120.84558)
				)
			)
		)
	)
	(zone
		(layers "In1.Cu" "In3.Cu" "In5.Cu" "In6.Cu" "In8.Cu" "In10.Cu")
		(hatch none 0.5)
		(connect_pads
			(clearance 0)
		)
		(min_thickness 0.25)
		(keepout
			(tracks not_allowed)
			(vias allowed)
			(pads allowed)
			(copperpour not_allowed)
			(footprints allowed)
		)
		(placement
			(enabled no)
			(sheetname "")
		)
		(fill yes
			(thermal_gap 0.5)
			(thermal_bridge_width 0.5)
			(island_removal_mode 0)
		)
		(polygon
			(pts
				(arc
					(start 279.236678 -324.756526)
					(mid 278.688038 -325.305166)
					(end 279.236678 -325.853806)
				)
				(arc
					(start 280.636726 -325.853806)
					(mid 281.185366 -325.305166)
					(end 280.636726 -324.756526)
				)
				(xy 279.236932 -324.756526)
			)
		)
	)
	(zone
		(layers "In1.Cu" "In3.Cu" "In5.Cu" "In6.Cu" "In8.Cu" "In10.Cu")
		(hatch none 0.5)
		(connect_pads
			(clearance 0)
		)
		(min_thickness 0.25)
		(keepout
			(tracks not_allowed)
			(vias allowed)
			(pads allowed)
			(copperpour not_allowed)
			(footprints allowed)
		)
		(placement
			(enabled no)
			(sheetname "")
		)
		(fill yes
			(thermal_gap 0.5)
			(thermal_bridge_width 0.5)
			(island_removal_mode 0)
		)
		(polygon
			(pts
				(arc
					(start 127.53975 -162.178746)
					(mid 127.158877 -161.797492)
					(end 126.77775 -162.178492)
				)
				(arc
					(start 126.77775 -163.321492)
					(mid 127.15875 -163.702492)
					(end 127.53975 -163.321492)
				)
			)
		)
	)
	(zone
		(layers "In1.Cu" "In3.Cu" "In5.Cu" "In6.Cu" "In8.Cu" "In10.Cu")
		(hatch none 0.5)
		(connect_pads
			(clearance 0)
		)
		(min_thickness 0.25)
		(keepout
			(tracks not_allowed)
			(vias allowed)
			(pads allowed)
			(copperpour not_allowed)
			(footprints allowed)
		)
		(placement
			(enabled no)
			(sheetname "")
		)
		(fill yes
			(thermal_gap 0.5)
			(thermal_bridge_width 0.5)
			(island_removal_mode 0)
		)
		(polygon
			(pts
				(arc
					(start 279.236678 -259.55117)
					(mid 278.685498 -260.10235)
					(end 279.236678 -260.65353)
				)
				(arc
					(start 280.636726 -260.65353)
					(mid 281.187906 -260.10235)
					(end 280.636726 -259.55117)
				)
				(xy 279.236932 -259.55117)
			)
		)
	)
	(zone
		(layers "In1.Cu" "In3.Cu" "In5.Cu" "In6.Cu" "In8.Cu" "In10.Cu")
		(hatch none 0.5)
		(connect_pads
			(clearance 0)
		)
		(min_thickness 0.25)
		(keepout
			(tracks not_allowed)
			(vias allowed)
			(pads allowed)
			(copperpour not_allowed)
			(footprints allowed)
		)
		(placement
			(enabled no)
			(sheetname "")
		)
		(fill yes
			(thermal_gap 0.5)
			(thermal_bridge_width 0.5)
			(island_removal_mode 0)
		)
		(polygon
			(pts
				(arc
					(start 278.23668 -340.956392)
					(mid 277.68804 -341.505032)
					(end 278.23668 -342.053672)
				)
				(arc
					(start 279.636728 -342.053672)
					(mid 280.185368 -341.505032)
					(end 279.636728 -340.956392)
				)
				(xy 278.236934 -340.956392)
			)
		)
	)
	(zone
		(layers "In1.Cu" "In3.Cu" "In5.Cu" "In6.Cu" "In8.Cu" "In10.Cu")
		(hatch none 0.5)
		(connect_pads
			(clearance 0)
		)
		(min_thickness 0.25)
		(keepout
			(tracks not_allowed)
			(vias allowed)
			(pads allowed)
			(copperpour not_allowed)
			(footprints allowed)
		)
		(placement
			(enabled no)
			(sheetname "")
		)
		(fill yes
			(thermal_gap 0.5)
			(thermal_bridge_width 0.5)
			(island_removal_mode 0)
		)
		(polygon
			(pts
				(arc
					(start 271.970754 -337.52155)
					(mid 271.58696 -337.904963)
					(end 271.9705 -338.28863)
				)
				(arc
					(start 273.1135 -338.28863)
					(mid 273.49704 -337.90509)
					(end 273.1135 -337.52155)
				)
			)
		)
	)
	(zone
		(layers "In1.Cu" "In3.Cu" "In5.Cu" "In6.Cu" "In8.Cu" "In10.Cu")
		(hatch none 0.5)
		(connect_pads
			(clearance 0)
		)
		(min_thickness 0.25)
		(keepout
			(tracks not_allowed)
			(vias allowed)
			(pads allowed)
			(copperpour not_allowed)
			(footprints allowed)
		)
		(placement
			(enabled no)
			(sheetname "")
		)
		(fill yes
			(thermal_gap 0.5)
			(thermal_bridge_width 0.5)
			(island_removal_mode 0)
		)
		(polygon
			(pts
				(arc
					(start 113.298732 -20.950428)
					(mid 112.750219 -20.401534)
					(end 112.201452 -20.950174)
				)
				(arc
					(start 112.201452 -22.350222)
					(mid 112.750092 -22.898862)
					(end 113.298732 -22.350222)
				)
			)
		)
	)
	(zone
		(layers "In1.Cu" "In3.Cu" "In5.Cu" "In6.Cu" "In8.Cu" "In10.Cu")
		(hatch none 0.5)
		(connect_pads
			(clearance 0)
		)
		(min_thickness 0.25)
		(keepout
			(tracks not_allowed)
			(vias allowed)
			(pads allowed)
			(copperpour not_allowed)
			(footprints allowed)
		)
		(placement
			(enabled no)
			(sheetname "")
		)
		(fill yes
			(thermal_gap 0.5)
			(thermal_bridge_width 0.5)
			(island_removal_mode 0)
		)
		(polygon
			(pts
				(arc
					(start 278.23668 -319.356486)
					(mid 277.68804 -319.905126)
					(end 278.23668 -320.453766)
				)
				(arc
					(start 279.636728 -320.453766)
					(mid 280.185368 -319.905126)
					(end 279.636728 -319.356486)
				)
				(xy 278.236934 -319.356486)
			)
		)
	)
	(zone
		(layers "In1.Cu" "In3.Cu" "In5.Cu" "In6.Cu" "In8.Cu" "In10.Cu")
		(hatch none 0.5)
		(connect_pads
			(clearance 0)
		)
		(min_thickness 0.25)
		(keepout
			(tracks not_allowed)
			(vias allowed)
			(pads allowed)
			(copperpour not_allowed)
			(footprints allowed)
		)
		(placement
			(enabled no)
			(sheetname "")
		)
		(fill yes
			(thermal_gap 0.5)
			(thermal_bridge_width 0.5)
			(island_removal_mode 0)
		)
		(polygon
			(pts
				(arc
					(start 281.074876 -178.149504)
					(mid 281.399742 -177.174906)
					(end 280.425144 -176.85004)
				)
				(xy 280.423874 -176.847754) (xy 278.424132 -177.847752) (xy 278.424132 -177.848006)
				(arc
					(start 278.425148 -177.850038)
					(mid 278.100282 -178.824636)
					(end 279.07488 -179.149502)
				)
				(xy 279.07615 -179.151788) (xy 281.076146 -178.15179)
			)
		)
	)
	(zone
		(layers "In1.Cu" "In3.Cu" "In5.Cu" "In6.Cu" "In8.Cu" "In10.Cu")
		(hatch none 0.5)
		(connect_pads
			(clearance 0)
		)
		(min_thickness 0.25)
		(keepout
			(tracks not_allowed)
			(vias allowed)
			(pads allowed)
			(copperpour not_allowed)
			(footprints allowed)
		)
		(placement
			(enabled no)
			(sheetname "")
		)
		(fill yes
			(thermal_gap 0.5)
			(thermal_bridge_width 0.5)
			(island_removal_mode 0)
		)
		(polygon
			(pts
				(arc
					(start 278.23668 -355.356414)
					(mid 277.68804 -355.905054)
					(end 278.23668 -356.453694)
				)
				(arc
					(start 279.636728 -356.453694)
					(mid 280.185368 -355.905054)
					(end 279.636728 -355.356414)
				)
				(xy 278.236934 -355.356414)
			)
		)
	)
	(zone
		(layers "In1.Cu" "In3.Cu" "In5.Cu" "In6.Cu" "In8.Cu" "In10.Cu")
		(hatch none 0.5)
		(connect_pads
			(clearance 0)
		)
		(min_thickness 0.25)
		(keepout
			(tracks not_allowed)
			(vias allowed)
			(pads allowed)
			(copperpour not_allowed)
			(footprints allowed)
		)
		(placement
			(enabled no)
			(sheetname "")
		)
		(fill yes
			(thermal_gap 0.5)
			(thermal_bridge_width 0.5)
			(island_removal_mode 0)
		)
		(polygon
			(pts
				(xy 279.07615 -54.852062) (xy 281.076146 -53.852064)
				(arc
					(start 281.074876 -53.849778)
					(mid 281.399742 -52.87518)
					(end 280.425144 -52.550314)
				)
				(xy 280.423874 -52.548028) (xy 278.424132 -53.548026) (xy 278.424132 -53.54828)
				(arc
					(start 278.425148 -53.550312)
					(mid 278.100282 -54.52491)
					(end 279.07488 -54.849776)
				)
			)
		)
	)
	(zone
		(layers "In1.Cu" "In3.Cu" "In5.Cu" "In6.Cu" "In8.Cu" "In10.Cu")
		(hatch none 0.5)
		(connect_pads
			(clearance 0)
		)
		(min_thickness 0.25)
		(keepout
			(tracks not_allowed)
			(vias allowed)
			(pads allowed)
			(copperpour not_allowed)
			(footprints allowed)
		)
		(placement
			(enabled no)
			(sheetname "")
		)
		(fill yes
			(thermal_gap 0.5)
			(thermal_bridge_width 0.5)
			(island_removal_mode 0)
		)
		(polygon
			(pts
				(arc
					(start 419.770052 -162.178746)
					(mid 419.389179 -161.797492)
					(end 419.008052 -162.178492)
				)
				(arc
					(start 419.008052 -163.321492)
					(mid 419.389052 -163.702492)
					(end 419.770052 -163.321492)
				)
			)
		)
	)
	(zone
		(layers "In1.Cu" "In3.Cu" "In5.Cu" "In6.Cu" "In8.Cu" "In10.Cu")
		(hatch none 0.5)
		(connect_pads
			(clearance 0)
		)
		(min_thickness 0.25)
		(keepout
			(tracks not_allowed)
			(vias allowed)
			(pads allowed)
			(copperpour not_allowed)
			(footprints allowed)
		)
		(placement
			(enabled no)
			(sheetname "")
		)
		(fill yes
			(thermal_gap 0.5)
			(thermal_bridge_width 0.5)
			(island_removal_mode 0)
		)
		(polygon
			(pts
				(arc
					(start 283.563314 -118.872762)
					(mid 282.622752 -119.186452)
					(end 282.936442 -120.127014)
				)
				(arc
					(start 284.928056 -121.122694)
					(mid 285.874832 -120.817509)
					(end 285.56331 -119.87276)
				)
			)
		)
	)
	(zone
		(layers "In1.Cu" "In3.Cu" "In5.Cu" "In6.Cu" "In8.Cu" "In10.Cu")
		(hatch none 0.5)
		(connect_pads
			(clearance 0)
		)
		(min_thickness 0.25)
		(keepout
			(tracks not_allowed)
			(vias allowed)
			(pads allowed)
			(copperpour not_allowed)
			(footprints allowed)
		)
		(placement
			(enabled no)
			(sheetname "")
		)
		(fill yes
			(thermal_gap 0.5)
			(thermal_bridge_width 0.5)
			(island_removal_mode 0)
		)
		(polygon
			(pts
				(arc
					(start 415.020252 -43.368468)
					(mid 414.639252 -42.987468)
					(end 414.258252 -43.368468)
				)
				(arc
					(start 414.258252 -44.511214)
					(mid 414.639125 -44.892468)
					(end 415.020252 -44.511468)
				)
			)
		)
	)
	(zone
		(layers "In1.Cu" "In3.Cu" "In5.Cu" "In6.Cu" "In8.Cu" "In10.Cu")
		(hatch none 0.5)
		(connect_pads
			(clearance 0)
		)
		(min_thickness 0.25)
		(keepout
			(tracks not_allowed)
			(vias allowed)
			(pads allowed)
			(copperpour not_allowed)
			(footprints allowed)
		)
		(placement
			(enabled no)
			(sheetname "")
		)
		(fill yes
			(thermal_gap 0.5)
			(thermal_bridge_width 0.5)
			(island_removal_mode 0)
		)
		(polygon
			(pts
				(arc
					(start 190.639954 -277.17877)
					(mid 190.259081 -276.797516)
					(end 189.877954 -277.178516)
				)
				(arc
					(start 189.877954 -278.321516)
					(mid 190.258954 -278.702516)
					(end 190.639954 -278.321516)
				)
			)
		)
	)
	(zone
		(layers "In1.Cu" "In3.Cu" "In5.Cu" "In6.Cu" "In8.Cu" "In10.Cu")
		(hatch none 0.5)
		(connect_pads
			(clearance 0)
		)
		(min_thickness 0.25)
		(keepout
			(tracks not_allowed)
			(vias allowed)
			(pads allowed)
			(copperpour not_allowed)
			(footprints allowed)
		)
		(placement
			(enabled no)
			(sheetname "")
		)
		(fill yes
			(thermal_gap 0.5)
			(thermal_bridge_width 0.5)
			(island_removal_mode 0)
		)
		(polygon
			(pts
				(arc
					(start 271.970754 -335.721452)
					(mid 271.58696 -336.104865)
					(end 271.9705 -336.488532)
				)
				(arc
					(start 273.1135 -336.488532)
					(mid 273.49704 -336.104992)
					(end 273.1135 -335.721452)
				)
			)
		)
	)
	(zone
		(layers "In1.Cu" "In3.Cu" "In5.Cu" "In6.Cu" "In8.Cu" "In10.Cu")
		(hatch none 0.5)
		(connect_pads
			(clearance 0)
		)
		(min_thickness 0.25)
		(keepout
			(tracks not_allowed)
			(vias allowed)
			(pads allowed)
			(copperpour not_allowed)
			(footprints allowed)
		)
		(placement
			(enabled no)
			(sheetname "")
		)
		(fill yes
			(thermal_gap 0.5)
			(thermal_bridge_width 0.5)
			(island_removal_mode 0)
		)
		(polygon
			(pts
				(arc
					(start 279.236678 -339.156548)
					(mid 278.688038 -339.705188)
					(end 279.236678 -340.253828)
				)
				(arc
					(start 280.636726 -340.253828)
					(mid 281.185366 -339.705188)
					(end 280.636726 -339.156548)
				)
				(xy 279.236932 -339.156548)
			)
		)
	)
	(zone
		(layers "In1.Cu" "In3.Cu" "In5.Cu" "In6.Cu" "In8.Cu" "In10.Cu")
		(hatch none 0.5)
		(connect_pads
			(clearance 0)
		)
		(min_thickness 0.25)
		(keepout
			(tracks not_allowed)
			(vias allowed)
			(pads allowed)
			(copperpour not_allowed)
			(footprints allowed)
		)
		(placement
			(enabled no)
			(sheetname "")
		)
		(fill yes
			(thermal_gap 0.5)
			(thermal_bridge_width 0.5)
			(island_removal_mode 0)
		)
		(polygon
			(pts
				(arc
					(start 242.236498 -64.82715)
					(mid 243.17706 -64.51346)
					(end 242.86337 -63.572898)
				)
				(arc
					(start 240.871756 -62.577218)
					(mid 239.92498 -62.882403)
					(end 240.236502 -63.827152)
				)
			)
		)
	)
	(zone
		(layers "In1.Cu" "In3.Cu" "In5.Cu" "In6.Cu" "In8.Cu" "In10.Cu")
		(hatch none 0.5)
		(connect_pads
			(clearance 0)
		)
		(min_thickness 0.25)
		(keepout
			(tracks not_allowed)
			(vias allowed)
			(pads allowed)
			(copperpour not_allowed)
			(footprints allowed)
		)
		(placement
			(enabled no)
			(sheetname "")
		)
		(fill yes
			(thermal_gap 0.5)
			(thermal_bridge_width 0.5)
			(island_removal_mode 0)
		)
		(polygon
			(pts
				(arc
					(start 286.436562 -346.356432)
					(mid 285.887922 -346.905072)
					(end 286.436562 -347.453712)
				)
				(arc
					(start 287.83661 -347.453712)
					(mid 288.38525 -346.905072)
					(end 287.83661 -346.356432)
				)
				(xy 286.436816 -346.356432)
			)
		)
	)
	(zone
		(layers "In1.Cu" "In3.Cu" "In5.Cu" "In6.Cu" "In8.Cu" "In10.Cu")
		(hatch none 0.5)
		(connect_pads
			(clearance 0)
		)
		(min_thickness 0.25)
		(keepout
			(tracks not_allowed)
			(vias allowed)
			(pads allowed)
			(copperpour not_allowed)
			(footprints allowed)
		)
		(placement
			(enabled no)
			(sheetname "")
		)
		(fill yes
			(thermal_gap 0.5)
			(thermal_bridge_width 0.5)
			(island_removal_mode 0)
		)
		(polygon
			(pts
				(arc
					(start 120.498616 -17.350232)
					(mid 119.950103 -16.801338)
					(end 119.401336 -17.349978)
				)
				(arc
					(start 119.401336 -18.750026)
					(mid 119.949976 -19.298666)
					(end 120.498616 -18.750026)
				)
			)
		)
	)
	(zone
		(layers "In1.Cu" "In3.Cu" "In5.Cu" "In6.Cu" "In8.Cu" "In10.Cu")
		(hatch none 0.5)
		(connect_pads
			(clearance 0)
		)
		(min_thickness 0.25)
		(keepout
			(tracks not_allowed)
			(vias allowed)
			(pads allowed)
			(copperpour not_allowed)
			(footprints allowed)
		)
		(placement
			(enabled no)
			(sheetname "")
		)
		(fill yes
			(thermal_gap 0.5)
			(thermal_bridge_width 0.5)
			(island_removal_mode 0)
		)
		(polygon
			(pts
				(arc
					(start 116.898674 -28.150312)
					(mid 116.350161 -27.601418)
					(end 115.801394 -28.150058)
				)
				(arc
					(start 115.801394 -29.550106)
					(mid 116.350034 -30.098746)
					(end 116.898674 -29.550106)
				)
			)
		)
	)
	(zone
		(layers "In1.Cu" "In3.Cu" "In5.Cu" "In6.Cu" "In8.Cu" "In10.Cu")
		(hatch none 0.5)
		(connect_pads
			(clearance 0)
		)
		(min_thickness 0.25)
		(keepout
			(tracks not_allowed)
			(vias allowed)
			(pads allowed)
			(copperpour not_allowed)
			(footprints allowed)
		)
		(placement
			(enabled no)
			(sheetname "")
		)
		(fill yes
			(thermal_gap 0.5)
			(thermal_bridge_width 0.5)
			(island_removal_mode 0)
		)
		(polygon
			(pts
				(arc
					(start 285.436564 -344.556588)
					(mid 284.887924 -345.105228)
					(end 285.436564 -345.653868)
				)
				(arc
					(start 286.836612 -345.653868)
					(mid 287.385252 -345.105228)
					(end 286.836612 -344.556588)
				)
				(xy 285.436818 -344.556588)
			)
		)
	)
	(zone
		(layers "In1.Cu" "In3.Cu" "In5.Cu" "In6.Cu" "In8.Cu" "In10.Cu")
		(hatch none 0.5)
		(connect_pads
			(clearance 0)
		)
		(min_thickness 0.25)
		(keepout
			(tracks not_allowed)
			(vias allowed)
			(pads allowed)
			(copperpour not_allowed)
			(footprints allowed)
		)
		(placement
			(enabled no)
			(sheetname "")
		)
		(fill yes
			(thermal_gap 0.5)
			(thermal_bridge_width 0.5)
			(island_removal_mode 0)
		)
		(polygon
			(pts
				(arc
					(start 238.374936 -166.149528)
					(mid 238.699802 -165.17493)
					(end 237.725204 -164.850064)
				)
				(xy 237.723934 -164.847778) (xy 235.724192 -165.847776) (xy 235.724192 -165.84803)
				(arc
					(start 235.725208 -165.850062)
					(mid 235.400342 -166.82466)
					(end 236.37494 -167.149526)
				)
				(xy 236.37621 -167.151812) (xy 238.376206 -166.151814)
			)
		)
	)
	(zone
		(layers "In1.Cu" "In3.Cu" "In5.Cu" "In6.Cu" "In8.Cu" "In10.Cu")
		(hatch none 0.5)
		(connect_pads
			(clearance 0)
		)
		(min_thickness 0.25)
		(keepout
			(tracks not_allowed)
			(vias allowed)
			(pads allowed)
			(copperpour not_allowed)
			(footprints allowed)
		)
		(placement
			(enabled no)
			(sheetname "")
		)
		(fill yes
			(thermal_gap 0.5)
			(thermal_bridge_width 0.5)
			(island_removal_mode 0)
		)
		(polygon
			(pts
				(arc
					(start 278.23668 -351.756472)
					(mid 277.68804 -352.305112)
					(end 278.23668 -352.853752)
				)
				(arc
					(start 279.636728 -352.853752)
					(mid 280.185368 -352.305112)
					(end 279.636728 -351.756472)
				)
				(xy 278.236934 -351.756472)
			)
		)
	)
	(zone
		(layers "In1.Cu" "In3.Cu" "In5.Cu" "In6.Cu" "In8.Cu" "In10.Cu")
		(hatch none 0.5)
		(connect_pads
			(clearance 0)
		)
		(min_thickness 0.25)
		(keepout
			(tracks not_allowed)
			(vias allowed)
			(pads allowed)
			(copperpour not_allowed)
			(footprints allowed)
		)
		(placement
			(enabled no)
			(sheetname "")
		)
		(fill yes
			(thermal_gap 0.5)
			(thermal_bridge_width 0.5)
			(island_removal_mode 0)
		)
		(polygon
			(pts
				(arc
					(start 285.436564 -315.756544)
					(mid 284.887924 -316.305184)
					(end 285.436564 -316.853824)
				)
				(arc
					(start 286.836612 -316.853824)
					(mid 287.385252 -316.305184)
					(end 286.836612 -315.756544)
				)
				(xy 285.436818 -315.756544)
			)
		)
	)
	(zone
		(layers "In1.Cu" "In3.Cu" "In5.Cu" "In6.Cu" "In8.Cu" "In10.Cu")
		(hatch none 0.5)
		(connect_pads
			(clearance 0)
		)
		(min_thickness 0.25)
		(keepout
			(tracks not_allowed)
			(vias allowed)
			(pads allowed)
			(copperpour not_allowed)
			(footprints allowed)
		)
		(placement
			(enabled no)
			(sheetname "")
		)
		(fill yes
			(thermal_gap 0.5)
			(thermal_bridge_width 0.5)
			(island_removal_mode 0)
		)
		(polygon
			(pts
				(arc
					(start 325.12 -277.17877)
					(mid 324.739127 -276.797516)
					(end 324.358 -277.178516)
				)
				(arc
					(start 324.358 -278.321516)
					(mid 324.739 -278.702516)
					(end 325.12 -278.321516)
				)
			)
		)
	)
	(zone
		(layers "In1.Cu" "In3.Cu" "In5.Cu" "In6.Cu" "In8.Cu" "In10.Cu")
		(hatch none 0.5)
		(connect_pads
			(clearance 0)
		)
		(min_thickness 0.25)
		(keepout
			(tracks not_allowed)
			(vias allowed)
			(pads allowed)
			(copperpour not_allowed)
			(footprints allowed)
		)
		(placement
			(enabled no)
			(sheetname "")
		)
		(fill yes
			(thermal_gap 0.5)
			(thermal_bridge_width 0.5)
			(island_removal_mode 0)
		)
		(polygon
			(pts
				(arc
					(start 136.698736 -18.350484)
					(mid 136.150223 -17.80159)
					(end 135.601456 -18.35023)
				)
				(arc
					(start 135.601456 -19.750024)
					(mid 136.150096 -20.298664)
					(end 136.698736 -19.750024)
				)
			)
		)
	)
	(zone
		(layers "In1.Cu" "In3.Cu" "In5.Cu" "In6.Cu" "In8.Cu" "In10.Cu")
		(hatch none 0.5)
		(connect_pads
			(clearance 0)
		)
		(min_thickness 0.25)
		(keepout
			(tracks not_allowed)
			(vias allowed)
			(pads allowed)
			(copperpour not_allowed)
			(footprints allowed)
		)
		(placement
			(enabled no)
			(sheetname "")
		)
		(fill yes
			(thermal_gap 0.5)
			(thermal_bridge_width 0.5)
			(island_removal_mode 0)
		)
		(polygon
			(pts
				(arc
					(start 366.498632 -17.350232)
					(mid 365.950119 -16.801338)
					(end 365.401352 -17.349978)
				)
				(arc
					(start 365.401352 -18.750026)
					(mid 365.949992 -19.298666)
					(end 366.498632 -18.750026)
				)
			)
		)
	)
	(zone
		(layers "In1.Cu" "In3.Cu" "In5.Cu" "In6.Cu" "In8.Cu" "In10.Cu")
		(hatch none 0.5)
		(connect_pads
			(clearance 0)
		)
		(min_thickness 0.25)
		(keepout
			(tracks not_allowed)
			(vias allowed)
			(pads allowed)
			(copperpour not_allowed)
			(footprints allowed)
		)
		(placement
			(enabled no)
			(sheetname "")
		)
		(fill yes
			(thermal_gap 0.5)
			(thermal_bridge_width 0.5)
			(island_removal_mode 0)
		)
		(polygon
			(pts
				(arc
					(start 355.698552 -20.950428)
					(mid 355.150039 -20.401534)
					(end 354.601272 -20.950174)
				)
				(arc
					(start 354.601272 -22.350222)
					(mid 355.149912 -22.898862)
					(end 355.698552 -22.350222)
				)
			)
		)
	)
	(zone
		(layers "In1.Cu" "In3.Cu" "In5.Cu" "In6.Cu" "In8.Cu" "In10.Cu")
		(hatch none 0.5)
		(connect_pads
			(clearance 0)
		)
		(min_thickness 0.25)
		(keepout
			(tracks not_allowed)
			(vias allowed)
			(pads allowed)
			(copperpour not_allowed)
			(footprints allowed)
		)
		(placement
			(enabled no)
			(sheetname "")
		)
		(fill yes
			(thermal_gap 0.5)
			(thermal_bridge_width 0.5)
			(island_removal_mode 0)
		)
		(polygon
			(pts
				(arc
					(start 361.098592 -21.950426)
					(mid 360.550079 -21.401532)
					(end 360.001312 -21.950172)
				)
				(arc
					(start 360.001312 -23.35022)
					(mid 360.549952 -23.89886)
					(end 361.098592 -23.35022)
				)
			)
		)
	)
	(zone
		(layers "In1.Cu" "In3.Cu" "In5.Cu" "In6.Cu" "In8.Cu" "In10.Cu")
		(hatch none 0.5)
		(connect_pads
			(clearance 0)
		)
		(min_thickness 0.25)
		(keepout
			(tracks not_allowed)
			(vias allowed)
			(pads allowed)
			(copperpour not_allowed)
			(footprints allowed)
		)
		(placement
			(enabled no)
			(sheetname "")
		)
		(fill yes
			(thermal_gap 0.5)
			(thermal_bridge_width 0.5)
			(island_removal_mode 0)
		)
		(polygon
			(pts
				(arc
					(start 242.236498 -44.82719)
					(mid 243.17706 -44.5135)
					(end 242.86337 -43.572938)
				)
				(arc
					(start 240.871756 -42.577258)
					(mid 239.92498 -42.882443)
					(end 240.236502 -43.827192)
				)
			)
		)
	)
	(zone
		(layers "In1.Cu" "In3.Cu" "In5.Cu" "In6.Cu" "In8.Cu" "In10.Cu")
		(hatch none 0.5)
		(connect_pads
			(clearance 0)
		)
		(min_thickness 0.25)
		(keepout
			(tracks not_allowed)
			(vias allowed)
			(pads allowed)
			(copperpour not_allowed)
			(footprints allowed)
		)
		(placement
			(enabled no)
			(sheetname "")
		)
		(fill yes
			(thermal_gap 0.5)
			(thermal_bridge_width 0.5)
			(island_removal_mode 0)
		)
		(polygon
			(pts
				(arc
					(start 238.374936 -49.849786)
					(mid 238.699802 -48.875188)
					(end 237.725204 -48.550322)
				)
				(xy 237.723934 -48.548036) (xy 235.724192 -49.548034) (xy 235.724192 -49.548288)
				(arc
					(start 235.725208 -49.55032)
					(mid 235.400342 -50.524918)
					(end 236.37494 -50.849784)
				)
				(xy 236.37621 -50.85207) (xy 238.376206 -49.852072)
			)
		)
	)
	(zone
		(layers "In1.Cu" "In3.Cu" "In5.Cu" "In6.Cu" "In8.Cu" "In10.Cu")
		(hatch none 0.5)
		(connect_pads
			(clearance 0)
		)
		(min_thickness 0.25)
		(keepout
			(tracks not_allowed)
			(vias allowed)
			(pads allowed)
			(copperpour not_allowed)
			(footprints allowed)
		)
		(placement
			(enabled no)
			(sheetname "")
		)
		(fill yes
			(thermal_gap 0.5)
			(thermal_bridge_width 0.5)
			(island_removal_mode 0)
		)
		(polygon
			(pts
				(arc
					(start 190.639954 -162.178746)
					(mid 190.259081 -161.797492)
					(end 189.877954 -162.178492)
				)
				(arc
					(start 189.877954 -163.321492)
					(mid 190.258954 -163.702492)
					(end 190.639954 -163.321492)
				)
			)
		)
	)
	(zone
		(layers "In1.Cu" "In3.Cu" "In5.Cu" "In6.Cu" "In8.Cu" "In10.Cu")
		(hatch none 0.5)
		(connect_pads
			(clearance 0)
		)
		(min_thickness 0.25)
		(keepout
			(tracks not_allowed)
			(vias allowed)
			(pads allowed)
			(copperpour not_allowed)
			(footprints allowed)
		)
		(placement
			(enabled no)
			(sheetname "")
		)
		(fill yes
			(thermal_gap 0.5)
			(thermal_bridge_width 0.5)
			(island_removal_mode 0)
		)
		(polygon
			(pts
				(arc
					(start 111.498634 -21.950426)
					(mid 110.950121 -21.401532)
					(end 110.401354 -21.950172)
				)
				(arc
					(start 110.401354 -23.35022)
					(mid 110.949994 -23.89886)
					(end 111.498634 -23.35022)
				)
			)
		)
	)
	(zone
		(layers "In1.Cu" "In3.Cu" "In5.Cu" "In6.Cu" "In8.Cu" "In10.Cu")
		(hatch none 0.5)
		(connect_pads
			(clearance 0)
		)
		(min_thickness 0.25)
		(keepout
			(tracks not_allowed)
			(vias allowed)
			(pads allowed)
			(copperpour not_allowed)
			(footprints allowed)
		)
		(placement
			(enabled no)
			(sheetname "")
		)
		(fill yes
			(thermal_gap 0.5)
			(thermal_bridge_width 0.5)
			(island_removal_mode 0)
		)
		(polygon
			(pts
				(arc
					(start 285.436564 -337.35645)
					(mid 284.887924 -337.90509)
					(end 285.436564 -338.45373)
				)
				(arc
					(start 286.836612 -338.45373)
					(mid 287.385252 -337.90509)
					(end 286.836612 -337.35645)
				)
				(xy 285.436818 -337.35645)
			)
		)
	)
	(zone
		(layers "In1.Cu" "In3.Cu" "In5.Cu" "In6.Cu" "In8.Cu" "In10.Cu")
		(hatch none 0.5)
		(connect_pads
			(clearance 0)
		)
		(min_thickness 0.25)
		(keepout
			(tracks not_allowed)
			(vias allowed)
			(pads allowed)
			(copperpour not_allowed)
			(footprints allowed)
		)
		(placement
			(enabled no)
			(sheetname "")
		)
		(fill yes
			(thermal_gap 0.5)
			(thermal_bridge_width 0.5)
			(island_removal_mode 0)
		)
		(polygon
			(pts
				(arc
					(start 271.970754 -333.921354)
					(mid 271.58696 -334.304767)
					(end 271.9705 -334.688434)
				)
				(arc
					(start 273.1135 -334.688434)
					(mid 273.49704 -334.304894)
					(end 273.1135 -333.921354)
				)
			)
		)
	)
	(zone
		(layers "In1.Cu" "In3.Cu" "In5.Cu" "In6.Cu" "In8.Cu" "In10.Cu")
		(hatch none 0.5)
		(connect_pads
			(clearance 0)
		)
		(min_thickness 0.25)
		(keepout
			(tracks not_allowed)
			(vias allowed)
			(pads allowed)
			(copperpour not_allowed)
			(footprints allowed)
		)
		(placement
			(enabled no)
			(sheetname "")
		)
		(fill yes
			(thermal_gap 0.5)
			(thermal_bridge_width 0.5)
			(island_removal_mode 0)
		)
		(polygon
			(pts
				(arc
					(start 283.563314 -74.572876)
					(mid 282.622752 -74.886566)
					(end 282.936442 -75.827128)
				)
				(arc
					(start 284.928056 -76.822808)
					(mid 285.874832 -76.517623)
					(end 285.56331 -75.572874)
				)
			)
		)
	)
	(zone
		(layers "In1.Cu" "In3.Cu" "In5.Cu" "In6.Cu" "In8.Cu" "In10.Cu")
		(hatch none 0.5)
		(connect_pads
			(clearance 0)
		)
		(min_thickness 0.25)
		(keepout
			(tracks not_allowed)
			(vias allowed)
			(pads allowed)
			(copperpour not_allowed)
			(footprints allowed)
		)
		(placement
			(enabled no)
			(sheetname "")
		)
		(fill yes
			(thermal_gap 0.5)
			(thermal_bridge_width 0.5)
			(island_removal_mode 0)
		)
		(polygon
			(pts
				(arc
					(start 238.374936 -41.849802)
					(mid 238.699802 -40.875204)
					(end 237.725204 -40.550338)
				)
				(xy 237.723934 -40.548052) (xy 235.724192 -41.54805) (xy 235.724192 -41.548304)
				(arc
					(start 235.725208 -41.550336)
					(mid 235.400342 -42.524934)
					(end 236.37494 -42.8498)
				)
				(xy 236.37621 -42.852086) (xy 238.376206 -41.852088)
			)
		)
	)
	(zone
		(layers "In1.Cu" "In3.Cu" "In5.Cu" "In6.Cu" "In8.Cu" "In10.Cu")
		(hatch none 0.5)
		(connect_pads
			(clearance 0)
		)
		(min_thickness 0.25)
		(keepout
			(tracks not_allowed)
			(vias allowed)
			(pads allowed)
			(copperpour not_allowed)
			(footprints allowed)
		)
		(placement
			(enabled no)
			(sheetname "")
		)
		(fill yes
			(thermal_gap 0.5)
			(thermal_bridge_width 0.5)
			(island_removal_mode 0)
		)
		(polygon
			(pts
				(arc
					(start 271.970754 -353.723956)
					(mid 271.5895 -354.104829)
					(end 271.9705 -354.485956)
				)
				(arc
					(start 273.1135 -354.485956)
					(mid 273.4945 -354.104956)
					(end 273.1135 -353.723956)
				)
			)
		)
	)
	(zone
		(layers "In1.Cu" "In3.Cu" "In5.Cu" "In6.Cu" "In8.Cu" "In10.Cu")
		(hatch none 0.5)
		(connect_pads
			(clearance 0)
		)
		(min_thickness 0.25)
		(keepout
			(tracks not_allowed)
			(vias allowed)
			(pads allowed)
			(copperpour not_allowed)
			(footprints allowed)
		)
		(placement
			(enabled no)
			(sheetname "")
		)
		(fill yes
			(thermal_gap 0.5)
			(thermal_bridge_width 0.5)
			(island_removal_mode 0)
		)
		(polygon
			(pts
				(arc
					(start 389.898636 -29.15031)
					(mid 389.350123 -28.601416)
					(end 388.801356 -29.150056)
				)
				(arc
					(start 388.801356 -30.550104)
					(mid 389.349996 -31.098744)
					(end 389.898636 -30.550104)
				)
			)
		)
	)
	(zone
		(layers "In1.Cu" "In3.Cu" "In5.Cu" "In6.Cu" "In8.Cu" "In10.Cu")
		(hatch none 0.5)
		(connect_pads
			(clearance 0)
		)
		(min_thickness 0.25)
		(keepout
			(tracks not_allowed)
			(vias allowed)
			(pads allowed)
			(copperpour not_allowed)
			(footprints allowed)
		)
		(placement
			(enabled no)
			(sheetname "")
		)
		(fill yes
			(thermal_gap 0.5)
			(thermal_bridge_width 0.5)
			(island_removal_mode 0)
		)
		(polygon
			(pts
				(arc
					(start 238.377222 -158.154116)
					(mid 238.704374 -157.17266)
					(end 237.722918 -156.845508)
				)
				(arc
					(start 235.733844 -157.840172)
					(mid 235.393447 -158.821202)
					(end 236.377226 -159.154114)
				)
			)
		)
	)
	(zone
		(layers "In1.Cu" "In3.Cu" "In5.Cu" "In6.Cu" "In8.Cu" "In10.Cu")
		(hatch none 0.5)
		(connect_pads
			(clearance 0)
		)
		(min_thickness 0.25)
		(keepout
			(tracks not_allowed)
			(vias allowed)
			(pads allowed)
			(copperpour not_allowed)
			(footprints allowed)
		)
		(placement
			(enabled no)
			(sheetname "")
		)
		(fill yes
			(thermal_gap 0.5)
			(thermal_bridge_width 0.5)
			(island_removal_mode 0)
		)
		(polygon
			(pts
				(arc
					(start 286.436562 -324.756526)
					(mid 285.887922 -325.305166)
					(end 286.436562 -325.853806)
				)
				(arc
					(start 287.83661 -325.853806)
					(mid 288.38525 -325.305166)
					(end 287.83661 -324.756526)
				)
				(xy 286.436816 -324.756526)
			)
		)
	)
	(zone
		(layers "In1.Cu" "In3.Cu" "In5.Cu" "In6.Cu" "In8.Cu" "In10.Cu")
		(hatch none 0.5)
		(connect_pads
			(clearance 0)
		)
		(min_thickness 0.25)
		(keepout
			(tracks not_allowed)
			(vias allowed)
			(pads allowed)
			(copperpour not_allowed)
			(footprints allowed)
		)
		(placement
			(enabled no)
			(sheetname "")
		)
		(fill yes
			(thermal_gap 0.5)
			(thermal_bridge_width 0.5)
			(island_removal_mode 0)
		)
		(polygon
			(pts
				(arc
					(start 215.948768 -416.800284)
					(mid 215.400255 -416.25139)
					(end 214.851488 -416.80003)
				)
				(arc
					(start 214.851488 -418.200078)
					(mid 215.400128 -418.748718)
					(end 215.948768 -418.200078)
				)
			)
		)
	)
	(zone
		(layers "In1.Cu" "In3.Cu" "In5.Cu" "In6.Cu" "In8.Cu" "In10.Cu")
		(hatch none 0.5)
		(connect_pads
			(clearance 0)
		)
		(min_thickness 0.25)
		(keepout
			(tracks not_allowed)
			(vias allowed)
			(pads allowed)
			(copperpour not_allowed)
			(footprints allowed)
		)
		(placement
			(enabled no)
			(sheetname "")
		)
		(fill yes
			(thermal_gap 0.5)
			(thermal_bridge_width 0.5)
			(island_removal_mode 0)
		)
		(polygon
			(pts
				(arc
					(start 242.236498 -40.827198)
					(mid 243.17706 -40.513508)
					(end 242.86337 -39.572946)
				)
				(arc
					(start 240.871756 -38.577266)
					(mid 239.92498 -38.882451)
					(end 240.236502 -39.8272)
				)
			)
		)
	)
	(zone
		(layers "In1.Cu" "In3.Cu" "In5.Cu" "In6.Cu" "In8.Cu" "In10.Cu")
		(hatch none 0.5)
		(connect_pads
			(clearance 0)
		)
		(min_thickness 0.25)
		(keepout
			(tracks not_allowed)
			(vias allowed)
			(pads allowed)
			(copperpour not_allowed)
			(footprints allowed)
		)
		(placement
			(enabled no)
			(sheetname "")
		)
		(fill yes
			(thermal_gap 0.5)
			(thermal_bridge_width 0.5)
			(island_removal_mode 0)
		)
		(polygon
			(pts
				(arc
					(start 286.436562 -321.156584)
					(mid 285.887922 -321.705224)
					(end 286.436562 -322.253864)
				)
				(arc
					(start 287.83661 -322.253864)
					(mid 288.38525 -321.705224)
					(end 287.83661 -321.156584)
				)
				(xy 286.436816 -321.156584)
			)
		)
	)
	(zone
		(layers "In1.Cu" "In3.Cu" "In5.Cu" "In6.Cu" "In8.Cu" "In10.Cu")
		(hatch none 0.5)
		(connect_pads
			(clearance 0)
		)
		(min_thickness 0.25)
		(keepout
			(tracks not_allowed)
			(vias allowed)
			(pads allowed)
			(copperpour not_allowed)
			(footprints allowed)
		)
		(placement
			(enabled no)
			(sheetname "")
		)
		(fill yes
			(thermal_gap 0.5)
			(thermal_bridge_width 0.5)
			(island_removal_mode 0)
		)
		(polygon
			(pts
				(arc
					(start 286.436562 -303.15662)
					(mid 285.887922 -303.70526)
					(end 286.436562 -304.2539)
				)
				(arc
					(start 287.83661 -304.2539)
					(mid 288.38525 -303.70526)
					(end 287.83661 -303.15662)
				)
				(xy 286.436816 -303.15662)
			)
		)
	)
	(zone
		(layers "In1.Cu" "In3.Cu" "In5.Cu" "In6.Cu" "In8.Cu" "In10.Cu")
		(hatch none 0.5)
		(connect_pads
			(clearance 0)
		)
		(min_thickness 0.25)
		(keepout
			(tracks not_allowed)
			(vias allowed)
			(pads allowed)
			(copperpour not_allowed)
			(footprints allowed)
		)
		(placement
			(enabled no)
			(sheetname "")
		)
		(fill yes
			(thermal_gap 0.5)
			(thermal_bridge_width 0.5)
			(island_removal_mode 0)
		)
		(polygon
			(pts
				(arc
					(start 379.098556 -18.350484)
					(mid 378.550043 -17.80159)
					(end 378.001276 -18.35023)
				)
				(arc
					(start 378.001276 -19.750024)
					(mid 378.549916 -20.298664)
					(end 379.098556 -19.750024)
				)
			)
		)
	)
	(zone
		(layers "In1.Cu" "In3.Cu" "In5.Cu" "In6.Cu" "In8.Cu" "In10.Cu")
		(hatch none 0.5)
		(connect_pads
			(clearance 0)
		)
		(min_thickness 0.25)
		(keepout
			(tracks not_allowed)
			(vias allowed)
			(pads allowed)
			(copperpour not_allowed)
			(footprints allowed)
		)
		(placement
			(enabled no)
			(sheetname "")
		)
		(fill yes
			(thermal_gap 0.5)
			(thermal_bridge_width 0.5)
			(island_removal_mode 0)
		)
		(polygon
			(pts
				(arc
					(start 242.236498 -68.827142)
					(mid 243.17706 -68.513452)
					(end 242.86337 -67.57289)
				)
				(arc
					(start 240.871756 -66.57721)
					(mid 239.92498 -66.882395)
					(end 240.236502 -67.827144)
				)
			)
		)
	)
	(zone
		(layers "In1.Cu" "In3.Cu" "In5.Cu" "In6.Cu" "In8.Cu" "In10.Cu")
		(hatch none 0.5)
		(connect_pads
			(clearance 0)
		)
		(min_thickness 0.25)
		(keepout
			(tracks not_allowed)
			(vias allowed)
			(pads allowed)
			(copperpour not_allowed)
			(footprints allowed)
		)
		(placement
			(enabled no)
			(sheetname "")
		)
		(fill yes
			(thermal_gap 0.5)
			(thermal_bridge_width 0.5)
			(island_removal_mode 0)
		)
		(polygon
			(pts
				(arc
					(start 446.5701 -43.368468)
					(mid 446.1891 -42.987468)
					(end 445.8081 -43.368468)
				)
				(arc
					(start 445.8081 -44.511214)
					(mid 446.188973 -44.892468)
					(end 446.5701 -44.511468)
				)
			)
		)
	)
	(zone
		(layers "In1.Cu" "In3.Cu" "In5.Cu" "In6.Cu" "In8.Cu" "In10.Cu")
		(hatch none 0.5)
		(connect_pads
			(clearance 0)
		)
		(min_thickness 0.25)
		(keepout
			(tracks not_allowed)
			(vias allowed)
			(pads allowed)
			(copperpour not_allowed)
			(footprints allowed)
		)
		(placement
			(enabled no)
			(sheetname "")
		)
		(fill yes
			(thermal_gap 0.5)
			(thermal_bridge_width 0.5)
			(island_removal_mode 0)
		)
		(polygon
			(pts
				(arc
					(start 415.020252 -158.368492)
					(mid 414.639252 -157.987492)
					(end 414.258252 -158.368492)
				)
				(arc
					(start 414.258252 -159.511238)
					(mid 414.639125 -159.892492)
					(end 415.020252 -159.511492)
				)
			)
		)
	)
	(zone
		(layers "In1.Cu" "In3.Cu" "In5.Cu" "In6.Cu" "In8.Cu" "In10.Cu")
		(hatch none 0.5)
		(connect_pads
			(clearance 0)
		)
		(min_thickness 0.25)
		(keepout
			(tracks not_allowed)
			(vias allowed)
			(pads allowed)
			(copperpour not_allowed)
			(footprints allowed)
		)
		(placement
			(enabled no)
			(sheetname "")
		)
		(fill yes
			(thermal_gap 0.5)
			(thermal_bridge_width 0.5)
			(island_removal_mode 0)
		)
		(polygon
			(pts
				(arc
					(start 283.563314 -170.872658)
					(mid 282.622752 -171.186348)
					(end 282.936442 -172.12691)
				)
				(arc
					(start 284.928056 -173.12259)
					(mid 285.874832 -172.817405)
					(end 285.56331 -171.872656)
				)
			)
		)
	)
	(zone
		(layers "In1.Cu" "In3.Cu" "In5.Cu" "In6.Cu" "In8.Cu" "In10.Cu")
		(hatch none 0.5)
		(connect_pads
			(clearance 0)
		)
		(min_thickness 0.25)
		(keepout
			(tracks not_allowed)
			(vias allowed)
			(pads allowed)
			(copperpour not_allowed)
			(footprints allowed)
		)
		(placement
			(enabled no)
			(sheetname "")
		)
		(fill yes
			(thermal_gap 0.5)
			(thermal_bridge_width 0.5)
			(island_removal_mode 0)
		)
		(polygon
			(pts
				(arc
					(start 355.698552 -17.350232)
					(mid 355.150039 -16.801338)
					(end 354.601272 -17.349978)
				)
				(arc
					(start 354.601272 -18.750026)
					(mid 355.149912 -19.298666)
					(end 355.698552 -18.750026)
				)
			)
		)
	)
	(zone
		(layers "In1.Cu" "In3.Cu" "In5.Cu" "In6.Cu" "In8.Cu" "In10.Cu")
		(hatch none 0.5)
		(connect_pads
			(clearance 0)
		)
		(min_thickness 0.25)
		(keepout
			(tracks not_allowed)
			(vias allowed)
			(pads allowed)
			(copperpour not_allowed)
			(footprints allowed)
		)
		(placement
			(enabled no)
			(sheetname "")
		)
		(fill yes
			(thermal_gap 0.5)
			(thermal_bridge_width 0.5)
			(island_removal_mode 0)
		)
		(polygon
			(pts
				(arc
					(start 238.377222 -150.154132)
					(mid 238.704374 -149.172676)
					(end 237.722918 -148.845524)
				)
				(arc
					(start 235.733844 -149.840188)
					(mid 235.393447 -150.821218)
					(end 236.377226 -151.15413)
				)
			)
		)
	)
	(zone
		(layers "In1.Cu" "In3.Cu" "In5.Cu" "In6.Cu" "In8.Cu" "In10.Cu")
		(hatch none 0.5)
		(connect_pads
			(clearance 0)
		)
		(min_thickness 0.25)
		(keepout
			(tracks not_allowed)
			(vias allowed)
			(pads allowed)
			(copperpour not_allowed)
			(footprints allowed)
		)
		(placement
			(enabled no)
			(sheetname "")
		)
		(fill yes
			(thermal_gap 0.5)
			(thermal_bridge_width 0.5)
			(island_removal_mode 0)
		)
		(polygon
			(pts
				(arc
					(start 238.374936 -45.849794)
					(mid 238.699802 -44.875196)
					(end 237.725204 -44.55033)
				)
				(xy 237.723934 -44.548044) (xy 235.724192 -45.548042) (xy 235.724192 -45.548296)
				(arc
					(start 235.725208 -45.550328)
					(mid 235.400342 -46.524926)
					(end 236.37494 -46.849792)
				)
				(xy 236.37621 -46.852078) (xy 238.376206 -45.85208)
			)
		)
	)
	(zone
		(layers "In1.Cu" "In3.Cu" "In5.Cu" "In6.Cu" "In8.Cu" "In10.Cu")
		(hatch none 0.5)
		(connect_pads
			(clearance 0)
		)
		(min_thickness 0.25)
		(keepout
			(tracks not_allowed)
			(vias allowed)
			(pads allowed)
			(copperpour not_allowed)
			(footprints allowed)
		)
		(placement
			(enabled no)
			(sheetname "")
		)
		(fill yes
			(thermal_gap 0.5)
			(thermal_bridge_width 0.5)
			(island_removal_mode 0)
		)
		(polygon
			(pts
				(xy 279.07615 -78.852014) (xy 281.076146 -77.852016)
				(arc
					(start 281.074876 -77.84973)
					(mid 281.399742 -76.875132)
					(end 280.425144 -76.550266)
				)
				(xy 280.423874 -76.54798) (xy 278.424132 -77.547978) (xy 278.424132 -77.548232)
				(arc
					(start 278.425148 -77.550264)
					(mid 278.100282 -78.524862)
					(end 279.07488 -78.849728)
				)
			)
		)
	)
	(zone
		(layers "In1.Cu" "In3.Cu" "In5.Cu" "In6.Cu" "In8.Cu" "In10.Cu")
		(hatch none 0.5)
		(connect_pads
			(clearance 0)
		)
		(min_thickness 0.25)
		(keepout
			(tracks not_allowed)
			(vias allowed)
			(pads allowed)
			(copperpour not_allowed)
			(footprints allowed)
		)
		(placement
			(enabled no)
			(sheetname "")
		)
		(fill yes
			(thermal_gap 0.5)
			(thermal_bridge_width 0.5)
			(island_removal_mode 0)
		)
		(polygon
			(pts
				(arc
					(start 271.970754 -359.123996)
					(mid 271.5895 -359.504869)
					(end 271.9705 -359.885996)
				)
				(arc
					(start 273.1135 -359.885996)
					(mid 273.4945 -359.504996)
					(end 273.1135 -359.123996)
				)
			)
		)
	)
	(zone
		(layers "In1.Cu" "In3.Cu" "In5.Cu" "In6.Cu" "In8.Cu" "In10.Cu")
		(hatch none 0.5)
		(connect_pads
			(clearance 0)
		)
		(min_thickness 0.25)
		(keepout
			(tracks not_allowed)
			(vias allowed)
			(pads allowed)
			(copperpour not_allowed)
			(footprints allowed)
		)
		(placement
			(enabled no)
			(sheetname "")
		)
		(fill yes
			(thermal_gap 0.5)
			(thermal_bridge_width 0.5)
			(island_removal_mode 0)
		)
		(polygon
			(pts
				(arc
					(start 279.236678 -342.75649)
					(mid 278.688038 -343.30513)
					(end 279.236678 -343.85377)
				)
				(arc
					(start 280.636726 -343.85377)
					(mid 281.185366 -343.30513)
					(end 280.636726 -342.75649)
				)
				(xy 279.236932 -342.75649)
			)
		)
	)
	(zone
		(layers "In1.Cu" "In3.Cu" "In5.Cu" "In6.Cu" "In8.Cu" "In10.Cu")
		(hatch none 0.5)
		(connect_pads
			(clearance 0)
		)
		(min_thickness 0.25)
		(keepout
			(tracks not_allowed)
			(vias allowed)
			(pads allowed)
			(copperpour not_allowed)
			(footprints allowed)
		)
		(placement
			(enabled no)
			(sheetname "")
		)
		(fill yes
			(thermal_gap 0.5)
			(thermal_bridge_width 0.5)
			(island_removal_mode 0)
		)
		(polygon
			(pts
				(arc
					(start 438.6199 -162.178746)
					(mid 438.239027 -161.797492)
					(end 437.8579 -162.178492)
				)
				(arc
					(start 437.8579 -163.321492)
					(mid 438.2389 -163.702492)
					(end 438.6199 -163.321492)
				)
			)
		)
	)
	(zone
		(layers "In1.Cu" "In3.Cu" "In5.Cu" "In6.Cu" "In8.Cu" "In10.Cu")
		(hatch none 0.5)
		(connect_pads
			(clearance 0)
		)
		(min_thickness 0.25)
		(keepout
			(tracks not_allowed)
			(vias allowed)
			(pads allowed)
			(copperpour not_allowed)
			(footprints allowed)
		)
		(placement
			(enabled no)
			(sheetname "")
		)
		(fill yes
			(thermal_gap 0.5)
			(thermal_bridge_width 0.5)
			(island_removal_mode 0)
		)
		(polygon
			(pts
				(arc
					(start 271.970754 -332.12151)
					(mid 271.58696 -332.504923)
					(end 271.9705 -332.88859)
				)
				(arc
					(start 273.1135 -332.88859)
					(mid 273.49704 -332.50505)
					(end 273.1135 -332.12151)
				)
			)
		)
	)
	(zone
		(layers "In1.Cu" "In3.Cu" "In5.Cu" "In6.Cu" "In8.Cu" "In10.Cu")
		(hatch none 0.5)
		(connect_pads
			(clearance 0)
		)
		(min_thickness 0.25)
		(keepout
			(tracks not_allowed)
			(vias allowed)
			(pads allowed)
			(copperpour not_allowed)
			(footprints allowed)
		)
		(placement
			(enabled no)
			(sheetname "")
		)
		(fill yes
			(thermal_gap 0.5)
			(thermal_bridge_width 0.5)
			(island_removal_mode 0)
		)
		(polygon
			(pts
				(arc
					(start 386.298694 -21.950426)
					(mid 385.750181 -21.401532)
					(end 385.201414 -21.950172)
				)
				(arc
					(start 385.201414 -23.35022)
					(mid 385.750054 -23.89886)
					(end 386.298694 -23.35022)
				)
			)
		)
	)
	(zone
		(layers "In1.Cu" "In3.Cu" "In5.Cu" "In6.Cu" "In8.Cu" "In10.Cu")
		(hatch none 0.5)
		(connect_pads
			(clearance 0)
		)
		(min_thickness 0.25)
		(keepout
			(tracks not_allowed)
			(vias allowed)
			(pads allowed)
			(copperpour not_allowed)
			(footprints allowed)
		)
		(placement
			(enabled no)
			(sheetname "")
		)
		(fill yes
			(thermal_gap 0.5)
			(thermal_bridge_width 0.5)
			(island_removal_mode 0)
		)
		(polygon
			(pts
				(arc
					(start 212.348826 -416.800284)
					(mid 211.800313 -416.25139)
					(end 211.251546 -416.80003)
				)
				(arc
					(start 211.251546 -418.200078)
					(mid 211.800186 -418.748718)
					(end 212.348826 -418.200078)
				)
			)
		)
	)
	(zone
		(layers "In1.Cu" "In3.Cu" "In5.Cu" "In6.Cu" "In8.Cu" "In10.Cu")
		(hatch none 0.5)
		(connect_pads
			(clearance 0)
		)
		(min_thickness 0.25)
		(keepout
			(tracks not_allowed)
			(vias allowed)
			(pads allowed)
			(copperpour not_allowed)
			(footprints allowed)
		)
		(placement
			(enabled no)
			(sheetname "")
		)
		(fill yes
			(thermal_gap 0.5)
			(thermal_bridge_width 0.5)
			(island_removal_mode 0)
		)
		(polygon
			(pts
				(arc
					(start 32.889952 -277.17877)
					(mid 32.509079 -276.797516)
					(end 32.127952 -277.178516)
				)
				(arc
					(start 32.127952 -278.321516)
					(mid 32.508952 -278.702516)
					(end 32.889952 -278.321516)
				)
			)
		)
	)
	(zone
		(layers "In1.Cu" "In3.Cu" "In5.Cu" "In6.Cu" "In8.Cu" "In10.Cu")
		(hatch none 0.5)
		(connect_pads
			(clearance 0)
		)
		(min_thickness 0.25)
		(keepout
			(tracks not_allowed)
			(vias allowed)
			(pads allowed)
			(copperpour not_allowed)
			(footprints allowed)
		)
		(placement
			(enabled no)
			(sheetname "")
		)
		(fill yes
			(thermal_gap 0.5)
			(thermal_bridge_width 0.5)
			(island_removal_mode 0)
		)
		(polygon
			(pts
				(arc
					(start 286.436562 -255.951228)
					(mid 285.885382 -256.502408)
					(end 286.436562 -257.053588)
				)
				(arc
					(start 287.83661 -257.053588)
					(mid 288.38779 -256.502408)
					(end 287.83661 -255.951228)
				)
				(xy 286.436816 -255.951228)
			)
		)
	)
	(zone
		(layers "In1.Cu" "In3.Cu" "In5.Cu" "In6.Cu" "In8.Cu" "In10.Cu")
		(hatch none 0.5)
		(connect_pads
			(clearance 0)
		)
		(min_thickness 0.25)
		(keepout
			(tracks not_allowed)
			(vias allowed)
			(pads allowed)
			(copperpour not_allowed)
			(footprints allowed)
		)
		(placement
			(enabled no)
			(sheetname "")
		)
		(fill yes
			(thermal_gap 0.5)
			(thermal_bridge_width 0.5)
			(island_removal_mode 0)
		)
		(polygon
			(pts
				(arc
					(start 238.374936 -178.149504)
					(mid 238.699802 -177.174906)
					(end 237.725204 -176.85004)
				)
				(xy 237.723934 -176.847754) (xy 235.724192 -177.847752) (xy 235.724192 -177.848006)
				(arc
					(start 235.725208 -177.850038)
					(mid 235.400342 -178.824636)
					(end 236.37494 -179.149502)
				)
				(xy 236.37621 -179.151788) (xy 238.376206 -178.15179)
			)
		)
	)
	(zone
		(layers "In1.Cu" "In3.Cu" "In5.Cu" "In6.Cu" "In8.Cu" "In10.Cu")
		(hatch none 0.5)
		(connect_pads
			(clearance 0)
		)
		(min_thickness 0.25)
		(keepout
			(tracks not_allowed)
			(vias allowed)
			(pads allowed)
			(copperpour not_allowed)
			(footprints allowed)
		)
		(placement
			(enabled no)
			(sheetname "")
		)
		(fill yes
			(thermal_gap 0.5)
			(thermal_bridge_width 0.5)
			(island_removal_mode 0)
		)
		(polygon
			(pts
				(arc
					(start 377.298712 -20.950428)
					(mid 376.750199 -20.401534)
					(end 376.201432 -20.950174)
				)
				(arc
					(start 376.201432 -22.350222)
					(mid 376.750072 -22.898862)
					(end 377.298712 -22.350222)
				)
			)
		)
	)
	(zone
		(layers "In1.Cu" "In3.Cu" "In5.Cu" "In6.Cu" "In8.Cu" "In10.Cu")
		(hatch none 0.5)
		(connect_pads
			(clearance 0)
		)
		(min_thickness 0.25)
		(keepout
			(tracks not_allowed)
			(vias allowed)
			(pads allowed)
			(copperpour not_allowed)
			(footprints allowed)
		)
		(placement
			(enabled no)
			(sheetname "")
		)
		(fill yes
			(thermal_gap 0.5)
			(thermal_bridge_width 0.5)
			(island_removal_mode 0)
		)
		(polygon
			(pts
				(arc
					(start 482.870002 -277.17877)
					(mid 482.489129 -276.797516)
					(end 482.108002 -277.178516)
				)
				(arc
					(start 482.108002 -278.321516)
					(mid 482.489002 -278.702516)
					(end 482.870002 -278.321516)
				)
			)
		)
	)
	(zone
		(layers "In1.Cu" "In3.Cu" "In5.Cu" "In6.Cu" "In8.Cu" "In10.Cu")
		(hatch none 0.5)
		(connect_pads
			(clearance 0)
		)
		(min_thickness 0.25)
		(keepout
			(tracks not_allowed)
			(vias allowed)
			(pads allowed)
			(copperpour not_allowed)
			(footprints allowed)
		)
		(placement
			(enabled no)
			(sheetname "")
		)
		(fill yes
			(thermal_gap 0.5)
			(thermal_bridge_width 0.5)
			(island_removal_mode 0)
		)
		(polygon
			(pts
				(xy 279.07615 -46.852078) (xy 281.076146 -45.85208)
				(arc
					(start 281.074876 -45.849794)
					(mid 281.399742 -44.875196)
					(end 280.425144 -44.55033)
				)
				(xy 280.423874 -44.548044) (xy 278.424132 -45.548042) (xy 278.424132 -45.548296)
				(arc
					(start 278.425148 -45.550328)
					(mid 278.100282 -46.524926)
					(end 279.07488 -46.849792)
				)
			)
		)
	)
	(zone
		(layers "In1.Cu" "In3.Cu" "In5.Cu" "In6.Cu" "In8.Cu" "In10.Cu")
		(hatch none 0.5)
		(connect_pads
			(clearance 0)
		)
		(min_thickness 0.25)
		(keepout
			(tracks not_allowed)
			(vias allowed)
			(pads allowed)
			(copperpour not_allowed)
			(footprints allowed)
		)
		(placement
			(enabled no)
			(sheetname "")
		)
		(fill yes
			(thermal_gap 0.5)
			(thermal_bridge_width 0.5)
			(island_removal_mode 0)
		)
		(polygon
			(pts
				(arc
					(start 271.970754 -328.521568)
					(mid 271.58696 -328.904981)
					(end 271.9705 -329.288648)
				)
				(arc
					(start 273.1135 -329.288648)
					(mid 273.49704 -328.905108)
					(end 273.1135 -328.521568)
				)
			)
		)
	)
	(zone
		(layers "In1.Cu" "In3.Cu" "In5.Cu" "In6.Cu" "In8.Cu" "In10.Cu")
		(hatch none 0.5)
		(connect_pads
			(clearance 0)
		)
		(min_thickness 0.25)
		(keepout
			(tracks not_allowed)
			(vias allowed)
			(pads allowed)
			(copperpour not_allowed)
			(footprints allowed)
		)
		(placement
			(enabled no)
			(sheetname "")
		)
		(fill yes
			(thermal_gap 0.5)
			(thermal_bridge_width 0.5)
			(island_removal_mode 0)
		)
		(polygon
			(pts
				(arc
					(start 271.970754 -310.52135)
					(mid 271.58696 -310.904763)
					(end 271.9705 -311.28843)
				)
				(arc
					(start 273.1135 -311.28843)
					(mid 273.49704 -310.90489)
					(end 273.1135 -310.52135)
				)
			)
		)
	)
	(zone
		(layers "In1.Cu" "In3.Cu" "In5.Cu" "In6.Cu" "In8.Cu" "In10.Cu")
		(hatch none 0.5)
		(connect_pads
			(clearance 0)
		)
		(min_thickness 0.25)
		(keepout
			(tracks not_allowed)
			(vias allowed)
			(pads allowed)
			(copperpour not_allowed)
			(footprints allowed)
		)
		(placement
			(enabled no)
			(sheetname "")
		)
		(fill yes
			(thermal_gap 0.5)
			(thermal_bridge_width 0.5)
			(island_removal_mode 0)
		)
		(polygon
			(pts
				(arc
					(start 388.098538 -17.350232)
					(mid 387.550025 -16.801338)
					(end 387.001258 -17.349978)
				)
				(arc
					(start 387.001258 -18.750026)
					(mid 387.549898 -19.298666)
					(end 388.098538 -18.750026)
				)
			)
		)
	)
	(zone
		(layers "In1.Cu" "In3.Cu" "In5.Cu" "In6.Cu" "In8.Cu" "In10.Cu")
		(hatch none 0.5)
		(connect_pads
			(clearance 0)
		)
		(min_thickness 0.25)
		(keepout
			(tracks not_allowed)
			(vias allowed)
			(pads allowed)
			(copperpour not_allowed)
			(footprints allowed)
		)
		(placement
			(enabled no)
			(sheetname "")
		)
		(fill yes
			(thermal_gap 0.5)
			(thermal_bridge_width 0.5)
			(island_removal_mode 0)
		)
		(polygon
			(pts
				(arc
					(start 379.098556 -21.950426)
					(mid 378.550043 -21.401532)
					(end 378.001276 -21.950172)
				)
				(arc
					(start 378.001276 -23.35022)
					(mid 378.549916 -23.89886)
					(end 379.098556 -23.35022)
				)
			)
		)
	)
	(zone
		(layers "In1.Cu" "In3.Cu" "In5.Cu" "In6.Cu" "In8.Cu" "In10.Cu")
		(hatch none 0.5)
		(connect_pads
			(clearance 0)
		)
		(min_thickness 0.25)
		(keepout
			(tracks not_allowed)
			(vias allowed)
			(pads allowed)
			(copperpour not_allowed)
			(footprints allowed)
		)
		(placement
			(enabled no)
			(sheetname "")
		)
		(fill yes
			(thermal_gap 0.5)
			(thermal_bridge_width 0.5)
			(island_removal_mode 0)
		)
		(polygon
			(pts
				(arc
					(start 285.436564 -351.753932)
					(mid 284.885384 -352.305112)
					(end 285.436564 -352.856292)
				)
				(arc
					(start 286.836612 -352.856292)
					(mid 287.387792 -352.305112)
					(end 286.836612 -351.753932)
				)
				(xy 285.436818 -351.753932)
			)
		)
	)
	(zone
		(layers "In1.Cu" "In3.Cu" "In5.Cu" "In6.Cu" "In8.Cu" "In10.Cu")
		(hatch none 0.5)
		(connect_pads
			(clearance 0)
		)
		(min_thickness 0.25)
		(keepout
			(tracks not_allowed)
			(vias allowed)
			(pads allowed)
			(copperpour not_allowed)
			(footprints allowed)
		)
		(placement
			(enabled no)
			(sheetname "")
		)
		(fill yes
			(thermal_gap 0.5)
			(thermal_bridge_width 0.5)
			(island_removal_mode 0)
		)
		(polygon
			(pts
				(arc
					(start 240.880392 -122.838718)
					(mid 239.888776 -123.169426)
					(end 240.219484 -124.161042)
				)
				(arc
					(start 242.20805 -125.155198)
					(mid 243.208198 -124.836059)
					(end 242.880388 -123.838716)
				)
			)
		)
	)
	(zone
		(layers "In1.Cu" "In3.Cu" "In5.Cu" "In6.Cu" "In8.Cu" "In10.Cu")
		(hatch none 0.5)
		(connect_pads
			(clearance 0)
		)
		(min_thickness 0.25)
		(keepout
			(tracks not_allowed)
			(vias allowed)
			(pads allowed)
			(copperpour not_allowed)
			(footprints allowed)
		)
		(placement
			(enabled no)
			(sheetname "")
		)
		(fill yes
			(thermal_gap 0.5)
			(thermal_bridge_width 0.5)
			(island_removal_mode 0)
		)
		(polygon
			(pts
				(arc
					(start 118.698518 -18.350484)
					(mid 118.150005 -17.80159)
					(end 117.601238 -18.35023)
				)
				(arc
					(start 117.601238 -19.750024)
					(mid 118.149878 -20.298664)
					(end 118.698518 -19.750024)
				)
			)
		)
	)
	(zone
		(layers "In1.Cu" "In3.Cu" "In5.Cu" "In6.Cu" "In8.Cu" "In10.Cu")
		(hatch none 0.5)
		(connect_pads
			(clearance 0)
		)
		(min_thickness 0.25)
		(keepout
			(tracks not_allowed)
			(vias allowed)
			(pads allowed)
			(copperpour not_allowed)
			(footprints allowed)
		)
		(placement
			(enabled no)
			(sheetname "")
		)
		(fill yes
			(thermal_gap 0.5)
			(thermal_bridge_width 0.5)
			(island_removal_mode 0)
		)
		(polygon
			(pts
				(arc
					(start 159.089852 -162.178746)
					(mid 158.708979 -161.797492)
					(end 158.327852 -162.178492)
				)
				(arc
					(start 158.327852 -163.321492)
					(mid 158.708852 -163.702492)
					(end 159.089852 -163.321492)
				)
			)
		)
	)
	(zone
		(layers "In1.Cu" "In3.Cu" "In5.Cu" "In6.Cu" "In8.Cu" "In10.Cu")
		(hatch none 0.5)
		(connect_pads
			(clearance 0)
		)
		(min_thickness 0.25)
		(keepout
			(tracks not_allowed)
			(vias allowed)
			(pads allowed)
			(copperpour not_allowed)
			(footprints allowed)
		)
		(placement
			(enabled no)
			(sheetname "")
		)
		(fill yes
			(thermal_gap 0.5)
			(thermal_bridge_width 0.5)
			(island_removal_mode 0)
		)
		(polygon
			(pts
				(arc
					(start 364.698534 -18.350484)
					(mid 364.150021 -17.80159)
					(end 363.601254 -18.35023)
				)
				(arc
					(start 363.601254 -19.750024)
					(mid 364.149894 -20.298664)
					(end 364.698534 -19.750024)
				)
			)
		)
	)
	(zone
		(layers "In1.Cu" "In3.Cu" "In5.Cu" "In6.Cu" "In8.Cu" "In10.Cu")
		(hatch none 0.5)
		(connect_pads
			(clearance 0)
		)
		(min_thickness 0.25)
		(keepout
			(tracks not_allowed)
			(vias allowed)
			(pads allowed)
			(copperpour not_allowed)
			(footprints allowed)
		)
		(placement
			(enabled no)
			(sheetname "")
		)
		(fill yes
			(thermal_gap 0.5)
			(thermal_bridge_width 0.5)
			(island_removal_mode 0)
		)
		(polygon
			(pts
				(arc
					(start 279.236678 -317.556388)
					(mid 278.688038 -318.105028)
					(end 279.236678 -318.653668)
				)
				(arc
					(start 280.636726 -318.653668)
					(mid 281.185366 -318.105028)
					(end 280.636726 -317.556388)
				)
				(xy 279.236932 -317.556388)
			)
		)
	)
	(zone
		(layers "In1.Cu" "In3.Cu" "In5.Cu" "In6.Cu" "In8.Cu" "In10.Cu")
		(hatch none 0.5)
		(connect_pads
			(clearance 0)
		)
		(min_thickness 0.25)
		(keepout
			(tracks not_allowed)
			(vias allowed)
			(pads allowed)
			(copperpour not_allowed)
			(footprints allowed)
		)
		(placement
			(enabled no)
			(sheetname "")
		)
		(fill yes
			(thermal_gap 0.5)
			(thermal_bridge_width 0.5)
			(island_removal_mode 0)
		)
		(polygon
			(pts
				(arc
					(start 285.436564 -312.154062)
					(mid 284.885384 -312.705242)
					(end 285.436564 -313.256422)
				)
				(arc
					(start 286.836612 -313.256422)
					(mid 287.387792 -312.705242)
					(end 286.836612 -312.154062)
				)
				(xy 285.436818 -312.154062)
			)
		)
	)
	(zone
		(layers "In1.Cu" "In3.Cu" "In5.Cu" "In6.Cu" "In8.Cu" "In10.Cu")
		(hatch none 0.5)
		(connect_pads
			(clearance 0)
		)
		(min_thickness 0.25)
		(keepout
			(tracks not_allowed)
			(vias allowed)
			(pads allowed)
			(copperpour not_allowed)
			(footprints allowed)
		)
		(placement
			(enabled no)
			(sheetname "")
		)
		(fill yes
			(thermal_gap 0.5)
			(thermal_bridge_width 0.5)
			(island_removal_mode 0)
		)
		(polygon
			(pts
				(arc
					(start 238.377222 -126.15418)
					(mid 238.704374 -125.172724)
					(end 237.722918 -124.845572)
				)
				(arc
					(start 235.733844 -125.840236)
					(mid 235.393447 -126.821266)
					(end 236.377226 -127.154178)
				)
			)
		)
	)
	(zone
		(layers "In1.Cu" "In3.Cu" "In5.Cu" "In6.Cu" "In8.Cu" "In10.Cu")
		(hatch none 0.5)
		(connect_pads
			(clearance 0)
		)
		(min_thickness 0.25)
		(keepout
			(tracks not_allowed)
			(vias allowed)
			(pads allowed)
			(copperpour not_allowed)
			(footprints allowed)
		)
		(placement
			(enabled no)
			(sheetname "")
		)
		(fill yes
			(thermal_gap 0.5)
			(thermal_bridge_width 0.5)
			(island_removal_mode 0)
		)
		(polygon
			(pts
				(arc
					(start 115.098576 -18.350484)
					(mid 114.550063 -17.80159)
					(end 114.001296 -18.35023)
				)
				(arc
					(start 114.001296 -19.750024)
					(mid 114.549936 -20.298664)
					(end 115.098576 -19.750024)
				)
			)
		)
	)
	(zone
		(layers "In1.Cu" "In3.Cu" "In5.Cu" "In6.Cu" "In8.Cu" "In10.Cu")
		(hatch none 0.5)
		(connect_pads
			(clearance 0)
		)
		(min_thickness 0.25)
		(keepout
			(tracks not_allowed)
			(vias allowed)
			(pads allowed)
			(copperpour not_allowed)
			(footprints allowed)
		)
		(placement
			(enabled no)
			(sheetname "")
		)
		(fill yes
			(thermal_gap 0.5)
			(thermal_bridge_width 0.5)
			(island_removal_mode 0)
		)
		(polygon
			(pts
				(arc
					(start 278.23668 -330.156566)
					(mid 277.68804 -330.705206)
					(end 278.23668 -331.253846)
				)
				(arc
					(start 279.636728 -331.253846)
					(mid 280.185368 -330.705206)
					(end 279.636728 -330.156566)
				)
				(xy 278.236934 -330.156566)
			)
		)
	)
	(zone
		(layers "In1.Cu" "In3.Cu" "In5.Cu" "In6.Cu" "In8.Cu" "In10.Cu")
		(hatch none 0.5)
		(connect_pads
			(clearance 0)
		)
		(min_thickness 0.25)
		(keepout
			(tracks not_allowed)
			(vias allowed)
			(pads allowed)
			(copperpour not_allowed)
			(footprints allowed)
		)
		(placement
			(enabled no)
			(sheetname "")
		)
		(fill yes
			(thermal_gap 0.5)
			(thermal_bridge_width 0.5)
			(island_removal_mode 0)
		)
		(polygon
			(pts
				(arc
					(start 238.377222 -154.154124)
					(mid 238.704374 -153.172668)
					(end 237.722918 -152.845516)
				)
				(arc
					(start 235.733844 -153.84018)
					(mid 235.393447 -154.82121)
					(end 236.377226 -155.154122)
				)
			)
		)
	)
	(zone
		(layers "In1.Cu" "In3.Cu" "In5.Cu" "In6.Cu" "In8.Cu" "In10.Cu")
		(hatch none 0.5)
		(connect_pads
			(clearance 0)
		)
		(min_thickness 0.25)
		(keepout
			(tracks not_allowed)
			(vias allowed)
			(pads allowed)
			(copperpour not_allowed)
			(footprints allowed)
		)
		(placement
			(enabled no)
			(sheetname "")
		)
		(fill yes
			(thermal_gap 0.5)
			(thermal_bridge_width 0.5)
			(island_removal_mode 0)
		)
		(polygon
			(pts
				(arc
					(start 242.236498 -56.827166)
					(mid 243.17706 -56.513476)
					(end 242.86337 -55.572914)
				)
				(arc
					(start 240.871756 -54.577234)
					(mid 239.92498 -54.882419)
					(end 240.236502 -55.827168)
				)
			)
		)
	)
	(zone
		(layers "In1.Cu" "In3.Cu" "In5.Cu" "In6.Cu" "In8.Cu" "In10.Cu")
		(hatch none 0.5)
		(connect_pads
			(clearance 0)
		)
		(min_thickness 0.25)
		(keepout
			(tracks not_allowed)
			(vias allowed)
			(pads allowed)
			(copperpour not_allowed)
			(footprints allowed)
		)
		(placement
			(enabled no)
			(sheetname "")
		)
		(fill yes
			(thermal_gap 0.5)
			(thermal_bridge_width 0.5)
			(island_removal_mode 0)
		)
		(polygon
			(pts
				(arc
					(start 286.436562 -328.353928)
					(mid 285.885382 -328.905108)
					(end 286.436562 -329.456288)
				)
				(arc
					(start 287.83661 -329.456288)
					(mid 288.38779 -328.905108)
					(end 287.83661 -328.353928)
				)
				(xy 286.436816 -328.353928)
			)
		)
	)
	(zone
		(layers "In1.Cu" "In3.Cu" "In5.Cu" "In6.Cu" "In8.Cu" "In10.Cu")
		(hatch none 0.5)
		(connect_pads
			(clearance 0)
		)
		(min_thickness 0.25)
		(keepout
			(tracks not_allowed)
			(vias allowed)
			(pads allowed)
			(copperpour not_allowed)
			(footprints allowed)
		)
		(placement
			(enabled no)
			(sheetname "")
		)
		(fill yes
			(thermal_gap 0.5)
			(thermal_bridge_width 0.5)
			(island_removal_mode 0)
		)
		(polygon
			(pts
				(arc
					(start 242.236498 -181.126892)
					(mid 243.17706 -180.813202)
					(end 242.86337 -179.87264)
				)
				(arc
					(start 240.871756 -178.87696)
					(mid 239.92498 -179.182145)
					(end 240.236502 -180.126894)
				)
			)
		)
	)
	(zone
		(layers "In1.Cu" "In3.Cu" "In5.Cu" "In6.Cu" "In8.Cu" "In10.Cu")
		(hatch none 0.5)
		(connect_pads
			(clearance 0)
		)
		(min_thickness 0.25)
		(keepout
			(tracks not_allowed)
			(vias allowed)
			(pads allowed)
			(copperpour not_allowed)
			(footprints allowed)
		)
		(placement
			(enabled no)
			(sheetname "")
		)
		(fill yes
			(thermal_gap 0.5)
			(thermal_bridge_width 0.5)
			(island_removal_mode 0)
		)
		(polygon
			(pts
				(arc
					(start 278.23668 -257.751072)
					(mid 277.6855 -258.302252)
					(end 278.23668 -258.853432)
				)
				(arc
					(start 279.636728 -258.853432)
					(mid 280.187908 -258.302252)
					(end 279.636728 -257.751072)
				)
				(xy 278.236934 -257.751072)
			)
		)
	)
	(zone
		(layers "In1.Cu" "In3.Cu" "In5.Cu" "In6.Cu" "In8.Cu" "In10.Cu")
		(hatch none 0.5)
		(connect_pads
			(clearance 0)
		)
		(min_thickness 0.25)
		(keepout
			(tracks not_allowed)
			(vias allowed)
			(pads allowed)
			(copperpour not_allowed)
			(footprints allowed)
		)
		(placement
			(enabled no)
			(sheetname "")
		)
		(fill yes
			(thermal_gap 0.5)
			(thermal_bridge_width 0.5)
			(island_removal_mode 0)
		)
		(polygon
			(pts
				(arc
					(start 380.898654 -17.350232)
					(mid 380.350141 -16.801338)
					(end 379.801374 -17.349978)
				)
				(arc
					(start 379.801374 -18.750026)
					(mid 380.350014 -19.298666)
					(end 380.898654 -18.750026)
				)
			)
		)
	)
	(zone
		(layers "In1.Cu" "In3.Cu" "In5.Cu" "In6.Cu" "In8.Cu" "In10.Cu")
		(hatch none 0.5)
		(connect_pads
			(clearance 0)
		)
		(min_thickness 0.25)
		(keepout
			(tracks not_allowed)
			(vias allowed)
			(pads allowed)
			(copperpour not_allowed)
			(footprints allowed)
		)
		(placement
			(enabled no)
			(sheetname "")
		)
		(fill yes
			(thermal_gap 0.5)
			(thermal_bridge_width 0.5)
			(island_removal_mode 0)
		)
		(polygon
			(pts
				(arc
					(start 240.876074 -34.548064)
					(mid 239.89792 -34.873946)
					(end 240.223802 -35.8521)
				)
				(arc
					(start 242.223798 -36.852098)
					(mid 243.201952 -36.526216)
					(end 242.87607 -35.548062)
				)
			)
		)
	)
	(zone
		(layers "In1.Cu" "In3.Cu" "In5.Cu" "In6.Cu" "In8.Cu" "In10.Cu")
		(hatch none 0.5)
		(connect_pads
			(clearance 0)
		)
		(min_thickness 0.25)
		(keepout
			(tracks not_allowed)
			(vias allowed)
			(pads allowed)
			(copperpour not_allowed)
			(footprints allowed)
		)
		(placement
			(enabled no)
			(sheetname "")
		)
		(fill yes
			(thermal_gap 0.5)
			(thermal_bridge_width 0.5)
			(island_removal_mode 0)
		)
		(polygon
			(pts
				(arc
					(start 283.563314 -82.57286)
					(mid 282.622752 -82.88655)
					(end 282.936442 -83.827112)
				)
				(arc
					(start 284.928056 -84.822792)
					(mid 285.874832 -84.517607)
					(end 285.56331 -83.572858)
				)
			)
		)
	)
	(zone
		(layers "In1.Cu" "In3.Cu" "In5.Cu" "In6.Cu" "In8.Cu" "In10.Cu")
		(hatch none 0.5)
		(connect_pads
			(clearance 0)
		)
		(min_thickness 0.25)
		(keepout
			(tracks not_allowed)
			(vias allowed)
			(pads allowed)
			(copperpour not_allowed)
			(footprints allowed)
		)
		(placement
			(enabled no)
			(sheetname "")
		)
		(fill yes
			(thermal_gap 0.5)
			(thermal_bridge_width 0.5)
			(island_removal_mode 0)
		)
		(polygon
			(pts
				(arc
					(start 285.436564 -355.353874)
					(mid 284.885384 -355.905054)
					(end 285.436564 -356.456234)
				)
				(arc
					(start 286.836612 -356.456234)
					(mid 287.387792 -355.905054)
					(end 286.836612 -355.353874)
				)
				(xy 285.436818 -355.353874)
			)
		)
	)
	(zone
		(layers "In1.Cu" "In3.Cu" "In5.Cu" "In6.Cu" "In8.Cu" "In10.Cu")
		(hatch none 0.5)
		(connect_pads
			(clearance 0)
		)
		(min_thickness 0.25)
		(keepout
			(tracks not_allowed)
			(vias allowed)
			(pads allowed)
			(copperpour not_allowed)
			(footprints allowed)
		)
		(placement
			(enabled no)
			(sheetname "")
		)
		(fill yes
			(thermal_gap 0.5)
			(thermal_bridge_width 0.5)
			(island_removal_mode 0)
		)
		(polygon
			(pts
				(arc
					(start 238.374936 -57.84977)
					(mid 238.699802 -56.875172)
					(end 237.725204 -56.550306)
				)
				(xy 237.723934 -56.54802) (xy 235.724192 -57.548018) (xy 235.724192 -57.548272)
				(arc
					(start 235.725208 -57.550304)
					(mid 235.400342 -58.524902)
					(end 236.37494 -58.849768)
				)
				(xy 236.37621 -58.852054) (xy 238.376206 -57.852056)
			)
		)
	)
	(zone
		(layers "In1.Cu" "In3.Cu" "In5.Cu" "In6.Cu" "In8.Cu" "In10.Cu")
		(hatch none 0.5)
		(connect_pads
			(clearance 0)
		)
		(min_thickness 0.25)
		(keepout
			(tracks not_allowed)
			(vias allowed)
			(pads allowed)
			(copperpour not_allowed)
			(footprints allowed)
		)
		(placement
			(enabled no)
			(sheetname "")
		)
		(fill yes
			(thermal_gap 0.5)
			(thermal_bridge_width 0.5)
			(island_removal_mode 0)
		)
		(polygon
			(pts
				(xy 279.07615 -18.852134) (xy 281.076146 -17.852136)
				(arc
					(start 281.074876 -17.84985)
					(mid 281.399742 -16.875252)
					(end 280.425144 -16.550386)
				)
				(xy 280.423874 -16.5481) (xy 278.424132 -17.548098) (xy 278.424132 -17.548352)
				(arc
					(start 278.425148 -17.550384)
					(mid 278.100282 -18.524982)
					(end 279.07488 -18.849848)
				)
			)
		)
	)
	(zone
		(layers "In1.Cu" "In3.Cu" "In5.Cu" "In6.Cu" "In8.Cu" "In10.Cu")
		(hatch none 0.5)
		(connect_pads
			(clearance 0)
		)
		(min_thickness 0.25)
		(keepout
			(tracks not_allowed)
			(vias allowed)
			(pads allowed)
			(copperpour not_allowed)
			(footprints allowed)
		)
		(placement
			(enabled no)
			(sheetname "")
		)
		(fill yes
			(thermal_gap 0.5)
			(thermal_bridge_width 0.5)
			(island_removal_mode 0)
		)
		(polygon
			(pts
				(arc
					(start 242.236498 -60.827158)
					(mid 243.17706 -60.513468)
					(end 242.86337 -59.572906)
				)
				(arc
					(start 240.871756 -58.577226)
					(mid 239.92498 -58.882411)
					(end 240.236502 -59.82716)
				)
			)
		)
	)
	(zone
		(layers "In1.Cu" "In3.Cu" "In5.Cu" "In6.Cu" "In8.Cu" "In10.Cu")
		(hatch none 0.5)
		(connect_pads
			(clearance 0)
		)
		(min_thickness 0.25)
		(keepout
			(tracks not_allowed)
			(vias allowed)
			(pads allowed)
			(copperpour not_allowed)
			(footprints allowed)
		)
		(placement
			(enabled no)
			(sheetname "")
		)
		(fill yes
			(thermal_gap 0.5)
			(thermal_bridge_width 0.5)
			(island_removal_mode 0)
		)
		(polygon
			(pts
				(arc
					(start 278.23668 -301.356522)
					(mid 277.68804 -301.905162)
					(end 278.23668 -302.453802)
				)
				(arc
					(start 279.636728 -302.453802)
					(mid 280.185368 -301.905162)
					(end 279.636728 -301.356522)
				)
				(xy 278.236934 -301.356522)
			)
		)
	)
	(zone
		(layers "In1.Cu" "In3.Cu" "In5.Cu" "In6.Cu" "In8.Cu" "In10.Cu")
		(hatch none 0.5)
		(connect_pads
			(clearance 0)
		)
		(min_thickness 0.25)
		(keepout
			(tracks not_allowed)
			(vias allowed)
			(pads allowed)
			(copperpour not_allowed)
			(footprints allowed)
		)
		(placement
			(enabled no)
			(sheetname "")
		)
		(fill yes
			(thermal_gap 0.5)
			(thermal_bridge_width 0.5)
			(island_removal_mode 0)
		)
		(polygon
			(pts
				(arc
					(start 279.236678 -306.756562)
					(mid 278.688038 -307.305202)
					(end 279.236678 -307.853842)
				)
				(arc
					(start 280.636726 -307.853842)
					(mid 281.185366 -307.305202)
					(end 280.636726 -306.756562)
				)
				(xy 279.236932 -306.756562)
			)
		)
	)
	(zone
		(layers "In1.Cu" "In3.Cu" "In5.Cu" "In6.Cu" "In8.Cu" "In10.Cu")
		(hatch none 0.5)
		(connect_pads
			(clearance 0)
		)
		(min_thickness 0.25)
		(keepout
			(tracks not_allowed)
			(vias allowed)
			(pads allowed)
			(copperpour not_allowed)
			(footprints allowed)
		)
		(placement
			(enabled no)
			(sheetname "")
		)
		(fill yes
			(thermal_gap 0.5)
			(thermal_bridge_width 0.5)
			(island_removal_mode 0)
		)
		(polygon
			(pts
				(arc
					(start 283.563314 -46.572932)
					(mid 282.622752 -46.886622)
					(end 282.936442 -47.827184)
				)
				(arc
					(start 284.928056 -48.822864)
					(mid 285.874832 -48.517679)
					(end 285.56331 -47.57293)
				)
			)
		)
	)
	(zone
		(layers "In1.Cu" "In3.Cu" "In5.Cu" "In6.Cu" "In8.Cu" "In10.Cu")
		(hatch none 0.5)
		(connect_pads
			(clearance 0)
		)
		(min_thickness 0.25)
		(keepout
			(tracks not_allowed)
			(vias allowed)
			(pads allowed)
			(copperpour not_allowed)
			(footprints allowed)
		)
		(placement
			(enabled no)
			(sheetname "")
		)
		(fill yes
			(thermal_gap 0.5)
			(thermal_bridge_width 0.5)
			(island_removal_mode 0)
		)
		(polygon
			(pts
				(arc
					(start 368.29873 -18.350484)
					(mid 367.750217 -17.80159)
					(end 367.20145 -18.35023)
				)
				(arc
					(start 367.20145 -19.750024)
					(mid 367.75009 -20.298664)
					(end 368.29873 -19.750024)
				)
			)
		)
	)
	(zone
		(layers "In1.Cu" "In3.Cu" "In5.Cu" "In6.Cu" "In8.Cu" "In10.Cu")
		(hatch none 0.5)
		(connect_pads
			(clearance 0)
		)
		(min_thickness 0.25)
		(keepout
			(tracks not_allowed)
			(vias allowed)
			(pads allowed)
			(copperpour not_allowed)
			(footprints allowed)
		)
		(placement
			(enabled no)
			(sheetname "")
		)
		(fill yes
			(thermal_gap 0.5)
			(thermal_bridge_width 0.5)
			(island_removal_mode 0)
		)
		(polygon
			(pts
				(arc
					(start 131.298696 -20.950428)
					(mid 130.750183 -20.401534)
					(end 130.201416 -20.950174)
				)
				(arc
					(start 130.201416 -22.350222)
					(mid 130.750056 -22.898862)
					(end 131.298696 -22.350222)
				)
			)
		)
	)
	(zone
		(layers "In1.Cu" "In3.Cu" "In5.Cu" "In6.Cu" "In8.Cu" "In10.Cu")
		(hatch none 0.5)
		(connect_pads
			(clearance 0)
		)
		(min_thickness 0.25)
		(keepout
			(tracks not_allowed)
			(vias allowed)
			(pads allowed)
			(copperpour not_allowed)
			(footprints allowed)
		)
		(placement
			(enabled no)
			(sheetname "")
		)
		(fill yes
			(thermal_gap 0.5)
			(thermal_bridge_width 0.5)
			(island_removal_mode 0)
		)
		(polygon
			(pts
				(arc
					(start 223.148652 -406.000204)
					(mid 222.600139 -405.45131)
					(end 222.051372 -405.99995)
				)
				(arc
					(start 222.051372 -407.399998)
					(mid 222.600012 -407.948638)
					(end 223.148652 -407.399998)
				)
			)
		)
	)
	(zone
		(layers "In1.Cu" "In3.Cu" "In5.Cu" "In6.Cu" "In8.Cu" "In10.Cu")
		(hatch none 0.5)
		(connect_pads
			(clearance 0)
		)
		(min_thickness 0.25)
		(keepout
			(tracks not_allowed)
			(vias allowed)
			(pads allowed)
			(copperpour not_allowed)
			(footprints allowed)
		)
		(placement
			(enabled no)
			(sheetname "")
		)
		(fill yes
			(thermal_gap 0.5)
			(thermal_bridge_width 0.5)
			(island_removal_mode 0)
		)
		(polygon
			(pts
				(arc
					(start 283.563314 -154.87269)
					(mid 282.622752 -155.18638)
					(end 282.936442 -156.126942)
				)
				(arc
					(start 284.928056 -157.122622)
					(mid 285.874832 -156.817437)
					(end 285.56331 -155.872688)
				)
			)
		)
	)
	(zone
		(layers "In1.Cu" "In3.Cu" "In5.Cu" "In6.Cu" "In8.Cu" "In10.Cu")
		(hatch none 0.5)
		(connect_pads
			(clearance 0)
		)
		(min_thickness 0.25)
		(keepout
			(tracks not_allowed)
			(vias allowed)
			(pads allowed)
			(copperpour not_allowed)
			(footprints allowed)
		)
		(placement
			(enabled no)
			(sheetname "")
		)
		(fill yes
			(thermal_gap 0.5)
			(thermal_bridge_width 0.5)
			(island_removal_mode 0)
		)
		(polygon
			(pts
				(arc
					(start 377.298712 -17.350232)
					(mid 376.750199 -16.801338)
					(end 376.201432 -17.349978)
				)
				(arc
					(start 376.201432 -18.750026)
					(mid 376.750072 -19.298666)
					(end 377.298712 -18.750026)
				)
			)
		)
	)
	(zone
		(layers "In1.Cu" "In3.Cu" "In5.Cu" "In6.Cu" "In8.Cu" "In10.Cu")
		(hatch none 0.5)
		(connect_pads
			(clearance 0)
		)
		(min_thickness 0.25)
		(keepout
			(tracks not_allowed)
			(vias allowed)
			(pads allowed)
			(copperpour not_allowed)
			(footprints allowed)
		)
		(placement
			(enabled no)
			(sheetname "")
		)
		(fill yes
			(thermal_gap 0.5)
			(thermal_bridge_width 0.5)
			(island_removal_mode 0)
		)
		(polygon
			(pts
				(xy 279.07615 -74.852022) (xy 281.076146 -73.852024)
				(arc
					(start 281.074876 -73.849738)
					(mid 281.399742 -72.87514)
					(end 280.425144 -72.550274)
				)
				(xy 280.423874 -72.547988) (xy 278.424132 -73.547986) (xy 278.424132 -73.54824)
				(arc
					(start 278.425148 -73.550272)
					(mid 278.100282 -74.52487)
					(end 279.07488 -74.849736)
				)
			)
		)
	)
	(zone
		(layers "In1.Cu" "In3.Cu" "In5.Cu" "In6.Cu" "In8.Cu" "In10.Cu")
		(hatch none 0.5)
		(connect_pads
			(clearance 0)
		)
		(min_thickness 0.25)
		(keepout
			(tracks not_allowed)
			(vias allowed)
			(pads allowed)
			(copperpour not_allowed)
			(footprints allowed)
		)
		(placement
			(enabled no)
			(sheetname "")
		)
		(fill yes
			(thermal_gap 0.5)
			(thermal_bridge_width 0.5)
			(island_removal_mode 0)
		)
		(polygon
			(pts
				(arc
					(start 286.436562 -349.954088)
					(mid 285.885382 -350.505268)
					(end 286.436562 -351.056448)
				)
				(arc
					(start 287.83661 -351.056448)
					(mid 288.38779 -350.505268)
					(end 287.83661 -349.954088)
				)
				(xy 286.436816 -349.954088)
			)
		)
	)
	(zone
		(layers "In1.Cu" "In3.Cu" "In5.Cu" "In6.Cu" "In8.Cu" "In10.Cu")
		(hatch none 0.5)
		(connect_pads
			(clearance 0)
		)
		(min_thickness 0.25)
		(keepout
			(tracks not_allowed)
			(vias allowed)
			(pads allowed)
			(copperpour not_allowed)
			(footprints allowed)
		)
		(placement
			(enabled no)
			(sheetname "")
		)
		(fill yes
			(thermal_gap 0.5)
			(thermal_bridge_width 0.5)
			(island_removal_mode 0)
		)
		(polygon
			(pts
				(arc
					(start 95.989902 -162.178746)
					(mid 95.609029 -161.797492)
					(end 95.227902 -162.178492)
				)
				(arc
					(start 95.227902 -163.321492)
					(mid 95.608902 -163.702492)
					(end 95.989902 -163.321492)
				)
			)
		)
	)
	(zone
		(layers "In1.Cu" "In3.Cu" "In5.Cu" "In6.Cu" "In8.Cu" "In10.Cu")
		(hatch none 0.5)
		(connect_pads
			(clearance 0)
		)
		(min_thickness 0.25)
		(keepout
			(tracks not_allowed)
			(vias allowed)
			(pads allowed)
			(copperpour not_allowed)
			(footprints allowed)
		)
		(placement
			(enabled no)
			(sheetname "")
		)
		(fill yes
			(thermal_gap 0.5)
			(thermal_bridge_width 0.5)
			(island_removal_mode 0)
		)
		(polygon
			(pts
				(arc
					(start 281.074876 -174.149512)
					(mid 281.399742 -173.174914)
					(end 280.425144 -172.850048)
				)
				(xy 280.423874 -172.847762) (xy 278.424132 -173.84776) (xy 278.424132 -173.848014)
				(arc
					(start 278.425148 -173.850046)
					(mid 278.100282 -174.824644)
					(end 279.07488 -175.14951)
				)
				(xy 279.07615 -175.151796) (xy 281.076146 -174.151798)
			)
		)
	)
	(zone
		(layers "In1.Cu" "In3.Cu" "In5.Cu" "In6.Cu" "In8.Cu" "In10.Cu")
		(hatch none 0.5)
		(connect_pads
			(clearance 0)
		)
		(min_thickness 0.25)
		(keepout
			(tracks not_allowed)
			(vias allowed)
			(pads allowed)
			(copperpour not_allowed)
			(footprints allowed)
		)
		(placement
			(enabled no)
			(sheetname "")
		)
		(fill yes
			(thermal_gap 0.5)
			(thermal_bridge_width 0.5)
			(island_removal_mode 0)
		)
		(polygon
			(pts
				(arc
					(start 122.298714 -21.950426)
					(mid 121.750201 -21.401532)
					(end 121.201434 -21.950172)
				)
				(arc
					(start 121.201434 -23.35022)
					(mid 121.750074 -23.89886)
					(end 122.298714 -23.35022)
				)
			)
		)
	)
	(zone
		(layers "In1.Cu" "In3.Cu" "In5.Cu" "In6.Cu" "In8.Cu" "In10.Cu")
		(hatch none 0.5)
		(connect_pads
			(clearance 0)
		)
		(min_thickness 0.25)
		(keepout
			(tracks not_allowed)
			(vias allowed)
			(pads allowed)
			(copperpour not_allowed)
			(footprints allowed)
		)
		(placement
			(enabled no)
			(sheetname "")
		)
		(fill yes
			(thermal_gap 0.5)
			(thermal_bridge_width 0.5)
			(island_removal_mode 0)
		)
		(polygon
			(pts
				(arc
					(start 238.374936 -170.14952)
					(mid 238.699802 -169.174922)
					(end 237.725204 -168.850056)
				)
				(xy 237.723934 -168.84777) (xy 235.724192 -169.847768) (xy 235.724192 -169.848022)
				(arc
					(start 235.725208 -169.850054)
					(mid 235.400342 -170.824652)
					(end 236.37494 -171.149518)
				)
				(xy 236.37621 -171.151804) (xy 238.376206 -170.151806)
			)
		)
	)
	(zone
		(layers "In1.Cu" "In3.Cu" "In5.Cu" "In6.Cu" "In8.Cu" "In10.Cu")
		(hatch none 0.5)
		(connect_pads
			(clearance 0)
		)
		(min_thickness 0.25)
		(keepout
			(tracks not_allowed)
			(vias allowed)
			(pads allowed)
			(copperpour not_allowed)
			(footprints allowed)
		)
		(placement
			(enabled no)
			(sheetname "")
		)
		(fill yes
			(thermal_gap 0.5)
			(thermal_bridge_width 0.5)
			(island_removal_mode 0)
		)
		(polygon
			(pts
				(arc
					(start 279.236678 -252.351032)
					(mid 278.685498 -252.902212)
					(end 279.236678 -253.453392)
				)
				(arc
					(start 280.636726 -253.453392)
					(mid 281.187906 -252.902212)
					(end 280.636726 -252.351032)
				)
				(xy 279.236932 -252.351032)
			)
		)
	)
	(zone
		(layers "In1.Cu" "In3.Cu" "In5.Cu" "In6.Cu" "In8.Cu" "In10.Cu")
		(hatch none 0.5)
		(connect_pads
			(clearance 0)
		)
		(min_thickness 0.25)
		(keepout
			(tracks not_allowed)
			(vias allowed)
			(pads allowed)
			(copperpour not_allowed)
			(footprints allowed)
		)
		(placement
			(enabled no)
			(sheetname "")
		)
		(fill yes
			(thermal_gap 0.5)
			(thermal_bridge_width 0.5)
			(island_removal_mode 0)
		)
		(polygon
			(pts
				(arc
					(start 242.236498 -177.1269)
					(mid 243.17706 -176.81321)
					(end 242.86337 -175.872648)
				)
				(arc
					(start 240.871756 -174.876968)
					(mid 239.92498 -175.182153)
					(end 240.236502 -176.126902)
				)
			)
		)
	)
	(zone
		(layers "In1.Cu" "In3.Cu" "In5.Cu" "In6.Cu" "In8.Cu" "In10.Cu")
		(hatch none 0.5)
		(connect_pads
			(clearance 0)
		)
		(min_thickness 0.25)
		(keepout
			(tracks not_allowed)
			(vias allowed)
			(pads allowed)
			(copperpour not_allowed)
			(footprints allowed)
		)
		(placement
			(enabled no)
			(sheetname "")
		)
		(fill yes
			(thermal_gap 0.5)
			(thermal_bridge_width 0.5)
			(island_removal_mode 0)
		)
		(polygon
			(pts
				(arc
					(start 451.3199 -47.178722)
					(mid 450.939027 -46.797468)
					(end 450.5579 -47.178468)
				)
				(arc
					(start 450.5579 -48.321468)
					(mid 450.9389 -48.702468)
					(end 451.3199 -48.321468)
				)
			)
		)
	)
	(zone
		(layers "In1.Cu" "In3.Cu" "In5.Cu" "In6.Cu" "In8.Cu" "In10.Cu")
		(hatch none 0.5)
		(connect_pads
			(clearance 0)
		)
		(min_thickness 0.25)
		(keepout
			(tracks not_allowed)
			(vias allowed)
			(pads allowed)
			(copperpour not_allowed)
			(footprints allowed)
		)
		(placement
			(enabled no)
			(sheetname "")
		)
		(fill yes
			(thermal_gap 0.5)
			(thermal_bridge_width 0.5)
			(island_removal_mode 0)
		)
		(polygon
			(pts
				(arc
					(start 271.970754 -355.524054)
					(mid 271.5895 -355.904927)
					(end 271.9705 -356.286054)
				)
				(arc
					(start 273.1135 -356.286054)
					(mid 273.4945 -355.905054)
					(end 273.1135 -355.524054)
				)
			)
		)
	)
	(zone
		(layers "In1.Cu" "In3.Cu" "In5.Cu" "In6.Cu" "In8.Cu" "In10.Cu")
		(hatch none 0.5)
		(connect_pads
			(clearance 0)
		)
		(min_thickness 0.25)
		(keepout
			(tracks not_allowed)
			(vias allowed)
			(pads allowed)
			(copperpour not_allowed)
			(footprints allowed)
		)
		(placement
			(enabled no)
			(sheetname "")
		)
		(fill yes
			(thermal_gap 0.5)
			(thermal_bridge_width 0.5)
			(island_removal_mode 0)
		)
		(polygon
			(pts
				(arc
					(start 283.563314 -66.572892)
					(mid 282.622752 -66.886582)
					(end 282.936442 -67.827144)
				)
				(arc
					(start 284.928056 -68.822824)
					(mid 285.874832 -68.517639)
					(end 285.56331 -67.57289)
				)
			)
		)
	)
	(zone
		(layers "In1.Cu" "In3.Cu" "In5.Cu" "In6.Cu" "In8.Cu" "In10.Cu")
		(hatch none 0.5)
		(connect_pads
			(clearance 0)
		)
		(min_thickness 0.25)
		(keepout
			(tracks not_allowed)
			(vias allowed)
			(pads allowed)
			(copperpour not_allowed)
			(footprints allowed)
		)
		(placement
			(enabled no)
			(sheetname "")
		)
		(fill yes
			(thermal_gap 0.5)
			(thermal_bridge_width 0.5)
			(island_removal_mode 0)
		)
		(polygon
			(pts
				(arc
					(start 388.21995 -47.178722)
					(mid 387.839077 -46.797468)
					(end 387.45795 -47.178468)
				)
				(arc
					(start 387.45795 -48.321468)
					(mid 387.83895 -48.702468)
					(end 388.21995 -48.321468)
				)
			)
		)
	)
	(zone
		(layers "In1.Cu" "In3.Cu" "In5.Cu" "In6.Cu" "In8.Cu" "In10.Cu")
		(hatch none 0.5)
		(connect_pads
			(clearance 0)
		)
		(min_thickness 0.25)
		(keepout
			(tracks not_allowed)
			(vias allowed)
			(pads allowed)
			(copperpour not_allowed)
			(footprints allowed)
		)
		(placement
			(enabled no)
			(sheetname "")
		)
		(fill yes
			(thermal_gap 0.5)
			(thermal_bridge_width 0.5)
			(island_removal_mode 0)
		)
		(polygon
			(pts
				(arc
					(start 356.670102 -277.17877)
					(mid 356.289229 -276.797516)
					(end 355.908102 -277.178516)
				)
				(arc
					(start 355.908102 -278.321516)
					(mid 356.289102 -278.702516)
					(end 356.670102 -278.321516)
				)
			)
		)
	)
	(zone
		(layers "In1.Cu" "In3.Cu" "In5.Cu" "In6.Cu" "In8.Cu" "In10.Cu")
		(hatch none 0.5)
		(connect_pads
			(clearance 0)
		)
		(min_thickness 0.25)
		(keepout
			(tracks not_allowed)
			(vias allowed)
			(pads allowed)
			(copperpour not_allowed)
			(footprints allowed)
		)
		(placement
			(enabled no)
			(sheetname "")
		)
		(fill yes
			(thermal_gap 0.5)
			(thermal_bridge_width 0.5)
			(island_removal_mode 0)
		)
		(polygon
			(pts
				(arc
					(start 221.348808 -414.20034)
					(mid 220.800295 -413.651446)
					(end 220.251528 -414.200086)
				)
				(arc
					(start 220.251528 -415.600134)
					(mid 220.800168 -416.148774)
					(end 221.348808 -415.600134)
				)
			)
		)
	)
	(zone
		(layers "In1.Cu" "In3.Cu" "In5.Cu" "In6.Cu" "In8.Cu" "In10.Cu")
		(hatch none 0.5)
		(connect_pads
			(clearance 0)
		)
		(min_thickness 0.25)
		(keepout
			(tracks not_allowed)
			(vias allowed)
			(pads allowed)
			(copperpour not_allowed)
			(footprints allowed)
		)
		(placement
			(enabled no)
			(sheetname "")
		)
		(fill yes
			(thermal_gap 0.5)
			(thermal_bridge_width 0.5)
			(island_removal_mode 0)
		)
		(polygon
			(pts
				(arc
					(start 271.970754 -315.92139)
					(mid 271.58696 -316.304803)
					(end 271.9705 -316.68847)
				)
				(arc
					(start 273.1135 -316.68847)
					(mid 273.49704 -316.30493)
					(end 273.1135 -315.92139)
				)
			)
		)
	)
	(zone
		(layers "In1.Cu" "In3.Cu" "In5.Cu" "In6.Cu" "In8.Cu" "In10.Cu")
		(hatch none 0.5)
		(connect_pads
			(clearance 0)
		)
		(min_thickness 0.25)
		(keepout
			(tracks not_allowed)
			(vias allowed)
			(pads allowed)
			(copperpour not_allowed)
			(footprints allowed)
		)
		(placement
			(enabled no)
			(sheetname "")
		)
		(fill yes
			(thermal_gap 0.5)
			(thermal_bridge_width 0.5)
			(island_removal_mode 0)
		)
		(polygon
			(pts
				(arc
					(start 286.436562 -295.953942)
					(mid 285.885382 -296.505122)
					(end 286.436562 -297.056302)
				)
				(arc
					(start 287.83661 -297.056302)
					(mid 288.38779 -296.505122)
					(end 287.83661 -295.953942)
				)
				(xy 286.436816 -295.953942)
			)
		)
	)
	(zone
		(layers "In1.Cu" "In3.Cu" "In5.Cu" "In6.Cu" "In8.Cu" "In10.Cu")
		(hatch none 0.5)
		(connect_pads
			(clearance 0)
		)
		(min_thickness 0.25)
		(keepout
			(tracks not_allowed)
			(vias allowed)
			(pads allowed)
			(copperpour not_allowed)
			(footprints allowed)
		)
		(placement
			(enabled no)
			(sheetname "")
		)
		(fill yes
			(thermal_gap 0.5)
			(thermal_bridge_width 0.5)
			(island_removal_mode 0)
		)
		(polygon
			(pts
				(arc
					(start 238.374936 -138.149584)
					(mid 238.699802 -137.174986)
					(end 237.725204 -136.85012)
				)
				(xy 237.723934 -136.847834) (xy 235.724192 -137.847832) (xy 235.724192 -137.848086)
				(arc
					(start 235.725208 -137.850118)
					(mid 235.400342 -138.824716)
					(end 236.37494 -139.149582)
				)
				(xy 236.37621 -139.151868) (xy 238.376206 -138.15187)
			)
		)
	)
	(zone
		(layers "In1.Cu" "In3.Cu" "In5.Cu" "In6.Cu" "In8.Cu" "In10.Cu")
		(hatch none 0.5)
		(connect_pads
			(clearance 0)
		)
		(min_thickness 0.25)
		(keepout
			(tracks not_allowed)
			(vias allowed)
			(pads allowed)
			(copperpour not_allowed)
			(footprints allowed)
		)
		(placement
			(enabled no)
			(sheetname "")
		)
		(fill yes
			(thermal_gap 0.5)
			(thermal_bridge_width 0.5)
			(island_removal_mode 0)
		)
		(polygon
			(pts
				(arc
					(start 283.563314 -122.872754)
					(mid 282.622752 -123.186444)
					(end 282.936442 -124.127006)
				)
				(arc
					(start 284.928056 -125.122686)
					(mid 285.874832 -124.817501)
					(end 285.56331 -123.872752)
				)
			)
		)
	)
	(zone
		(layers "In1.Cu" "In3.Cu" "In5.Cu" "In6.Cu" "In8.Cu" "In10.Cu")
		(hatch none 0.5)
		(connect_pads
			(clearance 0)
		)
		(min_thickness 0.25)
		(keepout
			(tracks not_allowed)
			(vias allowed)
			(pads allowed)
			(copperpour not_allowed)
			(footprints allowed)
		)
		(placement
			(enabled no)
			(sheetname "")
		)
		(fill yes
			(thermal_gap 0.5)
			(thermal_bridge_width 0.5)
			(island_removal_mode 0)
		)
		(polygon
			(pts
				(arc
					(start 281.07386 -154.147266)
					(mid 281.397456 -153.17597)
					(end 280.42616 -152.852374)
				)
				(xy 278.426418 -153.852118)
				(arc
					(start 278.426418 -153.852372)
					(mid 278.102619 -154.823516)
					(end 279.073864 -155.147264)
				)
			)
		)
	)
	(zone
		(layers "In1.Cu" "In3.Cu" "In5.Cu" "In6.Cu" "In8.Cu" "In10.Cu")
		(hatch none 0.5)
		(connect_pads
			(clearance 0)
		)
		(min_thickness 0.25)
		(keepout
			(tracks not_allowed)
			(vias allowed)
			(pads allowed)
			(copperpour not_allowed)
			(footprints allowed)
		)
		(placement
			(enabled no)
			(sheetname "")
		)
		(fill yes
			(thermal_gap 0.5)
			(thermal_bridge_width 0.5)
			(island_removal_mode 0)
		)
		(polygon
			(pts
				(arc
					(start 279.236678 -349.956628)
					(mid 278.688038 -350.505268)
					(end 279.236678 -351.053908)
				)
				(arc
					(start 280.636726 -351.053908)
					(mid 281.185366 -350.505268)
					(end 280.636726 -349.956628)
				)
				(xy 279.236932 -349.956628)
			)
		)
	)
	(zone
		(layers "In1.Cu" "In3.Cu" "In5.Cu" "In6.Cu" "In8.Cu" "In10.Cu")
		(hatch none 0.5)
		(connect_pads
			(clearance 0)
		)
		(min_thickness 0.25)
		(keepout
			(tracks not_allowed)
			(vias allowed)
			(pads allowed)
			(copperpour not_allowed)
			(footprints allowed)
		)
		(placement
			(enabled no)
			(sheetname "")
		)
		(fill yes
			(thermal_gap 0.5)
			(thermal_bridge_width 0.5)
			(island_removal_mode 0)
		)
		(polygon
			(pts
				(arc
					(start 389.898636 -21.950426)
					(mid 389.350123 -21.401532)
					(end 388.801356 -21.950172)
				)
				(arc
					(start 388.801356 -23.35022)
					(mid 389.349996 -23.89886)
					(end 389.898636 -23.35022)
				)
			)
		)
	)
	(zone
		(layers "In1.Cu" "In3.Cu" "In5.Cu" "In6.Cu" "In8.Cu" "In10.Cu")
		(hatch none 0.5)
		(connect_pads
			(clearance 0)
		)
		(min_thickness 0.25)
		(keepout
			(tracks not_allowed)
			(vias allowed)
			(pads allowed)
			(copperpour not_allowed)
			(footprints allowed)
		)
		(placement
			(enabled no)
			(sheetname "")
		)
		(fill yes
			(thermal_gap 0.5)
			(thermal_bridge_width 0.5)
			(island_removal_mode 0)
		)
		(polygon
			(pts
				(arc
					(start 278.23668 -250.551188)
					(mid 277.6855 -251.102368)
					(end 278.23668 -251.653548)
				)
				(arc
					(start 279.636728 -251.653548)
					(mid 280.187908 -251.102368)
					(end 279.636728 -250.551188)
				)
				(xy 278.236934 -250.551188)
			)
		)
	)
	(zone
		(layers "In1.Cu" "In3.Cu" "In5.Cu" "In6.Cu" "In8.Cu" "In10.Cu")
		(hatch none 0.5)
		(connect_pads
			(clearance 0)
		)
		(min_thickness 0.25)
		(keepout
			(tracks not_allowed)
			(vias allowed)
			(pads allowed)
			(copperpour not_allowed)
			(footprints allowed)
		)
		(placement
			(enabled no)
			(sheetname "")
		)
		(fill yes
			(thermal_gap 0.5)
			(thermal_bridge_width 0.5)
			(island_removal_mode 0)
		)
		(polygon
			(pts
				(arc
					(start 278.23668 -322.956428)
					(mid 277.68804 -323.505068)
					(end 278.23668 -324.053708)
				)
				(arc
					(start 279.636728 -324.053708)
					(mid 280.185368 -323.505068)
					(end 279.636728 -322.956428)
				)
				(xy 278.236934 -322.956428)
			)
		)
	)
	(zone
		(layers "In1.Cu" "In3.Cu" "In5.Cu" "In6.Cu" "In8.Cu" "In10.Cu")
		(hatch none 0.5)
		(connect_pads
			(clearance 0)
		)
		(min_thickness 0.25)
		(keepout
			(tracks not_allowed)
			(vias allowed)
			(pads allowed)
			(copperpour not_allowed)
			(footprints allowed)
		)
		(placement
			(enabled no)
			(sheetname "")
		)
		(fill yes
			(thermal_gap 0.5)
			(thermal_bridge_width 0.5)
			(island_removal_mode 0)
		)
		(polygon
			(pts
				(arc
					(start 279.236678 -310.356504)
					(mid 278.688038 -310.905144)
					(end 279.236678 -311.453784)
				)
				(arc
					(start 280.636726 -311.453784)
					(mid 281.185366 -310.905144)
					(end 280.636726 -310.356504)
				)
				(xy 279.236932 -310.356504)
			)
		)
	)
	(zone
		(layers "In1.Cu" "In3.Cu" "In5.Cu" "In6.Cu" "In8.Cu" "In10.Cu")
		(hatch none 0.5)
		(connect_pads
			(clearance 0)
		)
		(min_thickness 0.25)
		(keepout
			(tracks not_allowed)
			(vias allowed)
			(pads allowed)
			(copperpour not_allowed)
			(footprints allowed)
		)
		(placement
			(enabled no)
			(sheetname "")
		)
		(fill yes
			(thermal_gap 0.5)
			(thermal_bridge_width 0.5)
			(island_removal_mode 0)
		)
		(polygon
			(pts
				(arc
					(start 362.89869 -17.350232)
					(mid 362.350177 -16.801338)
					(end 361.80141 -17.349978)
				)
				(arc
					(start 361.80141 -18.750026)
					(mid 362.35005 -19.298666)
					(end 362.89869 -18.750026)
				)
			)
		)
	)
	(zone
		(layers "In1.Cu" "In3.Cu" "In5.Cu" "In6.Cu" "In8.Cu" "In10.Cu")
		(hatch none 0.5)
		(connect_pads
			(clearance 0)
		)
		(min_thickness 0.25)
		(keepout
			(tracks not_allowed)
			(vias allowed)
			(pads allowed)
			(copperpour not_allowed)
			(footprints allowed)
		)
		(placement
			(enabled no)
			(sheetname "")
		)
		(fill yes
			(thermal_gap 0.5)
			(thermal_bridge_width 0.5)
			(island_removal_mode 0)
		)
		(polygon
			(pts
				(arc
					(start 238.377222 -162.154108)
					(mid 238.704374 -161.172652)
					(end 237.722918 -160.8455)
				)
				(arc
					(start 235.733844 -161.840164)
					(mid 235.393447 -162.821194)
					(end 236.377226 -163.154106)
				)
			)
		)
	)
	(zone
		(layers "In1.Cu" "In3.Cu" "In5.Cu" "In6.Cu" "In8.Cu" "In10.Cu")
		(hatch none 0.5)
		(connect_pads
			(clearance 0)
		)
		(min_thickness 0.25)
		(keepout
			(tracks not_allowed)
			(vias allowed)
			(pads allowed)
			(copperpour not_allowed)
			(footprints allowed)
		)
		(placement
			(enabled no)
			(sheetname "")
		)
		(fill yes
			(thermal_gap 0.5)
			(thermal_bridge_width 0.5)
			(island_removal_mode 0)
		)
		(polygon
			(pts
				(arc
					(start 368.30127 -29.150056)
					(mid 367.75009 -28.598876)
					(end 367.19891 -29.150056)
				)
				(arc
					(start 367.19891 -30.54985)
					(mid 367.749963 -31.101284)
					(end 368.30127 -30.550104)
				)
			)
		)
	)
	(zone
		(layers "In1.Cu" "In3.Cu" "In5.Cu" "In6.Cu" "In8.Cu" "In10.Cu")
		(hatch none 0.5)
		(connect_pads
			(clearance 0)
		)
		(min_thickness 0.25)
		(keepout
			(tracks not_allowed)
			(vias allowed)
			(pads allowed)
			(copperpour not_allowed)
			(footprints allowed)
		)
		(placement
			(enabled no)
			(sheetname "")
		)
		(fill yes
			(thermal_gap 0.5)
			(thermal_bridge_width 0.5)
			(island_removal_mode 0)
		)
		(polygon
			(pts
				(arc
					(start 142.098522 -20.950428)
					(mid 141.550009 -20.401534)
					(end 141.001242 -20.950174)
				)
				(arc
					(start 141.001242 -22.350222)
					(mid 141.549882 -22.898862)
					(end 142.098522 -22.350222)
				)
			)
		)
	)
	(zone
		(layers "In1.Cu" "In3.Cu" "In5.Cu" "In6.Cu" "In8.Cu" "In10.Cu")
		(hatch none 0.5)
		(connect_pads
			(clearance 0)
		)
		(min_thickness 0.25)
		(keepout
			(tracks not_allowed)
			(vias allowed)
			(pads allowed)
			(copperpour not_allowed)
			(footprints allowed)
		)
		(placement
			(enabled no)
			(sheetname "")
		)
		(fill yes
			(thermal_gap 0.5)
			(thermal_bridge_width 0.5)
			(island_removal_mode 0)
		)
		(polygon
			(pts
				(arc
					(start 284.922468 -36.854384)
					(mid 285.904229 -36.527384)
					(end 285.577026 -35.545776)
				)
				(arc
					(start 283.57703 -34.545778)
					(mid 282.595574 -34.87293)
					(end 282.922726 -35.854386)
				)
			)
		)
	)
	(zone
		(layers "In1.Cu" "In3.Cu" "In5.Cu" "In6.Cu" "In8.Cu" "In10.Cu")
		(hatch none 0.5)
		(connect_pads
			(clearance 0)
		)
		(min_thickness 0.25)
		(keepout
			(tracks not_allowed)
			(vias allowed)
			(pads allowed)
			(copperpour not_allowed)
			(footprints allowed)
		)
		(placement
			(enabled no)
			(sheetname "")
		)
		(fill yes
			(thermal_gap 0.5)
			(thermal_bridge_width 0.5)
			(island_removal_mode 0)
		)
		(polygon
			(pts
				(arc
					(start 419.770052 -47.178722)
					(mid 419.389179 -46.797468)
					(end 419.008052 -47.178468)
				)
				(arc
					(start 419.008052 -48.321468)
					(mid 419.389052 -48.702468)
					(end 419.770052 -48.321468)
				)
			)
		)
	)
	(zone
		(layers "In1.Cu" "In3.Cu" "In5.Cu" "In6.Cu" "In8.Cu" "In10.Cu")
		(hatch none 0.5)
		(connect_pads
			(clearance 0)
		)
		(min_thickness 0.25)
		(keepout
			(tracks not_allowed)
			(vias allowed)
			(pads allowed)
			(copperpour not_allowed)
			(footprints allowed)
		)
		(placement
			(enabled no)
			(sheetname "")
		)
		(fill yes
			(thermal_gap 0.5)
			(thermal_bridge_width 0.5)
			(island_removal_mode 0)
		)
		(polygon
			(pts
				(arc
					(start 279.236678 -299.556424)
					(mid 278.688038 -300.105064)
					(end 279.236678 -300.653704)
				)
				(arc
					(start 280.636726 -300.653704)
					(mid 281.185366 -300.105064)
					(end 280.636726 -299.556424)
				)
				(xy 279.236932 -299.556424)
			)
		)
	)
	(zone
		(layers "In1.Cu" "In3.Cu" "In5.Cu" "In6.Cu" "In8.Cu" "In10.Cu")
		(hatch none 0.5)
		(connect_pads
			(clearance 0)
		)
		(min_thickness 0.25)
		(keepout
			(tracks not_allowed)
			(vias allowed)
			(pads allowed)
			(copperpour not_allowed)
			(footprints allowed)
		)
		(placement
			(enabled no)
			(sheetname "")
		)
		(fill yes
			(thermal_gap 0.5)
			(thermal_bridge_width 0.5)
			(island_removal_mode 0)
		)
		(polygon
			(pts
				(arc
					(start 238.374936 -174.149512)
					(mid 238.699802 -173.174914)
					(end 237.725204 -172.850048)
				)
				(xy 237.723934 -172.847762) (xy 235.724192 -173.84776) (xy 235.724192 -173.848014)
				(arc
					(start 235.725208 -173.850046)
					(mid 235.400342 -174.824644)
					(end 236.37494 -175.14951)
				)
				(xy 236.37621 -175.151796) (xy 238.376206 -174.151798)
			)
		)
	)
	(zone
		(layers "In1.Cu" "In3.Cu" "In5.Cu" "In6.Cu" "In8.Cu" "In10.Cu")
		(hatch none 0.5)
		(connect_pads
			(clearance 0)
		)
		(min_thickness 0.25)
		(keepout
			(tracks not_allowed)
			(vias allowed)
			(pads allowed)
			(copperpour not_allowed)
			(footprints allowed)
		)
		(placement
			(enabled no)
			(sheetname "")
		)
		(fill yes
			(thermal_gap 0.5)
			(thermal_bridge_width 0.5)
			(island_removal_mode 0)
		)
		(polygon
			(pts
				(arc
					(start 271.970754 -351.924112)
					(mid 271.5895 -352.304985)
					(end 271.9705 -352.686112)
				)
				(arc
					(start 273.1135 -352.686112)
					(mid 273.4945 -352.305112)
					(end 273.1135 -351.924112)
				)
			)
		)
	)
	(zone
		(layers "In1.Cu" "In3.Cu" "In5.Cu" "In6.Cu" "In8.Cu" "In10.Cu")
		(hatch none 0.5)
		(connect_pads
			(clearance 0)
		)
		(min_thickness 0.25)
		(keepout
			(tracks not_allowed)
			(vias allowed)
			(pads allowed)
			(copperpour not_allowed)
			(footprints allowed)
		)
		(placement
			(enabled no)
			(sheetname "")
		)
		(fill yes
			(thermal_gap 0.5)
			(thermal_bridge_width 0.5)
			(island_removal_mode 0)
		)
		(polygon
			(pts
				(arc
					(start 419.770052 -277.17877)
					(mid 419.389179 -276.797516)
					(end 419.008052 -277.178516)
				)
				(arc
					(start 419.008052 -278.321516)
					(mid 419.389052 -278.702516)
					(end 419.770052 -278.321516)
				)
			)
		)
	)
	(zone
		(layers "In1.Cu" "In3.Cu" "In5.Cu" "In6.Cu" "In8.Cu" "In10.Cu")
		(hatch none 0.5)
		(connect_pads
			(clearance 0)
		)
		(min_thickness 0.25)
		(keepout
			(tracks not_allowed)
			(vias allowed)
			(pads allowed)
			(copperpour not_allowed)
			(footprints allowed)
		)
		(placement
			(enabled no)
			(sheetname "")
		)
		(fill yes
			(thermal_gap 0.5)
			(thermal_bridge_width 0.5)
			(island_removal_mode 0)
		)
		(polygon
			(pts
				(arc
					(start 238.377222 -114.154204)
					(mid 238.704374 -113.172748)
					(end 237.722918 -112.845596)
				)
				(arc
					(start 235.733844 -113.84026)
					(mid 235.393447 -114.82129)
					(end 236.377226 -115.154202)
				)
			)
		)
	)
	(zone
		(layers "In1.Cu" "In3.Cu" "In5.Cu" "In6.Cu" "In8.Cu" "In10.Cu")
		(hatch none 0.5)
		(connect_pads
			(clearance 0)
		)
		(min_thickness 0.25)
		(keepout
			(tracks not_allowed)
			(vias allowed)
			(pads allowed)
			(copperpour not_allowed)
			(footprints allowed)
		)
		(placement
			(enabled no)
			(sheetname "")
		)
		(fill yes
			(thermal_gap 0.5)
			(thermal_bridge_width 0.5)
			(island_removal_mode 0)
		)
		(polygon
			(pts
				(arc
					(start 136.698736 -29.15031)
					(mid 136.150223 -28.601416)
					(end 135.601456 -29.150056)
				)
				(arc
					(start 135.601456 -30.550104)
					(mid 136.150096 -31.098744)
					(end 136.698736 -30.550104)
				)
			)
		)
	)
	(zone
		(layers "In1.Cu" "In3.Cu" "In5.Cu" "In6.Cu" "In8.Cu" "In10.Cu")
		(hatch none 0.5)
		(connect_pads
			(clearance 0)
		)
		(min_thickness 0.25)
		(keepout
			(tracks not_allowed)
			(vias allowed)
			(pads allowed)
			(copperpour not_allowed)
			(footprints allowed)
		)
		(placement
			(enabled no)
			(sheetname "")
		)
		(fill yes
			(thermal_gap 0.5)
			(thermal_bridge_width 0.5)
			(island_removal_mode 0)
		)
		(polygon
			(pts
				(arc
					(start 238.377222 -118.154196)
					(mid 238.704374 -117.17274)
					(end 237.722918 -116.845588)
				)
				(arc
					(start 235.733844 -117.840252)
					(mid 235.393447 -118.821282)
					(end 236.377226 -119.154194)
				)
			)
		)
	)
	(zone
		(layers "In1.Cu" "In3.Cu" "In5.Cu" "In6.Cu" "In8.Cu" "In10.Cu")
		(hatch none 0.5)
		(connect_pads
			(clearance 0)
		)
		(min_thickness 0.25)
		(keepout
			(tracks not_allowed)
			(vias allowed)
			(pads allowed)
			(copperpour not_allowed)
			(footprints allowed)
		)
		(placement
			(enabled no)
			(sheetname "")
		)
		(fill yes
			(thermal_gap 0.5)
			(thermal_bridge_width 0.5)
			(island_removal_mode 0)
		)
		(polygon
			(pts
				(arc
					(start 383.47015 -273.368516)
					(mid 383.08915 -272.987516)
					(end 382.70815 -273.368516)
				)
				(arc
					(start 382.70815 -274.511262)
					(mid 383.089023 -274.892516)
					(end 383.47015 -274.511516)
				)
			)
		)
	)
	(zone
		(layers "In1.Cu" "In3.Cu" "In5.Cu" "In6.Cu" "In8.Cu" "In10.Cu")
		(hatch none 0.5)
		(connect_pads
			(clearance 0)
		)
		(min_thickness 0.25)
		(keepout
			(tracks not_allowed)
			(vias allowed)
			(pads allowed)
			(copperpour not_allowed)
			(footprints allowed)
		)
		(placement
			(enabled no)
			(sheetname "")
		)
		(fill yes
			(thermal_gap 0.5)
			(thermal_bridge_width 0.5)
			(island_removal_mode 0)
		)
		(polygon
			(pts
				(arc
					(start 382.698752 -21.950426)
					(mid 382.150239 -21.401532)
					(end 381.601472 -21.950172)
				)
				(arc
					(start 381.601472 -23.35022)
					(mid 382.150112 -23.89886)
					(end 382.698752 -23.35022)
				)
			)
		)
	)
	(zone
		(layers "In1.Cu" "In3.Cu" "In5.Cu" "In6.Cu" "In8.Cu" "In10.Cu")
		(hatch none 0.5)
		(connect_pads
			(clearance 0)
		)
		(min_thickness 0.25)
		(keepout
			(tracks not_allowed)
			(vias allowed)
			(pads allowed)
			(copperpour not_allowed)
			(footprints allowed)
		)
		(placement
			(enabled no)
			(sheetname "")
		)
		(fill yes
			(thermal_gap 0.5)
			(thermal_bridge_width 0.5)
			(island_removal_mode 0)
		)
		(polygon
			(pts
				(arc
					(start 283.563314 -38.572948)
					(mid 282.622752 -38.886638)
					(end 282.936442 -39.8272)
				)
				(arc
					(start 284.928056 -40.82288)
					(mid 285.874832 -40.517695)
					(end 285.56331 -39.572946)
				)
			)
		)
	)
	(zone
		(layers "In1.Cu" "In3.Cu" "In5.Cu" "In6.Cu" "In8.Cu" "In10.Cu")
		(hatch none 0.5)
		(connect_pads
			(clearance 0)
		)
		(min_thickness 0.25)
		(keepout
			(tracks not_allowed)
			(vias allowed)
			(pads allowed)
			(copperpour not_allowed)
			(footprints allowed)
		)
		(placement
			(enabled no)
			(sheetname "")
		)
		(fill yes
			(thermal_gap 0.5)
			(thermal_bridge_width 0.5)
			(island_removal_mode 0)
		)
		(polygon
			(pts
				(arc
					(start 281.07386 -150.147274)
					(mid 281.397456 -149.175978)
					(end 280.42616 -148.852382)
				)
				(xy 278.426418 -149.852126)
				(arc
					(start 278.426418 -149.85238)
					(mid 278.102619 -150.823524)
					(end 279.073864 -151.147272)
				)
			)
		)
	)
	(zone
		(layers "In1.Cu" "In3.Cu" "In5.Cu" "In6.Cu" "In8.Cu" "In10.Cu")
		(hatch none 0.5)
		(connect_pads
			(clearance 0)
		)
		(min_thickness 0.25)
		(keepout
			(tracks not_allowed)
			(vias allowed)
			(pads allowed)
			(copperpour not_allowed)
			(footprints allowed)
		)
		(placement
			(enabled no)
			(sheetname "")
		)
		(fill yes
			(thermal_gap 0.5)
			(thermal_bridge_width 0.5)
			(island_removal_mode 0)
		)
		(polygon
			(pts
				(arc
					(start 286.436562 -317.556388)
					(mid 285.887922 -318.105028)
					(end 286.436562 -318.653668)
				)
				(arc
					(start 287.83661 -318.653668)
					(mid 288.38525 -318.105028)
					(end 287.83661 -317.556388)
				)
				(xy 286.436816 -317.556388)
			)
		)
	)
	(zone
		(layers "In1.Cu" "In3.Cu" "In5.Cu" "In6.Cu" "In8.Cu" "In10.Cu")
		(hatch none 0.5)
		(connect_pads
			(clearance 0)
		)
		(min_thickness 0.25)
		(keepout
			(tracks not_allowed)
			(vias allowed)
			(pads allowed)
			(copperpour not_allowed)
			(footprints allowed)
		)
		(placement
			(enabled no)
			(sheetname "")
		)
		(fill yes
			(thermal_gap 0.5)
			(thermal_bridge_width 0.5)
			(island_removal_mode 0)
		)
		(polygon
			(pts
				(arc
					(start 286.436562 -353.55403)
					(mid 285.885382 -354.10521)
					(end 286.436562 -354.65639)
				)
				(arc
					(start 287.83661 -354.65639)
					(mid 288.38779 -354.10521)
					(end 287.83661 -353.55403)
				)
				(xy 286.436816 -353.55403)
			)
		)
	)
	(zone
		(layers "In1.Cu" "In3.Cu" "In5.Cu" "In6.Cu" "In8.Cu" "In10.Cu")
		(hatch none 0.5)
		(connect_pads
			(clearance 0)
		)
		(min_thickness 0.25)
		(keepout
			(tracks not_allowed)
			(vias allowed)
			(pads allowed)
			(copperpour not_allowed)
			(footprints allowed)
		)
		(placement
			(enabled no)
			(sheetname "")
		)
		(fill yes
			(thermal_gap 0.5)
			(thermal_bridge_width 0.5)
			(island_removal_mode 0)
		)
		(polygon
			(pts
				(arc
					(start 122.301254 -29.150056)
					(mid 121.750074 -28.598876)
					(end 121.198894 -29.150056)
				)
				(arc
					(start 121.198894 -30.54985)
					(mid 121.749947 -31.101284)
					(end 122.301254 -30.550104)
				)
			)
		)
	)
	(zone
		(layers "In1.Cu" "In3.Cu" "In5.Cu" "In6.Cu" "In8.Cu" "In10.Cu")
		(hatch none 0.5)
		(connect_pads
			(clearance 0)
		)
		(min_thickness 0.25)
		(keepout
			(tracks not_allowed)
			(vias allowed)
			(pads allowed)
			(copperpour not_allowed)
			(footprints allowed)
		)
		(placement
			(enabled no)
			(sheetname "")
		)
		(fill yes
			(thermal_gap 0.5)
			(thermal_bridge_width 0.5)
			(island_removal_mode 0)
		)
		(polygon
			(pts
				(arc
					(start 32.889952 -162.178746)
					(mid 32.509079 -161.797492)
					(end 32.127952 -162.178492)
				)
				(arc
					(start 32.127952 -163.321492)
					(mid 32.508952 -163.702492)
					(end 32.889952 -163.321492)
				)
			)
		)
	)
	(zone
		(layers "In1.Cu" "In3.Cu" "In5.Cu" "In6.Cu" "In8.Cu" "In10.Cu")
		(hatch none 0.5)
		(connect_pads
			(clearance 0)
		)
		(min_thickness 0.25)
		(keepout
			(tracks not_allowed)
			(vias allowed)
			(pads allowed)
			(copperpour not_allowed)
			(footprints allowed)
		)
		(placement
			(enabled no)
			(sheetname "")
		)
		(fill yes
			(thermal_gap 0.5)
			(thermal_bridge_width 0.5)
			(island_removal_mode 0)
		)
		(polygon
			(pts
				(arc
					(start 283.563314 -114.87277)
					(mid 282.622752 -115.18646)
					(end 282.936442 -116.127022)
				)
				(arc
					(start 284.928056 -117.122702)
					(mid 285.874832 -116.817517)
					(end 285.56331 -115.872768)
				)
			)
		)
	)
	(zone
		(layers "In1.Cu" "In3.Cu" "In5.Cu" "In6.Cu" "In8.Cu" "In10.Cu")
		(hatch none 0.5)
		(connect_pads
			(clearance 0)
		)
		(min_thickness 0.25)
		(keepout
			(tracks not_allowed)
			(vias allowed)
			(pads allowed)
			(copperpour not_allowed)
			(footprints allowed)
		)
		(placement
			(enabled no)
			(sheetname "")
		)
		(fill yes
			(thermal_gap 0.5)
			(thermal_bridge_width 0.5)
			(island_removal_mode 0)
		)
		(polygon
			(pts
				(arc
					(start 113.298732 -17.350232)
					(mid 112.750219 -16.801338)
					(end 112.201452 -17.349978)
				)
				(arc
					(start 112.201452 -18.750026)
					(mid 112.750092 -19.298666)
					(end 113.298732 -18.750026)
				)
			)
		)
	)
	(zone
		(layers "In1.Cu" "In3.Cu" "In5.Cu" "In6.Cu" "In8.Cu" "In10.Cu")
		(hatch none 0.5)
		(connect_pads
			(clearance 0)
		)
		(min_thickness 0.25)
		(keepout
			(tracks not_allowed)
			(vias allowed)
			(pads allowed)
			(copperpour not_allowed)
			(footprints allowed)
		)
		(placement
			(enabled no)
			(sheetname "")
		)
		(fill yes
			(thermal_gap 0.5)
			(thermal_bridge_width 0.5)
			(island_removal_mode 0)
		)
		(polygon
			(pts
				(arc
					(start 383.908046 -46.5328)
					(mid 384.2893 -46.151927)
					(end 383.9083 -45.7708)
				)
				(arc
					(start 382.7653 -45.7708)
					(mid 382.3843 -46.1518)
					(end 382.7653 -46.5328)
				)
			)
		)
	)
	(zone
		(layers "In1.Cu" "In3.Cu" "In5.Cu" "In6.Cu" "In8.Cu" "In10.Cu")
		(hatch none 0.5)
		(connect_pads
			(clearance 0)
		)
		(min_thickness 0.25)
		(keepout
			(tracks not_allowed)
			(vias allowed)
			(pads allowed)
			(copperpour not_allowed)
			(footprints allowed)
		)
		(placement
			(enabled no)
			(sheetname "")
		)
		(fill yes
			(thermal_gap 0.5)
			(thermal_bridge_width 0.5)
			(island_removal_mode 0)
		)
		(polygon
			(pts
				(arc
					(start 285.436564 -297.75658)
					(mid 284.887924 -298.30522)
					(end 285.436564 -298.85386)
				)
				(arc
					(start 286.836612 -298.85386)
					(mid 287.385252 -298.30522)
					(end 286.836612 -297.75658)
				)
				(xy 285.436818 -297.75658)
			)
		)
	)
	(zone
		(layers "In1.Cu" "In3.Cu" "In5.Cu" "In6.Cu" "In8.Cu" "In10.Cu")
		(hatch none 0.5)
		(connect_pads
			(clearance 0)
		)
		(min_thickness 0.25)
		(keepout
			(tracks not_allowed)
			(vias allowed)
			(pads allowed)
			(copperpour not_allowed)
			(footprints allowed)
		)
		(placement
			(enabled no)
			(sheetname "")
		)
		(fill yes
			(thermal_gap 0.5)
			(thermal_bridge_width 0.5)
			(island_removal_mode 0)
		)
		(polygon
			(pts
				(arc
					(start 210.548728 -410.600398)
					(mid 210.000215 -410.051504)
					(end 209.451448 -410.600144)
				)
				(arc
					(start 209.451448 -412.000192)
					(mid 210.000088 -412.548832)
					(end 210.548728 -412.000192)
				)
			)
		)
	)
	(zone
		(layers "In1.Cu" "In3.Cu" "In5.Cu" "In6.Cu" "In8.Cu" "In10.Cu")
		(hatch none 0.5)
		(connect_pads
			(clearance 0)
		)
		(min_thickness 0.25)
		(keepout
			(tracks not_allowed)
			(vias allowed)
			(pads allowed)
			(copperpour not_allowed)
			(footprints allowed)
		)
		(placement
			(enabled no)
			(sheetname "")
		)
		(fill yes
			(thermal_gap 0.5)
			(thermal_bridge_width 0.5)
			(island_removal_mode 0)
		)
		(polygon
			(pts
				(arc
					(start 131.298696 -17.350232)
					(mid 130.750183 -16.801338)
					(end 130.201416 -17.349978)
				)
				(arc
					(start 130.201416 -18.750026)
					(mid 130.750056 -19.298666)
					(end 131.298696 -18.750026)
				)
			)
		)
	)
	(zone
		(layers "In1.Cu" "In3.Cu" "In5.Cu" "In6.Cu" "In8.Cu" "In10.Cu")
		(hatch none 0.5)
		(connect_pads
			(clearance 0)
		)
		(min_thickness 0.25)
		(keepout
			(tracks not_allowed)
			(vias allowed)
			(pads allowed)
			(copperpour not_allowed)
			(footprints allowed)
		)
		(placement
			(enabled no)
			(sheetname "")
		)
		(fill yes
			(thermal_gap 0.5)
			(thermal_bridge_width 0.5)
			(island_removal_mode 0)
		)
		(polygon
			(pts
				(arc
					(start 159.089852 -277.17877)
					(mid 158.708979 -276.797516)
					(end 158.327852 -277.178516)
				)
				(arc
					(start 158.327852 -278.321516)
					(mid 158.708852 -278.702516)
					(end 159.089852 -278.321516)
				)
			)
		)
	)
	(zone
		(layers "In1.Cu" "In3.Cu" "In5.Cu" "In6.Cu" "In8.Cu" "In10.Cu")
		(hatch none 0.5)
		(connect_pads
			(clearance 0)
		)
		(min_thickness 0.25)
		(keepout
			(tracks not_allowed)
			(vias allowed)
			(pads allowed)
			(copperpour not_allowed)
			(footprints allowed)
		)
		(placement
			(enabled no)
			(sheetname "")
		)
		(fill yes
			(thermal_gap 0.5)
			(thermal_bridge_width 0.5)
			(island_removal_mode 0)
		)
		(polygon
			(pts
				(arc
					(start 235.733844 -11.54049)
					(mid 235.393447 -12.52152)
					(end 236.377226 -12.854432)
				)
				(arc
					(start 238.377222 -11.854434)
					(mid 238.704374 -10.872978)
					(end 237.722918 -10.545826)
				)
			)
		)
	)
	(zone
		(layers "In1.Cu" "In3.Cu" "In5.Cu" "In6.Cu" "In8.Cu" "In10.Cu")
		(hatch none 0.5)
		(connect_pads
			(clearance 0)
		)
		(min_thickness 0.25)
		(keepout
			(tracks not_allowed)
			(vias allowed)
			(pads allowed)
			(copperpour not_allowed)
			(footprints allowed)
		)
		(placement
			(enabled no)
			(sheetname "")
		)
		(fill yes
			(thermal_gap 0.5)
			(thermal_bridge_width 0.5)
			(island_removal_mode 0)
		)
		(polygon
			(pts
				(arc
					(start 95.989902 -277.17877)
					(mid 95.609029 -276.797516)
					(end 95.227902 -277.178516)
				)
				(arc
					(start 95.227902 -278.321516)
					(mid 95.608902 -278.702516)
					(end 95.989902 -278.321516)
				)
			)
		)
	)
	(zone
		(layers "In1.Cu" "In3.Cu" "In5.Cu" "In6.Cu" "In8.Cu" "In10.Cu")
		(hatch none 0.5)
		(connect_pads
			(clearance 0)
		)
		(min_thickness 0.25)
		(keepout
			(tracks not_allowed)
			(vias allowed)
			(pads allowed)
			(copperpour not_allowed)
			(footprints allowed)
		)
		(placement
			(enabled no)
			(sheetname "")
		)
		(fill yes
			(thermal_gap 0.5)
			(thermal_bridge_width 0.5)
			(island_removal_mode 0)
		)
		(polygon
			(pts
				(arc
					(start 240.87709 -154.845512)
					(mid 239.895634 -155.172664)
					(end 240.222786 -156.15412)
				)
				(arc
					(start 242.222528 -157.154118)
					(mid 243.204289 -156.827118)
					(end 242.877086 -155.84551)
				)
			)
		)
	)
	(zone
		(layers "In1.Cu" "In3.Cu" "In5.Cu" "In6.Cu" "In8.Cu" "In10.Cu")
		(hatch none 0.5)
		(connect_pads
			(clearance 0)
		)
		(min_thickness 0.25)
		(keepout
			(tracks not_allowed)
			(vias allowed)
			(pads allowed)
			(copperpour not_allowed)
			(footprints allowed)
		)
		(placement
			(enabled no)
			(sheetname "")
		)
		(fill yes
			(thermal_gap 0.5)
			(thermal_bridge_width 0.5)
			(island_removal_mode 0)
		)
		(polygon
			(pts
				(arc
					(start 278.23668 -254.15113)
					(mid 277.6855 -254.70231)
					(end 278.23668 -255.25349)
				)
				(arc
					(start 279.636728 -255.25349)
					(mid 280.187908 -254.70231)
					(end 279.636728 -254.15113)
				)
				(xy 278.236934 -254.15113)
			)
		)
	)
	(zone
		(layers "In1.Cu" "In3.Cu" "In5.Cu" "In6.Cu" "In8.Cu" "In10.Cu")
		(hatch none 0.5)
		(connect_pads
			(clearance 0)
		)
		(min_thickness 0.25)
		(keepout
			(tracks not_allowed)
			(vias allowed)
			(pads allowed)
			(copperpour not_allowed)
			(footprints allowed)
		)
		(placement
			(enabled no)
			(sheetname "")
		)
		(fill yes
			(thermal_gap 0.5)
			(thermal_bridge_width 0.5)
			(island_removal_mode 0)
		)
		(polygon
			(pts
				(arc
					(start 285.436564 -301.356522)
					(mid 284.887924 -301.905162)
					(end 285.436564 -302.453802)
				)
				(arc
					(start 286.836612 -302.453802)
					(mid 287.385252 -301.905162)
					(end 286.836612 -301.356522)
				)
				(xy 285.436818 -301.356522)
			)
		)
	)
	(zone
		(layers "In1.Cu" "In3.Cu" "In5.Cu" "In6.Cu" "In8.Cu" "In10.Cu")
		(hatch none 0.5)
		(connect_pads
			(clearance 0)
		)
		(min_thickness 0.25)
		(keepout
			(tracks not_allowed)
			(vias allowed)
			(pads allowed)
			(copperpour not_allowed)
			(footprints allowed)
		)
		(placement
			(enabled no)
			(sheetname "")
		)
		(fill yes
			(thermal_gap 0.5)
			(thermal_bridge_width 0.5)
			(island_removal_mode 0)
		)
		(polygon
			(pts
				(arc
					(start 285.436564 -308.553866)
					(mid 284.885384 -309.105046)
					(end 285.436564 -309.656226)
				)
				(arc
					(start 286.836612 -309.656226)
					(mid 287.387792 -309.105046)
					(end 286.836612 -308.553866)
				)
				(xy 285.436818 -308.553866)
			)
		)
	)
	(zone
		(layers "In1.Cu" "In3.Cu" "In5.Cu" "In6.Cu" "In8.Cu" "In10.Cu")
		(hatch none 0.5)
		(connect_pads
			(clearance 0)
		)
		(min_thickness 0.25)
		(keepout
			(tracks not_allowed)
			(vias allowed)
			(pads allowed)
			(copperpour not_allowed)
			(footprints allowed)
		)
		(placement
			(enabled no)
			(sheetname "")
		)
		(fill yes
			(thermal_gap 0.5)
			(thermal_bridge_width 0.5)
			(island_removal_mode 0)
		)
		(polygon
			(pts
				(arc
					(start 320.3702 -158.368492)
					(mid 319.9892 -157.987492)
					(end 319.6082 -158.368492)
				)
				(arc
					(start 319.6082 -159.511238)
					(mid 319.989073 -159.892492)
					(end 320.3702 -159.511492)
				)
			)
		)
	)
	(zone
		(layers "In1.Cu" "In3.Cu" "In5.Cu" "In6.Cu" "In8.Cu" "In10.Cu")
		(hatch none 0.5)
		(connect_pads
			(clearance 0)
		)
		(min_thickness 0.25)
		(keepout
			(tracks not_allowed)
			(vias allowed)
			(pads allowed)
			(copperpour not_allowed)
			(footprints allowed)
		)
		(placement
			(enabled no)
			(sheetname "")
		)
		(fill yes
			(thermal_gap 0.5)
			(thermal_bridge_width 0.5)
			(island_removal_mode 0)
		)
		(polygon
			(pts
				(xy 279.07615 -70.85203) (xy 281.076146 -69.852032)
				(arc
					(start 281.074876 -69.849746)
					(mid 281.399742 -68.875148)
					(end 280.425144 -68.550282)
				)
				(xy 280.423874 -68.547996) (xy 278.424132 -69.547994) (xy 278.424132 -69.548248)
				(arc
					(start 278.425148 -69.55028)
					(mid 278.100282 -70.524878)
					(end 279.07488 -70.849744)
				)
			)
		)
	)
	(zone
		(layers "In1.Cu" "In3.Cu" "In5.Cu" "In6.Cu" "In8.Cu" "In10.Cu")
		(hatch none 0.5)
		(connect_pads
			(clearance 0)
		)
		(min_thickness 0.25)
		(keepout
			(tracks not_allowed)
			(vias allowed)
			(pads allowed)
			(copperpour not_allowed)
			(footprints allowed)
		)
		(placement
			(enabled no)
			(sheetname "")
		)
		(fill yes
			(thermal_gap 0.5)
			(thermal_bridge_width 0.5)
			(island_removal_mode 0)
		)
		(polygon
			(pts
				(arc
					(start 286.436562 -342.75649)
					(mid 285.887922 -343.30513)
					(end 286.436562 -343.85377)
				)
				(arc
					(start 287.83661 -343.85377)
					(mid 288.38525 -343.30513)
					(end 287.83661 -342.75649)
				)
				(xy 286.436816 -342.75649)
			)
		)
	)
	(zone
		(layers "In1.Cu" "In3.Cu" "In5.Cu" "In6.Cu" "In8.Cu" "In10.Cu")
		(hatch none 0.5)
		(connect_pads
			(clearance 0)
		)
		(min_thickness 0.25)
		(keepout
			(tracks not_allowed)
			(vias allowed)
			(pads allowed)
			(copperpour not_allowed)
			(footprints allowed)
		)
		(placement
			(enabled no)
			(sheetname "")
		)
		(fill yes
			(thermal_gap 0.5)
			(thermal_bridge_width 0.5)
			(island_removal_mode 0)
		)
		(polygon
			(pts
				(arc
					(start 285.436564 -330.154026)
					(mid 284.885384 -330.705206)
					(end 285.436564 -331.256386)
				)
				(arc
					(start 286.836612 -331.256386)
					(mid 287.387792 -330.705206)
					(end 286.836612 -330.154026)
				)
				(xy 285.436818 -330.154026)
			)
		)
	)
	(zone
		(layers "In1.Cu" "In3.Cu" "In5.Cu" "In6.Cu" "In8.Cu" "In10.Cu")
		(hatch none 0.5)
		(connect_pads
			(clearance 0)
		)
		(min_thickness 0.25)
		(keepout
			(tracks not_allowed)
			(vias allowed)
			(pads allowed)
			(copperpour not_allowed)
			(footprints allowed)
		)
		(placement
			(enabled no)
			(sheetname "")
		)
		(fill yes
			(thermal_gap 0.5)
			(thermal_bridge_width 0.5)
			(island_removal_mode 0)
		)
		(polygon
			(pts
				(arc
					(start 238.374936 -69.849746)
					(mid 238.699802 -68.875148)
					(end 237.725204 -68.550282)
				)
				(xy 237.723934 -68.547996) (xy 235.724192 -69.547994) (xy 235.724192 -69.548248)
				(arc
					(start 235.725208 -69.55028)
					(mid 235.400342 -70.524878)
					(end 236.37494 -70.849744)
				)
				(xy 236.37621 -70.85203) (xy 238.376206 -69.852032)
			)
		)
	)
	(zone
		(layers "In1.Cu" "In3.Cu" "In5.Cu" "In6.Cu" "In8.Cu" "In10.Cu")
		(hatch none 0.5)
		(connect_pads
			(clearance 0)
		)
		(min_thickness 0.25)
		(keepout
			(tracks not_allowed)
			(vias allowed)
			(pads allowed)
			(copperpour not_allowed)
			(footprints allowed)
		)
		(placement
			(enabled no)
			(sheetname "")
		)
		(fill yes
			(thermal_gap 0.5)
			(thermal_bridge_width 0.5)
			(island_removal_mode 0)
		)
		(polygon
			(pts
				(arc
					(start 238.374936 -37.84981)
					(mid 238.699802 -36.875212)
					(end 237.725204 -36.550346)
				)
				(xy 237.723934 -36.54806) (xy 235.724192 -37.548058) (xy 235.724192 -37.548312)
				(arc
					(start 235.725208 -37.550344)
					(mid 235.400342 -38.524942)
					(end 236.37494 -38.849808)
				)
				(xy 236.37621 -38.852094) (xy 238.376206 -37.852096)
			)
		)
	)
	(zone
		(layers "In1.Cu" "In3.Cu" "In5.Cu" "In6.Cu" "In8.Cu" "In10.Cu")
		(hatch none 0.5)
		(connect_pads
			(clearance 0)
		)
		(min_thickness 0.25)
		(keepout
			(tracks not_allowed)
			(vias allowed)
			(pads allowed)
			(copperpour not_allowed)
			(footprints allowed)
		)
		(placement
			(enabled no)
			(sheetname "")
		)
		(fill yes
			(thermal_gap 0.5)
			(thermal_bridge_width 0.5)
			(island_removal_mode 0)
		)
		(polygon
			(pts
				(arc
					(start 281.07386 -126.147322)
					(mid 281.397456 -125.176026)
					(end 280.42616 -124.85243)
				)
				(xy 278.426418 -125.852174)
				(arc
					(start 278.426418 -125.852428)
					(mid 278.102619 -126.823572)
					(end 279.073864 -127.14732)
				)
			)
		)
	)
	(zone
		(layers "In1.Cu" "In3.Cu" "In5.Cu" "In6.Cu" "In8.Cu" "In10.Cu")
		(hatch none 0.5)
		(connect_pads
			(clearance 0)
		)
		(min_thickness 0.25)
		(keepout
			(tracks not_allowed)
			(vias allowed)
			(pads allowed)
			(copperpour not_allowed)
			(footprints allowed)
		)
		(placement
			(enabled no)
			(sheetname "")
		)
		(fill yes
			(thermal_gap 0.5)
			(thermal_bridge_width 0.5)
			(island_removal_mode 0)
		)
		(polygon
			(pts
				(arc
					(start 388.21995 -277.17877)
					(mid 387.839077 -276.797516)
					(end 387.45795 -277.178516)
				)
				(arc
					(start 387.45795 -278.321516)
					(mid 387.83895 -278.702516)
					(end 388.21995 -278.321516)
				)
			)
		)
	)
	(zone
		(layers "In1.Cu" "In3.Cu" "In5.Cu" "In6.Cu" "In8.Cu" "In10.Cu")
		(hatch none 0.5)
		(connect_pads
			(clearance 0)
		)
		(min_thickness 0.25)
		(keepout
			(tracks not_allowed)
			(vias allowed)
			(pads allowed)
			(copperpour not_allowed)
			(footprints allowed)
		)
		(placement
			(enabled no)
			(sheetname "")
		)
		(fill yes
			(thermal_gap 0.5)
			(thermal_bridge_width 0.5)
			(island_removal_mode 0)
		)
		(polygon
			(pts
				(arc
					(start 240.863374 -74.572876)
					(mid 239.922812 -74.886566)
					(end 240.236502 -75.827128)
				)
				(arc
					(start 242.228116 -76.822808)
					(mid 243.174892 -76.517623)
					(end 242.86337 -75.572874)
				)
			)
		)
	)
	(zone
		(layers "In1.Cu" "In3.Cu" "In5.Cu" "In6.Cu" "In8.Cu" "In10.Cu")
		(hatch none 0.5)
		(connect_pads
			(clearance 0)
		)
		(min_thickness 0.25)
		(keepout
			(tracks not_allowed)
			(vias allowed)
			(pads allowed)
			(copperpour not_allowed)
			(footprints allowed)
		)
		(placement
			(enabled no)
			(sheetname "")
		)
		(fill yes
			(thermal_gap 0.5)
			(thermal_bridge_width 0.5)
			(island_removal_mode 0)
		)
		(polygon
			(pts
				(arc
					(start 242.236498 -169.126916)
					(mid 243.17706 -168.813226)
					(end 242.86337 -167.872664)
				)
				(arc
					(start 240.871756 -166.876984)
					(mid 239.92498 -167.182169)
					(end 240.236502 -168.126918)
				)
			)
		)
	)
	(zone
		(layers "In1.Cu" "In3.Cu" "In5.Cu" "In6.Cu" "In8.Cu" "In10.Cu")
		(hatch none 0.5)
		(connect_pads
			(clearance 0)
		)
		(min_thickness 0.25)
		(keepout
			(tracks not_allowed)
			(vias allowed)
			(pads allowed)
			(copperpour not_allowed)
			(footprints allowed)
		)
		(placement
			(enabled no)
			(sheetname "")
		)
		(fill yes
			(thermal_gap 0.5)
			(thermal_bridge_width 0.5)
			(island_removal_mode 0)
		)
		(polygon
			(pts
				(arc
					(start 140.298678 -18.350484)
					(mid 139.750165 -17.80159)
					(end 139.201398 -18.35023)
				)
				(arc
					(start 139.201398 -19.750024)
					(mid 139.750038 -20.298664)
					(end 140.298678 -19.750024)
				)
			)
		)
	)
	(zone
		(layers "In1.Cu" "In3.Cu" "In5.Cu" "In6.Cu" "In8.Cu" "In10.Cu")
		(hatch none 0.5)
		(connect_pads
			(clearance 0)
		)
		(min_thickness 0.25)
		(keepout
			(tracks not_allowed)
			(vias allowed)
			(pads allowed)
			(copperpour not_allowed)
			(footprints allowed)
		)
		(placement
			(enabled no)
			(sheetname "")
		)
		(fill yes
			(thermal_gap 0.5)
			(thermal_bridge_width 0.5)
			(island_removal_mode 0)
		)
		(polygon
			(pts
				(arc
					(start 382.698752 -18.350484)
					(mid 382.150239 -17.80159)
					(end 381.601472 -18.35023)
				)
				(arc
					(start 381.601472 -19.750024)
					(mid 382.150112 -20.298664)
					(end 382.698752 -19.750024)
				)
			)
		)
	)
	(zone
		(layers "In1.Cu" "In3.Cu" "In5.Cu" "In6.Cu" "In8.Cu" "In10.Cu")
		(hatch none 0.5)
		(connect_pads
			(clearance 0)
		)
		(min_thickness 0.25)
		(keepout
			(tracks not_allowed)
			(vias allowed)
			(pads allowed)
			(copperpour not_allowed)
			(footprints allowed)
		)
		(placement
			(enabled no)
			(sheetname "")
		)
		(fill yes
			(thermal_gap 0.5)
			(thermal_bridge_width 0.5)
			(island_removal_mode 0)
		)
		(polygon
			(pts
				(arc
					(start 278.23668 -326.556624)
					(mid 277.68804 -327.105264)
					(end 278.23668 -327.653904)
				)
				(arc
					(start 279.636728 -327.653904)
					(mid 280.185368 -327.105264)
					(end 279.636728 -326.556624)
				)
				(xy 278.236934 -326.556624)
			)
		)
	)
	(zone
		(layers "In1.Cu" "In3.Cu" "In5.Cu" "In6.Cu" "In8.Cu" "In10.Cu")
		(hatch none 0.5)
		(connect_pads
			(clearance 0)
		)
		(min_thickness 0.25)
		(keepout
			(tracks not_allowed)
			(vias allowed)
			(pads allowed)
			(copperpour not_allowed)
			(footprints allowed)
		)
		(placement
			(enabled no)
			(sheetname "")
		)
		(fill yes
			(thermal_gap 0.5)
			(thermal_bridge_width 0.5)
			(island_removal_mode 0)
		)
		(polygon
			(pts
				(arc
					(start 278.433784 -11.54049)
					(mid 278.093387 -12.52152)
					(end 279.077166 -12.854432)
				)
				(arc
					(start 281.077162 -11.854434)
					(mid 281.404314 -10.872978)
					(end 280.422858 -10.545826)
				)
			)
		)
	)
	(zone
		(layers "In1.Cu" "In3.Cu" "In5.Cu" "In6.Cu" "In8.Cu" "In10.Cu")
		(hatch none 0.5)
		(connect_pads
			(clearance 0)
		)
		(min_thickness 0.25)
		(keepout
			(tracks not_allowed)
			(vias allowed)
			(pads allowed)
			(copperpour not_allowed)
			(footprints allowed)
		)
		(placement
			(enabled no)
			(sheetname "")
		)
		(fill yes
			(thermal_gap 0.5)
			(thermal_bridge_width 0.5)
			(island_removal_mode 0)
		)
		(polygon
			(pts
				(arc
					(start 240.863374 -50.572924)
					(mid 239.922812 -50.886614)
					(end 240.236502 -51.827176)
				)
				(arc
					(start 242.228116 -52.822856)
					(mid 243.174892 -52.517671)
					(end 242.86337 -51.572922)
				)
			)
		)
	)
	(zone
		(layers "In1.Cu" "In3.Cu" "In5.Cu" "In6.Cu" "In8.Cu" "In10.Cu")
		(hatch none 0.5)
		(connect_pads
			(clearance 0)
		)
		(min_thickness 0.25)
		(keepout
			(tracks not_allowed)
			(vias allowed)
			(pads allowed)
			(copperpour not_allowed)
			(footprints allowed)
		)
		(placement
			(enabled no)
			(sheetname "")
		)
		(fill yes
			(thermal_gap 0.5)
			(thermal_bridge_width 0.5)
			(island_removal_mode 0)
		)
		(polygon
			(pts
				(arc
					(start 283.563314 -42.57294)
					(mid 282.622752 -42.88663)
					(end 282.936442 -43.827192)
				)
				(arc
					(start 284.928056 -44.822872)
					(mid 285.874832 -44.517687)
					(end 285.56331 -43.572938)
				)
			)
		)
	)
	(zone
		(layers "In1.Cu" "In3.Cu" "In5.Cu" "In6.Cu" "In8.Cu" "In10.Cu")
		(hatch none 0.5)
		(connect_pads
			(clearance 0)
		)
		(min_thickness 0.25)
		(keepout
			(tracks not_allowed)
			(vias allowed)
			(pads allowed)
			(copperpour not_allowed)
			(footprints allowed)
		)
		(placement
			(enabled no)
			(sheetname "")
		)
		(fill yes
			(thermal_gap 0.5)
			(thermal_bridge_width 0.5)
			(island_removal_mode 0)
		)
		(polygon
			(pts
				(arc
					(start 362.89869 -28.150312)
					(mid 362.350177 -27.601418)
					(end 361.80141 -28.150058)
				)
				(arc
					(start 361.80141 -29.550106)
					(mid 362.35005 -30.098746)
					(end 362.89869 -29.550106)
				)
			)
		)
	)
	(zone
		(layers "In1.Cu" "In3.Cu" "In5.Cu" "In6.Cu" "In8.Cu" "In10.Cu")
		(hatch none 0.5)
		(connect_pads
			(clearance 0)
		)
		(min_thickness 0.25)
		(keepout
			(tracks not_allowed)
			(vias allowed)
			(pads allowed)
			(copperpour not_allowed)
			(footprints allowed)
		)
		(placement
			(enabled no)
			(sheetname "")
		)
		(fill yes
			(thermal_gap 0.5)
			(thermal_bridge_width 0.5)
			(island_removal_mode 0)
		)
		(polygon
			(pts
				(arc
					(start 285.436564 -257.751072)
					(mid 284.885384 -258.302252)
					(end 285.436564 -258.853432)
				)
				(arc
					(start 286.836612 -258.853432)
					(mid 287.387792 -258.302252)
					(end 286.836612 -257.751072)
				)
				(xy 285.436818 -257.751072)
			)
		)
	)
	(zone
		(layers "In1.Cu" "In3.Cu" "In5.Cu" "In6.Cu" "In8.Cu" "In10.Cu")
		(hatch none 0.5)
		(connect_pads
			(clearance 0)
		)
		(min_thickness 0.25)
		(keepout
			(tracks not_allowed)
			(vias allowed)
			(pads allowed)
			(copperpour not_allowed)
			(footprints allowed)
		)
		(placement
			(enabled no)
			(sheetname "")
		)
		(fill yes
			(thermal_gap 0.5)
			(thermal_bridge_width 0.5)
			(island_removal_mode 0)
		)
		(polygon
			(pts
				(arc
					(start 238.374936 -73.849738)
					(mid 238.699802 -72.87514)
					(end 237.725204 -72.550274)
				)
				(xy 237.723934 -72.547988) (xy 235.724192 -73.547986) (xy 235.724192 -73.54824)
				(arc
					(start 235.725208 -73.550272)
					(mid 235.400342 -74.52487)
					(end 236.37494 -74.849736)
				)
				(xy 236.37621 -74.852022) (xy 238.376206 -73.852024)
			)
		)
	)
	(zone
		(layers "In1.Cu" "In3.Cu" "In5.Cu" "In6.Cu" "In8.Cu" "In10.Cu")
		(hatch none 0.5)
		(connect_pads
			(clearance 0)
		)
		(min_thickness 0.25)
		(keepout
			(tracks not_allowed)
			(vias allowed)
			(pads allowed)
			(copperpour not_allowed)
			(footprints allowed)
		)
		(placement
			(enabled no)
			(sheetname "")
		)
		(fill yes
			(thermal_gap 0.5)
			(thermal_bridge_width 0.5)
			(island_removal_mode 0)
		)
		(polygon
			(pts
				(arc
					(start 279.236678 -335.556606)
					(mid 278.688038 -336.105246)
					(end 279.236678 -336.653886)
				)
				(arc
					(start 280.636726 -336.653886)
					(mid 281.185366 -336.105246)
					(end 280.636726 -335.556606)
				)
				(xy 279.236932 -335.556606)
			)
		)
	)
	(zone
		(layers "In1.Cu" "In3.Cu" "In5.Cu" "In6.Cu" "In8.Cu" "In10.Cu")
		(hatch none 0.5)
		(connect_pads
			(clearance 0)
		)
		(min_thickness 0.25)
		(keepout
			(tracks not_allowed)
			(vias allowed)
			(pads allowed)
			(copperpour not_allowed)
			(footprints allowed)
		)
		(placement
			(enabled no)
			(sheetname "")
		)
		(fill yes
			(thermal_gap 0.5)
			(thermal_bridge_width 0.5)
			(island_removal_mode 0)
		)
		(polygon
			(pts
				(arc
					(start 278.23668 -312.156602)
					(mid 277.68804 -312.705242)
					(end 278.23668 -313.253882)
				)
				(arc
					(start 279.636728 -313.253882)
					(mid 280.185368 -312.705242)
					(end 279.636728 -312.156602)
				)
				(xy 278.236934 -312.156602)
			)
		)
	)
	(zone
		(layers "In1.Cu" "In3.Cu" "In5.Cu" "In6.Cu" "In8.Cu" "In10.Cu")
		(hatch none 0.5)
		(connect_pads
			(clearance 0)
		)
		(min_thickness 0.25)
		(keepout
			(tracks not_allowed)
			(vias allowed)
			(pads allowed)
			(copperpour not_allowed)
			(footprints allowed)
		)
		(placement
			(enabled no)
			(sheetname "")
		)
		(fill yes
			(thermal_gap 0.5)
			(thermal_bridge_width 0.5)
			(island_removal_mode 0)
		)
		(polygon
			(pts
				(arc
					(start 271.970754 -350.124014)
					(mid 271.5895 -350.504887)
					(end 271.9705 -350.886014)
				)
				(arc
					(start 273.1135 -350.886014)
					(mid 273.4945 -350.505014)
					(end 273.1135 -350.124014)
				)
			)
		)
	)
	(zone
		(layers "In1.Cu" "In3.Cu" "In5.Cu" "In6.Cu" "In8.Cu" "In10.Cu")
		(hatch none 0.5)
		(connect_pads
			(clearance 0)
		)
		(min_thickness 0.25)
		(keepout
			(tracks not_allowed)
			(vias allowed)
			(pads allowed)
			(copperpour not_allowed)
			(footprints allowed)
		)
		(placement
			(enabled no)
			(sheetname "")
		)
		(fill yes
			(thermal_gap 0.5)
			(thermal_bridge_width 0.5)
			(island_removal_mode 0)
		)
		(polygon
			(pts
				(arc
					(start 111.498634 -18.350484)
					(mid 110.950121 -17.80159)
					(end 110.401354 -18.35023)
				)
				(arc
					(start 110.401354 -19.750024)
					(mid 110.949994 -20.298664)
					(end 111.498634 -19.750024)
				)
			)
		)
	)
	(zone
		(layers "In1.Cu" "In3.Cu" "In5.Cu" "In6.Cu" "In8.Cu" "In10.Cu")
		(hatch none 0.5)
		(connect_pads
			(clearance 0)
		)
		(min_thickness 0.25)
		(keepout
			(tracks not_allowed)
			(vias allowed)
			(pads allowed)
			(copperpour not_allowed)
			(footprints allowed)
		)
		(placement
			(enabled no)
			(sheetname "")
		)
		(fill yes
			(thermal_gap 0.5)
			(thermal_bridge_width 0.5)
			(island_removal_mode 0)
		)
		(polygon
			(pts
				(arc
					(start 279.236678 -353.55657)
					(mid 278.688038 -354.10521)
					(end 279.236678 -354.65385)
				)
				(arc
					(start 280.636726 -354.65385)
					(mid 281.185366 -354.10521)
					(end 280.636726 -353.55657)
				)
				(xy 279.236932 -353.55657)
			)
		)
	)
	(zone
		(layers "In1.Cu" "In3.Cu" "In5.Cu" "In6.Cu" "In8.Cu" "In10.Cu")
		(hatch none 0.5)
		(connect_pads
			(clearance 0)
		)
		(min_thickness 0.25)
		(keepout
			(tracks not_allowed)
			(vias allowed)
			(pads allowed)
			(copperpour not_allowed)
			(footprints allowed)
		)
		(placement
			(enabled no)
			(sheetname "")
		)
		(fill yes
			(thermal_gap 0.5)
			(thermal_bridge_width 0.5)
			(island_removal_mode 0)
		)
		(polygon
			(pts
				(arc
					(start 279.236678 -263.151112)
					(mid 278.685498 -263.702292)
					(end 279.236678 -264.253472)
				)
				(arc
					(start 280.636726 -264.253472)
					(mid 281.187906 -263.702292)
					(end 280.636726 -263.151112)
				)
				(xy 279.236932 -263.151112)
			)
		)
	)
	(zone
		(layers "In1.Cu" "In3.Cu" "In5.Cu" "In6.Cu" "In8.Cu" "In10.Cu")
		(hatch none 0.5)
		(connect_pads
			(clearance 0)
		)
		(min_thickness 0.25)
		(keepout
			(tracks not_allowed)
			(vias allowed)
			(pads allowed)
			(copperpour not_allowed)
			(footprints allowed)
		)
		(placement
			(enabled no)
			(sheetname "")
		)
		(fill yes
			(thermal_gap 0.5)
			(thermal_bridge_width 0.5)
			(island_removal_mode 0)
		)
		(polygon
			(pts
				(arc
					(start 279.236678 -255.951228)
					(mid 278.685498 -256.502408)
					(end 279.236678 -257.053588)
				)
				(arc
					(start 280.636726 -257.053588)
					(mid 281.187906 -256.502408)
					(end 280.636726 -255.951228)
				)
				(xy 279.236932 -255.951228)
			)
		)
	)
	(zone
		(layers "In1.Cu" "In3.Cu" "In5.Cu" "In6.Cu" "In8.Cu" "In10.Cu")
		(hatch none 0.5)
		(connect_pads
			(clearance 0)
		)
		(min_thickness 0.25)
		(keepout
			(tracks not_allowed)
			(vias allowed)
			(pads allowed)
			(copperpour not_allowed)
			(footprints allowed)
		)
		(placement
			(enabled no)
			(sheetname "")
		)
		(fill yes
			(thermal_gap 0.5)
			(thermal_bridge_width 0.5)
			(island_removal_mode 0)
		)
		(polygon
			(pts
				(arc
					(start 127.53975 -47.178722)
					(mid 127.158877 -46.797468)
					(end 126.77775 -47.178468)
				)
				(arc
					(start 126.77775 -48.321468)
					(mid 127.15875 -48.702468)
					(end 127.53975 -48.321468)
				)
			)
		)
	)
	(zone
		(layers "In1.Cu" "In3.Cu" "In5.Cu" "In6.Cu" "In8.Cu" "In10.Cu")
		(hatch none 0.5)
		(connect_pads
			(clearance 0)
		)
		(min_thickness 0.25)
		(keepout
			(tracks not_allowed)
			(vias allowed)
			(pads allowed)
			(copperpour not_allowed)
			(footprints allowed)
		)
		(placement
			(enabled no)
			(sheetname "")
		)
		(fill yes
			(thermal_gap 0.5)
			(thermal_bridge_width 0.5)
			(island_removal_mode 0)
		)
		(polygon
			(pts
				(arc
					(start 278.23668 -308.556406)
					(mid 277.68804 -309.105046)
					(end 278.23668 -309.653686)
				)
				(arc
					(start 279.636728 -309.653686)
					(mid 280.185368 -309.105046)
					(end 279.636728 -308.556406)
				)
				(xy 278.236934 -308.556406)
			)
		)
	)
	(zone
		(layers "In1.Cu" "In3.Cu" "In5.Cu" "In6.Cu" "In8.Cu" "In10.Cu")
		(hatch none 0.5)
		(connect_pads
			(clearance 0)
		)
		(min_thickness 0.25)
		(keepout
			(tracks not_allowed)
			(vias allowed)
			(pads allowed)
			(copperpour not_allowed)
			(footprints allowed)
		)
		(placement
			(enabled no)
			(sheetname "")
		)
		(fill yes
			(thermal_gap 0.5)
			(thermal_bridge_width 0.5)
			(island_removal_mode 0)
		)
		(polygon
			(pts
				(arc
					(start 143.89862 -29.15031)
					(mid 143.350107 -28.601416)
					(end 142.80134 -29.150056)
				)
				(arc
					(start 142.80134 -30.550104)
					(mid 143.34998 -31.098744)
					(end 143.89862 -30.550104)
				)
			)
		)
	)
	(zone
		(layers "In1.Cu" "In3.Cu" "In5.Cu" "In6.Cu" "In8.Cu" "In10.Cu")
		(hatch none 0.5)
		(connect_pads
			(clearance 0)
		)
		(min_thickness 0.25)
		(keepout
			(tracks not_allowed)
			(vias allowed)
			(pads allowed)
			(copperpour not_allowed)
			(footprints allowed)
		)
		(placement
			(enabled no)
			(sheetname "")
		)
		(fill yes
			(thermal_gap 0.5)
			(thermal_bridge_width 0.5)
			(island_removal_mode 0)
		)
		(polygon
			(pts
				(arc
					(start 285.436564 -304.953924)
					(mid 284.885384 -305.505104)
					(end 285.436564 -306.056284)
				)
				(arc
					(start 286.836612 -306.056284)
					(mid 287.387792 -305.505104)
					(end 286.836612 -304.953924)
				)
				(xy 285.436818 -304.953924)
			)
		)
	)
	(zone
		(layers "In1.Cu" "In3.Cu" "In5.Cu" "In6.Cu" "In8.Cu" "In10.Cu")
		(hatch none 0.5)
		(connect_pads
			(clearance 0)
		)
		(min_thickness 0.25)
		(keepout
			(tracks not_allowed)
			(vias allowed)
			(pads allowed)
			(copperpour not_allowed)
			(footprints allowed)
		)
		(placement
			(enabled no)
			(sheetname "")
		)
		(fill yes
			(thermal_gap 0.5)
			(thermal_bridge_width 0.5)
			(island_removal_mode 0)
		)
		(polygon
			(pts
				(arc
					(start 278.23668 -294.156638)
					(mid 277.68804 -294.705278)
					(end 278.23668 -295.253918)
				)
				(arc
					(start 279.636728 -295.253918)
					(mid 280.185368 -294.705278)
					(end 279.636728 -294.156638)
				)
				(xy 278.236934 -294.156638)
			)
		)
	)
	(zone
		(layers "In1.Cu" "In3.Cu" "In5.Cu" "In6.Cu" "In8.Cu" "In10.Cu")
		(hatch none 0.5)
		(connect_pads
			(clearance 0)
		)
		(min_thickness 0.25)
		(keepout
			(tracks not_allowed)
			(vias allowed)
			(pads allowed)
			(copperpour not_allowed)
			(footprints allowed)
		)
		(placement
			(enabled no)
			(sheetname "")
		)
		(fill yes
			(thermal_gap 0.5)
			(thermal_bridge_width 0.5)
			(island_removal_mode 0)
		)
		(polygon
			(pts
				(arc
					(start 285.436564 -319.356486)
					(mid 284.887924 -319.905126)
					(end 285.436564 -320.453766)
				)
				(arc
					(start 286.836612 -320.453766)
					(mid 287.385252 -319.905126)
					(end 286.836612 -319.356486)
				)
				(xy 285.436818 -319.356486)
			)
		)
	)
	(zone
		(layers "In1.Cu" "In3.Cu" "In5.Cu" "In6.Cu" "In8.Cu" "In10.Cu")
		(hatch none 0.5)
		(connect_pads
			(clearance 0)
		)
		(min_thickness 0.25)
		(keepout
			(tracks not_allowed)
			(vias allowed)
			(pads allowed)
			(copperpour not_allowed)
			(footprints allowed)
		)
		(placement
			(enabled no)
			(sheetname "")
		)
		(fill yes
			(thermal_gap 0.5)
			(thermal_bridge_width 0.5)
			(island_removal_mode 0)
		)
		(polygon
			(pts
				(arc
					(start 217.748612 -414.20034)
					(mid 217.200099 -413.651446)
					(end 216.651332 -414.200086)
				)
				(arc
					(start 216.651332 -415.600134)
					(mid 217.199972 -416.148774)
					(end 217.748612 -415.600134)
				)
			)
		)
	)
	(zone
		(layers "In1.Cu" "In3.Cu" "In5.Cu" "In6.Cu" "In8.Cu" "In10.Cu")
		(hatch none 0.5)
		(connect_pads
			(clearance 0)
		)
		(min_thickness 0.25)
		(keepout
			(tracks not_allowed)
			(vias allowed)
			(pads allowed)
			(copperpour not_allowed)
			(footprints allowed)
		)
		(placement
			(enabled no)
			(sheetname "")
		)
		(fill yes
			(thermal_gap 0.5)
			(thermal_bridge_width 0.5)
			(island_removal_mode 0)
		)
		(polygon
			(pts
				(xy 279.07615 -42.852086) (xy 281.076146 -41.852088)
				(arc
					(start 281.074876 -41.849802)
					(mid 281.399742 -40.875204)
					(end 280.425144 -40.550338)
				)
				(xy 280.423874 -40.548052) (xy 278.424132 -41.54805) (xy 278.424132 -41.548304)
				(arc
					(start 278.425148 -41.550336)
					(mid 278.100282 -42.524934)
					(end 279.07488 -42.8498)
				)
			)
		)
	)
	(zone
		(layers "In1.Cu" "In3.Cu" "In5.Cu" "In6.Cu" "In8.Cu" "In10.Cu")
		(hatch none 0.5)
		(connect_pads
			(clearance 0)
		)
		(min_thickness 0.25)
		(keepout
			(tracks not_allowed)
			(vias allowed)
			(pads allowed)
			(copperpour not_allowed)
			(footprints allowed)
		)
		(placement
			(enabled no)
			(sheetname "")
		)
		(fill yes
			(thermal_gap 0.5)
			(thermal_bridge_width 0.5)
			(island_removal_mode 0)
		)
		(polygon
			(pts
				(arc
					(start 279.236678 -313.956446)
					(mid 278.688038 -314.505086)
					(end 279.236678 -315.053726)
				)
				(arc
					(start 280.636726 -315.053726)
					(mid 281.185366 -314.505086)
					(end 280.636726 -313.956446)
				)
				(xy 279.236932 -313.956446)
			)
		)
	)
	(zone
		(layers "In1.Cu" "In3.Cu" "In5.Cu" "In6.Cu" "In8.Cu" "In10.Cu")
		(hatch none 0.5)
		(connect_pads
			(clearance 0)
		)
		(min_thickness 0.25)
		(keepout
			(tracks not_allowed)
			(vias allowed)
			(pads allowed)
			(copperpour not_allowed)
			(footprints allowed)
		)
		(placement
			(enabled no)
			(sheetname "")
		)
		(fill yes
			(thermal_gap 0.5)
			(thermal_bridge_width 0.5)
			(island_removal_mode 0)
		)
		(polygon
			(pts
				(xy 279.07615 -50.85207) (xy 281.076146 -49.852072)
				(arc
					(start 281.074876 -49.849786)
					(mid 281.399742 -48.875188)
					(end 280.425144 -48.550322)
				)
				(xy 280.423874 -48.548036) (xy 278.424132 -49.548034) (xy 278.424132 -49.548288)
				(arc
					(start 278.425148 -49.55032)
					(mid 278.100282 -50.524918)
					(end 279.07488 -50.849784)
				)
			)
		)
	)
	(zone
		(layers "In1.Cu" "In3.Cu" "In5.Cu" "In6.Cu" "In8.Cu" "In10.Cu")
		(hatch none 0.5)
		(connect_pads
			(clearance 0)
		)
		(min_thickness 0.25)
		(keepout
			(tracks not_allowed)
			(vias allowed)
			(pads allowed)
			(copperpour not_allowed)
			(footprints allowed)
		)
		(placement
			(enabled no)
			(sheetname "")
		)
		(fill yes
			(thermal_gap 0.5)
			(thermal_bridge_width 0.5)
			(island_removal_mode 0)
		)
		(polygon
			(pts
				(arc
					(start 142.098522 -17.350232)
					(mid 141.550009 -16.801338)
					(end 141.001242 -17.349978)
				)
				(arc
					(start 141.001242 -18.750026)
					(mid 141.549882 -19.298666)
					(end 142.098522 -18.750026)
				)
			)
		)
	)
	(zone
		(layers "In1.Cu" "In3.Cu" "In5.Cu" "In6.Cu" "In8.Cu" "In10.Cu")
		(hatch none 0.5)
		(connect_pads
			(clearance 0)
		)
		(min_thickness 0.25)
		(keepout
			(tracks not_allowed)
			(vias allowed)
			(pads allowed)
			(copperpour not_allowed)
			(footprints allowed)
		)
		(placement
			(enabled no)
			(sheetname "")
		)
		(fill yes
			(thermal_gap 0.5)
			(thermal_bridge_width 0.5)
			(island_removal_mode 0)
		)
		(polygon
			(pts
				(arc
					(start 285.436564 -261.351014)
					(mid 284.885384 -261.902194)
					(end 285.436564 -262.453374)
				)
				(arc
					(start 286.836612 -262.453374)
					(mid 287.387792 -261.902194)
					(end 286.836612 -261.351014)
				)
				(xy 285.436818 -261.351014)
			)
		)
	)
	(zone
		(layers "In1.Cu" "In3.Cu" "In5.Cu" "In6.Cu" "In8.Cu" "In10.Cu")
		(hatch none 0.5)
		(connect_pads
			(clearance 0)
		)
		(min_thickness 0.25)
		(keepout
			(tracks not_allowed)
			(vias allowed)
			(pads allowed)
			(copperpour not_allowed)
			(footprints allowed)
		)
		(placement
			(enabled no)
			(sheetname "")
		)
		(fill yes
			(thermal_gap 0.5)
			(thermal_bridge_width 0.5)
			(island_removal_mode 0)
		)
		(polygon
			(pts
				(arc
					(start 286.436562 -306.754022)
					(mid 285.885382 -307.305202)
					(end 286.436562 -307.856382)
				)
				(arc
					(start 287.83661 -307.856382)
					(mid 288.38779 -307.305202)
					(end 287.83661 -306.754022)
				)
				(xy 286.436816 -306.754022)
			)
		)
	)
	(zone
		(layers "In1.Cu" "In3.Cu" "In5.Cu" "In6.Cu" "In8.Cu" "In10.Cu")
		(hatch none 0.5)
		(connect_pads
			(clearance 0)
		)
		(min_thickness 0.25)
		(keepout
			(tracks not_allowed)
			(vias allowed)
			(pads allowed)
			(copperpour not_allowed)
			(footprints allowed)
		)
		(placement
			(enabled no)
			(sheetname "")
		)
		(fill yes
			(thermal_gap 0.5)
			(thermal_bridge_width 0.5)
			(island_removal_mode 0)
		)
		(polygon
			(pts
				(arc
					(start 283.574744 -134.850124)
					(mid 282.600146 -135.17499)
					(end 282.925012 -136.149588)
				)
				(xy 282.923742 -136.151874) (xy 284.923738 -137.151872) (xy 284.923992 -137.151618)
				(arc
					(start 284.925008 -137.149586)
					(mid 285.899606 -136.82472)
					(end 285.57474 -135.850122)
				)
				(xy 285.57601 -135.847836) (xy 283.576014 -134.847838)
			)
		)
	)
	(zone
		(layers "In1.Cu" "In3.Cu" "In5.Cu" "In6.Cu" "In8.Cu" "In10.Cu")
		(hatch none 0.5)
		(connect_pads
			(clearance 0)
		)
		(min_thickness 0.25)
		(keepout
			(tracks not_allowed)
			(vias allowed)
			(pads allowed)
			(copperpour not_allowed)
			(footprints allowed)
		)
		(placement
			(enabled no)
			(sheetname "")
		)
		(fill yes
			(thermal_gap 0.5)
			(thermal_bridge_width 0.5)
			(island_removal_mode 0)
		)
		(polygon
			(pts
				(arc
					(start 415.020252 -273.368516)
					(mid 414.639252 -272.987516)
					(end 414.258252 -273.368516)
				)
				(arc
					(start 414.258252 -274.511262)
					(mid 414.639125 -274.892516)
					(end 415.020252 -274.511516)
				)
			)
		)
	)
	(zone
		(layers "In1.Cu" "In3.Cu" "In5.Cu" "In6.Cu" "In8.Cu" "In10.Cu")
		(hatch none 0.5)
		(connect_pads
			(clearance 0)
		)
		(min_thickness 0.25)
		(keepout
			(tracks not_allowed)
			(vias allowed)
			(pads allowed)
			(copperpour not_allowed)
			(footprints allowed)
		)
		(placement
			(enabled no)
			(sheetname "")
		)
		(fill yes
			(thermal_gap 0.5)
			(thermal_bridge_width 0.5)
			(island_removal_mode 0)
		)
		(polygon
			(pts
				(arc
					(start 285.436564 -294.154098)
					(mid 284.885384 -294.705278)
					(end 285.436564 -295.256458)
				)
				(arc
					(start 286.836612 -295.256458)
					(mid 287.387792 -294.705278)
					(end 286.836612 -294.154098)
				)
				(xy 285.436818 -294.154098)
			)
		)
	)
	(zone
		(layers "In1.Cu" "In3.Cu" "In5.Cu" "In6.Cu" "In8.Cu" "In10.Cu")
		(hatch none 0.5)
		(connect_pads
			(clearance 0)
		)
		(min_thickness 0.25)
		(keepout
			(tracks not_allowed)
			(vias allowed)
			(pads allowed)
			(copperpour not_allowed)
			(footprints allowed)
		)
		(placement
			(enabled no)
			(sheetname "")
		)
		(fill yes
			(thermal_gap 0.5)
			(thermal_bridge_width 0.5)
			(island_removal_mode 0)
		)
		(polygon
			(pts
				(arc
					(start 242.236498 -84.82711)
					(mid 243.17706 -84.51342)
					(end 242.86337 -83.572858)
				)
				(arc
					(start 240.871756 -82.577178)
					(mid 239.92498 -82.882363)
					(end 240.236502 -83.827112)
				)
			)
		)
	)
	(zone
		(layers "In1.Cu" "In3.Cu" "In5.Cu" "In6.Cu" "In8.Cu" "In10.Cu")
		(hatch none 0.5)
		(connect_pads
			(clearance 0)
		)
		(min_thickness 0.25)
		(keepout
			(tracks not_allowed)
			(vias allowed)
			(pads allowed)
			(copperpour not_allowed)
			(footprints allowed)
		)
		(placement
			(enabled no)
			(sheetname "")
		)
		(fill yes
			(thermal_gap 0.5)
			(thermal_bridge_width 0.5)
			(island_removal_mode 0)
		)
		(polygon
			(pts
				(arc
					(start 281.07386 -158.147258)
					(mid 281.397456 -157.175962)
					(end 280.42616 -156.852366)
				)
				(xy 278.426418 -157.85211)
				(arc
					(start 278.426418 -157.852364)
					(mid 278.102619 -158.823508)
					(end 279.073864 -159.147256)
				)
			)
		)
	)
	(zone
		(layers "In1.Cu" "In3.Cu" "In5.Cu" "In6.Cu" "In8.Cu" "In10.Cu")
		(hatch none 0.5)
		(connect_pads
			(clearance 0)
		)
		(min_thickness 0.25)
		(keepout
			(tracks not_allowed)
			(vias allowed)
			(pads allowed)
			(copperpour not_allowed)
			(footprints allowed)
		)
		(placement
			(enabled no)
			(sheetname "")
		)
		(fill yes
			(thermal_gap 0.5)
			(thermal_bridge_width 0.5)
			(island_removal_mode 0)
		)
		(polygon
			(pts
				(arc
					(start 356.670102 -162.178746)
					(mid 356.289229 -161.797492)
					(end 355.908102 -162.178492)
				)
				(arc
					(start 355.908102 -163.321492)
					(mid 356.289102 -163.702492)
					(end 356.670102 -163.321492)
				)
			)
		)
	)
	(zone
		(layers "In1.Cu" "In3.Cu" "In5.Cu" "In6.Cu" "In8.Cu" "In10.Cu")
		(hatch none 0.5)
		(connect_pads
			(clearance 0)
		)
		(min_thickness 0.25)
		(keepout
			(tracks not_allowed)
			(vias allowed)
			(pads allowed)
			(copperpour not_allowed)
			(footprints allowed)
		)
		(placement
			(enabled no)
			(sheetname "")
		)
		(fill yes
			(thermal_gap 0.5)
			(thermal_bridge_width 0.5)
			(island_removal_mode 0)
		)
		(polygon
			(pts
				(arc
					(start 357.49865 -18.350484)
					(mid 356.950137 -17.80159)
					(end 356.40137 -18.35023)
				)
				(arc
					(start 356.40137 -19.750024)
					(mid 356.95001 -20.298664)
					(end 357.49865 -19.750024)
				)
			)
		)
	)
	(zone
		(layers "In1.Cu" "In3.Cu" "In5.Cu" "In6.Cu" "In8.Cu" "In10.Cu")
		(hatch none 0.5)
		(connect_pads
			(clearance 0)
		)
		(min_thickness 0.25)
		(keepout
			(tracks not_allowed)
			(vias allowed)
			(pads allowed)
			(copperpour not_allowed)
			(footprints allowed)
		)
		(placement
			(enabled no)
			(sheetname "")
		)
		(fill yes
			(thermal_gap 0.5)
			(thermal_bridge_width 0.5)
			(island_removal_mode 0)
		)
		(polygon
			(pts
				(arc
					(start 278.23668 -297.75658)
					(mid 277.68804 -298.30522)
					(end 278.23668 -298.85386)
				)
				(arc
					(start 279.636728 -298.85386)
					(mid 280.185368 -298.30522)
					(end 279.636728 -297.75658)
				)
				(xy 278.236934 -297.75658)
			)
		)
	)
	(zone
		(layers "In1.Cu" "In3.Cu" "In5.Cu" "In6.Cu" "In8.Cu" "In10.Cu")
		(hatch none 0.5)
		(connect_pads
			(clearance 0)
		)
		(min_thickness 0.25)
		(keepout
			(tracks not_allowed)
			(vias allowed)
			(pads allowed)
			(copperpour not_allowed)
			(footprints allowed)
		)
		(placement
			(enabled no)
			(sheetname "")
		)
		(fill yes
			(thermal_gap 0.5)
			(thermal_bridge_width 0.5)
			(island_removal_mode 0)
		)
		(polygon
			(pts
				(arc
					(start 238.374936 -77.84973)
					(mid 238.699802 -76.875132)
					(end 237.725204 -76.550266)
				)
				(xy 237.723934 -76.54798) (xy 235.724192 -77.547978) (xy 235.724192 -77.548232)
				(arc
					(start 235.725208 -77.550264)
					(mid 235.400342 -78.524862)
					(end 236.37494 -78.849728)
				)
				(xy 236.37621 -78.852014) (xy 238.376206 -77.852016)
			)
		)
	)
	(zone
		(layers "In1.Cu" "In3.Cu" "In5.Cu" "In6.Cu" "In8.Cu" "In10.Cu")
		(hatch none 0.5)
		(connect_pads
			(clearance 0)
		)
		(min_thickness 0.25)
		(keepout
			(tracks not_allowed)
			(vias allowed)
			(pads allowed)
			(copperpour not_allowed)
			(footprints allowed)
		)
		(placement
			(enabled no)
			(sheetname "")
		)
		(fill yes
			(thermal_gap 0.5)
			(thermal_bridge_width 0.5)
			(island_removal_mode 0)
		)
		(polygon
			(pts
				(arc
					(start 286.436562 -339.156548)
					(mid 285.887922 -339.705188)
					(end 286.436562 -340.253828)
				)
				(arc
					(start 287.83661 -340.253828)
					(mid 288.38525 -339.705188)
					(end 287.83661 -339.156548)
				)
				(xy 286.436816 -339.156548)
			)
		)
	)
	(zone
		(layers "In1.Cu" "In3.Cu" "In5.Cu" "In6.Cu" "In8.Cu" "In10.Cu")
		(hatch none 0.5)
		(connect_pads
			(clearance 0)
		)
		(min_thickness 0.25)
		(keepout
			(tracks not_allowed)
			(vias allowed)
			(pads allowed)
			(copperpour not_allowed)
			(footprints allowed)
		)
		(placement
			(enabled no)
			(sheetname "")
		)
		(fill yes
			(thermal_gap 0.5)
			(thermal_bridge_width 0.5)
			(island_removal_mode 0)
		)
		(polygon
			(pts
				(arc
					(start 221.348808 -407.000456)
					(mid 220.800295 -406.451562)
					(end 220.251528 -407.000202)
				)
				(arc
					(start 220.251528 -408.399996)
					(mid 220.800168 -408.948636)
					(end 221.348808 -408.399996)
				)
			)
		)
	)
	(zone
		(layers "In1.Cu" "In3.Cu" "In5.Cu" "In6.Cu" "In8.Cu" "In10.Cu")
		(hatch none 0.5)
		(connect_pads
			(clearance 0)
		)
		(min_thickness 0.25)
		(keepout
			(tracks not_allowed)
			(vias allowed)
			(pads allowed)
			(copperpour not_allowed)
			(footprints allowed)
		)
		(placement
			(enabled no)
			(sheetname "")
		)
		(fill yes
			(thermal_gap 0.5)
			(thermal_bridge_width 0.5)
			(island_removal_mode 0)
		)
		(polygon
			(pts
				(arc
					(start 384.498596 -17.350232)
					(mid 383.950083 -16.801338)
					(end 383.401316 -17.349978)
				)
				(arc
					(start 383.401316 -18.750026)
					(mid 383.949956 -19.298666)
					(end 384.498596 -18.750026)
				)
			)
		)
	)
	(zone
		(layers "In1.Cu" "In3.Cu" "In5.Cu" "In6.Cu" "In8.Cu" "In10.Cu")
		(hatch none 0.5)
		(connect_pads
			(clearance 0)
		)
		(min_thickness 0.25)
		(keepout
			(tracks not_allowed)
			(vias allowed)
			(pads allowed)
			(copperpour not_allowed)
			(footprints allowed)
		)
		(placement
			(enabled no)
			(sheetname "")
		)
		(fill yes
			(thermal_gap 0.5)
			(thermal_bridge_width 0.5)
			(island_removal_mode 0)
		)
		(polygon
			(pts
				(arc
					(start 286.436562 -331.95387)
					(mid 285.885382 -332.50505)
					(end 286.436562 -333.05623)
				)
				(arc
					(start 287.83661 -333.05623)
					(mid 288.38779 -332.50505)
					(end 287.83661 -331.95387)
				)
				(xy 286.436816 -331.95387)
			)
		)
	)
	(zone
		(layers "In1.Cu" "In3.Cu" "In5.Cu" "In6.Cu" "In8.Cu" "In10.Cu")
		(hatch none 0.5)
		(connect_pads
			(clearance 0)
		)
		(min_thickness 0.25)
		(keepout
			(tracks not_allowed)
			(vias allowed)
			(pads allowed)
			(copperpour not_allowed)
			(footprints allowed)
		)
		(placement
			(enabled no)
			(sheetname "")
		)
		(fill yes
			(thermal_gap 0.5)
			(thermal_bridge_width 0.5)
			(island_removal_mode 0)
		)
		(polygon
			(pts
				(arc
					(start 271.970754 -312.321448)
					(mid 271.58696 -312.704861)
					(end 271.9705 -313.088528)
				)
				(arc
					(start 273.1135 -313.088528)
					(mid 273.49704 -312.704988)
					(end 273.1135 -312.321448)
				)
			)
		)
	)
	(zone
		(layers "In1.Cu" "In3.Cu" "In5.Cu" "In6.Cu" "In8.Cu" "In10.Cu")
		(hatch none 0.5)
		(connect_pads
			(clearance 0)
		)
		(min_thickness 0.25)
		(keepout
			(tracks not_allowed)
			(vias allowed)
			(pads allowed)
			(copperpour not_allowed)
			(footprints allowed)
		)
		(placement
			(enabled no)
			(sheetname "")
		)
		(fill yes
			(thermal_gap 0.5)
			(thermal_bridge_width 0.5)
			(island_removal_mode 0)
		)
		(polygon
			(pts
				(arc
					(start 478.120202 -158.368492)
					(mid 477.739202 -157.987492)
					(end 477.358202 -158.368492)
				)
				(arc
					(start 477.358202 -159.511238)
					(mid 477.739075 -159.892492)
					(end 478.120202 -159.511492)
				)
			)
		)
	)
	(zone
		(layers "In1.Cu" "In3.Cu" "In5.Cu" "In6.Cu" "In8.Cu" "In10.Cu")
		(hatch none 0.5)
		(connect_pads
			(clearance 0)
		)
		(min_thickness 0.25)
		(keepout
			(tracks not_allowed)
			(vias allowed)
			(pads allowed)
			(copperpour not_allowed)
			(footprints allowed)
		)
		(placement
			(enabled no)
			(sheetname "")
		)
		(fill yes
			(thermal_gap 0.5)
			(thermal_bridge_width 0.5)
			(island_removal_mode 0)
		)
		(polygon
			(pts
				(xy 279.07615 -62.852046) (xy 281.076146 -61.852048)
				(arc
					(start 281.074876 -61.849762)
					(mid 281.399742 -60.875164)
					(end 280.425144 -60.550298)
				)
				(xy 280.423874 -60.548012) (xy 278.424132 -61.54801) (xy 278.424132 -61.548264)
				(arc
					(start 278.425148 -61.550296)
					(mid 278.100282 -62.524894)
					(end 279.07488 -62.84976)
				)
			)
		)
	)
	(zone
		(layers "In1.Cu" "In3.Cu" "In5.Cu" "In6.Cu" "In8.Cu" "In10.Cu")
		(hatch none 0.5)
		(connect_pads
			(clearance 0)
		)
		(min_thickness 0.25)
		(keepout
			(tracks not_allowed)
			(vias allowed)
			(pads allowed)
			(copperpour not_allowed)
			(footprints allowed)
		)
		(placement
			(enabled no)
			(sheetname "")
		)
		(fill yes
			(thermal_gap 0.5)
			(thermal_bridge_width 0.5)
			(island_removal_mode 0)
		)
		(polygon
			(pts
				(arc
					(start 279.236678 -357.156512)
					(mid 278.688038 -357.705152)
					(end 279.236678 -358.253792)
				)
				(arc
					(start 280.636726 -358.253792)
					(mid 281.185366 -357.705152)
					(end 280.636726 -357.156512)
				)
				(xy 279.236932 -357.156512)
			)
		)
	)
	(zone
		(layers "In1.Cu" "In3.Cu" "In5.Cu" "In6.Cu" "In8.Cu" "In10.Cu")
		(hatch none 0.5)
		(connect_pads
			(clearance 0)
		)
		(min_thickness 0.25)
		(keepout
			(tracks not_allowed)
			(vias allowed)
			(pads allowed)
			(copperpour not_allowed)
			(footprints allowed)
		)
		(placement
			(enabled no)
			(sheetname "")
		)
		(fill yes
			(thermal_gap 0.5)
			(thermal_bridge_width 0.5)
			(island_removal_mode 0)
		)
		(polygon
			(pts
				(arc
					(start 388.21995 -162.178746)
					(mid 387.839077 -161.797492)
					(end 387.45795 -162.178492)
				)
				(arc
					(start 387.45795 -163.321492)
					(mid 387.83895 -163.702492)
					(end 388.21995 -163.321492)
				)
			)
		)
	)
	(zone
		(layers "In1.Cu" "In3.Cu" "In5.Cu" "In6.Cu" "In8.Cu" "In10.Cu")
		(hatch none 0.5)
		(connect_pads
			(clearance 0)
		)
		(min_thickness 0.25)
		(keepout
			(tracks not_allowed)
			(vias allowed)
			(pads allowed)
			(copperpour not_allowed)
			(footprints allowed)
		)
		(placement
			(enabled no)
			(sheetname "")
		)
		(fill yes
			(thermal_gap 0.5)
			(thermal_bridge_width 0.5)
			(island_removal_mode 0)
		)
		(polygon
			(pts
				(arc
					(start 127.53975 -277.17877)
					(mid 127.158877 -276.797516)
					(end 126.77775 -277.178516)
				)
				(arc
					(start 126.77775 -278.321516)
					(mid 127.15875 -278.702516)
					(end 127.53975 -278.321516)
				)
			)
		)
	)
	(zone
		(layers "In1.Cu" "In3.Cu" "In5.Cu" "In6.Cu" "In8.Cu" "In10.Cu")
		(hatch none 0.5)
		(connect_pads
			(clearance 0)
		)
		(min_thickness 0.25)
		(keepout
			(tracks not_allowed)
			(vias allowed)
			(pads allowed)
			(copperpour not_allowed)
			(footprints allowed)
		)
		(placement
			(enabled no)
			(sheetname "")
		)
		(fill yes
			(thermal_gap 0.5)
			(thermal_bridge_width 0.5)
			(island_removal_mode 0)
		)
		(polygon
			(pts
				(arc
					(start 283.563314 -70.572884)
					(mid 282.622752 -70.886574)
					(end 282.936442 -71.827136)
				)
				(arc
					(start 284.928056 -72.822816)
					(mid 285.874832 -72.517631)
					(end 285.56331 -71.572882)
				)
			)
		)
	)
	(zone
		(layers "In1.Cu" "In3.Cu" "In5.Cu" "In6.Cu" "In8.Cu" "In10.Cu")
		(hatch none 0.5)
		(connect_pads
			(clearance 0)
		)
		(min_thickness 0.25)
		(keepout
			(tracks not_allowed)
			(vias allowed)
			(pads allowed)
			(copperpour not_allowed)
			(footprints allowed)
		)
		(placement
			(enabled no)
			(sheetname "")
		)
		(fill yes
			(thermal_gap 0.5)
			(thermal_bridge_width 0.5)
			(island_removal_mode 0)
		)
		(polygon
			(pts
				(arc
					(start 283.563314 -126.872746)
					(mid 282.622752 -127.186436)
					(end 282.936442 -128.126998)
				)
				(arc
					(start 284.928056 -129.122678)
					(mid 285.874832 -128.817493)
					(end 285.56331 -127.872744)
				)
			)
		)
	)
	(zone
		(layers "In1.Cu" "In3.Cu" "In5.Cu" "In6.Cu" "In8.Cu" "In10.Cu")
		(hatch none 0.5)
		(connect_pads
			(clearance 0)
		)
		(min_thickness 0.25)
		(keepout
			(tracks not_allowed)
			(vias allowed)
			(pads allowed)
			(copperpour not_allowed)
			(footprints allowed)
		)
		(placement
			(enabled no)
			(sheetname "")
		)
		(fill yes
			(thermal_gap 0.5)
			(thermal_bridge_width 0.5)
			(island_removal_mode 0)
		)
		(polygon
			(pts
				(arc
					(start 446.5701 -273.368516)
					(mid 446.1891 -272.987516)
					(end 445.8081 -273.368516)
				)
				(arc
					(start 445.8081 -274.511262)
					(mid 446.188973 -274.892516)
					(end 446.5701 -274.511516)
				)
			)
		)
	)
	(zone
		(layers "In1.Cu" "In3.Cu" "In5.Cu" "In6.Cu" "In8.Cu" "In10.Cu")
		(hatch none 0.5)
		(connect_pads
			(clearance 0)
		)
		(min_thickness 0.25)
		(keepout
			(tracks not_allowed)
			(vias allowed)
			(pads allowed)
			(copperpour not_allowed)
			(footprints allowed)
		)
		(placement
			(enabled no)
			(sheetname "")
		)
		(fill yes
			(thermal_gap 0.5)
			(thermal_bridge_width 0.5)
			(island_removal_mode 0)
		)
		(polygon
			(pts
				(arc
					(start 325.12 -162.178746)
					(mid 324.739127 -161.797492)
					(end 324.358 -162.178492)
				)
				(arc
					(start 324.358 -163.321492)
					(mid 324.739 -163.702492)
					(end 325.12 -163.321492)
				)
			)
		)
	)
	(zone
		(layers "In1.Cu" "In3.Cu" "In5.Cu" "In6.Cu" "In8.Cu" "In10.Cu")
		(hatch none 0.5)
		(connect_pads
			(clearance 0)
		)
		(min_thickness 0.25)
		(keepout
			(tracks not_allowed)
			(vias allowed)
			(pads allowed)
			(copperpour not_allowed)
			(footprints allowed)
		)
		(placement
			(enabled no)
			(sheetname "")
		)
		(fill yes
			(thermal_gap 0.5)
			(thermal_bridge_width 0.5)
			(island_removal_mode 0)
		)
		(polygon
			(pts
				(arc
					(start 359.298748 -17.350232)
					(mid 358.750235 -16.801338)
					(end 358.201468 -17.349978)
				)
				(arc
					(start 358.201468 -18.750026)
					(mid 358.750108 -19.298666)
					(end 359.298748 -18.750026)
				)
			)
		)
	)
	(zone
		(layers "In1.Cu" "In3.Cu" "In5.Cu" "In6.Cu" "In8.Cu" "In10.Cu")
		(hatch none 0.5)
		(connect_pads
			(clearance 0)
		)
		(min_thickness 0.25)
		(keepout
			(tracks not_allowed)
			(vias allowed)
			(pads allowed)
			(copperpour not_allowed)
			(footprints allowed)
		)
		(placement
			(enabled no)
			(sheetname "")
		)
		(fill yes
			(thermal_gap 0.5)
			(thermal_bridge_width 0.5)
			(island_removal_mode 0)
		)
		(polygon
			(pts
				(arc
					(start 286.436562 -299.556424)
					(mid 285.887922 -300.105064)
					(end 286.436562 -300.653704)
				)
				(arc
					(start 287.83661 -300.653704)
					(mid 288.38525 -300.105064)
					(end 287.83661 -299.556424)
				)
				(xy 286.436816 -299.556424)
			)
		)
	)
	(zone
		(layers "In1.Cu" "In3.Cu" "In5.Cu" "In6.Cu" "In8.Cu" "In10.Cu")
		(hatch none 0.5)
		(connect_pads
			(clearance 0)
		)
		(min_thickness 0.25)
		(keepout
			(tracks not_allowed)
			(vias allowed)
			(pads allowed)
			(copperpour not_allowed)
			(footprints allowed)
		)
		(placement
			(enabled no)
			(sheetname "")
		)
		(fill yes
			(thermal_gap 0.5)
			(thermal_bridge_width 0.5)
			(island_removal_mode 0)
		)
		(polygon
			(pts
				(arc
					(start 133.09854 -18.35023)
					(mid 132.5499 -17.80159)
					(end 132.00126 -18.35023)
				)
				(arc
					(start 132.00126 -19.74977)
					(mid 132.549773 -20.298664)
					(end 133.09854 -19.750024)
				)
			)
		)
	)
	(zone
		(layers "In1.Cu" "In3.Cu" "In5.Cu" "In6.Cu" "In8.Cu" "In10.Cu")
		(hatch none 0.5)
		(connect_pads
			(clearance 0)
		)
		(min_thickness 0.25)
		(keepout
			(tracks not_allowed)
			(vias allowed)
			(pads allowed)
			(copperpour not_allowed)
			(footprints allowed)
		)
		(placement
			(enabled no)
			(sheetname "")
		)
		(fill yes
			(thermal_gap 0.5)
			(thermal_bridge_width 0.5)
			(island_removal_mode 0)
		)
		(polygon
			(pts
				(arc
					(start 323.824346 -46.818042)
					(mid 324.2056 -46.437169)
					(end 323.8246 -46.056042)
				)
				(arc
					(start 322.6816 -46.056042)
					(mid 322.3006 -46.437042)
					(end 322.6816 -46.818042)
				)
			)
		)
	)
	(zone
		(layers "In1.Cu" "In3.Cu" "In5.Cu" "In6.Cu" "In8.Cu" "In10.Cu")
		(hatch none 0.5)
		(connect_pads
			(clearance 0)
		)
		(min_thickness 0.25)
		(keepout
			(tracks not_allowed)
			(vias allowed)
			(pads allowed)
			(copperpour not_allowed)
			(footprints allowed)
		)
		(placement
			(enabled no)
			(sheetname "")
		)
		(fill yes
			(thermal_gap 0.5)
			(thermal_bridge_width 0.5)
			(island_removal_mode 0)
		)
		(polygon
			(pts
				(arc
					(start 283.563314 -166.872666)
					(mid 282.622752 -167.186356)
					(end 282.936442 -168.126918)
				)
				(arc
					(start 284.928056 -169.122598)
					(mid 285.874832 -168.817413)
					(end 285.56331 -167.872664)
				)
			)
		)
	)
	(zone
		(layers "In1.Cu" "In3.Cu" "In5.Cu" "In6.Cu" "In8.Cu" "In10.Cu")
		(hatch none 0.5)
		(connect_pads
			(clearance 0)
		)
		(min_thickness 0.25)
		(keepout
			(tracks not_allowed)
			(vias allowed)
			(pads allowed)
			(copperpour not_allowed)
			(footprints allowed)
		)
		(placement
			(enabled no)
			(sheetname "")
		)
		(fill yes
			(thermal_gap 0.5)
			(thermal_bridge_width 0.5)
			(island_removal_mode 0)
		)
		(polygon
			(pts
				(arc
					(start 134.898638 -17.350232)
					(mid 134.350125 -16.801338)
					(end 133.801358 -17.349978)
				)
				(arc
					(start 133.801358 -18.750026)
					(mid 134.349998 -19.298666)
					(end 134.898638 -18.750026)
				)
			)
		)
	)
	(zone
		(layers "In1.Cu" "In3.Cu" "In5.Cu" "In6.Cu" "In8.Cu" "In10.Cu")
		(hatch none 0.5)
		(connect_pads
			(clearance 0)
		)
		(min_thickness 0.25)
		(keepout
			(tracks not_allowed)
			(vias allowed)
			(pads allowed)
			(copperpour not_allowed)
			(footprints allowed)
		)
		(placement
			(enabled no)
			(sheetname "")
		)
		(fill yes
			(thermal_gap 0.5)
			(thermal_bridge_width 0.5)
			(island_removal_mode 0)
		)
		(polygon
			(pts
				(arc
					(start 223.148652 -416.800284)
					(mid 222.600139 -416.25139)
					(end 222.051372 -416.80003)
				)
				(arc
					(start 222.051372 -418.200078)
					(mid 222.600012 -418.748718)
					(end 223.148652 -418.200078)
				)
			)
		)
	)
	(zone
		(layers "In1.Cu" "In3.Cu" "In5.Cu" "In6.Cu" "In8.Cu" "In10.Cu")
		(hatch none 0.5)
		(connect_pads
			(clearance 0)
		)
		(min_thickness 0.25)
		(keepout
			(tracks not_allowed)
			(vias allowed)
			(pads allowed)
			(copperpour not_allowed)
			(footprints allowed)
		)
		(placement
			(enabled no)
			(sheetname "")
		)
		(fill yes
			(thermal_gap 0.5)
			(thermal_bridge_width 0.5)
			(island_removal_mode 0)
		)
		(polygon
			(pts
				(arc
					(start 136.698736 -21.950426)
					(mid 136.150223 -21.401532)
					(end 135.601456 -21.950172)
				)
				(arc
					(start 135.601456 -23.35022)
					(mid 136.150096 -23.89886)
					(end 136.698736 -23.35022)
				)
			)
		)
	)
	(zone
		(layers "In1.Cu" "In3.Cu" "In5.Cu" "In6.Cu" "In8.Cu" "In10.Cu")
		(hatch none 0.5)
		(connect_pads
			(clearance 0)
		)
		(min_thickness 0.25)
		(keepout
			(tracks not_allowed)
			(vias allowed)
			(pads allowed)
			(copperpour not_allowed)
			(footprints allowed)
		)
		(placement
			(enabled no)
			(sheetname "")
		)
		(fill yes
			(thermal_gap 0.5)
			(thermal_bridge_width 0.5)
			(island_removal_mode 0)
		)
		(polygon
			(pts
				(arc
					(start 138.49858 -17.350232)
					(mid 137.950067 -16.801338)
					(end 137.4013 -17.349978)
				)
				(arc
					(start 137.4013 -18.750026)
					(mid 137.94994 -19.298666)
					(end 138.49858 -18.750026)
				)
			)
		)
	)
	(zone
		(layers "In1.Cu" "In3.Cu" "In5.Cu" "In6.Cu" "In8.Cu" "In10.Cu")
		(hatch none 0.5)
		(connect_pads
			(clearance 0)
		)
		(min_thickness 0.25)
		(keepout
			(tracks not_allowed)
			(vias allowed)
			(pads allowed)
			(copperpour not_allowed)
			(footprints allowed)
		)
		(placement
			(enabled no)
			(sheetname "")
		)
		(fill yes
			(thermal_gap 0.5)
			(thermal_bridge_width 0.5)
			(island_removal_mode 0)
		)
		(polygon
			(pts
				(arc
					(start 285.436564 -340.956392)
					(mid 284.887924 -341.505032)
					(end 285.436564 -342.053672)
				)
				(arc
					(start 286.836612 -342.053672)
					(mid 287.385252 -341.505032)
					(end 286.836612 -340.956392)
				)
				(xy 285.436818 -340.956392)
			)
		)
	)
	(zone
		(layers "In1.Cu" "In3.Cu" "In5.Cu" "In6.Cu" "In8.Cu" "In10.Cu")
		(hatch none 0.5)
		(connect_pads
			(clearance 0)
		)
		(min_thickness 0.25)
		(keepout
			(tracks not_allowed)
			(vias allowed)
			(pads allowed)
			(copperpour not_allowed)
			(footprints allowed)
		)
		(placement
			(enabled no)
			(sheetname "")
		)
		(fill yes
			(thermal_gap 0.5)
			(thermal_bridge_width 0.5)
			(island_removal_mode 0)
		)
		(polygon
			(pts
				(arc
					(start 64.4398 -162.178746)
					(mid 64.058927 -161.797492)
					(end 63.6778 -162.178492)
				)
				(arc
					(start 63.6778 -163.321492)
					(mid 64.0588 -163.702492)
					(end 64.4398 -163.321492)
				)
			)
		)
	)
	(zone
		(layers "In1.Cu" "In3.Cu" "In5.Cu" "In6.Cu" "In8.Cu" "In10.Cu")
		(hatch none 0.5)
		(connect_pads
			(clearance 0)
		)
		(min_thickness 0.25)
		(keepout
			(tracks not_allowed)
			(vias allowed)
			(pads allowed)
			(copperpour not_allowed)
			(footprints allowed)
		)
		(placement
			(enabled no)
			(sheetname "")
		)
		(fill yes
			(thermal_gap 0.5)
			(thermal_bridge_width 0.5)
			(island_removal_mode 0)
		)
		(polygon
			(pts
				(arc
					(start 271.970754 -308.721506)
					(mid 271.58696 -309.104919)
					(end 271.9705 -309.488586)
				)
				(arc
					(start 273.1135 -309.488586)
					(mid 273.49704 -309.105046)
					(end 273.1135 -308.721506)
				)
			)
		)
	)
	(zone
		(layers "In1.Cu" "In3.Cu" "In5.Cu" "In6.Cu" "In8.Cu" "In10.Cu")
		(hatch none 0.5)
		(connect_pads
			(clearance 0)
		)
		(min_thickness 0.25)
		(keepout
			(tracks not_allowed)
			(vias allowed)
			(pads allowed)
			(copperpour not_allowed)
			(footprints allowed)
		)
		(placement
			(enabled no)
			(sheetname "")
		)
		(fill yes
			(thermal_gap 0.5)
			(thermal_bridge_width 0.5)
			(island_removal_mode 0)
		)
		(polygon
			(pts
				(arc
					(start 286.436562 -310.353964)
					(mid 285.885382 -310.905144)
					(end 286.436562 -311.456324)
				)
				(arc
					(start 287.83661 -311.456324)
					(mid 288.38779 -310.905144)
					(end 287.83661 -310.353964)
				)
				(xy 286.436816 -310.353964)
			)
		)
	)
	(zone
		(layers "In1.Cu" "In3.Cu" "In5.Cu" "In6.Cu" "In8.Cu" "In10.Cu")
		(hatch none 0.5)
		(connect_pads
			(clearance 0)
		)
		(min_thickness 0.25)
		(keepout
			(tracks not_allowed)
			(vias allowed)
			(pads allowed)
			(copperpour not_allowed)
			(footprints allowed)
		)
		(placement
			(enabled no)
			(sheetname "")
		)
		(fill yes
			(thermal_gap 0.5)
			(thermal_bridge_width 0.5)
			(island_removal_mode 0)
		)
		(polygon
			(pts
				(arc
					(start 366.498632 -20.950428)
					(mid 365.950119 -20.401534)
					(end 365.401352 -20.950174)
				)
				(arc
					(start 365.401352 -22.350222)
					(mid 365.949992 -22.898862)
					(end 366.498632 -22.350222)
				)
			)
		)
	)
	(zone
		(layers "In1.Cu" "In3.Cu" "In5.Cu" "In6.Cu" "In8.Cu" "In10.Cu")
		(hatch none 0.5)
		(connect_pads
			(clearance 0)
		)
		(min_thickness 0.25)
		(keepout
			(tracks not_allowed)
			(vias allowed)
			(pads allowed)
			(copperpour not_allowed)
			(footprints allowed)
		)
		(placement
			(enabled no)
			(sheetname "")
		)
		(fill yes
			(thermal_gap 0.5)
			(thermal_bridge_width 0.5)
			(island_removal_mode 0)
		)
		(polygon
			(pts
				(arc
					(start 64.4398 -47.178722)
					(mid 64.058927 -46.797468)
					(end 63.6778 -47.178468)
				)
				(arc
					(start 63.6778 -48.321468)
					(mid 64.0588 -48.702468)
					(end 64.4398 -48.321468)
				)
			)
		)
	)
	(zone
		(layers "In1.Cu" "In3.Cu" "In5.Cu" "In6.Cu" "In8.Cu" "In10.Cu")
		(hatch none 0.5)
		(connect_pads
			(clearance 0)
		)
		(min_thickness 0.25)
		(keepout
			(tracks not_allowed)
			(vias allowed)
			(pads allowed)
			(copperpour not_allowed)
			(footprints allowed)
		)
		(placement
			(enabled no)
			(sheetname "")
		)
		(fill yes
			(thermal_gap 0.5)
			(thermal_bridge_width 0.5)
			(island_removal_mode 0)
		)
		(polygon
			(pts
				(arc
					(start 383.47015 -158.368492)
					(mid 383.08915 -157.987492)
					(end 382.70815 -158.368492)
				)
				(arc
					(start 382.70815 -159.511238)
					(mid 383.089023 -159.892492)
					(end 383.47015 -159.511492)
				)
			)
		)
	)
	(zone
		(layers "In1.Cu" "In3.Cu" "In5.Cu" "In6.Cu" "In8.Cu" "In10.Cu")
		(hatch none 0.5)
		(connect_pads
			(clearance 0)
		)
		(min_thickness 0.25)
		(keepout
			(tracks not_allowed)
			(vias allowed)
			(pads allowed)
			(copperpour not_allowed)
			(footprints allowed)
		)
		(placement
			(enabled no)
			(sheetname "")
		)
		(fill yes
			(thermal_gap 0.5)
			(thermal_bridge_width 0.5)
			(island_removal_mode 0)
		)
		(polygon
			(pts
				(arc
					(start 190.639954 -47.178722)
					(mid 190.259081 -46.797468)
					(end 189.877954 -47.178468)
				)
				(arc
					(start 189.877954 -48.321468)
					(mid 190.258954 -48.702468)
					(end 190.639954 -48.321468)
				)
			)
		)
	)
	(zone
		(layers "In1.Cu" "In3.Cu" "In5.Cu" "In6.Cu" "In8.Cu" "In10.Cu")
		(hatch none 0.5)
		(connect_pads
			(clearance 0)
		)
		(min_thickness 0.25)
		(keepout
			(tracks not_allowed)
			(vias allowed)
			(pads allowed)
			(copperpour not_allowed)
			(footprints allowed)
		)
		(placement
			(enabled no)
			(sheetname "")
		)
		(fill yes
			(thermal_gap 0.5)
			(thermal_bridge_width 0.5)
			(island_removal_mode 0)
		)
		(polygon
			(pts
				(arc
					(start 362.89869 -20.950428)
					(mid 362.350177 -20.401534)
					(end 361.80141 -20.950174)
				)
				(arc
					(start 361.80141 -22.350222)
					(mid 362.35005 -22.898862)
					(end 362.89869 -22.350222)
				)
			)
		)
	)
	(zone
		(layers "In1.Cu" "In3.Cu" "In5.Cu" "In6.Cu" "In8.Cu" "In10.Cu")
		(hatch none 0.5)
		(connect_pads
			(clearance 0)
		)
		(min_thickness 0.25)
		(keepout
			(tracks not_allowed)
			(vias allowed)
			(pads allowed)
			(copperpour not_allowed)
			(footprints allowed)
		)
		(placement
			(enabled no)
			(sheetname "")
		)
		(fill yes
			(thermal_gap 0.5)
			(thermal_bridge_width 0.5)
			(island_removal_mode 0)
		)
		(polygon
			(pts
				(arc
					(start 279.236678 -303.15662)
					(mid 278.688038 -303.70526)
					(end 279.236678 -304.2539)
				)
				(arc
					(start 280.636726 -304.2539)
					(mid 281.185366 -303.70526)
					(end 280.636726 -303.15662)
				)
				(xy 279.236932 -303.15662)
			)
		)
	)
	(zone
		(layers "In1.Cu" "In3.Cu" "In5.Cu" "In6.Cu" "In8.Cu" "In10.Cu")
		(hatch none 0.5)
		(connect_pads
			(clearance 0)
		)
		(min_thickness 0.25)
		(keepout
			(tracks not_allowed)
			(vias allowed)
			(pads allowed)
			(copperpour not_allowed)
			(footprints allowed)
		)
		(placement
			(enabled no)
			(sheetname "")
		)
		(fill yes
			(thermal_gap 0.5)
			(thermal_bridge_width 0.5)
			(island_removal_mode 0)
		)
		(polygon
			(pts
				(arc
					(start 286.436562 -357.153972)
					(mid 285.885382 -357.705152)
					(end 286.436562 -358.256332)
				)
				(arc
					(start 287.83661 -358.256332)
					(mid 288.38779 -357.705152)
					(end 287.83661 -357.153972)
				)
				(xy 286.436816 -357.153972)
			)
		)
	)
	(zone
		(layers "In1.Cu" "In3.Cu" "In5.Cu" "In6.Cu" "In8.Cu" "In10.Cu")
		(hatch none 0.5)
		(connect_pads
			(clearance 0)
		)
		(min_thickness 0.25)
		(keepout
			(tracks not_allowed)
			(vias allowed)
			(pads allowed)
			(copperpour not_allowed)
			(footprints allowed)
		)
		(placement
			(enabled no)
			(sheetname "")
		)
		(fill yes
			(thermal_gap 0.5)
			(thermal_bridge_width 0.5)
			(island_removal_mode 0)
		)
		(polygon
			(pts
				(arc
					(start 283.563314 -78.572868)
					(mid 282.622752 -78.886558)
					(end 282.936442 -79.82712)
				)
				(arc
					(start 284.928056 -80.8228)
					(mid 285.874832 -80.517615)
					(end 285.56331 -79.572866)
				)
			)
		)
	)
	(zone
		(layers "In1.Cu" "In3.Cu" "In5.Cu" "In6.Cu" "In8.Cu" "In10.Cu")
		(hatch none 0.5)
		(connect_pads
			(clearance 0)
		)
		(min_thickness 0.25)
		(keepout
			(tracks not_allowed)
			(vias allowed)
			(pads allowed)
			(copperpour not_allowed)
			(footprints allowed)
		)
		(placement
			(enabled no)
			(sheetname "")
		)
		(fill yes
			(thermal_gap 0.5)
			(thermal_bridge_width 0.5)
			(island_removal_mode 0)
		)
		(polygon
			(pts
				(xy 236.37621 -18.852134) (xy 238.376206 -17.852136)
				(arc
					(start 238.374936 -17.84985)
					(mid 238.699802 -16.875252)
					(end 237.725204 -16.550386)
				)
				(xy 237.723934 -16.5481) (xy 235.724192 -17.548098) (xy 235.724192 -17.548352)
				(arc
					(start 235.725208 -17.550384)
					(mid 235.400342 -18.524982)
					(end 236.37494 -18.849848)
				)
			)
		)
	)
	(zone
		(layers "In1.Cu" "In3.Cu" "In5.Cu" "In6.Cu" "In8.Cu" "In10.Cu")
		(hatch none 0.5)
		(connect_pads
			(clearance 0)
		)
		(min_thickness 0.25)
		(keepout
			(tracks not_allowed)
			(vias allowed)
			(pads allowed)
			(copperpour not_allowed)
			(footprints allowed)
		)
		(placement
			(enabled no)
			(sheetname "")
		)
		(fill yes
			(thermal_gap 0.5)
			(thermal_bridge_width 0.5)
			(island_removal_mode 0)
		)
		(polygon
			(pts
				(arc
					(start 219.54871 -406.000204)
					(mid 219.000197 -405.45131)
					(end 218.45143 -405.99995)
				)
				(arc
					(start 218.45143 -407.399998)
					(mid 219.00007 -407.948638)
					(end 219.54871 -407.399998)
				)
			)
		)
	)
	(zone
		(layers "In1.Cu" "In3.Cu" "In5.Cu" "In6.Cu" "In8.Cu" "In10.Cu")
		(hatch none 0.5)
		(connect_pads
			(clearance 0)
		)
		(min_thickness 0.25)
		(keepout
			(tracks not_allowed)
			(vias allowed)
			(pads allowed)
			(copperpour not_allowed)
			(footprints allowed)
		)
		(placement
			(enabled no)
			(sheetname "")
		)
		(fill yes
			(thermal_gap 0.5)
			(thermal_bridge_width 0.5)
			(island_removal_mode 0)
		)
		(polygon
			(pts
				(xy 279.07615 -82.852006) (xy 281.076146 -81.852008)
				(arc
					(start 281.074876 -81.849722)
					(mid 281.399742 -80.875124)
					(end 280.425144 -80.550258)
				)
				(xy 280.423874 -80.547972) (xy 278.424132 -81.54797) (xy 278.424132 -81.548224)
				(arc
					(start 278.425148 -81.550256)
					(mid 278.100282 -82.524854)
					(end 279.07488 -82.84972)
				)
			)
		)
	)
	(zone
		(layers "In1.Cu" "In3.Cu" "In5.Cu" "In6.Cu" "In8.Cu" "In10.Cu")
		(hatch none 0.5)
		(connect_pads
			(clearance 0)
		)
		(min_thickness 0.25)
		(keepout
			(tracks not_allowed)
			(vias allowed)
			(pads allowed)
			(copperpour not_allowed)
			(footprints allowed)
		)
		(placement
			(enabled no)
			(sheetname "")
		)
		(fill yes
			(thermal_gap 0.5)
			(thermal_bridge_width 0.5)
			(island_removal_mode 0)
		)
		(polygon
			(pts
				(arc
					(start 271.970754 -306.921408)
					(mid 271.58696 -307.304821)
					(end 271.9705 -307.688488)
				)
				(arc
					(start 273.1135 -307.688488)
					(mid 273.49704 -307.304948)
					(end 273.1135 -306.921408)
				)
			)
		)
	)
	(zone
		(layers "In1.Cu" "In3.Cu" "In5.Cu" "In6.Cu" "In8.Cu" "In10.Cu")
		(hatch none 0.5)
		(connect_pads
			(clearance 0)
		)
		(min_thickness 0.25)
		(keepout
			(tracks not_allowed)
			(vias allowed)
			(pads allowed)
			(copperpour not_allowed)
			(footprints allowed)
		)
		(placement
			(enabled no)
			(sheetname "")
		)
		(fill yes
			(thermal_gap 0.5)
			(thermal_bridge_width 0.5)
			(island_removal_mode 0)
		)
		(polygon
			(pts
				(arc
					(start 350.764856 -42.240962)
					(mid 350.378522 -42.626915)
					(end 350.764602 -43.013122)
				)
				(arc
					(start 351.907602 -43.013122)
					(mid 352.293682 -42.627042)
					(end 351.907602 -42.240962)
				)
			)
		)
	)
	(zone
		(layers "In1.Cu" "In3.Cu" "In5.Cu" "In6.Cu" "In8.Cu" "In10.Cu")
		(hatch none 0.5)
		(connect_pads
			(clearance 0)
		)
		(min_thickness 0.25)
		(keepout
			(tracks not_allowed)
			(vias allowed)
			(pads allowed)
			(copperpour not_allowed)
			(footprints allowed)
		)
		(placement
			(enabled no)
			(sheetname "")
		)
		(fill yes
			(thermal_gap 0.5)
			(thermal_bridge_width 0.5)
			(island_removal_mode 0)
		)
		(polygon
			(pts
				(arc
					(start 285.436564 -250.551188)
					(mid 284.885384 -251.102368)
					(end 285.436564 -251.653548)
				)
				(arc
					(start 286.836612 -251.653548)
					(mid 287.387792 -251.102368)
					(end 286.836612 -250.551188)
				)
				(xy 285.436818 -250.551188)
			)
		)
	)
	(zone
		(layers "In1.Cu" "In3.Cu" "In5.Cu" "In6.Cu" "In8.Cu" "In10.Cu")
		(hatch none 0.5)
		(connect_pads
			(clearance 0)
		)
		(min_thickness 0.25)
		(keepout
			(tracks not_allowed)
			(vias allowed)
			(pads allowed)
			(copperpour not_allowed)
			(footprints allowed)
		)
		(placement
			(enabled no)
			(sheetname "")
		)
		(fill yes
			(thermal_gap 0.5)
			(thermal_bridge_width 0.5)
			(island_removal_mode 0)
		)
		(polygon
			(pts
				(arc
					(start 285.436564 -322.956428)
					(mid 284.887924 -323.505068)
					(end 285.436564 -324.053708)
				)
				(arc
					(start 286.836612 -324.053708)
					(mid 287.385252 -323.505068)
					(end 286.836612 -322.956428)
				)
				(xy 285.436818 -322.956428)
			)
		)
	)
	(zone
		(layers "In1.Cu" "In3.Cu" "In5.Cu" "In6.Cu" "In8.Cu" "In10.Cu")
		(hatch none 0.5)
		(connect_pads
			(clearance 0)
		)
		(min_thickness 0.25)
		(keepout
			(tracks not_allowed)
			(vias allowed)
			(pads allowed)
			(copperpour not_allowed)
			(footprints allowed)
		)
		(placement
			(enabled no)
			(sheetname "")
		)
		(fill yes
			(thermal_gap 0.5)
			(thermal_bridge_width 0.5)
			(island_removal_mode 0)
		)
		(polygon
			(pts
				(arc
					(start 242.222782 -165.154102)
					(mid 243.204238 -164.82695)
					(end 242.877086 -163.845494)
				)
				(arc
					(start 240.877344 -162.845496)
					(mid 239.895939 -163.172546)
					(end 240.222786 -164.154104)
				)
			)
		)
	)
	(zone
		(layers "In1.Cu" "In3.Cu" "In5.Cu" "In6.Cu" "In8.Cu" "In10.Cu")
		(hatch none 0.5)
		(connect_pads
			(clearance 0)
		)
		(min_thickness 0.25)
		(keepout
			(tracks not_allowed)
			(vias allowed)
			(pads allowed)
			(copperpour not_allowed)
			(footprints allowed)
		)
		(placement
			(enabled no)
			(sheetname "")
		)
		(fill yes
			(thermal_gap 0.5)
			(thermal_bridge_width 0.5)
			(island_removal_mode 0)
		)
		(polygon
			(pts
				(arc
					(start 210.548728 -414.20034)
					(mid 210.000215 -413.651446)
					(end 209.451448 -414.200086)
				)
				(arc
					(start 209.451448 -415.600134)
					(mid 210.000088 -416.148774)
					(end 210.548728 -415.600134)
				)
			)
		)
	)
	(zone
		(layers "In1.Cu" "In3.Cu" "In5.Cu" "In6.Cu" "In8.Cu" "In10.Cu")
		(hatch none 0.5)
		(connect_pads
			(clearance 0)
		)
		(min_thickness 0.25)
		(keepout
			(tracks not_allowed)
			(vias allowed)
			(pads allowed)
			(copperpour not_allowed)
			(footprints allowed)
		)
		(placement
			(enabled no)
			(sheetname "")
		)
		(fill yes
			(thermal_gap 0.5)
			(thermal_bridge_width 0.5)
			(island_removal_mode 0)
		)
		(polygon
			(pts
				(arc
					(start 109.698536 -17.350232)
					(mid 109.150023 -16.801338)
					(end 108.601256 -17.349978)
				)
				(arc
					(start 108.601256 -18.750026)
					(mid 109.149896 -19.298666)
					(end 109.698536 -18.750026)
				)
			)
		)
	)
	(zone
		(layers "In1.Cu" "In3.Cu" "In5.Cu" "In6.Cu" "In8.Cu" "In10.Cu")
		(hatch none 0.5)
		(connect_pads
			(clearance 0)
		)
		(min_thickness 0.25)
		(keepout
			(tracks not_allowed)
			(vias allowed)
			(pads allowed)
			(copperpour not_allowed)
			(footprints allowed)
		)
		(placement
			(enabled no)
			(sheetname "")
		)
		(fill yes
			(thermal_gap 0.5)
			(thermal_bridge_width 0.5)
			(island_removal_mode 0)
		)
		(polygon
			(pts
				(arc
					(start 364.698534 -21.950426)
					(mid 364.150021 -21.401532)
					(end 363.601254 -21.950172)
				)
				(arc
					(start 363.601254 -23.35022)
					(mid 364.149894 -23.89886)
					(end 364.698534 -23.35022)
				)
			)
		)
	)
	(zone
		(layers "In1.Cu" "In3.Cu" "In5.Cu" "In6.Cu" "In8.Cu" "In10.Cu")
		(hatch none 0.5)
		(connect_pads
			(clearance 0)
		)
		(min_thickness 0.25)
		(keepout
			(tracks not_allowed)
			(vias allowed)
			(pads allowed)
			(copperpour not_allowed)
			(footprints allowed)
		)
		(placement
			(enabled no)
			(sheetname "")
		)
		(fill yes
			(thermal_gap 0.5)
			(thermal_bridge_width 0.5)
			(island_removal_mode 0)
		)
		(polygon
			(pts
				(arc
					(start 240.863374 -78.572868)
					(mid 239.922812 -78.886558)
					(end 240.236502 -79.82712)
				)
				(arc
					(start 242.228116 -80.8228)
					(mid 243.174892 -80.517615)
					(end 242.86337 -79.572866)
				)
			)
		)
	)
	(zone
		(layers "In1.Cu" "In3.Cu" "In5.Cu" "In6.Cu" "In8.Cu" "In10.Cu")
		(hatch none 0.5)
		(connect_pads
			(clearance 0)
		)
		(min_thickness 0.25)
		(keepout
			(tracks not_allowed)
			(vias allowed)
			(pads allowed)
			(copperpour not_allowed)
			(footprints allowed)
		)
		(placement
			(enabled no)
			(sheetname "")
		)
		(fill yes
			(thermal_gap 0.5)
			(thermal_bridge_width 0.5)
			(island_removal_mode 0)
		)
		(polygon
			(pts
				(arc
					(start 95.989902 -47.178722)
					(mid 95.609029 -46.797468)
					(end 95.227902 -47.178468)
				)
				(arc
					(start 95.227902 -48.321468)
					(mid 95.608902 -48.702468)
					(end 95.989902 -48.321468)
				)
			)
		)
	)
	(zone
		(layers "In1.Cu" "In3.Cu" "In5.Cu" "In6.Cu" "In8.Cu" "In10.Cu")
		(hatch none 0.5)
		(connect_pads
			(clearance 0)
		)
		(min_thickness 0.25)
		(keepout
			(tracks not_allowed)
			(vias allowed)
			(pads allowed)
			(copperpour not_allowed)
			(footprints allowed)
		)
		(placement
			(enabled no)
			(sheetname "")
		)
		(fill yes
			(thermal_gap 0.5)
			(thermal_bridge_width 0.5)
			(island_removal_mode 0)
		)
		(polygon
			(pts
				(arc
					(start 388.098538 -20.950428)
					(mid 387.550025 -20.401534)
					(end 387.001258 -20.950174)
				)
				(arc
					(start 387.001258 -22.350222)
					(mid 387.549898 -22.898862)
					(end 388.098538 -22.350222)
				)
			)
		)
	)
	(zone
		(layers "In1.Cu" "In3.Cu" "In5.Cu" "In6.Cu" "In8.Cu" "In10.Cu")
		(hatch none 0.5)
		(connect_pads
			(clearance 0)
		)
		(min_thickness 0.25)
		(keepout
			(tracks not_allowed)
			(vias allowed)
			(pads allowed)
			(copperpour not_allowed)
			(footprints allowed)
		)
		(placement
			(enabled no)
			(sheetname "")
		)
		(fill yes
			(thermal_gap 0.5)
			(thermal_bridge_width 0.5)
			(island_removal_mode 0)
		)
		(polygon
			(pts
				(arc
					(start 159.089852 -47.178722)
					(mid 158.708979 -46.797468)
					(end 158.327852 -47.178468)
				)
				(arc
					(start 158.327852 -48.321468)
					(mid 158.708852 -48.702468)
					(end 159.089852 -48.321468)
				)
			)
		)
	)
	(zone
		(layers "In1.Cu" "In3.Cu" "In5.Cu" "In6.Cu" "In8.Cu" "In10.Cu")
		(hatch none 0.5)
		(connect_pads
			(clearance 0)
		)
		(min_thickness 0.25)
		(keepout
			(tracks not_allowed)
			(vias allowed)
			(pads allowed)
			(copperpour not_allowed)
			(footprints allowed)
		)
		(placement
			(enabled no)
			(sheetname "")
		)
		(fill yes
			(thermal_gap 0.5)
			(thermal_bridge_width 0.5)
			(island_removal_mode 0)
		)
		(polygon
			(pts
				(arc
					(start 242.21948 -129.161032)
					(mid 243.211096 -128.830324)
					(end 242.880388 -127.838708)
				)
				(arc
					(start 240.891822 -126.844552)
					(mid 239.891674 -127.163691)
					(end 240.219484 -128.161034)
				)
			)
		)
	)
	(zone
		(layers "In1.Cu" "In3.Cu" "In5.Cu" "In6.Cu" "In8.Cu" "In10.Cu")
		(hatch none 0.5)
		(connect_pads
			(clearance 0)
		)
		(min_thickness 0.25)
		(keepout
			(tracks not_allowed)
			(vias allowed)
			(pads allowed)
			(copperpour not_allowed)
			(footprints allowed)
		)
		(placement
			(enabled no)
			(sheetname "")
		)
		(fill yes
			(thermal_gap 0.5)
			(thermal_bridge_width 0.5)
			(island_removal_mode 0)
		)
		(polygon
			(pts
				(arc
					(start 283.563314 -162.872674)
					(mid 282.622752 -163.186364)
					(end 282.936442 -164.126926)
				)
				(arc
					(start 284.928056 -165.122606)
					(mid 285.874832 -164.817421)
					(end 285.56331 -163.872672)
				)
			)
		)
	)
	(zone
		(layers "In1.Cu" "In3.Cu" "In5.Cu" "In6.Cu" "In8.Cu" "In10.Cu")
		(hatch none 0.5)
		(connect_pads
			(clearance 0)
		)
		(min_thickness 0.25)
		(keepout
			(tracks not_allowed)
			(vias allowed)
			(pads allowed)
			(copperpour not_allowed)
			(footprints allowed)
		)
		(placement
			(enabled no)
			(sheetname "")
		)
		(fill yes
			(thermal_gap 0.5)
			(thermal_bridge_width 0.5)
			(island_removal_mode 0)
		)
		(polygon
			(pts
				(arc
					(start 382.701292 -29.15031)
					(mid 382.150239 -28.598876)
					(end 381.598932 -29.150056)
				)
				(arc
					(start 381.598932 -30.550104)
					(mid 382.150112 -31.101284)
					(end 382.701292 -30.550104)
				)
			)
		)
	)
	(zone
		(layers "In1.Cu" "In3.Cu" "In5.Cu" "In6.Cu" "In8.Cu" "In10.Cu")
		(hatch none 0.5)
		(connect_pads
			(clearance 0)
		)
		(min_thickness 0.25)
		(keepout
			(tracks not_allowed)
			(vias allowed)
			(pads allowed)
			(copperpour not_allowed)
			(footprints allowed)
		)
		(placement
			(enabled no)
			(sheetname "")
		)
		(fill yes
			(thermal_gap 0.5)
			(thermal_bridge_width 0.5)
			(island_removal_mode 0)
		)
		(polygon
			(pts
				(arc
					(start 116.898674 -17.350232)
					(mid 116.350161 -16.801338)
					(end 115.801394 -17.349978)
				)
				(arc
					(start 115.801394 -18.750026)
					(mid 116.350034 -19.298666)
					(end 116.898674 -18.750026)
				)
			)
		)
	)
	(zone
		(layers "In1.Cu" "In3.Cu" "In5.Cu" "In6.Cu" "In8.Cu" "In10.Cu")
		(hatch none 0.5)
		(connect_pads
			(clearance 0)
		)
		(min_thickness 0.25)
		(keepout
			(tracks not_allowed)
			(vias allowed)
			(pads allowed)
			(copperpour not_allowed)
			(footprints allowed)
		)
		(placement
			(enabled no)
			(sheetname "")
		)
		(fill yes
			(thermal_gap 0.5)
			(thermal_bridge_width 0.5)
			(island_removal_mode 0)
		)
		(polygon
			(pts
				(arc
					(start 281.074876 -170.14952)
					(mid 281.399742 -169.174922)
					(end 280.425144 -168.850056)
				)
				(xy 280.423874 -168.84777) (xy 278.424132 -169.847768) (xy 278.424132 -169.848022)
				(arc
					(start 278.425148 -169.850054)
					(mid 278.100282 -170.824652)
					(end 279.07488 -171.149518)
				)
				(xy 279.07615 -171.151804) (xy 281.076146 -170.151806)
			)
		)
	)
	(zone
		(layers "In1.Cu" "In3.Cu" "In5.Cu" "In6.Cu" "In8.Cu" "In10.Cu")
		(hatch none 0.5)
		(connect_pads
			(clearance 0)
		)
		(min_thickness 0.25)
		(keepout
			(tracks not_allowed)
			(vias allowed)
			(pads allowed)
			(copperpour not_allowed)
			(footprints allowed)
		)
		(placement
			(enabled no)
			(sheetname "")
		)
		(fill yes
			(thermal_gap 0.5)
			(thermal_bridge_width 0.5)
			(island_removal_mode 0)
		)
		(polygon
			(pts
				(arc
					(start 284.936438 -161.126932)
					(mid 285.877 -160.813242)
					(end 285.56331 -159.87268)
				)
				(arc
					(start 283.571696 -158.877)
					(mid 282.62492 -159.182185)
					(end 282.936442 -160.126934)
				)
			)
		)
	)
	(zone
		(layers "In1.Cu" "In3.Cu" "In5.Cu" "In6.Cu" "In8.Cu" "In10.Cu")
		(hatch none 0.5)
		(connect_pads
			(clearance 0)
		)
		(min_thickness 0.25)
		(keepout
			(tracks not_allowed)
			(vias allowed)
			(pads allowed)
			(copperpour not_allowed)
			(footprints allowed)
		)
		(placement
			(enabled no)
			(sheetname "")
		)
		(fill yes
			(thermal_gap 0.5)
			(thermal_bridge_width 0.5)
			(island_removal_mode 0)
		)
		(polygon
			(pts
				(arc
					(start 143.89862 -21.950426)
					(mid 143.350107 -21.401532)
					(end 142.80134 -21.950172)
				)
				(arc
					(start 142.80134 -23.35022)
					(mid 143.34998 -23.89886)
					(end 143.89862 -23.35022)
				)
			)
		)
	)
	(zone
		(layers "In1.Cu" "In3.Cu" "In5.Cu" "In6.Cu" "In8.Cu" "In10.Cu")
		(hatch none 0.5)
		(connect_pads
			(clearance 0)
		)
		(min_thickness 0.25)
		(keepout
			(tracks not_allowed)
			(vias allowed)
			(pads allowed)
			(copperpour not_allowed)
			(footprints allowed)
		)
		(placement
			(enabled no)
			(sheetname "")
		)
		(fill yes
			(thermal_gap 0.5)
			(thermal_bridge_width 0.5)
			(island_removal_mode 0)
		)
		(polygon
			(pts
				(arc
					(start 389.898636 -18.350484)
					(mid 389.350123 -17.80159)
					(end 388.801356 -18.35023)
				)
				(arc
					(start 388.801356 -19.750024)
					(mid 389.349996 -20.298664)
					(end 389.898636 -19.750024)
				)
			)
		)
	)
	(zone
		(layers "In1.Cu" "In3.Cu" "In5.Cu" "In6.Cu" "In8.Cu" "In10.Cu")
		(hatch none 0.5)
		(connect_pads
			(clearance 0)
		)
		(min_thickness 0.25)
		(keepout
			(tracks not_allowed)
			(vias allowed)
			(pads allowed)
			(copperpour not_allowed)
			(footprints allowed)
		)
		(placement
			(enabled no)
			(sheetname "")
		)
		(fill yes
			(thermal_gap 0.5)
			(thermal_bridge_width 0.5)
			(island_removal_mode 0)
		)
		(polygon
			(pts
				(arc
					(start 281.074876 -166.149528)
					(mid 281.399742 -165.17493)
					(end 280.425144 -164.850064)
				)
				(xy 280.423874 -164.847778) (xy 278.424132 -165.847776) (xy 278.424132 -165.84803)
				(arc
					(start 278.425148 -165.850062)
					(mid 278.100282 -166.82466)
					(end 279.07488 -167.149526)
				)
				(xy 279.07615 -167.151812) (xy 281.076146 -166.151814)
			)
		)
	)
	(zone
		(layers "In1.Cu" "In3.Cu" "In5.Cu" "In6.Cu" "In8.Cu" "In10.Cu")
		(hatch none 0.5)
		(connect_pads
			(clearance 0)
		)
		(min_thickness 0.25)
		(keepout
			(tracks not_allowed)
			(vias allowed)
			(pads allowed)
			(copperpour not_allowed)
			(footprints allowed)
		)
		(placement
			(enabled no)
			(sheetname "")
		)
		(fill yes
			(thermal_gap 0.5)
			(thermal_bridge_width 0.5)
			(island_removal_mode 0)
		)
		(polygon
			(pts
				(arc
					(start 271.970754 -330.321412)
					(mid 271.58696 -330.704825)
					(end 271.9705 -331.088492)
				)
				(arc
					(start 273.1135 -331.088492)
					(mid 273.49704 -330.704952)
					(end 273.1135 -330.321412)
				)
			)
		)
	)
	(zone
		(layers "In1.Cu" "In3.Cu" "In5.Cu" "In6.Cu" "In8.Cu" "In10.Cu")
		(hatch none 0.5)
		(connect_pads
			(clearance 0)
		)
		(min_thickness 0.25)
		(keepout
			(tracks not_allowed)
			(vias allowed)
			(pads allowed)
			(copperpour not_allowed)
			(footprints allowed)
		)
		(placement
			(enabled no)
			(sheetname "")
		)
		(fill yes
			(thermal_gap 0.5)
			(thermal_bridge_width 0.5)
			(island_removal_mode 0)
		)
		(polygon
			(pts
				(arc
					(start 278.23668 -315.756544)
					(mid 277.68804 -316.305184)
					(end 278.23668 -316.853824)
				)
				(arc
					(start 279.636728 -316.853824)
					(mid 280.185368 -316.305184)
					(end 279.636728 -315.756544)
				)
				(xy 278.236934 -315.756544)
			)
		)
	)
	(zone
		(layers "In1.Cu" "In3.Cu" "In5.Cu" "In6.Cu" "In8.Cu" "In10.Cu")
		(hatch none 0.5)
		(connect_pads
			(clearance 0)
		)
		(min_thickness 0.25)
		(keepout
			(tracks not_allowed)
			(vias allowed)
			(pads allowed)
			(copperpour not_allowed)
			(footprints allowed)
		)
		(placement
			(enabled no)
			(sheetname "")
		)
		(fill yes
			(thermal_gap 0.5)
			(thermal_bridge_width 0.5)
			(island_removal_mode 0)
		)
		(polygon
			(pts
				(arc
					(start 143.89862 -18.350484)
					(mid 143.350107 -17.80159)
					(end 142.80134 -18.35023)
				)
				(arc
					(start 142.80134 -19.750024)
					(mid 143.34998 -20.298664)
					(end 143.89862 -19.750024)
				)
			)
		)
	)
	(zone
		(layers "In1.Cu" "In3.Cu" "In5.Cu" "In6.Cu" "In8.Cu" "In10.Cu")
		(hatch none 0.5)
		(connect_pads
			(clearance 0)
		)
		(min_thickness 0.25)
		(keepout
			(tracks not_allowed)
			(vias allowed)
			(pads allowed)
			(copperpour not_allowed)
			(footprints allowed)
		)
		(placement
			(enabled no)
			(sheetname "")
		)
		(fill yes
			(thermal_gap 0.5)
			(thermal_bridge_width 0.5)
			(island_removal_mode 0)
		)
		(polygon
			(pts
				(arc
					(start 138.49858 -20.950428)
					(mid 137.950067 -20.401534)
					(end 137.4013 -20.950174)
				)
				(arc
					(start 137.4013 -22.350222)
					(mid 137.94994 -22.898862)
					(end 138.49858 -22.350222)
				)
			)
		)
	)
	(zone
		(layers "In1.Cu" "In3.Cu" "In5.Cu" "In6.Cu" "In8.Cu" "In10.Cu")
		(hatch none 0.5)
		(connect_pads
			(clearance 0)
		)
		(min_thickness 0.25)
		(keepout
			(tracks not_allowed)
			(vias allowed)
			(pads allowed)
			(copperpour not_allowed)
			(footprints allowed)
		)
		(placement
			(enabled no)
			(sheetname "")
		)
		(fill yes
			(thermal_gap 0.5)
			(thermal_bridge_width 0.5)
			(island_removal_mode 0)
		)
		(polygon
			(pts
				(arc
					(start 356.675182 -47.178722)
					(mid 356.289229 -46.792388)
					(end 355.903022 -47.178468)
				)
				(arc
					(start 355.903022 -48.321468)
					(mid 356.289102 -48.707548)
					(end 356.675182 -48.321468)
				)
			)
		)
	)
	(zone
		(layers "In1.Cu" "In3.Cu" "In5.Cu" "In6.Cu" "In8.Cu" "In10.Cu")
		(hatch none 0.5)
		(connect_pads
			(clearance 0)
		)
		(min_thickness 0.25)
		(keepout
			(tracks not_allowed)
			(vias allowed)
			(pads allowed)
			(copperpour not_allowed)
			(footprints allowed)
		)
		(placement
			(enabled no)
			(sheetname "")
		)
		(fill yes
			(thermal_gap 0.5)
			(thermal_bridge_width 0.5)
			(island_removal_mode 0)
		)
		(polygon
			(pts
				(arc
					(start 214.14867 -407.000456)
					(mid 213.600157 -406.451562)
					(end 213.05139 -407.000202)
				)
				(arc
					(start 213.05139 -408.399996)
					(mid 213.60003 -408.948636)
					(end 214.14867 -408.399996)
				)
			)
		)
	)
	(zone
		(layers "In1.Cu" "In3.Cu" "In5.Cu" "In6.Cu" "In8.Cu" "In10.Cu")
		(hatch none 0.5)
		(connect_pads
			(clearance 0)
		)
		(min_thickness 0.25)
		(keepout
			(tracks not_allowed)
			(vias allowed)
			(pads allowed)
			(copperpour not_allowed)
			(footprints allowed)
		)
		(placement
			(enabled no)
			(sheetname "")
		)
		(fill yes
			(thermal_gap 0.5)
			(thermal_bridge_width 0.5)
			(island_removal_mode 0)
		)
		(polygon
			(pts
				(arc
					(start 281.07386 -130.147314)
					(mid 281.397456 -129.176018)
					(end 280.42616 -128.852422)
				)
				(xy 278.426418 -129.852166)
				(arc
					(start 278.426418 -129.85242)
					(mid 278.102619 -130.823564)
					(end 279.073864 -131.147312)
				)
			)
		)
	)
	(zone
		(layers "In1.Cu" "In3.Cu" "In5.Cu" "In6.Cu" "In8.Cu" "In10.Cu")
		(hatch none 0.5)
		(connect_pads
			(clearance 0)
		)
		(min_thickness 0.25)
		(keepout
			(tracks not_allowed)
			(vias allowed)
			(pads allowed)
			(copperpour not_allowed)
			(footprints allowed)
		)
		(placement
			(enabled no)
			(sheetname "")
		)
		(fill yes
			(thermal_gap 0.5)
			(thermal_bridge_width 0.5)
			(island_removal_mode 0)
		)
		(polygon
			(pts
				(arc
					(start 219.54871 -416.800284)
					(mid 219.000197 -416.25139)
					(end 218.45143 -416.80003)
				)
				(arc
					(start 218.45143 -418.200078)
					(mid 219.00007 -418.748718)
					(end 219.54871 -418.200078)
				)
			)
		)
	)
	(zone
		(layers "In1.Cu" "In3.Cu" "In5.Cu" "In6.Cu" "In8.Cu" "In10.Cu")
		(hatch none 0.5)
		(connect_pads
			(clearance 0)
		)
		(min_thickness 0.25)
		(keepout
			(tracks not_allowed)
			(vias allowed)
			(pads allowed)
			(copperpour not_allowed)
			(footprints allowed)
		)
		(placement
			(enabled no)
			(sheetname "")
		)
		(fill yes
			(thermal_gap 0.5)
			(thermal_bridge_width 0.5)
			(island_removal_mode 0)
		)
		(polygon
			(pts
				(arc
					(start 283.563314 -150.872698)
					(mid 282.622752 -151.186388)
					(end 282.936442 -152.12695)
				)
				(arc
					(start 284.928056 -153.12263)
					(mid 285.874832 -152.817445)
					(end 285.56331 -151.872696)
				)
			)
		)
	)
	(zone
		(layers "In1.Cu" "In3.Cu" "In5.Cu" "In6.Cu" "In8.Cu" "In10.Cu")
		(hatch none 0.5)
		(connect_pads
			(clearance 0)
		)
		(min_thickness 0.25)
		(keepout
			(tracks not_allowed)
			(vias allowed)
			(pads allowed)
			(copperpour not_allowed)
			(footprints allowed)
		)
		(placement
			(enabled no)
			(sheetname "")
		)
		(fill yes
			(thermal_gap 0.5)
			(thermal_bridge_width 0.5)
			(island_removal_mode 0)
		)
		(polygon
			(pts
				(arc
					(start 286.436562 -259.55117)
					(mid 285.885382 -260.10235)
					(end 286.436562 -260.65353)
				)
				(arc
					(start 287.83661 -260.65353)
					(mid 288.38779 -260.10235)
					(end 287.83661 -259.55117)
				)
				(xy 286.436816 -259.55117)
			)
		)
	)
	(zone
		(layers "In1.Cu" "In3.Cu" "In5.Cu" "In6.Cu" "In8.Cu" "In10.Cu")
		(hatch none 0.5)
		(connect_pads
			(clearance 0)
		)
		(min_thickness 0.25)
		(keepout
			(tracks not_allowed)
			(vias allowed)
			(pads allowed)
			(copperpour not_allowed)
			(footprints allowed)
		)
		(placement
			(enabled no)
			(sheetname "")
		)
		(fill yes
			(thermal_gap 0.5)
			(thermal_bridge_width 0.5)
			(island_removal_mode 0)
		)
		(polygon
			(pts
				(arc
					(start 440.2201 -158.368492)
					(mid 439.8391 -157.987492)
					(end 439.4581 -158.368492)
				)
				(arc
					(start 439.4581 -159.511238)
					(mid 439.838973 -159.892492)
					(end 440.2201 -159.511492)
				)
			)
		)
	)
	(zone
		(layers "In1.Cu" "In3.Cu" "In5.Cu" "In6.Cu" "In8.Cu" "In10.Cu")
		(hatch none 0.5)
		(connect_pads
			(clearance 0)
		)
		(min_thickness 0.25)
		(keepout
			(tracks not_allowed)
			(vias allowed)
			(pads allowed)
			(copperpour not_allowed)
			(footprints allowed)
		)
		(placement
			(enabled no)
			(sheetname "")
		)
		(fill yes
			(thermal_gap 0.5)
			(thermal_bridge_width 0.5)
			(island_removal_mode 0)
		)
		(polygon
			(pts
				(arc
					(start 386.298694 -18.350484)
					(mid 385.750181 -17.80159)
					(end 385.201414 -18.35023)
				)
				(arc
					(start 385.201414 -19.750024)
					(mid 385.750054 -20.298664)
					(end 386.298694 -19.750024)
				)
			)
		)
	)
	(zone
		(layers "In1.Cu" "In3.Cu" "In5.Cu" "In6.Cu" "In8.Cu" "In10.Cu")
		(hatch none 0.5)
		(connect_pads
			(clearance 0)
		)
		(min_thickness 0.25)
		(keepout
			(tracks not_allowed)
			(vias allowed)
			(pads allowed)
			(copperpour not_allowed)
			(footprints allowed)
		)
		(placement
			(enabled no)
			(sheetname "")
		)
		(fill yes
			(thermal_gap 0.5)
			(thermal_bridge_width 0.5)
			(island_removal_mode 0)
		)
		(polygon
			(pts
				(arc
					(start 478.120202 -43.368468)
					(mid 477.739202 -42.987468)
					(end 477.358202 -43.368468)
				)
				(arc
					(start 477.358202 -44.511214)
					(mid 477.739075 -44.892468)
					(end 478.120202 -44.511468)
				)
			)
		)
	)
	(zone
		(layers "In1.Cu" "In3.Cu" "In5.Cu" "In6.Cu" "In8.Cu" "In10.Cu")
		(hatch none 0.5)
		(connect_pads
			(clearance 0)
		)
		(min_thickness 0.25)
		(keepout
			(tracks not_allowed)
			(vias allowed)
			(pads allowed)
			(copperpour not_allowed)
			(footprints allowed)
		)
		(placement
			(enabled no)
			(sheetname "")
		)
		(fill yes
			(thermal_gap 0.5)
			(thermal_bridge_width 0.5)
			(island_removal_mode 0)
		)
		(polygon
			(pts
				(arc
					(start 120.498616 -20.950428)
					(mid 119.950103 -20.401534)
					(end 119.401336 -20.950174)
				)
				(arc
					(start 119.401336 -22.350222)
					(mid 119.949976 -22.898862)
					(end 120.498616 -22.350222)
				)
			)
		)
	)
	(zone
		(layers "In1.Cu" "In3.Cu" "In5.Cu" "In6.Cu" "In8.Cu" "In10.Cu")
		(hatch none 0.5)
		(connect_pads
			(clearance 0)
		)
		(min_thickness 0.25)
		(keepout
			(tracks not_allowed)
			(vias allowed)
			(pads allowed)
			(copperpour not_allowed)
			(footprints allowed)
		)
		(placement
			(enabled no)
			(sheetname "")
		)
		(fill yes
			(thermal_gap 0.5)
			(thermal_bridge_width 0.5)
			(island_removal_mode 0)
		)
		(polygon
			(pts
				(arc
					(start 242.236498 -173.126908)
					(mid 243.17706 -172.813218)
					(end 242.86337 -171.872656)
				)
				(arc
					(start 240.871756 -170.876976)
					(mid 239.92498 -171.182161)
					(end 240.236502 -172.12691)
				)
			)
		)
	)
	(zone
		(layers "In1.Cu" "In3.Cu" "In5.Cu" "In6.Cu" "In8.Cu" "In10.Cu")
		(hatch none 0.5)
		(connect_pads
			(clearance 0)
		)
		(min_thickness 0.25)
		(keepout
			(tracks not_allowed)
			(vias allowed)
			(pads allowed)
			(copperpour not_allowed)
			(footprints allowed)
		)
		(placement
			(enabled no)
			(sheetname "")
		)
		(fill yes
			(thermal_gap 0.5)
			(thermal_bridge_width 0.5)
			(island_removal_mode 0)
		)
		(polygon
			(pts
				(arc
					(start 64.4398 -277.17877)
					(mid 64.058927 -276.797516)
					(end 63.6778 -277.178516)
				)
				(arc
					(start 63.6778 -278.321516)
					(mid 64.0588 -278.702516)
					(end 64.4398 -278.321516)
				)
			)
		)
	)
	(zone
		(layers "In1.Cu" "In3.Cu" "In5.Cu" "In6.Cu" "In8.Cu" "In10.Cu")
		(hatch none 0.5)
		(connect_pads
			(clearance 0)
		)
		(min_thickness 0.25)
		(keepout
			(tracks not_allowed)
			(vias allowed)
			(pads allowed)
			(copperpour not_allowed)
			(footprints allowed)
		)
		(placement
			(enabled no)
			(sheetname "")
		)
		(fill yes
			(thermal_gap 0.5)
			(thermal_bridge_width 0.5)
			(island_removal_mode 0)
		)
		(polygon
			(pts
				(arc
					(start 285.436564 -333.753968)
					(mid 284.885384 -334.305148)
					(end 285.436564 -334.856328)
				)
				(arc
					(start 286.836612 -334.856328)
					(mid 287.387792 -334.305148)
					(end 286.836612 -333.753968)
				)
				(xy 285.436818 -333.753968)
			)
		)
	)
	(zone
		(layers "In1.Cu" "In3.Cu" "In5.Cu" "In6.Cu" "In8.Cu" "In10.Cu")
		(hatch none 0.5)
		(connect_pads
			(clearance 0)
		)
		(min_thickness 0.25)
		(keepout
			(tracks not_allowed)
			(vias allowed)
			(pads allowed)
			(copperpour not_allowed)
			(footprints allowed)
		)
		(placement
			(enabled no)
			(sheetname "")
		)
		(fill yes
			(thermal_gap 0.5)
			(thermal_bridge_width 0.5)
			(island_removal_mode 0)
		)
		(polygon
			(pts
				(arc
					(start 284.236668 -264.250932)
					(mid 284.785308 -263.702292)
					(end 284.236668 -263.153652)
				)
				(arc
					(start 282.83662 -263.153652)
					(mid 282.28798 -263.702292)
					(end 282.83662 -264.250932)
				)
			)
		)
	)
	(zone
		(layers "In1.Cu" "In3.Cu" "In5.Cu" "In6.Cu" "In8.Cu" "In10.Cu")
		(hatch none 0.5)
		(connect_pads
			(clearance 0)
		)
		(min_thickness 0.25)
		(keepout
			(tracks not_allowed)
			(vias allowed)
			(pads allowed)
			(copperpour not_allowed)
			(footprints allowed)
		)
		(placement
			(enabled no)
			(sheetname "")
		)
		(fill yes
			(thermal_gap 0.5)
			(thermal_bridge_width 0.5)
			(island_removal_mode 0)
		)
		(polygon
			(pts
				(arc
					(start 278.23668 -348.15653)
					(mid 277.68804 -348.70517)
					(end 278.23668 -349.25381)
				)
				(arc
					(start 279.636728 -349.25381)
					(mid 280.185368 -348.70517)
					(end 279.636728 -348.15653)
				)
				(xy 278.236934 -348.15653)
			)
		)
	)
	(zone
		(layers "In1.Cu" "In3.Cu" "In5.Cu" "In6.Cu" "In8.Cu" "In10.Cu")
		(hatch none 0.5)
		(connect_pads
			(clearance 0)
		)
		(min_thickness 0.25)
		(keepout
			(tracks not_allowed)
			(vias allowed)
			(pads allowed)
			(copperpour not_allowed)
			(footprints allowed)
		)
		(placement
			(enabled no)
			(sheetname "")
		)
		(fill yes
			(thermal_gap 0.5)
			(thermal_bridge_width 0.5)
			(island_removal_mode 0)
		)
		(polygon
			(pts
				(arc
					(start 238.374936 -61.849762)
					(mid 238.699802 -60.875164)
					(end 237.725204 -60.550298)
				)
				(xy 237.723934 -60.548012) (xy 235.724192 -61.54801) (xy 235.724192 -61.548264)
				(arc
					(start 235.725208 -61.550296)
					(mid 235.400342 -62.524894)
					(end 236.37494 -62.84976)
				)
				(xy 236.37621 -62.852046) (xy 238.376206 -61.852048)
			)
		)
	)
	(zone
		(layers "In1.Cu" "In3.Cu" "In5.Cu" "In6.Cu" "In8.Cu" "In10.Cu")
		(hatch none 0.5)
		(connect_pads
			(clearance 0)
		)
		(min_thickness 0.25)
		(keepout
			(tracks not_allowed)
			(vias allowed)
			(pads allowed)
			(copperpour not_allowed)
			(footprints allowed)
		)
		(placement
			(enabled no)
			(sheetname "")
		)
		(fill yes
			(thermal_gap 0.5)
			(thermal_bridge_width 0.5)
			(island_removal_mode 0)
		)
		(polygon
			(pts
				(arc
					(start 279.236678 -321.156584)
					(mid 278.688038 -321.705224)
					(end 279.236678 -322.253864)
				)
				(arc
					(start 280.636726 -322.253864)
					(mid 281.185366 -321.705224)
					(end 280.636726 -321.156584)
				)
				(xy 279.236932 -321.156584)
			)
		)
	)
	(zone
		(layer "In2.Cu")
		(hatch none 0.5)
		(connect_pads
			(clearance 0)
		)
		(min_thickness 0.25)
		(keepout
			(tracks not_allowed)
			(vias allowed)
			(pads allowed)
			(copperpour not_allowed)
			(footprints allowed)
		)
		(placement
			(enabled no)
			(sheetname "")
		)
		(fill
			(thermal_gap 0.5)
			(thermal_bridge_width 0.5)
			(island_removal_mode 0)
		)
		(polygon
			(pts
				(arc
					(start 293.073074 -399.200624)
					(mid 300.20006 -406.32761)
					(end 307.327046 -399.200624)
				)
				(arc
					(start 307.327046 -393.200382)
					(mid 300.20006 -386.073396)
					(end 293.073074 -393.200382)
				)
			)
		)
	)
	(zone
		(layer "In2.Cu")
		(hatch none 0.5)
		(connect_pads
			(clearance 0)
		)
		(min_thickness 0.25)
		(keepout
			(tracks not_allowed)
			(vias allowed)
			(pads allowed)
			(copperpour not_allowed)
			(footprints allowed)
		)
		(placement
			(enabled no)
			(sheetname "")
		)
		(fill
			(thermal_gap 0.5)
			(thermal_bridge_width 0.5)
			(island_removal_mode 0)
		)
		(polygon
			(pts
				(arc
					(start 307.327046 -243.200428)
					(mid 300.20006 -236.073442)
					(end 293.073074 -243.200428)
				)
				(arc
					(start 293.073074 -249.20067)
					(mid 300.20006 -256.327402)
					(end 307.327046 -249.20067)
				)
			)
		)
	)
	(zone
		(layer "In2.Cu")
		(hatch none 0.5)
		(connect_pads
			(clearance 0)
		)
		(min_thickness 0.25)
		(keepout
			(tracks not_allowed)
			(vias allowed)
			(pads allowed)
			(copperpour not_allowed)
			(footprints allowed)
		)
		(placement
			(enabled no)
			(sheetname "")
		)
		(fill
			(thermal_gap 0.5)
			(thermal_bridge_width 0.5)
			(island_removal_mode 0)
		)
		(polygon
			(pts
				(arc
					(start 346.177108 -270.000476)
					(mid 336.423 -270.000476)
					(end 346.177108 -270.000476)
				)
			)
		)
	)
	(zone
		(layer "In2.Cu")
		(hatch none 0.5)
		(connect_pads
			(clearance 0)
		)
		(min_thickness 0.25)
		(keepout
			(tracks not_allowed)
			(vias allowed)
			(pads allowed)
			(copperpour not_allowed)
			(footprints allowed)
		)
		(placement
			(enabled no)
			(sheetname "")
		)
		(fill
			(thermal_gap 0.5)
			(thermal_bridge_width 0.5)
			(island_removal_mode 0)
		)
		(polygon
			(pts
				(arc
					(start 293.073074 -144.200626)
					(mid 300.20006 -151.327612)
					(end 307.327046 -144.200626)
				)
				(arc
					(start 307.327046 -138.200384)
					(mid 300.20006 -131.073398)
					(end 293.073074 -138.200384)
				)
			)
		)
	)
	(zone
		(layer "In2.Cu")
		(hatch none 0.5)
		(connect_pads
			(clearance 0)
		)
		(min_thickness 0.25)
		(keepout
			(tracks not_allowed)
			(vias allowed)
			(pads allowed)
			(copperpour not_allowed)
			(footprints allowed)
		)
		(placement
			(enabled no)
			(sheetname "")
		)
		(fill
			(thermal_gap 0.5)
			(thermal_bridge_width 0.5)
			(island_removal_mode 0)
		)
		(polygon
			(pts
				(arc
					(start 337.801966 -92.800424)
					(mid 330.67498 -85.673438)
					(end 323.547994 -92.800424)
				)
				(arc
					(start 323.547994 -98.800666)
					(mid 330.67498 -105.927398)
					(end 337.801966 -98.800666)
				)
			)
		)
	)
	(zone
		(layer "In2.Cu")
		(hatch none 0.5)
		(connect_pads
			(clearance 0)
		)
		(min_thickness 0.25)
		(keepout
			(tracks not_allowed)
			(vias allowed)
			(pads allowed)
			(copperpour not_allowed)
			(footprints allowed)
		)
		(placement
			(enabled no)
			(sheetname "")
		)
		(fill
			(thermal_gap 0.5)
			(thermal_bridge_width 0.5)
			(island_removal_mode 0)
		)
		(polygon
			(pts
				(arc
					(start 463.801968 -92.800424)
					(mid 456.674982 -85.673438)
					(end 449.547996 -92.800424)
				)
				(arc
					(start 449.547996 -98.800666)
					(mid 456.674982 -105.927398)
					(end 463.801968 -98.800666)
				)
			)
		)
	)
	(zone
		(net "GND")
		(layer "In2.Cu")
		(hatch none 0.5)
		(connect_pads
			(clearance 0.5)
		)
		(min_thickness 0.25)
		(fill yes
			(thermal_gap 0.5)
			(thermal_bridge_width 0.5)
			(island_removal_mode 0)
		)
		(polygon
			(pts
				(arc
					(start 221.000066 38.037008)
					(mid 220.832494 37.967598)
					(end 220.763084 37.800026)
				)
				(xy 220.763084 4.156964) (xy 222.032068 4.156964) (xy 222.032068 36.768024) (xy 297.967908 36.768024)
				(xy 297.967908 2.782824) (xy 299.236892 2.782824)
				(arc
					(start 299.236892 37.800026)
					(mid 299.167482 37.967598)
					(end 298.99991 38.037008)
				)
			)
		)
	)
	(zone
		(layer "In2.Cu")
		(hatch none 0.5)
		(connect_pads
			(clearance 0)
		)
		(min_thickness 0.25)
		(keepout
			(tracks not_allowed)
			(vias allowed)
			(pads allowed)
			(copperpour not_allowed)
			(footprints allowed)
		)
		(placement
			(enabled no)
			(sheetname "")
		)
		(fill
			(thermal_gap 0.5)
			(thermal_bridge_width 0.5)
			(island_removal_mode 0)
		)
		(polygon
			(pts
				(arc
					(start 103.451914 -92.800424)
					(mid 96.324928 -85.673438)
					(end 89.197942 -92.800424)
				)
				(arc
					(start 89.197942 -98.800666)
					(mid 96.324928 -105.927398)
					(end 103.451914 -98.800666)
				)
			)
		)
	)
	(zone
		(layer "In2.Cu")
		(hatch none 0.5)
		(connect_pads
			(clearance 0)
		)
		(min_thickness 0.25)
		(keepout
			(tracks not_allowed)
			(vias allowed)
			(pads allowed)
			(copperpour not_allowed)
			(footprints allowed)
		)
		(placement
			(enabled no)
			(sheetname "")
		)
		(fill
			(thermal_gap 0.5)
			(thermal_bridge_width 0.5)
			(island_removal_mode 0)
		)
		(polygon
			(pts
				(arc
					(start 240.876074 -34.548064)
					(mid 239.89792 -34.873946)
					(end 240.223802 -35.8521)
				)
				(arc
					(start 242.223798 -36.852098)
					(mid 243.201952 -36.526216)
					(end 242.87607 -35.548062)
				)
				(xy 241.918998 -35.069526) (xy 241.918998 -35.44062) (xy 241.925602 -35.460432) (xy 241.918998 -35.47364)
				(xy 241.918998 -35.488372) (xy 241.904266 -35.503104) (xy 241.832384 -35.646868) (xy 241.873024 -35.769296)
				(arc
					(start 242.104164 -35.884866)
					(mid 243.038256 -36.444818)
					(end 242.03025 -36.03244)
				)
				(xy 241.79911 -35.91687) (xy 241.768376 -35.901376) (xy 241.737896 -35.886136) (xy 241.727228 -35.853878)
				(xy 241.716306 -35.821366) (xy 241.664998 -35.66668) (xy 241.654076 -35.634168) (xy 241.669316 -35.603434)
				(xy 241.753898 -35.434524) (xy 241.753898 -34.986976) (xy 241.626898 -34.923476) (xy 241.626898 -35.371532)
				(xy 241.633502 -35.391344) (xy 241.626898 -35.404552) (xy 241.626898 -35.419284) (xy 241.612166 -35.434016)
				(xy 241.555778 -35.546792) (xy 241.540538 -35.577272) (xy 241.540284 -35.577526) (xy 241.508026 -35.588194)
				(xy 241.35334 -35.64001) (xy 241.353086 -35.640264) (xy 241.320828 -35.650932) (xy 241.28857 -35.661854)
				(xy 241.288316 -35.661854) (xy 241.257836 -35.646614) (xy 241.227356 -35.631374)
				(arc
					(start 240.995708 -35.51555)
					(mid 240.061593 -34.956226)
					(end 241.069622 -35.367722)
				)
				(xy 241.301016 -35.483546) (xy 241.42319 -35.442652) (xy 241.461798 -35.365436) (xy 241.461798 -34.849816)
				(xy 241.444272 -34.832036)
			)
		)
	)
	(zone
		(layer "In2.Cu")
		(hatch none 0.5)
		(connect_pads
			(clearance 0)
		)
		(min_thickness 0.25)
		(keepout
			(tracks not_allowed)
			(vias allowed)
			(pads allowed)
			(copperpour not_allowed)
			(footprints allowed)
		)
		(placement
			(enabled no)
			(sheetname "")
		)
		(fill
			(thermal_gap 0.5)
			(thermal_bridge_width 0.5)
			(island_removal_mode 0)
		)
		(polygon
			(pts
				(arc
					(start 166.452042 -207.800448)
					(mid 159.325056 -200.673462)
					(end 152.19807 -207.800448)
				)
				(arc
					(start 152.19807 -213.80069)
					(mid 159.325056 -220.927422)
					(end 166.452042 -213.80069)
				)
			)
		)
	)
	(zone
		(layer "In2.Cu")
		(hatch none 0.5)
		(connect_pads
			(clearance 0)
		)
		(min_thickness 0.25)
		(keepout
			(tracks not_allowed)
			(vias allowed)
			(pads allowed)
			(copperpour not_allowed)
			(footprints allowed)
		)
		(placement
			(enabled no)
			(sheetname "")
		)
		(fill
			(thermal_gap 0.5)
			(thermal_bridge_width 0.5)
			(island_removal_mode 0)
		)
		(polygon
			(pts
				(arc
					(start 400.802094 -322.800472)
					(mid 393.675108 -315.673486)
					(end 386.548122 -322.800472)
				)
				(arc
					(start 386.548122 -328.80046)
					(mid 393.675108 -335.927446)
					(end 400.802094 -328.80046)
				)
			)
		)
	)
	(zone
		(layer "In2.Cu")
		(hatch none 0.5)
		(connect_pads
			(clearance 0)
		)
		(min_thickness 0.25)
		(keepout
			(tracks not_allowed)
			(vias allowed)
			(pads allowed)
			(copperpour not_allowed)
			(footprints allowed)
		)
		(placement
			(enabled no)
			(sheetname "")
		)
		(fill
			(thermal_gap 0.5)
			(thermal_bridge_width 0.5)
			(island_removal_mode 0)
		)
		(polygon
			(pts
				(arc
					(start 472.377008 -270.000476)
					(mid 462.6229 -270.000476)
					(end 472.377008 -270.000476)
				)
			)
		)
	)
	(zone
		(net "P12V_A")
		(layer "In2.Cu")
		(hatch none 0.5)
		(connect_pads
			(clearance 0.5)
		)
		(min_thickness 0.25)
		(fill yes
			(thermal_gap 0.5)
			(thermal_bridge_width 0.5)
			(island_removal_mode 0)
		)
		(polygon
			(pts
				(xy 274.828 -381.508) (xy 274.828 -408.836622) (xy 276.026626 -410.035248) (xy 289.047428 -410.035248)
				(xy 291.079682 -408.002994) (xy 291.079682 -370.775738) (xy 288.830004 -368.52606) (xy 254.934974 -368.52606)
				(xy 252.598682 -370.862352) (xy 252.598682 -377.101862) (xy 252.81382 -377.317) (xy 274.37588 -377.317)
				(xy 274.828 -377.76912) (xy 274.828 -378.8918)
			)
		)
	)
	(zone
		(layer "In2.Cu")
		(hatch none 0.5)
		(connect_pads
			(clearance 0)
		)
		(min_thickness 0.25)
		(keepout
			(tracks not_allowed)
			(vias allowed)
			(pads allowed)
			(copperpour not_allowed)
			(footprints allowed)
		)
		(placement
			(enabled no)
			(sheetname "")
		)
		(fill
			(thermal_gap 0.5)
			(thermal_bridge_width 0.5)
			(island_removal_mode 0)
		)
		(polygon
			(pts
				(arc
					(start 136.698736 -29.15031)
					(mid 136.150223 -28.601416)
					(end 135.601456 -29.150056)
				)
				(xy 135.601456 -29.62148) (xy 135.975852 -29.62148)
				(arc
					(start 136.063228 -29.534104)
					(mid 136.152816 -28.756258)
					(end 136.232646 -29.53512)
				)
				(xy 136.232646 -29.598366) (xy 136.184386 -29.646626) (xy 136.092692 -29.73832) (xy 136.044432 -29.78658)
				(xy 135.975852 -29.78658) (xy 135.601456 -29.78658) (xy 135.601456 -29.91358) (xy 135.967216 -29.91358)
				(xy 136.035796 -29.91358) (xy 136.084056 -29.96184) (xy 136.184386 -30.06217) (xy 136.232646 -30.11043)
				(arc
					(start 136.232646 -30.16504)
					(mid 136.156858 -30.943761)
					(end 136.05637 -30.167834)
				)
				(xy 135.967216 -30.07868) (xy 135.601456 -30.07868)
				(arc
					(start 135.601456 -30.550104)
					(mid 136.150096 -31.098744)
					(end 136.698736 -30.550104)
				)
			)
		)
	)
	(zone
		(layer "In2.Cu")
		(hatch none 0.5)
		(connect_pads
			(clearance 0)
		)
		(min_thickness 0.25)
		(keepout
			(tracks not_allowed)
			(vias allowed)
			(pads allowed)
			(copperpour not_allowed)
			(footprints allowed)
		)
		(placement
			(enabled no)
			(sheetname "")
		)
		(fill
			(thermal_gap 0.5)
			(thermal_bridge_width 0.5)
			(island_removal_mode 0)
		)
		(polygon
			(pts
				(arc
					(start 103.451914 -207.800448)
					(mid 96.324928 -200.673462)
					(end 89.197942 -207.800448)
				)
				(arc
					(start 89.197942 -213.80069)
					(mid 96.324928 -220.927422)
					(end 103.451914 -213.80069)
				)
			)
		)
	)
	(zone
		(net "GND")
		(layer "In2.Cu")
		(hatch none 0.5)
		(connect_pads
			(clearance 0.5)
		)
		(min_thickness 0.25)
		(fill yes
			(thermal_gap 0.5)
			(thermal_bridge_width 0.5)
			(island_removal_mode 0)
		)
		(polygon
			(pts
				(arc
					(start 349.000064 -15.762986)
					(mid 347.753425 -15.246611)
					(end 347.23705 -13.999972)
				)
				(arc
					(start 347.23705 -0.999998)
					(mid 347.16764 -0.832426)
					(end 347.000068 -0.763016)
				)
				(arc
					(start 300.999906 -0.763016)
					(mid 299.753267 -0.246641)
					(end 299.236892 0.999998)
				)
				(xy 299.236892 2.38633) (xy 297.967908 2.38633)
				(arc
					(start 297.967908 0.999998)
					(mid 298.85596 -1.143948)
					(end 300.999906 -2.032)
				)
				(xy 345.968066 -2.032)
				(arc
					(start 345.968066 -13.999972)
					(mid 346.856118 -16.143918)
					(end 349.000064 -17.03197)
				)
				(xy 349.743776 -17.03197) (xy 349.743776 -15.762986)
			)
		)
	)
	(zone
		(layer "In2.Cu")
		(hatch none 0.5)
		(connect_pads
			(clearance 0)
		)
		(min_thickness 0.25)
		(keepout
			(tracks not_allowed)
			(vias allowed)
			(pads allowed)
			(copperpour not_allowed)
			(footprints allowed)
		)
		(placement
			(enabled no)
			(sheetname "")
		)
		(fill
			(thermal_gap 0.5)
			(thermal_bridge_width 0.5)
			(island_removal_mode 0)
		)
		(polygon
			(pts
				(arc
					(start 48.876966 -270.000476)
					(mid 44.000166 -265.123676)
					(end 39.123112 -270.000476)
				)
				(arc
					(start 39.123112 -270.000476)
					(mid 44.000166 -274.87753)
					(end 48.876966 -270.000476)
				)
			)
		)
	)
	(zone
		(layer "In2.Cu")
		(hatch none 0.5)
		(connect_pads
			(clearance 0)
		)
		(min_thickness 0.25)
		(keepout
			(tracks not_allowed)
			(vias allowed)
			(pads allowed)
			(copperpour not_allowed)
			(footprints allowed)
		)
		(placement
			(enabled no)
			(sheetname "")
		)
		(fill
			(thermal_gap 0.5)
			(thermal_bridge_width 0.5)
			(island_removal_mode 0)
		)
		(polygon
			(pts
				(arc
					(start 166.452042 -322.800472)
					(mid 159.325056 -315.673486)
					(end 152.19807 -322.800472)
				)
				(arc
					(start 152.19807 -328.80046)
					(mid 159.325056 -335.927446)
					(end 166.452042 -328.80046)
				)
			)
		)
	)
	(zone
		(layer "In2.Cu")
		(hatch none 0.5)
		(connect_pads
			(clearance 0)
		)
		(min_thickness 0.25)
		(keepout
			(tracks not_allowed)
			(vias allowed)
			(pads allowed)
			(copperpour not_allowed)
			(footprints allowed)
		)
		(placement
			(enabled no)
			(sheetname "")
		)
		(fill
			(thermal_gap 0.5)
			(thermal_bridge_width 0.5)
			(island_removal_mode 0)
		)
		(polygon
			(pts
				(arc
					(start 237.072932 -279.20061)
					(mid 244.199918 -286.327596)
					(end 251.326904 -279.20061)
				)
				(arc
					(start 251.326904 -273.200368)
					(mid 244.199918 -266.073636)
					(end 237.072932 -273.200368)
				)
			)
		)
	)
	(zone
		(layer "In2.Cu")
		(hatch none 0.5)
		(connect_pads
			(clearance 0)
		)
		(min_thickness 0.25)
		(keepout
			(tracks not_allowed)
			(vias allowed)
			(pads allowed)
			(copperpour not_allowed)
			(footprints allowed)
		)
		(placement
			(enabled no)
			(sheetname "")
		)
		(fill
			(thermal_gap 0.5)
			(thermal_bridge_width 0.5)
			(island_removal_mode 0)
		)
		(polygon
			(pts
				(arc
					(start 463.801968 -322.800472)
					(mid 456.674982 -315.673486)
					(end 449.547996 -322.800472)
				)
				(arc
					(start 449.547996 -328.80046)
					(mid 456.674982 -335.927446)
					(end 463.801968 -328.80046)
				)
			)
		)
	)
	(zone
		(layer "In2.Cu")
		(hatch none 0.5)
		(connect_pads
			(clearance 0)
		)
		(min_thickness 0.25)
		(keepout
			(tracks not_allowed)
			(vias allowed)
			(pads allowed)
			(copperpour not_allowed)
			(footprints allowed)
		)
		(placement
			(enabled no)
			(sheetname "")
		)
		(fill
			(thermal_gap 0.5)
			(thermal_bridge_width 0.5)
			(island_removal_mode 0)
		)
		(polygon
			(pts
				(arc
					(start 195.173092 -189.799976)
					(mid 202.300078 -196.926962)
					(end 209.427064 -189.799976)
				)
				(arc
					(start 209.427064 -183.799988)
					(mid 202.300078 -176.673002)
					(end 195.173092 -183.799988)
				)
			)
		)
	)
	(zone
		(layer "In2.Cu")
		(hatch none 0.5)
		(connect_pads
			(clearance 0)
		)
		(min_thickness 0.25)
		(keepout
			(tracks not_allowed)
			(vias allowed)
			(pads allowed)
			(copperpour not_allowed)
			(footprints allowed)
		)
		(placement
			(enabled no)
			(sheetname "")
		)
		(fill
			(thermal_gap 0.5)
			(thermal_bridge_width 0.5)
			(island_removal_mode 0)
		)
		(polygon
			(pts
				(arc
					(start 409.277058 -290.000436)
					(mid 399.52295 -290.000436)
					(end 409.277058 -290.000436)
				)
			)
		)
	)
	(zone
		(layer "In2.Cu")
		(hatch none 0.5)
		(connect_pads
			(clearance 0)
		)
		(min_thickness 0.25)
		(keepout
			(tracks not_allowed)
			(vias allowed)
			(pads allowed)
			(copperpour not_allowed)
			(footprints allowed)
		)
		(placement
			(enabled no)
			(sheetname "")
		)
		(fill
			(thermal_gap 0.5)
			(thermal_bridge_width 0.5)
			(island_removal_mode 0)
		)
		(polygon
			(pts
				(arc
					(start 463.801968 -207.800448)
					(mid 456.674982 -200.673462)
					(end 449.547996 -207.800448)
				)
				(arc
					(start 449.547996 -213.80069)
					(mid 456.674982 -220.927422)
					(end 463.801968 -213.80069)
				)
			)
		)
	)
	(zone
		(layer "In2.Cu")
		(hatch none 0.5)
		(connect_pads
			(clearance 0)
		)
		(min_thickness 0.25)
		(keepout
			(tracks not_allowed)
			(vias allowed)
			(pads allowed)
			(copperpour not_allowed)
			(footprints allowed)
		)
		(placement
			(enabled no)
			(sheetname "")
		)
		(fill
			(thermal_gap 0.5)
			(thermal_bridge_width 0.5)
			(island_removal_mode 0)
		)
		(polygon
			(pts
				(arc
					(start 337.801966 -207.800448)
					(mid 330.67498 -200.673462)
					(end 323.547994 -207.800448)
				)
				(arc
					(start 323.547994 -213.80069)
					(mid 330.67498 -220.927422)
					(end 337.801966 -213.80069)
				)
			)
		)
	)
	(zone
		(net "P12V_B_COMP")
		(layer "In2.Cu")
		(hatch none 0.5)
		(connect_pads
			(clearance 0.5)
		)
		(min_thickness 0.25)
		(fill yes
			(thermal_gap 0.5)
			(thermal_bridge_width 0.5)
			(island_removal_mode 0)
		)
		(polygon
			(pts
				(xy 283.7434 -179.5272) (xy 274.9042 -179.5272) (xy 274.2946 -180.1368) (xy 274.2946 -189.23) (xy 274.2946 -190.5)
				(xy 274.271232 -190.523368) (xy 274.271232 -191.044068) (xy 274.847812 -191.620648) (xy 296.967148 -191.620648)
				(xy 299.615352 -191.620648) (xy 300.355 -190.881) (xy 300.355 -180.086) (xy 299.8216 -179.5526)
				(xy 296.0116 -179.5526) (xy 283.7688 -179.5526)
			)
		)
	)
	(zone
		(layer "In2.Cu")
		(hatch none 0.5)
		(connect_pads
			(clearance 0)
		)
		(min_thickness 0.25)
		(keepout
			(tracks not_allowed)
			(vias allowed)
			(pads allowed)
			(copperpour not_allowed)
			(footprints allowed)
		)
		(placement
			(enabled no)
			(sheetname "")
		)
		(fill
			(thermal_gap 0.5)
			(thermal_bridge_width 0.5)
			(island_removal_mode 0)
		)
		(polygon
			(pts
				(arc
					(start 40.45204 -322.800472)
					(mid 33.325054 -315.673486)
					(end 26.198068 -322.800472)
				)
				(arc
					(start 26.198068 -328.80046)
					(mid 33.325054 -335.927446)
					(end 40.45204 -328.80046)
				)
			)
		)
	)
	(zone
		(layer "In2.Cu")
		(hatch none 0.5)
		(connect_pads
			(clearance 0)
		)
		(min_thickness 0.25)
		(keepout
			(tracks not_allowed)
			(vias allowed)
			(pads allowed)
			(copperpour not_allowed)
			(footprints allowed)
		)
		(placement
			(enabled no)
			(sheetname "")
		)
		(fill
			(thermal_gap 0.5)
			(thermal_bridge_width 0.5)
			(island_removal_mode 0)
		)
		(polygon
			(pts
				(arc
					(start 40.45204 -207.800448)
					(mid 33.325054 -200.673462)
					(end 26.198068 -207.800448)
				)
				(arc
					(start 26.198068 -213.80069)
					(mid 33.325054 -220.927422)
					(end 40.45204 -213.80069)
				)
			)
		)
	)
	(zone
		(layer "In2.Cu")
		(hatch none 0.5)
		(connect_pads
			(clearance 0)
		)
		(min_thickness 0.25)
		(keepout
			(tracks not_allowed)
			(vias allowed)
			(pads allowed)
			(copperpour not_allowed)
			(footprints allowed)
		)
		(placement
			(enabled no)
			(sheetname "")
		)
		(fill
			(thermal_gap 0.5)
			(thermal_bridge_width 0.5)
			(island_removal_mode 0)
		)
		(polygon
			(pts
				(arc
					(start 40.45204 -92.800424)
					(mid 33.325054 -85.673438)
					(end 26.198068 -92.800424)
				)
				(arc
					(start 26.198068 -98.800666)
					(mid 33.325054 -105.927398)
					(end 40.45204 -98.800666)
				)
			)
		)
	)
	(zone
		(layer "In2.Cu")
		(hatch none 0.5)
		(connect_pads
			(clearance 0)
		)
		(min_thickness 0.25)
		(keepout
			(tracks not_allowed)
			(vias allowed)
			(pads allowed)
			(copperpour not_allowed)
			(footprints allowed)
		)
		(placement
			(enabled no)
			(sheetname "")
		)
		(fill
			(thermal_gap 0.5)
			(thermal_bridge_width 0.5)
			(island_removal_mode 0)
		)
		(polygon
			(pts
				(arc
					(start 175.07712 -270.000476)
					(mid 165.323012 -270.000476)
					(end 175.07712 -270.000476)
				)
			)
		)
	)
	(zone
		(layer "In2.Cu")
		(hatch none 0.5)
		(connect_pads
			(clearance 0)
		)
		(min_thickness 0.25)
		(keepout
			(tracks not_allowed)
			(vias allowed)
			(pads allowed)
			(copperpour not_allowed)
			(footprints allowed)
		)
		(placement
			(enabled no)
			(sheetname "")
		)
		(fill
			(thermal_gap 0.5)
			(thermal_bridge_width 0.5)
			(island_removal_mode 0)
		)
		(polygon
			(pts
				(arc
					(start 337.801966 -322.800472)
					(mid 330.67498 -315.673486)
					(end 323.547994 -322.800472)
				)
				(arc
					(start 323.547994 -328.80046)
					(mid 330.67498 -335.927446)
					(end 337.801966 -328.80046)
				)
			)
		)
	)
	(zone
		(layer "In2.Cu")
		(hatch none 0.5)
		(connect_pads
			(clearance 0)
		)
		(min_thickness 0.25)
		(keepout
			(tracks not_allowed)
			(vias allowed)
			(pads allowed)
			(copperpour not_allowed)
			(footprints allowed)
		)
		(placement
			(enabled no)
			(sheetname "")
		)
		(fill
			(thermal_gap 0.5)
			(thermal_bridge_width 0.5)
			(island_removal_mode 0)
		)
		(polygon
			(pts
				(arc
					(start 400.802094 -207.800448)
					(mid 393.675108 -200.673462)
					(end 386.548122 -207.800448)
				)
				(arc
					(start 386.548122 -213.80069)
					(mid 393.675108 -220.927422)
					(end 400.802094 -213.80069)
				)
			)
		)
	)
	(zone
		(layer "In2.Cu")
		(hatch none 0.5)
		(connect_pads
			(clearance 0)
		)
		(min_thickness 0.25)
		(keepout
			(tracks not_allowed)
			(vias allowed)
			(pads allowed)
			(copperpour not_allowed)
			(footprints allowed)
		)
		(placement
			(enabled no)
			(sheetname "")
		)
		(fill
			(thermal_gap 0.5)
			(thermal_bridge_width 0.5)
			(island_removal_mode 0)
		)
		(polygon
			(pts
				(arc
					(start 400.802094 -92.800424)
					(mid 393.675108 -85.673438)
					(end 386.548122 -92.800424)
				)
				(arc
					(start 386.548122 -98.800666)
					(mid 393.675108 -105.927398)
					(end 400.802094 -98.800666)
				)
			)
		)
	)
	(zone
		(layer "In2.Cu")
		(hatch none 0.5)
		(connect_pads
			(clearance 0)
		)
		(min_thickness 0.25)
		(keepout
			(tracks not_allowed)
			(vias allowed)
			(pads allowed)
			(copperpour not_allowed)
			(footprints allowed)
		)
		(placement
			(enabled no)
			(sheetname "")
		)
		(fill
			(thermal_gap 0.5)
			(thermal_bridge_width 0.5)
			(island_removal_mode 0)
		)
		(polygon
			(pts
				(arc
					(start 111.976916 -290.000436)
					(mid 102.223316 -290.000436)
					(end 111.976916 -290.000436)
				)
			)
		)
	)
	(zone
		(net "MB3_P12V_IN_R")
		(layer "In2.Cu")
		(hatch none 0.5)
		(connect_pads
			(clearance 0.5)
		)
		(min_thickness 0.25)
		(fill yes
			(thermal_gap 0.5)
			(thermal_bridge_width 0.5)
			(island_removal_mode 0)
		)
		(polygon
			(pts
				(xy 253.111 -390.15416) (xy 265.951208 -390.15416) (xy 273.92884 -390.15416) (xy 274.066 -390.017)
				(xy 274.465542 -389.617458) (xy 274.465542 -386.81025) (xy 274.465542 -381.720598) (xy 274.465542 -379.113542)
				(xy 274.465542 -378.074682) (xy 274.21586 -377.825) (xy 253.14656 -377.825) (xy 252.975872 -377.825)
				(xy 252.552708 -378.248164) (xy 252.552708 -389.780018) (xy 252.92685 -390.15416)
			)
		)
	)
	(zone
		(layer "In2.Cu")
		(hatch none 0.5)
		(connect_pads
			(clearance 0)
		)
		(min_thickness 0.25)
		(keepout
			(tracks not_allowed)
			(vias allowed)
			(pads allowed)
			(copperpour not_allowed)
			(footprints allowed)
		)
		(placement
			(enabled no)
			(sheetname "")
		)
		(fill
			(thermal_gap 0.5)
			(thermal_bridge_width 0.5)
			(island_removal_mode 0)
		)
		(polygon
			(pts
				(arc
					(start 166.452042 -92.800424)
					(mid 159.325056 -85.673438)
					(end 152.19807 -92.800424)
				)
				(arc
					(start 152.19807 -98.800666)
					(mid 159.325056 -105.927398)
					(end 166.452042 -98.800666)
				)
			)
		)
	)
	(zone
		(layer "In2.Cu")
		(hatch none 0.5)
		(connect_pads
			(clearance 0)
		)
		(min_thickness 0.25)
		(keepout
			(tracks not_allowed)
			(vias allowed)
			(pads allowed)
			(copperpour not_allowed)
			(footprints allowed)
		)
		(placement
			(enabled no)
			(sheetname "")
		)
		(fill
			(thermal_gap 0.5)
			(thermal_bridge_width 0.5)
			(island_removal_mode 0)
		)
		(polygon
			(pts
				(arc
					(start 103.451914 -322.800472)
					(mid 96.324928 -315.673486)
					(end 89.197942 -322.800472)
				)
				(arc
					(start 89.197942 -328.80046)
					(mid 96.324928 -335.927446)
					(end 103.451914 -328.80046)
				)
			)
		)
	)
	(zone
		(layer "In2.Cu")
		(hatch none 0.5)
		(connect_pads
			(clearance 0)
		)
		(min_thickness 0.25)
		(keepout
			(tracks not_allowed)
			(vias allowed)
			(pads allowed)
			(copperpour not_allowed)
			(footprints allowed)
		)
		(placement
			(enabled no)
			(sheetname "")
		)
		(fill
			(thermal_gap 0.5)
			(thermal_bridge_width 0.5)
			(island_removal_mode 0)
		)
		(polygon
			(pts
				(arc
					(start 195.173092 -69.80047)
					(mid 202.300078 -76.927456)
					(end 209.427064 -69.80047)
				)
				(arc
					(start 209.427064 -63.800482)
					(mid 202.300078 -56.673496)
					(end 195.173092 -63.800482)
				)
			)
		)
	)
	(zone
		(layers "In2.Cu" "In4.Cu")
		(hatch none 0.5)
		(connect_pads
			(clearance 0)
		)
		(min_thickness 0.25)
		(keepout
			(tracks not_allowed)
			(vias allowed)
			(pads allowed)
			(copperpour not_allowed)
			(footprints allowed)
		)
		(placement
			(enabled no)
			(sheetname "")
		)
		(fill yes
			(thermal_gap 0.5)
			(thermal_bridge_width 0.5)
			(island_removal_mode 0)
		)
		(polygon
			(pts
				(arc
					(start 114.549936 -22.75332)
					(mid 114.549936 -23.94712)
					(end 114.549936 -22.75332)
				)
			)
		)
	)
	(zone
		(layers "In2.Cu" "In4.Cu")
		(hatch none 0.5)
		(connect_pads
			(clearance 0)
		)
		(min_thickness 0.25)
		(keepout
			(tracks not_allowed)
			(vias allowed)
			(pads allowed)
			(copperpour not_allowed)
			(footprints allowed)
		)
		(placement
			(enabled no)
			(sheetname "")
		)
		(fill yes
			(thermal_gap 0.5)
			(thermal_bridge_width 0.5)
			(island_removal_mode 0)
		)
		(polygon
			(pts
				(arc
					(start 367.75009 -21.353272)
					(mid 367.75009 -22.547072)
					(end 367.75009 -21.353272)
				)
			)
		)
	)
	(zone
		(layers "In2.Cu" "In4.Cu")
		(hatch none 0.5)
		(connect_pads
			(clearance 0)
		)
		(min_thickness 0.25)
		(keepout
			(tracks not_allowed)
			(vias allowed)
			(pads allowed)
			(copperpour not_allowed)
			(footprints allowed)
		)
		(placement
			(enabled no)
			(sheetname "")
		)
		(fill yes
			(thermal_gap 0.5)
			(thermal_bridge_width 0.5)
			(island_removal_mode 0)
		)
		(polygon
			(pts
				(arc
					(start 355.149912 -18.153126)
					(mid 355.149912 -19.346926)
					(end 355.149912 -18.153126)
				)
			)
		)
	)
	(zone
		(layers "In2.Cu" "In4.Cu")
		(hatch none 0.5)
		(connect_pads
			(clearance 0)
		)
		(min_thickness 0.25)
		(keepout
			(tracks not_allowed)
			(vias allowed)
			(pads allowed)
			(copperpour not_allowed)
			(footprints allowed)
		)
		(placement
			(enabled no)
			(sheetname "")
		)
		(fill yes
			(thermal_gap 0.5)
			(thermal_bridge_width 0.5)
			(island_removal_mode 0)
		)
		(polygon
			(pts
				(arc
					(start 385.750054 -17.75333)
					(mid 385.750054 -18.94713)
					(end 385.750054 -17.75333)
				)
			)
		)
	)
	(zone
		(layers "In2.Cu" "In4.Cu")
		(hatch none 0.5)
		(connect_pads
			(clearance 0)
		)
		(min_thickness 0.25)
		(keepout
			(tracks not_allowed)
			(vias allowed)
			(pads allowed)
			(copperpour not_allowed)
			(footprints allowed)
		)
		(placement
			(enabled no)
			(sheetname "")
		)
		(fill yes
			(thermal_gap 0.5)
			(thermal_bridge_width 0.5)
			(island_removal_mode 0)
		)
		(polygon
			(pts
				(arc
					(start 378.549916 -21.353272)
					(mid 378.549916 -22.547072)
					(end 378.549916 -21.353272)
				)
			)
		)
	)
	(zone
		(layers "In2.Cu" "In4.Cu")
		(hatch none 0.5)
		(connect_pads
			(clearance 0)
		)
		(min_thickness 0.25)
		(keepout
			(tracks not_allowed)
			(vias allowed)
			(pads allowed)
			(copperpour not_allowed)
			(footprints allowed)
		)
		(placement
			(enabled no)
			(sheetname "")
		)
		(fill yes
			(thermal_gap 0.5)
			(thermal_bridge_width 0.5)
			(island_removal_mode 0)
		)
		(polygon
			(pts
				(arc
					(start 136.150096 -19.153124)
					(mid 136.150096 -20.346924)
					(end 136.150096 -19.153124)
				)
			)
		)
	)
	(zone
		(layers "In2.Cu" "In4.Cu")
		(hatch none 0.5)
		(connect_pads
			(clearance 0)
		)
		(min_thickness 0.25)
		(keepout
			(tracks not_allowed)
			(vias allowed)
			(pads allowed)
			(copperpour not_allowed)
			(footprints allowed)
		)
		(placement
			(enabled no)
			(sheetname "")
		)
		(fill yes
			(thermal_gap 0.5)
			(thermal_bridge_width 0.5)
			(island_removal_mode 0)
		)
		(polygon
			(pts
				(arc
					(start 134.349998 -20.353274)
					(mid 134.349998 -21.547074)
					(end 134.349998 -20.353274)
				)
			)
		)
	)
	(zone
		(layers "In2.Cu" "In4.Cu")
		(hatch none 0.5)
		(connect_pads
			(clearance 0)
		)
		(min_thickness 0.25)
		(keepout
			(tracks not_allowed)
			(vias allowed)
			(pads allowed)
			(copperpour not_allowed)
			(footprints allowed)
		)
		(placement
			(enabled no)
			(sheetname "")
		)
		(fill yes
			(thermal_gap 0.5)
			(thermal_bridge_width 0.5)
			(island_removal_mode 0)
		)
		(polygon
			(pts
				(arc
					(start 376.750072 -21.753322)
					(mid 376.750072 -22.947122)
					(end 376.750072 -21.753322)
				)
			)
		)
	)
	(zone
		(layers "In2.Cu" "In4.Cu")
		(hatch none 0.5)
		(connect_pads
			(clearance 0)
		)
		(min_thickness 0.25)
		(keepout
			(tracks not_allowed)
			(vias allowed)
			(pads allowed)
			(copperpour not_allowed)
			(footprints allowed)
		)
		(placement
			(enabled no)
			(sheetname "")
		)
		(fill yes
			(thermal_gap 0.5)
			(thermal_bridge_width 0.5)
			(island_removal_mode 0)
		)
		(polygon
			(pts
				(arc
					(start 119.949976 -21.753322)
					(mid 119.949976 -22.947122)
					(end 119.949976 -21.753322)
				)
			)
		)
	)
	(zone
		(layers "In2.Cu" "In4.Cu")
		(hatch none 0.5)
		(connect_pads
			(clearance 0)
		)
		(min_thickness 0.25)
		(keepout
			(tracks not_allowed)
			(vias allowed)
			(pads allowed)
			(copperpour not_allowed)
			(footprints allowed)
		)
		(placement
			(enabled no)
			(sheetname "")
		)
		(fill yes
			(thermal_gap 0.5)
			(thermal_bridge_width 0.5)
			(island_removal_mode 0)
		)
		(polygon
			(pts
				(arc
					(start 367.75009 -17.75333)
					(mid 367.75009 -18.94713)
					(end 367.75009 -17.75333)
				)
			)
		)
	)
	(zone
		(layers "In2.Cu" "In4.Cu")
		(hatch none 0.5)
		(connect_pads
			(clearance 0)
		)
		(min_thickness 0.25)
		(keepout
			(tracks not_allowed)
			(vias allowed)
			(pads allowed)
			(copperpour not_allowed)
			(footprints allowed)
		)
		(placement
			(enabled no)
			(sheetname "")
		)
		(fill yes
			(thermal_gap 0.5)
			(thermal_bridge_width 0.5)
			(island_removal_mode 0)
		)
		(polygon
			(pts
				(arc
					(start 110.949994 -19.153124)
					(mid 110.949994 -20.346924)
					(end 110.949994 -19.153124)
				)
			)
		)
	)
	(zone
		(layers "In2.Cu" "In4.Cu")
		(hatch none 0.5)
		(connect_pads
			(clearance 0)
		)
		(min_thickness 0.25)
		(keepout
			(tracks not_allowed)
			(vias allowed)
			(pads allowed)
			(copperpour not_allowed)
			(footprints allowed)
		)
		(placement
			(enabled no)
			(sheetname "")
		)
		(fill yes
			(thermal_gap 0.5)
			(thermal_bridge_width 0.5)
			(island_removal_mode 0)
		)
		(polygon
			(pts
				(arc
					(start 139.750038 -22.75332)
					(mid 139.750038 -23.94712)
					(end 139.750038 -22.75332)
				)
			)
		)
	)
	(zone
		(layers "In2.Cu" "In4.Cu")
		(hatch none 0.5)
		(connect_pads
			(clearance 0)
		)
		(min_thickness 0.25)
		(keepout
			(tracks not_allowed)
			(vias allowed)
			(pads allowed)
			(copperpour not_allowed)
			(footprints allowed)
		)
		(placement
			(enabled no)
			(sheetname "")
		)
		(fill yes
			(thermal_gap 0.5)
			(thermal_bridge_width 0.5)
			(island_removal_mode 0)
		)
		(polygon
			(pts
				(arc
					(start 137.94994 -18.153126)
					(mid 137.94994 -19.346926)
					(end 137.94994 -18.153126)
				)
			)
		)
	)
	(zone
		(layers "In2.Cu" "In4.Cu")
		(hatch none 0.5)
		(connect_pads
			(clearance 0)
		)
		(min_thickness 0.25)
		(keepout
			(tracks not_allowed)
			(vias allowed)
			(pads allowed)
			(copperpour not_allowed)
			(footprints allowed)
		)
		(placement
			(enabled no)
			(sheetname "")
		)
		(fill yes
			(thermal_gap 0.5)
			(thermal_bridge_width 0.5)
			(island_removal_mode 0)
		)
		(polygon
			(pts
				(arc
					(start 355.149912 -20.353274)
					(mid 355.149912 -21.547074)
					(end 355.149912 -20.353274)
				)
			)
		)
	)
	(zone
		(layers "In2.Cu" "In4.Cu")
		(hatch none 0.5)
		(connect_pads
			(clearance 0)
		)
		(min_thickness 0.25)
		(keepout
			(tracks not_allowed)
			(vias allowed)
			(pads allowed)
			(copperpour not_allowed)
			(footprints allowed)
		)
		(placement
			(enabled no)
			(sheetname "")
		)
		(fill yes
			(thermal_gap 0.5)
			(thermal_bridge_width 0.5)
			(island_removal_mode 0)
		)
		(polygon
			(pts
				(arc
					(start 376.750072 -18.153126)
					(mid 376.750072 -19.346926)
					(end 376.750072 -18.153126)
				)
			)
		)
	)
	(zone
		(layers "In2.Cu" "In4.Cu")
		(hatch none 0.5)
		(connect_pads
			(clearance 0)
		)
		(min_thickness 0.25)
		(keepout
			(tracks not_allowed)
			(vias allowed)
			(pads allowed)
			(copperpour not_allowed)
			(footprints allowed)
		)
		(placement
			(enabled no)
			(sheetname "")
		)
		(fill yes
			(thermal_gap 0.5)
			(thermal_bridge_width 0.5)
			(island_removal_mode 0)
		)
		(polygon
			(pts
				(arc
					(start 143.34998 -19.153124)
					(mid 143.34998 -20.346924)
					(end 143.34998 -19.153124)
				)
			)
		)
	)
	(zone
		(layers "In2.Cu" "In4.Cu")
		(hatch none 0.5)
		(connect_pads
			(clearance 0)
		)
		(min_thickness 0.25)
		(keepout
			(tracks not_allowed)
			(vias allowed)
			(pads allowed)
			(copperpour not_allowed)
			(footprints allowed)
		)
		(placement
			(enabled no)
			(sheetname "")
		)
		(fill yes
			(thermal_gap 0.5)
			(thermal_bridge_width 0.5)
			(island_removal_mode 0)
		)
		(polygon
			(pts
				(arc
					(start 143.34998 -17.75333)
					(mid 143.34998 -18.94713)
					(end 143.34998 -17.75333)
				)
			)
		)
	)
	(zone
		(layers "In2.Cu" "In4.Cu")
		(hatch none 0.5)
		(connect_pads
			(clearance 0)
		)
		(min_thickness 0.25)
		(keepout
			(tracks not_allowed)
			(vias allowed)
			(pads allowed)
			(copperpour not_allowed)
			(footprints allowed)
		)
		(placement
			(enabled no)
			(sheetname "")
		)
		(fill yes
			(thermal_gap 0.5)
			(thermal_bridge_width 0.5)
			(island_removal_mode 0)
		)
		(polygon
			(pts
				(arc
					(start 382.150112 -22.75332)
					(mid 382.150112 -23.94712)
					(end 382.150112 -22.75332)
				)
			)
		)
	)
	(zone
		(layers "In2.Cu" "In4.Cu")
		(hatch none 0.5)
		(connect_pads
			(clearance 0)
		)
		(min_thickness 0.25)
		(keepout
			(tracks not_allowed)
			(vias allowed)
			(pads allowed)
			(copperpour not_allowed)
			(footprints allowed)
		)
		(placement
			(enabled no)
			(sheetname "")
		)
		(fill yes
			(thermal_gap 0.5)
			(thermal_bridge_width 0.5)
			(island_removal_mode 0)
		)
		(polygon
			(pts
				(arc
					(start 137.94994 -16.753078)
					(mid 137.94994 -17.946878)
					(end 137.94994 -16.753078)
				)
			)
		)
	)
	(zone
		(layers "In2.Cu" "In4.Cu")
		(hatch none 0.5)
		(connect_pads
			(clearance 0)
		)
		(min_thickness 0.25)
		(keepout
			(tracks not_allowed)
			(vias allowed)
			(pads allowed)
			(copperpour not_allowed)
			(footprints allowed)
		)
		(placement
			(enabled no)
			(sheetname "")
		)
		(fill yes
			(thermal_gap 0.5)
			(thermal_bridge_width 0.5)
			(island_removal_mode 0)
		)
		(polygon
			(pts
				(arc
					(start 365.949992 -18.153126)
					(mid 365.949992 -19.346926)
					(end 365.949992 -18.153126)
				)
			)
		)
	)
	(zone
		(layers "In2.Cu" "In4.Cu")
		(hatch none 0.5)
		(connect_pads
			(clearance 0)
		)
		(min_thickness 0.25)
		(keepout
			(tracks not_allowed)
			(vias allowed)
			(pads allowed)
			(copperpour not_allowed)
			(footprints allowed)
		)
		(placement
			(enabled no)
			(sheetname "")
		)
		(fill yes
			(thermal_gap 0.5)
			(thermal_bridge_width 0.5)
			(island_removal_mode 0)
		)
		(polygon
			(pts
				(arc
					(start 358.750108 -18.153126)
					(mid 358.750108 -19.346926)
					(end 358.750108 -18.153126)
				)
			)
		)
	)
	(zone
		(layers "In2.Cu" "In4.Cu")
		(hatch none 0.5)
		(connect_pads
			(clearance 0)
		)
		(min_thickness 0.25)
		(keepout
			(tracks not_allowed)
			(vias allowed)
			(pads allowed)
			(copperpour not_allowed)
			(footprints allowed)
		)
		(placement
			(enabled no)
			(sheetname "")
		)
		(fill yes
			(thermal_gap 0.5)
			(thermal_bridge_width 0.5)
			(island_removal_mode 0)
		)
		(polygon
			(pts
				(arc
					(start 378.549916 -17.75333)
					(mid 378.549916 -18.94713)
					(end 378.549916 -17.75333)
				)
			)
		)
	)
	(zone
		(layers "In2.Cu" "In4.Cu")
		(hatch none 0.5)
		(connect_pads
			(clearance 0)
		)
		(min_thickness 0.25)
		(keepout
			(tracks not_allowed)
			(vias allowed)
			(pads allowed)
			(copperpour not_allowed)
			(footprints allowed)
		)
		(placement
			(enabled no)
			(sheetname "")
		)
		(fill yes
			(thermal_gap 0.5)
			(thermal_bridge_width 0.5)
			(island_removal_mode 0)
		)
		(polygon
			(pts
				(arc
					(start 139.750038 -17.75333)
					(mid 139.750038 -18.94713)
					(end 139.750038 -17.75333)
				)
			)
		)
	)
	(zone
		(layers "In2.Cu" "In4.Cu")
		(hatch none 0.5)
		(connect_pads
			(clearance 0)
		)
		(min_thickness 0.25)
		(keepout
			(tracks not_allowed)
			(vias allowed)
			(pads allowed)
			(copperpour not_allowed)
			(footprints allowed)
		)
		(placement
			(enabled no)
			(sheetname "")
		)
		(fill yes
			(thermal_gap 0.5)
			(thermal_bridge_width 0.5)
			(island_removal_mode 0)
		)
		(polygon
			(pts
				(arc
					(start 383.949956 -18.153126)
					(mid 383.949956 -19.346926)
					(end 383.949956 -18.153126)
				)
			)
		)
	)
	(zone
		(layers "In2.Cu" "In4.Cu")
		(hatch none 0.5)
		(connect_pads
			(clearance 0)
		)
		(min_thickness 0.25)
		(keepout
			(tracks not_allowed)
			(vias allowed)
			(pads allowed)
			(copperpour not_allowed)
			(footprints allowed)
		)
		(placement
			(enabled no)
			(sheetname "")
		)
		(fill yes
			(thermal_gap 0.5)
			(thermal_bridge_width 0.5)
			(island_removal_mode 0)
		)
		(polygon
			(pts
				(arc
					(start 365.949992 -16.753078)
					(mid 365.949992 -17.946878)
					(end 365.949992 -16.753078)
				)
			)
		)
	)
	(zone
		(layers "In2.Cu" "In4.Cu")
		(hatch none 0.5)
		(connect_pads
			(clearance 0)
		)
		(min_thickness 0.25)
		(keepout
			(tracks not_allowed)
			(vias allowed)
			(pads allowed)
			(copperpour not_allowed)
			(footprints allowed)
		)
		(placement
			(enabled no)
			(sheetname "")
		)
		(fill yes
			(thermal_gap 0.5)
			(thermal_bridge_width 0.5)
			(island_removal_mode 0)
		)
		(polygon
			(pts
				(arc
					(start 389.349996 -21.353272)
					(mid 389.349996 -22.547072)
					(end 389.349996 -21.353272)
				)
			)
		)
	)
	(zone
		(layers "In2.Cu" "In4.Cu")
		(hatch none 0.5)
		(connect_pads
			(clearance 0)
		)
		(min_thickness 0.25)
		(keepout
			(tracks not_allowed)
			(vias allowed)
			(pads allowed)
			(copperpour not_allowed)
			(footprints allowed)
		)
		(placement
			(enabled no)
			(sheetname "")
		)
		(fill yes
			(thermal_gap 0.5)
			(thermal_bridge_width 0.5)
			(island_removal_mode 0)
		)
		(polygon
			(pts
				(arc
					(start 139.750038 -21.353272)
					(mid 139.750038 -22.547072)
					(end 139.750038 -21.353272)
				)
			)
		)
	)
	(zone
		(layers "In2.Cu" "In4.Cu")
		(hatch none 0.5)
		(connect_pads
			(clearance 0)
		)
		(min_thickness 0.25)
		(keepout
			(tracks not_allowed)
			(vias allowed)
			(pads allowed)
			(copperpour not_allowed)
			(footprints allowed)
		)
		(placement
			(enabled no)
			(sheetname "")
		)
		(fill yes
			(thermal_gap 0.5)
			(thermal_bridge_width 0.5)
			(island_removal_mode 0)
		)
		(polygon
			(pts
				(arc
					(start 376.750072 -20.353274)
					(mid 376.750072 -21.547074)
					(end 376.750072 -20.353274)
				)
			)
		)
	)
	(zone
		(layers "In2.Cu" "In4.Cu")
		(hatch none 0.5)
		(connect_pads
			(clearance 0)
		)
		(min_thickness 0.25)
		(keepout
			(tracks not_allowed)
			(vias allowed)
			(pads allowed)
			(copperpour not_allowed)
			(footprints allowed)
		)
		(placement
			(enabled no)
			(sheetname "")
		)
		(fill yes
			(thermal_gap 0.5)
			(thermal_bridge_width 0.5)
			(island_removal_mode 0)
		)
		(polygon
			(pts
				(arc
					(start 110.949994 -22.75332)
					(mid 110.949994 -23.94712)
					(end 110.949994 -22.75332)
				)
			)
		)
	)
	(zone
		(layers "In2.Cu" "In4.Cu")
		(hatch none 0.5)
		(connect_pads
			(clearance 0)
		)
		(min_thickness 0.25)
		(keepout
			(tracks not_allowed)
			(vias allowed)
			(pads allowed)
			(copperpour not_allowed)
			(footprints allowed)
		)
		(placement
			(enabled no)
			(sheetname "")
		)
		(fill yes
			(thermal_gap 0.5)
			(thermal_bridge_width 0.5)
			(island_removal_mode 0)
		)
		(polygon
			(pts
				(arc
					(start 114.549936 -21.353272)
					(mid 114.549936 -22.547072)
					(end 114.549936 -21.353272)
				)
			)
		)
	)
	(zone
		(layers "In2.Cu" "In4.Cu")
		(hatch none 0.5)
		(connect_pads
			(clearance 0)
		)
		(min_thickness 0.25)
		(keepout
			(tracks not_allowed)
			(vias allowed)
			(pads allowed)
			(copperpour not_allowed)
			(footprints allowed)
		)
		(placement
			(enabled no)
			(sheetname "")
		)
		(fill yes
			(thermal_gap 0.5)
			(thermal_bridge_width 0.5)
			(island_removal_mode 0)
		)
		(polygon
			(pts
				(arc
					(start 358.750108 -16.753078)
					(mid 358.750108 -17.946878)
					(end 358.750108 -16.753078)
				)
			)
		)
	)
	(zone
		(layers "In2.Cu" "In4.Cu")
		(hatch none 0.5)
		(connect_pads
			(clearance 0)
		)
		(min_thickness 0.25)
		(keepout
			(tracks not_allowed)
			(vias allowed)
			(pads allowed)
			(copperpour not_allowed)
			(footprints allowed)
		)
		(placement
			(enabled no)
			(sheetname "")
		)
		(fill yes
			(thermal_gap 0.5)
			(thermal_bridge_width 0.5)
			(island_removal_mode 0)
		)
		(polygon
			(pts
				(arc
					(start 136.150096 -22.75332)
					(mid 136.150096 -23.94712)
					(end 136.150096 -22.75332)
				)
			)
		)
	)
	(zone
		(layers "In2.Cu" "In4.Cu")
		(hatch none 0.5)
		(connect_pads
			(clearance 0)
		)
		(min_thickness 0.25)
		(keepout
			(tracks not_allowed)
			(vias allowed)
			(pads allowed)
			(copperpour not_allowed)
			(footprints allowed)
		)
		(placement
			(enabled no)
			(sheetname "")
		)
		(fill yes
			(thermal_gap 0.5)
			(thermal_bridge_width 0.5)
			(island_removal_mode 0)
		)
		(polygon
			(pts
				(arc
					(start 112.750092 -20.353274)
					(mid 112.750092 -21.547074)
					(end 112.750092 -20.353274)
				)
			)
		)
	)
	(zone
		(layers "In2.Cu" "In4.Cu")
		(hatch none 0.5)
		(connect_pads
			(clearance 0)
		)
		(min_thickness 0.25)
		(keepout
			(tracks not_allowed)
			(vias allowed)
			(pads allowed)
			(copperpour not_allowed)
			(footprints allowed)
		)
		(placement
			(enabled no)
			(sheetname "")
		)
		(fill yes
			(thermal_gap 0.5)
			(thermal_bridge_width 0.5)
			(island_removal_mode 0)
		)
		(polygon
			(pts
				(arc
					(start 387.549898 -18.153126)
					(mid 387.549898 -19.346926)
					(end 387.549898 -18.153126)
				)
			)
		)
	)
	(zone
		(layers "In2.Cu" "In4.Cu")
		(hatch none 0.5)
		(connect_pads
			(clearance 0)
		)
		(min_thickness 0.25)
		(keepout
			(tracks not_allowed)
			(vias allowed)
			(pads allowed)
			(copperpour not_allowed)
			(footprints allowed)
		)
		(placement
			(enabled no)
			(sheetname "")
		)
		(fill yes
			(thermal_gap 0.5)
			(thermal_bridge_width 0.5)
			(island_removal_mode 0)
		)
		(polygon
			(pts
				(arc
					(start 109.149896 -16.753078)
					(mid 109.149896 -17.946878)
					(end 109.149896 -16.753078)
				)
			)
		)
	)
	(zone
		(layers "In2.Cu" "In4.Cu")
		(hatch none 0.5)
		(connect_pads
			(clearance 0)
		)
		(min_thickness 0.25)
		(keepout
			(tracks not_allowed)
			(vias allowed)
			(pads allowed)
			(copperpour not_allowed)
			(footprints allowed)
		)
		(placement
			(enabled no)
			(sheetname "")
		)
		(fill yes
			(thermal_gap 0.5)
			(thermal_bridge_width 0.5)
			(island_removal_mode 0)
		)
		(polygon
			(pts
				(arc
					(start 367.75009 -22.75332)
					(mid 367.75009 -23.94712)
					(end 367.75009 -22.75332)
				)
			)
		)
	)
	(zone
		(layers "In2.Cu" "In4.Cu")
		(hatch none 0.5)
		(connect_pads
			(clearance 0)
		)
		(min_thickness 0.25)
		(keepout
			(tracks not_allowed)
			(vias allowed)
			(pads allowed)
			(copperpour not_allowed)
			(footprints allowed)
		)
		(placement
			(enabled no)
			(sheetname "")
		)
		(fill yes
			(thermal_gap 0.5)
			(thermal_bridge_width 0.5)
			(island_removal_mode 0)
		)
		(polygon
			(pts
				(arc
					(start 360.549952 -21.353272)
					(mid 360.549952 -22.547072)
					(end 360.549952 -21.353272)
				)
			)
		)
	)
	(zone
		(layers "In2.Cu" "In4.Cu")
		(hatch none 0.5)
		(connect_pads
			(clearance 0)
		)
		(min_thickness 0.25)
		(keepout
			(tracks not_allowed)
			(vias allowed)
			(pads allowed)
			(copperpour not_allowed)
			(footprints allowed)
		)
		(placement
			(enabled no)
			(sheetname "")
		)
		(fill yes
			(thermal_gap 0.5)
			(thermal_bridge_width 0.5)
			(island_removal_mode 0)
		)
		(polygon
			(pts
				(arc
					(start 358.750108 -21.753322)
					(mid 358.750108 -22.947122)
					(end 358.750108 -21.753322)
				)
			)
		)
	)
	(zone
		(layers "In2.Cu" "In4.Cu")
		(hatch none 0.5)
		(connect_pads
			(clearance 0)
		)
		(min_thickness 0.25)
		(keepout
			(tracks not_allowed)
			(vias allowed)
			(pads allowed)
			(copperpour not_allowed)
			(footprints allowed)
		)
		(placement
			(enabled no)
			(sheetname "")
		)
		(fill yes
			(thermal_gap 0.5)
			(thermal_bridge_width 0.5)
			(island_removal_mode 0)
		)
		(polygon
			(pts
				(arc
					(start 143.34998 -22.75332)
					(mid 143.34998 -23.94712)
					(end 143.34998 -22.75332)
				)
			)
		)
	)
	(zone
		(layers "In2.Cu" "In4.Cu")
		(hatch none 0.5)
		(connect_pads
			(clearance 0)
		)
		(min_thickness 0.25)
		(keepout
			(tracks not_allowed)
			(vias allowed)
			(pads allowed)
			(copperpour not_allowed)
			(footprints allowed)
		)
		(placement
			(enabled no)
			(sheetname "")
		)
		(fill yes
			(thermal_gap 0.5)
			(thermal_bridge_width 0.5)
			(island_removal_mode 0)
		)
		(polygon
			(pts
				(arc
					(start 118.149878 -22.75332)
					(mid 118.149878 -23.94712)
					(end 118.149878 -22.75332)
				)
			)
		)
	)
	(zone
		(layers "In2.Cu" "In4.Cu")
		(hatch none 0.5)
		(connect_pads
			(clearance 0)
		)
		(min_thickness 0.25)
		(keepout
			(tracks not_allowed)
			(vias allowed)
			(pads allowed)
			(copperpour not_allowed)
			(footprints allowed)
		)
		(placement
			(enabled no)
			(sheetname "")
		)
		(fill yes
			(thermal_gap 0.5)
			(thermal_bridge_width 0.5)
			(island_removal_mode 0)
		)
		(polygon
			(pts
				(arc
					(start 137.94994 -20.353274)
					(mid 137.94994 -21.547074)
					(end 137.94994 -20.353274)
				)
			)
		)
	)
	(zone
		(layers "In2.Cu" "In4.Cu")
		(hatch none 0.5)
		(connect_pads
			(clearance 0)
		)
		(min_thickness 0.25)
		(keepout
			(tracks not_allowed)
			(vias allowed)
			(pads allowed)
			(copperpour not_allowed)
			(footprints allowed)
		)
		(placement
			(enabled no)
			(sheetname "")
		)
		(fill yes
			(thermal_gap 0.5)
			(thermal_bridge_width 0.5)
			(island_removal_mode 0)
		)
		(polygon
			(pts
				(arc
					(start 110.949994 -17.75333)
					(mid 110.949994 -18.94713)
					(end 110.949994 -17.75333)
				)
			)
		)
	)
	(zone
		(layers "In2.Cu" "In4.Cu")
		(hatch none 0.5)
		(connect_pads
			(clearance 0)
		)
		(min_thickness 0.25)
		(keepout
			(tracks not_allowed)
			(vias allowed)
			(pads allowed)
			(copperpour not_allowed)
			(footprints allowed)
		)
		(placement
			(enabled no)
			(sheetname "")
		)
		(fill yes
			(thermal_gap 0.5)
			(thermal_bridge_width 0.5)
			(island_removal_mode 0)
		)
		(polygon
			(pts
				(arc
					(start 389.349996 -17.75333)
					(mid 389.349996 -18.94713)
					(end 389.349996 -17.75333)
				)
			)
		)
	)
	(zone
		(layers "In2.Cu" "In4.Cu")
		(hatch none 0.5)
		(connect_pads
			(clearance 0)
		)
		(min_thickness 0.25)
		(keepout
			(tracks not_allowed)
			(vias allowed)
			(pads allowed)
			(copperpour not_allowed)
			(footprints allowed)
		)
		(placement
			(enabled no)
			(sheetname "")
		)
		(fill yes
			(thermal_gap 0.5)
			(thermal_bridge_width 0.5)
			(island_removal_mode 0)
		)
		(polygon
			(pts
				(arc
					(start 134.349998 -21.753322)
					(mid 134.349998 -22.947122)
					(end 134.349998 -21.753322)
				)
			)
		)
	)
	(zone
		(layers "In2.Cu" "In4.Cu")
		(hatch none 0.5)
		(connect_pads
			(clearance 0)
		)
		(min_thickness 0.25)
		(keepout
			(tracks not_allowed)
			(vias allowed)
			(pads allowed)
			(copperpour not_allowed)
			(footprints allowed)
		)
		(placement
			(enabled no)
			(sheetname "")
		)
		(fill yes
			(thermal_gap 0.5)
			(thermal_bridge_width 0.5)
			(island_removal_mode 0)
		)
		(polygon
			(pts
				(arc
					(start 364.149894 -19.153124)
					(mid 364.149894 -20.346924)
					(end 364.149894 -19.153124)
				)
			)
		)
	)
	(zone
		(layers "In2.Cu" "In4.Cu")
		(hatch none 0.5)
		(connect_pads
			(clearance 0)
		)
		(min_thickness 0.25)
		(keepout
			(tracks not_allowed)
			(vias allowed)
			(pads allowed)
			(copperpour not_allowed)
			(footprints allowed)
		)
		(placement
			(enabled no)
			(sheetname "")
		)
		(fill yes
			(thermal_gap 0.5)
			(thermal_bridge_width 0.5)
			(island_removal_mode 0)
		)
		(polygon
			(pts
				(arc
					(start 378.549916 -22.75332)
					(mid 378.549916 -23.94712)
					(end 378.549916 -22.75332)
				)
			)
		)
	)
	(zone
		(layers "In2.Cu" "In4.Cu")
		(hatch none 0.5)
		(connect_pads
			(clearance 0)
		)
		(min_thickness 0.25)
		(keepout
			(tracks not_allowed)
			(vias allowed)
			(pads allowed)
			(copperpour not_allowed)
			(footprints allowed)
		)
		(placement
			(enabled no)
			(sheetname "")
		)
		(fill yes
			(thermal_gap 0.5)
			(thermal_bridge_width 0.5)
			(island_removal_mode 0)
		)
		(polygon
			(pts
				(arc
					(start 132.5499 -22.75332)
					(mid 132.5499 -23.94712)
					(end 132.5499 -22.75332)
				)
			)
		)
	)
	(zone
		(layers "In2.Cu" "In4.Cu")
		(hatch none 0.5)
		(connect_pads
			(clearance 0)
		)
		(min_thickness 0.25)
		(keepout
			(tracks not_allowed)
			(vias allowed)
			(pads allowed)
			(copperpour not_allowed)
			(footprints allowed)
		)
		(placement
			(enabled no)
			(sheetname "")
		)
		(fill yes
			(thermal_gap 0.5)
			(thermal_bridge_width 0.5)
			(island_removal_mode 0)
		)
		(polygon
			(pts
				(arc
					(start 364.149894 -21.353272)
					(mid 364.149894 -22.547072)
					(end 364.149894 -21.353272)
				)
			)
		)
	)
	(zone
		(layers "In2.Cu" "In4.Cu")
		(hatch none 0.5)
		(connect_pads
			(clearance 0)
		)
		(min_thickness 0.25)
		(keepout
			(tracks not_allowed)
			(vias allowed)
			(pads allowed)
			(copperpour not_allowed)
			(footprints allowed)
		)
		(placement
			(enabled no)
			(sheetname "")
		)
		(fill yes
			(thermal_gap 0.5)
			(thermal_bridge_width 0.5)
			(island_removal_mode 0)
		)
		(polygon
			(pts
				(arc
					(start 362.35005 -21.753322)
					(mid 362.35005 -22.947122)
					(end 362.35005 -21.753322)
				)
			)
		)
	)
	(zone
		(layers "In2.Cu" "In4.Cu")
		(hatch none 0.5)
		(connect_pads
			(clearance 0)
		)
		(min_thickness 0.25)
		(keepout
			(tracks not_allowed)
			(vias allowed)
			(pads allowed)
			(copperpour not_allowed)
			(footprints allowed)
		)
		(placement
			(enabled no)
			(sheetname "")
		)
		(fill yes
			(thermal_gap 0.5)
			(thermal_bridge_width 0.5)
			(island_removal_mode 0)
		)
		(polygon
			(pts
				(arc
					(start 130.750056 -16.753078)
					(mid 130.750056 -17.946878)
					(end 130.750056 -16.753078)
				)
			)
		)
	)
	(zone
		(layers "In2.Cu" "In4.Cu")
		(hatch none 0.5)
		(connect_pads
			(clearance 0)
		)
		(min_thickness 0.25)
		(keepout
			(tracks not_allowed)
			(vias allowed)
			(pads allowed)
			(copperpour not_allowed)
			(footprints allowed)
		)
		(placement
			(enabled no)
			(sheetname "")
		)
		(fill yes
			(thermal_gap 0.5)
			(thermal_bridge_width 0.5)
			(island_removal_mode 0)
		)
		(polygon
			(pts
				(arc
					(start 376.750072 -16.753078)
					(mid 376.750072 -17.946878)
					(end 376.750072 -16.753078)
				)
			)
		)
	)
	(zone
		(layers "In2.Cu" "In4.Cu")
		(hatch none 0.5)
		(connect_pads
			(clearance 0)
		)
		(min_thickness 0.25)
		(keepout
			(tracks not_allowed)
			(vias allowed)
			(pads allowed)
			(copperpour not_allowed)
			(footprints allowed)
		)
		(placement
			(enabled no)
			(sheetname "")
		)
		(fill yes
			(thermal_gap 0.5)
			(thermal_bridge_width 0.5)
			(island_removal_mode 0)
		)
		(polygon
			(pts
				(arc
					(start 112.750092 -16.753078)
					(mid 112.750092 -17.946878)
					(end 112.750092 -16.753078)
				)
			)
		)
	)
	(zone
		(layers "In2.Cu" "In4.Cu")
		(hatch none 0.5)
		(connect_pads
			(clearance 0)
		)
		(min_thickness 0.25)
		(keepout
			(tracks not_allowed)
			(vias allowed)
			(pads allowed)
			(copperpour not_allowed)
			(footprints allowed)
		)
		(placement
			(enabled no)
			(sheetname "")
		)
		(fill yes
			(thermal_gap 0.5)
			(thermal_bridge_width 0.5)
			(island_removal_mode 0)
		)
		(polygon
			(pts
				(arc
					(start 382.150112 -19.153124)
					(mid 382.150112 -20.346924)
					(end 382.150112 -19.153124)
				)
			)
		)
	)
	(zone
		(layers "In2.Cu" "In4.Cu")
		(hatch none 0.5)
		(connect_pads
			(clearance 0)
		)
		(min_thickness 0.25)
		(keepout
			(tracks not_allowed)
			(vias allowed)
			(pads allowed)
			(copperpour not_allowed)
			(footprints allowed)
		)
		(placement
			(enabled no)
			(sheetname "")
		)
		(fill yes
			(thermal_gap 0.5)
			(thermal_bridge_width 0.5)
			(island_removal_mode 0)
		)
		(polygon
			(pts
				(arc
					(start 132.5499 -19.153124)
					(mid 132.5499 -20.346924)
					(end 132.5499 -19.153124)
				)
			)
		)
	)
	(zone
		(layers "In2.Cu" "In4.Cu")
		(hatch none 0.5)
		(connect_pads
			(clearance 0)
		)
		(min_thickness 0.25)
		(keepout
			(tracks not_allowed)
			(vias allowed)
			(pads allowed)
			(copperpour not_allowed)
			(footprints allowed)
		)
		(placement
			(enabled no)
			(sheetname "")
		)
		(fill yes
			(thermal_gap 0.5)
			(thermal_bridge_width 0.5)
			(island_removal_mode 0)
		)
		(polygon
			(pts
				(arc
					(start 137.94994 -21.753322)
					(mid 137.94994 -22.947122)
					(end 137.94994 -21.753322)
				)
			)
		)
	)
	(zone
		(layers "In2.Cu" "In4.Cu")
		(hatch none 0.5)
		(connect_pads
			(clearance 0)
		)
		(min_thickness 0.25)
		(keepout
			(tracks not_allowed)
			(vias allowed)
			(pads allowed)
			(copperpour not_allowed)
			(footprints allowed)
		)
		(placement
			(enabled no)
			(sheetname "")
		)
		(fill yes
			(thermal_gap 0.5)
			(thermal_bridge_width 0.5)
			(island_removal_mode 0)
		)
		(polygon
			(pts
				(arc
					(start 380.350014 -16.753078)
					(mid 380.350014 -17.946878)
					(end 380.350014 -16.753078)
				)
			)
		)
	)
	(zone
		(layers "In2.Cu" "In4.Cu")
		(hatch none 0.5)
		(connect_pads
			(clearance 0)
		)
		(min_thickness 0.25)
		(keepout
			(tracks not_allowed)
			(vias allowed)
			(pads allowed)
			(copperpour not_allowed)
			(footprints allowed)
		)
		(placement
			(enabled no)
			(sheetname "")
		)
		(fill yes
			(thermal_gap 0.5)
			(thermal_bridge_width 0.5)
			(island_removal_mode 0)
		)
		(polygon
			(pts
				(arc
					(start 356.95001 -19.153124)
					(mid 356.95001 -20.346924)
					(end 356.95001 -19.153124)
				)
			)
		)
	)
	(zone
		(layers "In2.Cu" "In4.Cu")
		(hatch none 0.5)
		(connect_pads
			(clearance 0)
		)
		(min_thickness 0.25)
		(keepout
			(tracks not_allowed)
			(vias allowed)
			(pads allowed)
			(copperpour not_allowed)
			(footprints allowed)
		)
		(placement
			(enabled no)
			(sheetname "")
		)
		(fill yes
			(thermal_gap 0.5)
			(thermal_bridge_width 0.5)
			(island_removal_mode 0)
		)
		(polygon
			(pts
				(arc
					(start 387.549898 -16.753078)
					(mid 387.549898 -17.946878)
					(end 387.549898 -16.753078)
				)
			)
		)
	)
	(zone
		(layers "In2.Cu" "In4.Cu")
		(hatch none 0.5)
		(connect_pads
			(clearance 0)
		)
		(min_thickness 0.25)
		(keepout
			(tracks not_allowed)
			(vias allowed)
			(pads allowed)
			(copperpour not_allowed)
			(footprints allowed)
		)
		(placement
			(enabled no)
			(sheetname "")
		)
		(fill yes
			(thermal_gap 0.5)
			(thermal_bridge_width 0.5)
			(island_removal_mode 0)
		)
		(polygon
			(pts
				(arc
					(start 362.35005 -16.753078)
					(mid 362.35005 -17.946878)
					(end 362.35005 -16.753078)
				)
			)
		)
	)
	(zone
		(layers "In2.Cu" "In4.Cu")
		(hatch none 0.5)
		(connect_pads
			(clearance 0)
		)
		(min_thickness 0.25)
		(keepout
			(tracks not_allowed)
			(vias allowed)
			(pads allowed)
			(copperpour not_allowed)
			(footprints allowed)
		)
		(placement
			(enabled no)
			(sheetname "")
		)
		(fill yes
			(thermal_gap 0.5)
			(thermal_bridge_width 0.5)
			(island_removal_mode 0)
		)
		(polygon
			(pts
				(arc
					(start 365.949992 -21.753322)
					(mid 365.949992 -22.947122)
					(end 365.949992 -21.753322)
				)
			)
		)
	)
	(zone
		(layers "In2.Cu" "In4.Cu")
		(hatch none 0.5)
		(connect_pads
			(clearance 0)
		)
		(min_thickness 0.25)
		(keepout
			(tracks not_allowed)
			(vias allowed)
			(pads allowed)
			(copperpour not_allowed)
			(footprints allowed)
		)
		(placement
			(enabled no)
			(sheetname "")
		)
		(fill yes
			(thermal_gap 0.5)
			(thermal_bridge_width 0.5)
			(island_removal_mode 0)
		)
		(polygon
			(pts
				(arc
					(start 110.949994 -21.353272)
					(mid 110.949994 -22.547072)
					(end 110.949994 -21.353272)
				)
			)
		)
	)
	(zone
		(layers "In2.Cu" "In4.Cu")
		(hatch none 0.5)
		(connect_pads
			(clearance 0)
		)
		(min_thickness 0.25)
		(keepout
			(tracks not_allowed)
			(vias allowed)
			(pads allowed)
			(copperpour not_allowed)
			(footprints allowed)
		)
		(placement
			(enabled no)
			(sheetname "")
		)
		(fill yes
			(thermal_gap 0.5)
			(thermal_bridge_width 0.5)
			(island_removal_mode 0)
		)
		(polygon
			(pts
				(arc
					(start 387.549898 -21.753322)
					(mid 387.549898 -22.947122)
					(end 387.549898 -21.753322)
				)
			)
		)
	)
	(zone
		(layers "In2.Cu" "In4.Cu")
		(hatch none 0.5)
		(connect_pads
			(clearance 0)
		)
		(min_thickness 0.25)
		(keepout
			(tracks not_allowed)
			(vias allowed)
			(pads allowed)
			(copperpour not_allowed)
			(footprints allowed)
		)
		(placement
			(enabled no)
			(sheetname "")
		)
		(fill yes
			(thermal_gap 0.5)
			(thermal_bridge_width 0.5)
			(island_removal_mode 0)
		)
		(polygon
			(pts
				(arc
					(start 116.350034 -18.153126)
					(mid 116.350034 -19.346926)
					(end 116.350034 -18.153126)
				)
			)
		)
	)
	(zone
		(layers "In2.Cu" "In4.Cu")
		(hatch none 0.5)
		(connect_pads
			(clearance 0)
		)
		(min_thickness 0.25)
		(keepout
			(tracks not_allowed)
			(vias allowed)
			(pads allowed)
			(copperpour not_allowed)
			(footprints allowed)
		)
		(placement
			(enabled no)
			(sheetname "")
		)
		(fill yes
			(thermal_gap 0.5)
			(thermal_bridge_width 0.5)
			(island_removal_mode 0)
		)
		(polygon
			(pts
				(arc
					(start 364.149894 -17.75333)
					(mid 364.149894 -18.94713)
					(end 364.149894 -17.75333)
				)
			)
		)
	)
	(zone
		(layers "In2.Cu" "In4.Cu")
		(hatch none 0.5)
		(connect_pads
			(clearance 0)
		)
		(min_thickness 0.25)
		(keepout
			(tracks not_allowed)
			(vias allowed)
			(pads allowed)
			(copperpour not_allowed)
			(footprints allowed)
		)
		(placement
			(enabled no)
			(sheetname "")
		)
		(fill yes
			(thermal_gap 0.5)
			(thermal_bridge_width 0.5)
			(island_removal_mode 0)
		)
		(polygon
			(pts
				(arc
					(start 141.549882 -18.153126)
					(mid 141.549882 -19.346926)
					(end 141.549882 -18.153126)
				)
			)
		)
	)
	(zone
		(layers "In2.Cu" "In4.Cu")
		(hatch none 0.5)
		(connect_pads
			(clearance 0)
		)
		(min_thickness 0.25)
		(keepout
			(tracks not_allowed)
			(vias allowed)
			(pads allowed)
			(copperpour not_allowed)
			(footprints allowed)
		)
		(placement
			(enabled no)
			(sheetname "")
		)
		(fill yes
			(thermal_gap 0.5)
			(thermal_bridge_width 0.5)
			(island_removal_mode 0)
		)
		(polygon
			(pts
				(arc
					(start 380.350014 -18.153126)
					(mid 380.350014 -19.346926)
					(end 380.350014 -18.153126)
				)
			)
		)
	)
	(zone
		(layers "In2.Cu" "In4.Cu")
		(hatch none 0.5)
		(connect_pads
			(clearance 0)
		)
		(min_thickness 0.25)
		(keepout
			(tracks not_allowed)
			(vias allowed)
			(pads allowed)
			(copperpour not_allowed)
			(footprints allowed)
		)
		(placement
			(enabled no)
			(sheetname "")
		)
		(fill yes
			(thermal_gap 0.5)
			(thermal_bridge_width 0.5)
			(island_removal_mode 0)
		)
		(polygon
			(pts
				(arc
					(start 356.95001 -21.353272)
					(mid 356.95001 -22.547072)
					(end 356.95001 -21.353272)
				)
			)
		)
	)
	(zone
		(layers "In2.Cu" "In4.Cu")
		(hatch none 0.5)
		(connect_pads
			(clearance 0)
		)
		(min_thickness 0.25)
		(keepout
			(tracks not_allowed)
			(vias allowed)
			(pads allowed)
			(copperpour not_allowed)
			(footprints allowed)
		)
		(placement
			(enabled no)
			(sheetname "")
		)
		(fill yes
			(thermal_gap 0.5)
			(thermal_bridge_width 0.5)
			(island_removal_mode 0)
		)
		(polygon
			(pts
				(arc
					(start 355.149912 -21.753322)
					(mid 355.149912 -22.947122)
					(end 355.149912 -21.753322)
				)
			)
		)
	)
	(zone
		(layers "In2.Cu" "In4.Cu")
		(hatch none 0.5)
		(connect_pads
			(clearance 0)
		)
		(min_thickness 0.25)
		(keepout
			(tracks not_allowed)
			(vias allowed)
			(pads allowed)
			(copperpour not_allowed)
			(footprints allowed)
		)
		(placement
			(enabled no)
			(sheetname "")
		)
		(fill yes
			(thermal_gap 0.5)
			(thermal_bridge_width 0.5)
			(island_removal_mode 0)
		)
		(polygon
			(pts
				(arc
					(start 116.350034 -21.753322)
					(mid 116.350034 -22.947122)
					(end 116.350034 -21.753322)
				)
			)
		)
	)
	(zone
		(layers "In2.Cu" "In4.Cu")
		(hatch none 0.5)
		(connect_pads
			(clearance 0)
		)
		(min_thickness 0.25)
		(keepout
			(tracks not_allowed)
			(vias allowed)
			(pads allowed)
			(copperpour not_allowed)
			(footprints allowed)
		)
		(placement
			(enabled no)
			(sheetname "")
		)
		(fill yes
			(thermal_gap 0.5)
			(thermal_bridge_width 0.5)
			(island_removal_mode 0)
		)
		(polygon
			(pts
				(arc
					(start 116.350034 -16.753078)
					(mid 116.350034 -17.946878)
					(end 116.350034 -16.753078)
				)
			)
		)
	)
	(zone
		(layers "In2.Cu" "In4.Cu")
		(hatch none 0.5)
		(connect_pads
			(clearance 0)
		)
		(min_thickness 0.25)
		(keepout
			(tracks not_allowed)
			(vias allowed)
			(pads allowed)
			(copperpour not_allowed)
			(footprints allowed)
		)
		(placement
			(enabled no)
			(sheetname "")
		)
		(fill yes
			(thermal_gap 0.5)
			(thermal_bridge_width 0.5)
			(island_removal_mode 0)
		)
		(polygon
			(pts
				(arc
					(start 365.949992 -20.353274)
					(mid 365.949992 -21.547074)
					(end 365.949992 -20.353274)
				)
			)
		)
	)
	(zone
		(layers "In2.Cu" "In4.Cu")
		(hatch none 0.5)
		(connect_pads
			(clearance 0)
		)
		(min_thickness 0.25)
		(keepout
			(tracks not_allowed)
			(vias allowed)
			(pads allowed)
			(copperpour not_allowed)
			(footprints allowed)
		)
		(placement
			(enabled no)
			(sheetname "")
		)
		(fill yes
			(thermal_gap 0.5)
			(thermal_bridge_width 0.5)
			(island_removal_mode 0)
		)
		(polygon
			(pts
				(arc
					(start 383.949956 -20.353274)
					(mid 383.949956 -21.547074)
					(end 383.949956 -20.353274)
				)
			)
		)
	)
	(zone
		(layers "In2.Cu" "In4.Cu")
		(hatch none 0.5)
		(connect_pads
			(clearance 0)
		)
		(min_thickness 0.25)
		(keepout
			(tracks not_allowed)
			(vias allowed)
			(pads allowed)
			(copperpour not_allowed)
			(footprints allowed)
		)
		(placement
			(enabled no)
			(sheetname "")
		)
		(fill yes
			(thermal_gap 0.5)
			(thermal_bridge_width 0.5)
			(island_removal_mode 0)
		)
		(polygon
			(pts
				(arc
					(start 141.549882 -21.753322)
					(mid 141.549882 -22.947122)
					(end 141.549882 -21.753322)
				)
			)
		)
	)
	(zone
		(layers "In2.Cu" "In4.Cu")
		(hatch none 0.5)
		(connect_pads
			(clearance 0)
		)
		(min_thickness 0.25)
		(keepout
			(tracks not_allowed)
			(vias allowed)
			(pads allowed)
			(copperpour not_allowed)
			(footprints allowed)
		)
		(placement
			(enabled no)
			(sheetname "")
		)
		(fill yes
			(thermal_gap 0.5)
			(thermal_bridge_width 0.5)
			(island_removal_mode 0)
		)
		(polygon
			(pts
				(arc
					(start 118.149878 -21.353272)
					(mid 118.149878 -22.547072)
					(end 118.149878 -21.353272)
				)
			)
		)
	)
	(zone
		(layers "In2.Cu" "In4.Cu")
		(hatch none 0.5)
		(connect_pads
			(clearance 0)
		)
		(min_thickness 0.25)
		(keepout
			(tracks not_allowed)
			(vias allowed)
			(pads allowed)
			(copperpour not_allowed)
			(footprints allowed)
		)
		(placement
			(enabled no)
			(sheetname "")
		)
		(fill yes
			(thermal_gap 0.5)
			(thermal_bridge_width 0.5)
			(island_removal_mode 0)
		)
		(polygon
			(pts
				(arc
					(start 389.349996 -19.153124)
					(mid 389.349996 -20.346924)
					(end 389.349996 -19.153124)
				)
			)
		)
	)
	(zone
		(layers "In2.Cu" "In4.Cu")
		(hatch none 0.5)
		(connect_pads
			(clearance 0)
		)
		(min_thickness 0.25)
		(keepout
			(tracks not_allowed)
			(vias allowed)
			(pads allowed)
			(copperpour not_allowed)
			(footprints allowed)
		)
		(placement
			(enabled no)
			(sheetname "")
		)
		(fill yes
			(thermal_gap 0.5)
			(thermal_bridge_width 0.5)
			(island_removal_mode 0)
		)
		(polygon
			(pts
				(arc
					(start 121.750074 -22.75332)
					(mid 121.750074 -23.94712)
					(end 121.750074 -22.75332)
				)
			)
		)
	)
	(zone
		(layers "In2.Cu" "In4.Cu")
		(hatch none 0.5)
		(connect_pads
			(clearance 0)
		)
		(min_thickness 0.25)
		(keepout
			(tracks not_allowed)
			(vias allowed)
			(pads allowed)
			(copperpour not_allowed)
			(footprints allowed)
		)
		(placement
			(enabled no)
			(sheetname "")
		)
		(fill yes
			(thermal_gap 0.5)
			(thermal_bridge_width 0.5)
			(island_removal_mode 0)
		)
		(polygon
			(pts
				(arc
					(start 143.34998 -21.353272)
					(mid 143.34998 -22.547072)
					(end 143.34998 -21.353272)
				)
			)
		)
	)
	(zone
		(layers "In2.Cu" "In4.Cu")
		(hatch none 0.5)
		(connect_pads
			(clearance 0)
		)
		(min_thickness 0.25)
		(keepout
			(tracks not_allowed)
			(vias allowed)
			(pads allowed)
			(copperpour not_allowed)
			(footprints allowed)
		)
		(placement
			(enabled no)
			(sheetname "")
		)
		(fill yes
			(thermal_gap 0.5)
			(thermal_bridge_width 0.5)
			(island_removal_mode 0)
		)
		(polygon
			(pts
				(arc
					(start 378.549916 -19.153124)
					(mid 378.549916 -20.346924)
					(end 378.549916 -19.153124)
				)
			)
		)
	)
	(zone
		(layers "In2.Cu" "In4.Cu")
		(hatch none 0.5)
		(connect_pads
			(clearance 0)
		)
		(min_thickness 0.25)
		(keepout
			(tracks not_allowed)
			(vias allowed)
			(pads allowed)
			(copperpour not_allowed)
			(footprints allowed)
		)
		(placement
			(enabled no)
			(sheetname "")
		)
		(fill yes
			(thermal_gap 0.5)
			(thermal_bridge_width 0.5)
			(island_removal_mode 0)
		)
		(polygon
			(pts
				(arc
					(start 364.149894 -22.75332)
					(mid 364.149894 -23.94712)
					(end 364.149894 -22.75332)
				)
			)
		)
	)
	(zone
		(layers "In2.Cu" "In4.Cu")
		(hatch none 0.5)
		(connect_pads
			(clearance 0)
		)
		(min_thickness 0.25)
		(keepout
			(tracks not_allowed)
			(vias allowed)
			(pads allowed)
			(copperpour not_allowed)
			(footprints allowed)
		)
		(placement
			(enabled no)
			(sheetname "")
		)
		(fill yes
			(thermal_gap 0.5)
			(thermal_bridge_width 0.5)
			(island_removal_mode 0)
		)
		(polygon
			(pts
				(arc
					(start 385.750054 -21.353272)
					(mid 385.750054 -22.547072)
					(end 385.750054 -21.353272)
				)
			)
		)
	)
	(zone
		(layers "In2.Cu" "In4.Cu")
		(hatch none 0.5)
		(connect_pads
			(clearance 0)
		)
		(min_thickness 0.25)
		(keepout
			(tracks not_allowed)
			(vias allowed)
			(pads allowed)
			(copperpour not_allowed)
			(footprints allowed)
		)
		(placement
			(enabled no)
			(sheetname "")
		)
		(fill yes
			(thermal_gap 0.5)
			(thermal_bridge_width 0.5)
			(island_removal_mode 0)
		)
		(polygon
			(pts
				(arc
					(start 387.549898 -20.353274)
					(mid 387.549898 -21.547074)
					(end 387.549898 -20.353274)
				)
			)
		)
	)
	(zone
		(layers "In2.Cu" "In4.Cu")
		(hatch none 0.5)
		(connect_pads
			(clearance 0)
		)
		(min_thickness 0.25)
		(keepout
			(tracks not_allowed)
			(vias allowed)
			(pads allowed)
			(copperpour not_allowed)
			(footprints allowed)
		)
		(placement
			(enabled no)
			(sheetname "")
		)
		(fill yes
			(thermal_gap 0.5)
			(thermal_bridge_width 0.5)
			(island_removal_mode 0)
		)
		(polygon
			(pts
				(arc
					(start 132.5499 -17.75333)
					(mid 132.5499 -18.94713)
					(end 132.5499 -17.75333)
				)
			)
		)
	)
	(zone
		(layers "In2.Cu" "In4.Cu")
		(hatch none 0.5)
		(connect_pads
			(clearance 0)
		)
		(min_thickness 0.25)
		(keepout
			(tracks not_allowed)
			(vias allowed)
			(pads allowed)
			(copperpour not_allowed)
			(footprints allowed)
		)
		(placement
			(enabled no)
			(sheetname "")
		)
		(fill yes
			(thermal_gap 0.5)
			(thermal_bridge_width 0.5)
			(island_removal_mode 0)
		)
		(polygon
			(pts
				(arc
					(start 360.549952 -19.153124)
					(mid 360.549952 -20.346924)
					(end 360.549952 -19.153124)
				)
			)
		)
	)
	(zone
		(layers "In2.Cu" "In4.Cu")
		(hatch none 0.5)
		(connect_pads
			(clearance 0)
		)
		(min_thickness 0.25)
		(keepout
			(tracks not_allowed)
			(vias allowed)
			(pads allowed)
			(copperpour not_allowed)
			(footprints allowed)
		)
		(placement
			(enabled no)
			(sheetname "")
		)
		(fill yes
			(thermal_gap 0.5)
			(thermal_bridge_width 0.5)
			(island_removal_mode 0)
		)
		(polygon
			(pts
				(arc
					(start 114.549936 -17.75333)
					(mid 114.549936 -18.94713)
					(end 114.549936 -17.75333)
				)
			)
		)
	)
	(zone
		(layers "In2.Cu" "In4.Cu")
		(hatch none 0.5)
		(connect_pads
			(clearance 0)
		)
		(min_thickness 0.25)
		(keepout
			(tracks not_allowed)
			(vias allowed)
			(pads allowed)
			(copperpour not_allowed)
			(footprints allowed)
		)
		(placement
			(enabled no)
			(sheetname "")
		)
		(fill yes
			(thermal_gap 0.5)
			(thermal_bridge_width 0.5)
			(island_removal_mode 0)
		)
		(polygon
			(pts
				(arc
					(start 382.150112 -17.75333)
					(mid 382.150112 -18.94713)
					(end 382.150112 -17.75333)
				)
			)
		)
	)
	(zone
		(layers "In2.Cu" "In4.Cu")
		(hatch none 0.5)
		(connect_pads
			(clearance 0)
		)
		(min_thickness 0.25)
		(keepout
			(tracks not_allowed)
			(vias allowed)
			(pads allowed)
			(copperpour not_allowed)
			(footprints allowed)
		)
		(placement
			(enabled no)
			(sheetname "")
		)
		(fill yes
			(thermal_gap 0.5)
			(thermal_bridge_width 0.5)
			(island_removal_mode 0)
		)
		(polygon
			(pts
				(arc
					(start 136.150096 -17.75333)
					(mid 136.150096 -18.94713)
					(end 136.150096 -17.75333)
				)
			)
		)
	)
	(zone
		(layers "In2.Cu" "In4.Cu")
		(hatch none 0.5)
		(connect_pads
			(clearance 0)
		)
		(min_thickness 0.25)
		(keepout
			(tracks not_allowed)
			(vias allowed)
			(pads allowed)
			(copperpour not_allowed)
			(footprints allowed)
		)
		(placement
			(enabled no)
			(sheetname "")
		)
		(fill yes
			(thermal_gap 0.5)
			(thermal_bridge_width 0.5)
			(island_removal_mode 0)
		)
		(polygon
			(pts
				(arc
					(start 112.750092 -18.153126)
					(mid 112.750092 -19.346926)
					(end 112.750092 -18.153126)
				)
			)
		)
	)
	(zone
		(layers "In2.Cu" "In4.Cu")
		(hatch none 0.5)
		(connect_pads
			(clearance 0)
		)
		(min_thickness 0.25)
		(keepout
			(tracks not_allowed)
			(vias allowed)
			(pads allowed)
			(copperpour not_allowed)
			(footprints allowed)
		)
		(placement
			(enabled no)
			(sheetname "")
		)
		(fill yes
			(thermal_gap 0.5)
			(thermal_bridge_width 0.5)
			(island_removal_mode 0)
		)
		(polygon
			(pts
				(arc
					(start 360.549952 -17.75333)
					(mid 360.549952 -18.94713)
					(end 360.549952 -17.75333)
				)
			)
		)
	)
	(zone
		(layers "In2.Cu" "In4.Cu")
		(hatch none 0.5)
		(connect_pads
			(clearance 0)
		)
		(min_thickness 0.25)
		(keepout
			(tracks not_allowed)
			(vias allowed)
			(pads allowed)
			(copperpour not_allowed)
			(footprints allowed)
		)
		(placement
			(enabled no)
			(sheetname "")
		)
		(fill yes
			(thermal_gap 0.5)
			(thermal_bridge_width 0.5)
			(island_removal_mode 0)
		)
		(polygon
			(pts
				(arc
					(start 380.350014 -21.753322)
					(mid 380.350014 -22.947122)
					(end 380.350014 -21.753322)
				)
			)
		)
	)
	(zone
		(layers "In2.Cu" "In4.Cu")
		(hatch none 0.5)
		(connect_pads
			(clearance 0)
		)
		(min_thickness 0.25)
		(keepout
			(tracks not_allowed)
			(vias allowed)
			(pads allowed)
			(copperpour not_allowed)
			(footprints allowed)
		)
		(placement
			(enabled no)
			(sheetname "")
		)
		(fill yes
			(thermal_gap 0.5)
			(thermal_bridge_width 0.5)
			(island_removal_mode 0)
		)
		(polygon
			(pts
				(arc
					(start 121.750074 -19.153124)
					(mid 121.750074 -20.346924)
					(end 121.750074 -19.153124)
				)
			)
		)
	)
	(zone
		(layers "In2.Cu" "In4.Cu")
		(hatch none 0.5)
		(connect_pads
			(clearance 0)
		)
		(min_thickness 0.25)
		(keepout
			(tracks not_allowed)
			(vias allowed)
			(pads allowed)
			(copperpour not_allowed)
			(footprints allowed)
		)
		(placement
			(enabled no)
			(sheetname "")
		)
		(fill yes
			(thermal_gap 0.5)
			(thermal_bridge_width 0.5)
			(island_removal_mode 0)
		)
		(polygon
			(pts
				(arc
					(start 130.750056 -20.353274)
					(mid 130.750056 -21.547074)
					(end 130.750056 -20.353274)
				)
			)
		)
	)
	(zone
		(layers "In2.Cu" "In4.Cu")
		(hatch none 0.5)
		(connect_pads
			(clearance 0)
		)
		(min_thickness 0.25)
		(keepout
			(tracks not_allowed)
			(vias allowed)
			(pads allowed)
			(copperpour not_allowed)
			(footprints allowed)
		)
		(placement
			(enabled no)
			(sheetname "")
		)
		(fill yes
			(thermal_gap 0.5)
			(thermal_bridge_width 0.5)
			(island_removal_mode 0)
		)
		(polygon
			(pts
				(arc
					(start 119.949976 -16.753078)
					(mid 119.949976 -17.946878)
					(end 119.949976 -16.753078)
				)
			)
		)
	)
	(zone
		(layers "In2.Cu" "In4.Cu")
		(hatch none 0.5)
		(connect_pads
			(clearance 0)
		)
		(min_thickness 0.25)
		(keepout
			(tracks not_allowed)
			(vias allowed)
			(pads allowed)
			(copperpour not_allowed)
			(footprints allowed)
		)
		(placement
			(enabled no)
			(sheetname "")
		)
		(fill yes
			(thermal_gap 0.5)
			(thermal_bridge_width 0.5)
			(island_removal_mode 0)
		)
		(polygon
			(pts
				(arc
					(start 385.750054 -22.75332)
					(mid 385.750054 -23.94712)
					(end 385.750054 -22.75332)
				)
			)
		)
	)
	(zone
		(layers "In2.Cu" "In4.Cu")
		(hatch none 0.5)
		(connect_pads
			(clearance 0)
		)
		(min_thickness 0.25)
		(keepout
			(tracks not_allowed)
			(vias allowed)
			(pads allowed)
			(copperpour not_allowed)
			(footprints allowed)
		)
		(placement
			(enabled no)
			(sheetname "")
		)
		(fill yes
			(thermal_gap 0.5)
			(thermal_bridge_width 0.5)
			(island_removal_mode 0)
		)
		(polygon
			(pts
				(arc
					(start 114.549936 -19.153124)
					(mid 114.549936 -20.346924)
					(end 114.549936 -19.153124)
				)
			)
		)
	)
	(zone
		(layers "In2.Cu" "In4.Cu")
		(hatch none 0.5)
		(connect_pads
			(clearance 0)
		)
		(min_thickness 0.25)
		(keepout
			(tracks not_allowed)
			(vias allowed)
			(pads allowed)
			(copperpour not_allowed)
			(footprints allowed)
		)
		(placement
			(enabled no)
			(sheetname "")
		)
		(fill yes
			(thermal_gap 0.5)
			(thermal_bridge_width 0.5)
			(island_removal_mode 0)
		)
		(polygon
			(pts
				(arc
					(start 362.35005 -20.353274)
					(mid 362.35005 -21.547074)
					(end 362.35005 -20.353274)
				)
			)
		)
	)
	(zone
		(layers "In2.Cu" "In4.Cu")
		(hatch none 0.5)
		(connect_pads
			(clearance 0)
		)
		(min_thickness 0.25)
		(keepout
			(tracks not_allowed)
			(vias allowed)
			(pads allowed)
			(copperpour not_allowed)
			(footprints allowed)
		)
		(placement
			(enabled no)
			(sheetname "")
		)
		(fill yes
			(thermal_gap 0.5)
			(thermal_bridge_width 0.5)
			(island_removal_mode 0)
		)
		(polygon
			(pts
				(arc
					(start 116.350034 -20.353274)
					(mid 116.350034 -21.547074)
					(end 116.350034 -20.353274)
				)
			)
		)
	)
	(zone
		(layers "In2.Cu" "In4.Cu")
		(hatch none 0.5)
		(connect_pads
			(clearance 0)
		)
		(min_thickness 0.25)
		(keepout
			(tracks not_allowed)
			(vias allowed)
			(pads allowed)
			(copperpour not_allowed)
			(footprints allowed)
		)
		(placement
			(enabled no)
			(sheetname "")
		)
		(fill yes
			(thermal_gap 0.5)
			(thermal_bridge_width 0.5)
			(island_removal_mode 0)
		)
		(polygon
			(pts
				(arc
					(start 139.750038 -19.153124)
					(mid 139.750038 -20.346924)
					(end 139.750038 -19.153124)
				)
			)
		)
	)
	(zone
		(layers "In2.Cu" "In4.Cu")
		(hatch none 0.5)
		(connect_pads
			(clearance 0)
		)
		(min_thickness 0.25)
		(keepout
			(tracks not_allowed)
			(vias allowed)
			(pads allowed)
			(copperpour not_allowed)
			(footprints allowed)
		)
		(placement
			(enabled no)
			(sheetname "")
		)
		(fill yes
			(thermal_gap 0.5)
			(thermal_bridge_width 0.5)
			(island_removal_mode 0)
		)
		(polygon
			(pts
				(arc
					(start 119.949976 -18.153126)
					(mid 119.949976 -19.346926)
					(end 119.949976 -18.153126)
				)
			)
		)
	)
	(zone
		(layers "In2.Cu" "In4.Cu")
		(hatch none 0.5)
		(connect_pads
			(clearance 0)
		)
		(min_thickness 0.25)
		(keepout
			(tracks not_allowed)
			(vias allowed)
			(pads allowed)
			(copperpour not_allowed)
			(footprints allowed)
		)
		(placement
			(enabled no)
			(sheetname "")
		)
		(fill yes
			(thermal_gap 0.5)
			(thermal_bridge_width 0.5)
			(island_removal_mode 0)
		)
		(polygon
			(pts
				(arc
					(start 383.949956 -21.753322)
					(mid 383.949956 -22.947122)
					(end 383.949956 -21.753322)
				)
			)
		)
	)
	(zone
		(layers "In2.Cu" "In4.Cu")
		(hatch none 0.5)
		(connect_pads
			(clearance 0)
		)
		(min_thickness 0.25)
		(keepout
			(tracks not_allowed)
			(vias allowed)
			(pads allowed)
			(copperpour not_allowed)
			(footprints allowed)
		)
		(placement
			(enabled no)
			(sheetname "")
		)
		(fill yes
			(thermal_gap 0.5)
			(thermal_bridge_width 0.5)
			(island_removal_mode 0)
		)
		(polygon
			(pts
				(arc
					(start 109.149896 -20.353274)
					(mid 109.149896 -21.547074)
					(end 109.149896 -20.353274)
				)
			)
		)
	)
	(zone
		(layers "In2.Cu" "In4.Cu")
		(hatch none 0.5)
		(connect_pads
			(clearance 0)
		)
		(min_thickness 0.25)
		(keepout
			(tracks not_allowed)
			(vias allowed)
			(pads allowed)
			(copperpour not_allowed)
			(footprints allowed)
		)
		(placement
			(enabled no)
			(sheetname "")
		)
		(fill yes
			(thermal_gap 0.5)
			(thermal_bridge_width 0.5)
			(island_removal_mode 0)
		)
		(polygon
			(pts
				(arc
					(start 109.149896 -21.753322)
					(mid 109.149896 -22.947122)
					(end 109.149896 -21.753322)
				)
			)
		)
	)
	(zone
		(layers "In2.Cu" "In4.Cu")
		(hatch none 0.5)
		(connect_pads
			(clearance 0)
		)
		(min_thickness 0.25)
		(keepout
			(tracks not_allowed)
			(vias allowed)
			(pads allowed)
			(copperpour not_allowed)
			(footprints allowed)
		)
		(placement
			(enabled no)
			(sheetname "")
		)
		(fill yes
			(thermal_gap 0.5)
			(thermal_bridge_width 0.5)
			(island_removal_mode 0)
		)
		(polygon
			(pts
				(arc
					(start 109.149896 -18.153126)
					(mid 109.149896 -19.346926)
					(end 109.149896 -18.153126)
				)
			)
		)
	)
	(zone
		(layers "In2.Cu" "In4.Cu")
		(hatch none 0.5)
		(connect_pads
			(clearance 0)
		)
		(min_thickness 0.25)
		(keepout
			(tracks not_allowed)
			(vias allowed)
			(pads allowed)
			(copperpour not_allowed)
			(footprints allowed)
		)
		(placement
			(enabled no)
			(sheetname "")
		)
		(fill yes
			(thermal_gap 0.5)
			(thermal_bridge_width 0.5)
			(island_removal_mode 0)
		)
		(polygon
			(pts
				(arc
					(start 119.949976 -20.353274)
					(mid 119.949976 -21.547074)
					(end 119.949976 -20.353274)
				)
			)
		)
	)
	(zone
		(layers "In2.Cu" "In4.Cu")
		(hatch none 0.5)
		(connect_pads
			(clearance 0)
		)
		(min_thickness 0.25)
		(keepout
			(tracks not_allowed)
			(vias allowed)
			(pads allowed)
			(copperpour not_allowed)
			(footprints allowed)
		)
		(placement
			(enabled no)
			(sheetname "")
		)
		(fill yes
			(thermal_gap 0.5)
			(thermal_bridge_width 0.5)
			(island_removal_mode 0)
		)
		(polygon
			(pts
				(arc
					(start 389.349996 -22.75332)
					(mid 389.349996 -23.94712)
					(end 389.349996 -22.75332)
				)
			)
		)
	)
	(zone
		(layers "In2.Cu" "In4.Cu")
		(hatch none 0.5)
		(connect_pads
			(clearance 0)
		)
		(min_thickness 0.25)
		(keepout
			(tracks not_allowed)
			(vias allowed)
			(pads allowed)
			(copperpour not_allowed)
			(footprints allowed)
		)
		(placement
			(enabled no)
			(sheetname "")
		)
		(fill yes
			(thermal_gap 0.5)
			(thermal_bridge_width 0.5)
			(island_removal_mode 0)
		)
		(polygon
			(pts
				(arc
					(start 132.5499 -21.353272)
					(mid 132.5499 -22.547072)
					(end 132.5499 -21.353272)
				)
			)
		)
	)
	(zone
		(layers "In2.Cu" "In4.Cu")
		(hatch none 0.5)
		(connect_pads
			(clearance 0)
		)
		(min_thickness 0.25)
		(keepout
			(tracks not_allowed)
			(vias allowed)
			(pads allowed)
			(copperpour not_allowed)
			(footprints allowed)
		)
		(placement
			(enabled no)
			(sheetname "")
		)
		(fill yes
			(thermal_gap 0.5)
			(thermal_bridge_width 0.5)
			(island_removal_mode 0)
		)
		(polygon
			(pts
				(arc
					(start 358.750108 -20.353274)
					(mid 358.750108 -21.547074)
					(end 358.750108 -20.353274)
				)
			)
		)
	)
	(zone
		(layers "In2.Cu" "In4.Cu")
		(hatch none 0.5)
		(connect_pads
			(clearance 0)
		)
		(min_thickness 0.25)
		(keepout
			(tracks not_allowed)
			(vias allowed)
			(pads allowed)
			(copperpour not_allowed)
			(footprints allowed)
		)
		(placement
			(enabled no)
			(sheetname "")
		)
		(fill yes
			(thermal_gap 0.5)
			(thermal_bridge_width 0.5)
			(island_removal_mode 0)
		)
		(polygon
			(pts
				(arc
					(start 118.149878 -19.153124)
					(mid 118.149878 -20.346924)
					(end 118.149878 -19.153124)
				)
			)
		)
	)
	(zone
		(layers "In2.Cu" "In4.Cu")
		(hatch none 0.5)
		(connect_pads
			(clearance 0)
		)
		(min_thickness 0.25)
		(keepout
			(tracks not_allowed)
			(vias allowed)
			(pads allowed)
			(copperpour not_allowed)
			(footprints allowed)
		)
		(placement
			(enabled no)
			(sheetname "")
		)
		(fill yes
			(thermal_gap 0.5)
			(thermal_bridge_width 0.5)
			(island_removal_mode 0)
		)
		(polygon
			(pts
				(arc
					(start 112.750092 -21.753322)
					(mid 112.750092 -22.947122)
					(end 112.750092 -21.753322)
				)
			)
		)
	)
	(zone
		(layers "In2.Cu" "In4.Cu")
		(hatch none 0.5)
		(connect_pads
			(clearance 0)
		)
		(min_thickness 0.25)
		(keepout
			(tracks not_allowed)
			(vias allowed)
			(pads allowed)
			(copperpour not_allowed)
			(footprints allowed)
		)
		(placement
			(enabled no)
			(sheetname "")
		)
		(fill yes
			(thermal_gap 0.5)
			(thermal_bridge_width 0.5)
			(island_removal_mode 0)
		)
		(polygon
			(pts
				(arc
					(start 130.750056 -21.753322)
					(mid 130.750056 -22.947122)
					(end 130.750056 -21.753322)
				)
			)
		)
	)
	(zone
		(layers "In2.Cu" "In4.Cu")
		(hatch none 0.5)
		(connect_pads
			(clearance 0)
		)
		(min_thickness 0.25)
		(keepout
			(tracks not_allowed)
			(vias allowed)
			(pads allowed)
			(copperpour not_allowed)
			(footprints allowed)
		)
		(placement
			(enabled no)
			(sheetname "")
		)
		(fill yes
			(thermal_gap 0.5)
			(thermal_bridge_width 0.5)
			(island_removal_mode 0)
		)
		(polygon
			(pts
				(arc
					(start 385.750054 -19.153124)
					(mid 385.750054 -20.346924)
					(end 385.750054 -19.153124)
				)
			)
		)
	)
	(zone
		(layers "In2.Cu" "In4.Cu")
		(hatch none 0.5)
		(connect_pads
			(clearance 0)
		)
		(min_thickness 0.25)
		(keepout
			(tracks not_allowed)
			(vias allowed)
			(pads allowed)
			(copperpour not_allowed)
			(footprints allowed)
		)
		(placement
			(enabled no)
			(sheetname "")
		)
		(fill yes
			(thermal_gap 0.5)
			(thermal_bridge_width 0.5)
			(island_removal_mode 0)
		)
		(polygon
			(pts
				(arc
					(start 367.75009 -19.153124)
					(mid 367.75009 -20.346924)
					(end 367.75009 -19.153124)
				)
			)
		)
	)
	(zone
		(layers "In2.Cu" "In4.Cu")
		(hatch none 0.5)
		(connect_pads
			(clearance 0)
		)
		(min_thickness 0.25)
		(keepout
			(tracks not_allowed)
			(vias allowed)
			(pads allowed)
			(copperpour not_allowed)
			(footprints allowed)
		)
		(placement
			(enabled no)
			(sheetname "")
		)
		(fill yes
			(thermal_gap 0.5)
			(thermal_bridge_width 0.5)
			(island_removal_mode 0)
		)
		(polygon
			(pts
				(arc
					(start 382.150112 -21.353272)
					(mid 382.150112 -22.547072)
					(end 382.150112 -21.353272)
				)
			)
		)
	)
	(zone
		(layers "In2.Cu" "In4.Cu")
		(hatch none 0.5)
		(connect_pads
			(clearance 0)
		)
		(min_thickness 0.25)
		(keepout
			(tracks not_allowed)
			(vias allowed)
			(pads allowed)
			(copperpour not_allowed)
			(footprints allowed)
		)
		(placement
			(enabled no)
			(sheetname "")
		)
		(fill yes
			(thermal_gap 0.5)
			(thermal_bridge_width 0.5)
			(island_removal_mode 0)
		)
		(polygon
			(pts
				(arc
					(start 134.349998 -16.753078)
					(mid 134.349998 -17.946878)
					(end 134.349998 -16.753078)
				)
			)
		)
	)
	(zone
		(layers "In2.Cu" "In4.Cu")
		(hatch none 0.5)
		(connect_pads
			(clearance 0)
		)
		(min_thickness 0.25)
		(keepout
			(tracks not_allowed)
			(vias allowed)
			(pads allowed)
			(copperpour not_allowed)
			(footprints allowed)
		)
		(placement
			(enabled no)
			(sheetname "")
		)
		(fill yes
			(thermal_gap 0.5)
			(thermal_bridge_width 0.5)
			(island_removal_mode 0)
		)
		(polygon
			(pts
				(arc
					(start 356.95001 -17.75333)
					(mid 356.95001 -18.94713)
					(end 356.95001 -17.75333)
				)
			)
		)
	)
	(zone
		(layers "In2.Cu" "In4.Cu")
		(hatch none 0.5)
		(connect_pads
			(clearance 0)
		)
		(min_thickness 0.25)
		(keepout
			(tracks not_allowed)
			(vias allowed)
			(pads allowed)
			(copperpour not_allowed)
			(footprints allowed)
		)
		(placement
			(enabled no)
			(sheetname "")
		)
		(fill yes
			(thermal_gap 0.5)
			(thermal_bridge_width 0.5)
			(island_removal_mode 0)
		)
		(polygon
			(pts
				(arc
					(start 355.149912 -16.753078)
					(mid 355.149912 -17.946878)
					(end 355.149912 -16.753078)
				)
			)
		)
	)
	(zone
		(layers "In2.Cu" "In4.Cu")
		(hatch none 0.5)
		(connect_pads
			(clearance 0)
		)
		(min_thickness 0.25)
		(keepout
			(tracks not_allowed)
			(vias allowed)
			(pads allowed)
			(copperpour not_allowed)
			(footprints allowed)
		)
		(placement
			(enabled no)
			(sheetname "")
		)
		(fill yes
			(thermal_gap 0.5)
			(thermal_bridge_width 0.5)
			(island_removal_mode 0)
		)
		(polygon
			(pts
				(arc
					(start 356.95001 -22.75332)
					(mid 356.95001 -23.94712)
					(end 356.95001 -22.75332)
				)
			)
		)
	)
	(zone
		(layers "In2.Cu" "In4.Cu")
		(hatch none 0.5)
		(connect_pads
			(clearance 0)
		)
		(min_thickness 0.25)
		(keepout
			(tracks not_allowed)
			(vias allowed)
			(pads allowed)
			(copperpour not_allowed)
			(footprints allowed)
		)
		(placement
			(enabled no)
			(sheetname "")
		)
		(fill yes
			(thermal_gap 0.5)
			(thermal_bridge_width 0.5)
			(island_removal_mode 0)
		)
		(polygon
			(pts
				(arc
					(start 130.750056 -18.153126)
					(mid 130.750056 -19.346926)
					(end 130.750056 -18.153126)
				)
			)
		)
	)
	(zone
		(layers "In2.Cu" "In4.Cu")
		(hatch none 0.5)
		(connect_pads
			(clearance 0)
		)
		(min_thickness 0.25)
		(keepout
			(tracks not_allowed)
			(vias allowed)
			(pads allowed)
			(copperpour not_allowed)
			(footprints allowed)
		)
		(placement
			(enabled no)
			(sheetname "")
		)
		(fill yes
			(thermal_gap 0.5)
			(thermal_bridge_width 0.5)
			(island_removal_mode 0)
		)
		(polygon
			(pts
				(arc
					(start 136.150096 -21.353272)
					(mid 136.150096 -22.547072)
					(end 136.150096 -21.353272)
				)
			)
		)
	)
	(zone
		(layers "In2.Cu" "In4.Cu")
		(hatch none 0.5)
		(connect_pads
			(clearance 0)
		)
		(min_thickness 0.25)
		(keepout
			(tracks not_allowed)
			(vias allowed)
			(pads allowed)
			(copperpour not_allowed)
			(footprints allowed)
		)
		(placement
			(enabled no)
			(sheetname "")
		)
		(fill yes
			(thermal_gap 0.5)
			(thermal_bridge_width 0.5)
			(island_removal_mode 0)
		)
		(polygon
			(pts
				(arc
					(start 383.949956 -16.753078)
					(mid 383.949956 -17.946878)
					(end 383.949956 -16.753078)
				)
			)
		)
	)
	(zone
		(layers "In2.Cu" "In4.Cu")
		(hatch none 0.5)
		(connect_pads
			(clearance 0)
		)
		(min_thickness 0.25)
		(keepout
			(tracks not_allowed)
			(vias allowed)
			(pads allowed)
			(copperpour not_allowed)
			(footprints allowed)
		)
		(placement
			(enabled no)
			(sheetname "")
		)
		(fill yes
			(thermal_gap 0.5)
			(thermal_bridge_width 0.5)
			(island_removal_mode 0)
		)
		(polygon
			(pts
				(arc
					(start 141.549882 -16.753078)
					(mid 141.549882 -17.946878)
					(end 141.549882 -16.753078)
				)
			)
		)
	)
	(zone
		(layers "In2.Cu" "In4.Cu")
		(hatch none 0.5)
		(connect_pads
			(clearance 0)
		)
		(min_thickness 0.25)
		(keepout
			(tracks not_allowed)
			(vias allowed)
			(pads allowed)
			(copperpour not_allowed)
			(footprints allowed)
		)
		(placement
			(enabled no)
			(sheetname "")
		)
		(fill yes
			(thermal_gap 0.5)
			(thermal_bridge_width 0.5)
			(island_removal_mode 0)
		)
		(polygon
			(pts
				(arc
					(start 360.549952 -22.75332)
					(mid 360.549952 -23.94712)
					(end 360.549952 -22.75332)
				)
			)
		)
	)
	(zone
		(layers "In2.Cu" "In4.Cu")
		(hatch none 0.5)
		(connect_pads
			(clearance 0)
		)
		(min_thickness 0.25)
		(keepout
			(tracks not_allowed)
			(vias allowed)
			(pads allowed)
			(copperpour not_allowed)
			(footprints allowed)
		)
		(placement
			(enabled no)
			(sheetname "")
		)
		(fill yes
			(thermal_gap 0.5)
			(thermal_bridge_width 0.5)
			(island_removal_mode 0)
		)
		(polygon
			(pts
				(arc
					(start 118.149878 -17.75333)
					(mid 118.149878 -18.94713)
					(end 118.149878 -17.75333)
				)
			)
		)
	)
	(zone
		(layers "In2.Cu" "In4.Cu")
		(hatch none 0.5)
		(connect_pads
			(clearance 0)
		)
		(min_thickness 0.25)
		(keepout
			(tracks not_allowed)
			(vias allowed)
			(pads allowed)
			(copperpour not_allowed)
			(footprints allowed)
		)
		(placement
			(enabled no)
			(sheetname "")
		)
		(fill yes
			(thermal_gap 0.5)
			(thermal_bridge_width 0.5)
			(island_removal_mode 0)
		)
		(polygon
			(pts
				(arc
					(start 380.350014 -20.353274)
					(mid 380.350014 -21.547074)
					(end 380.350014 -20.353274)
				)
			)
		)
	)
	(zone
		(layers "In2.Cu" "In4.Cu")
		(hatch none 0.5)
		(connect_pads
			(clearance 0)
		)
		(min_thickness 0.25)
		(keepout
			(tracks not_allowed)
			(vias allowed)
			(pads allowed)
			(copperpour not_allowed)
			(footprints allowed)
		)
		(placement
			(enabled no)
			(sheetname "")
		)
		(fill yes
			(thermal_gap 0.5)
			(thermal_bridge_width 0.5)
			(island_removal_mode 0)
		)
		(polygon
			(pts
				(arc
					(start 134.349998 -18.153126)
					(mid 134.349998 -19.346926)
					(end 134.349998 -18.153126)
				)
			)
		)
	)
	(zone
		(layers "In2.Cu" "In4.Cu")
		(hatch none 0.5)
		(connect_pads
			(clearance 0)
		)
		(min_thickness 0.25)
		(keepout
			(tracks not_allowed)
			(vias allowed)
			(pads allowed)
			(copperpour not_allowed)
			(footprints allowed)
		)
		(placement
			(enabled no)
			(sheetname "")
		)
		(fill yes
			(thermal_gap 0.5)
			(thermal_bridge_width 0.5)
			(island_removal_mode 0)
		)
		(polygon
			(pts
				(arc
					(start 141.549882 -20.353274)
					(mid 141.549882 -21.547074)
					(end 141.549882 -20.353274)
				)
			)
		)
	)
	(zone
		(layers "In2.Cu" "In4.Cu")
		(hatch none 0.5)
		(connect_pads
			(clearance 0)
		)
		(min_thickness 0.25)
		(keepout
			(tracks not_allowed)
			(vias allowed)
			(pads allowed)
			(copperpour not_allowed)
			(footprints allowed)
		)
		(placement
			(enabled no)
			(sheetname "")
		)
		(fill yes
			(thermal_gap 0.5)
			(thermal_bridge_width 0.5)
			(island_removal_mode 0)
		)
		(polygon
			(pts
				(arc
					(start 121.750074 -21.353272)
					(mid 121.750074 -22.547072)
					(end 121.750074 -21.353272)
				)
			)
		)
	)
	(zone
		(layers "In2.Cu" "In4.Cu")
		(hatch none 0.5)
		(connect_pads
			(clearance 0)
		)
		(min_thickness 0.25)
		(keepout
			(tracks not_allowed)
			(vias allowed)
			(pads allowed)
			(copperpour not_allowed)
			(footprints allowed)
		)
		(placement
			(enabled no)
			(sheetname "")
		)
		(fill yes
			(thermal_gap 0.5)
			(thermal_bridge_width 0.5)
			(island_removal_mode 0)
		)
		(polygon
			(pts
				(arc
					(start 362.35005 -18.153126)
					(mid 362.35005 -19.346926)
					(end 362.35005 -18.153126)
				)
			)
		)
	)
	(zone
		(layers "In2.Cu" "In4.Cu")
		(hatch none 0.5)
		(connect_pads
			(clearance 0)
		)
		(min_thickness 0.25)
		(keepout
			(tracks not_allowed)
			(vias allowed)
			(pads allowed)
			(copperpour not_allowed)
			(footprints allowed)
		)
		(placement
			(enabled no)
			(sheetname "")
		)
		(fill yes
			(thermal_gap 0.5)
			(thermal_bridge_width 0.5)
			(island_removal_mode 0)
		)
		(polygon
			(pts
				(arc
					(start 121.750074 -17.75333)
					(mid 121.750074 -18.94713)
					(end 121.750074 -17.75333)
				)
			)
		)
	)
	(zone
		(layers "In2.Cu" "In4.Cu" "In7.Cu" "In9.Cu")
		(hatch none 0.5)
		(connect_pads
			(clearance 0)
		)
		(min_thickness 0.25)
		(keepout
			(tracks not_allowed)
			(vias allowed)
			(pads allowed)
			(copperpour not_allowed)
			(footprints allowed)
		)
		(placement
			(enabled no)
			(sheetname "")
		)
		(fill yes
			(thermal_gap 0.5)
			(thermal_bridge_width 0.5)
			(island_removal_mode 0)
		)
		(polygon
			(pts
				(arc
					(start 271.970754 -357.323898)
					(mid 271.5895 -357.704771)
					(end 271.9705 -358.085898)
				)
				(arc
					(start 273.1135 -358.085898)
					(mid 273.382008 -357.975202)
					(end 273.4945 -357.707438)
				)
				(arc
					(start 273.3802 -357.707438)
					(mid 273.1135 -357.97161)
					(end 272.8468 -357.707438)
				)
				(arc
					(start 272.2372 -357.707438)
					(mid 271.9705 -357.97161)
					(end 271.7038 -357.707438)
				)
				(arc
					(start 271.7038 -357.704898)
					(mid 271.9705 -357.438198)
					(end 272.2372 -357.704898)
				)
				(arc
					(start 272.8468 -357.704898)
					(mid 273.1135 -357.438198)
					(end 273.3802 -357.704898)
				)
				(arc
					(start 273.4945 -357.704898)
					(mid 273.382908 -357.43549)
					(end 273.1135 -357.323898)
				)
			)
		)
	)
	(zone
		(layers "In2.Cu" "In4.Cu" "In7.Cu" "In9.Cu")
		(hatch none 0.5)
		(connect_pads
			(clearance 0)
		)
		(min_thickness 0.25)
		(keepout
			(tracks not_allowed)
			(vias allowed)
			(pads allowed)
			(copperpour not_allowed)
			(footprints allowed)
		)
		(placement
			(enabled no)
			(sheetname "")
		)
		(fill yes
			(thermal_gap 0.5)
			(thermal_bridge_width 0.5)
			(island_removal_mode 0)
		)
		(polygon
			(pts
				(arc
					(start 325.12 -277.178516)
					(mid 324.739 -276.797516)
					(end 324.358 -277.178516)
				)
				(arc
					(start 324.358 -278.321516)
					(mid 324.73773 -278.702514)
					(end 325.12 -278.324056)
				)
				(arc
					(start 325.0057 -278.324056)
					(mid 324.739 -278.588228)
					(end 324.4723 -278.324056)
				)
				(arc
					(start 324.4723 -278.321516)
					(mid 324.739 -278.054816)
					(end 325.0057 -278.321516)
				)
				(xy 325.12 -278.321516) (xy 325.12 -277.181056)
				(arc
					(start 325.0057 -277.181056)
					(mid 324.739 -277.445228)
					(end 324.4723 -277.181056)
				)
				(arc
					(start 324.4723 -277.178516)
					(mid 324.739 -276.911816)
					(end 325.0057 -277.178516)
				)
			)
		)
	)
	(zone
		(layers "In2.Cu" "In4.Cu" "In7.Cu" "In9.Cu")
		(hatch none 0.5)
		(connect_pads
			(clearance 0)
		)
		(min_thickness 0.25)
		(keepout
			(tracks not_allowed)
			(vias allowed)
			(pads allowed)
			(copperpour not_allowed)
			(footprints allowed)
		)
		(placement
			(enabled no)
			(sheetname "")
		)
		(fill yes
			(thermal_gap 0.5)
			(thermal_bridge_width 0.5)
			(island_removal_mode 0)
		)
		(polygon
			(pts
				(arc
					(start 356.670102 -277.178516)
					(mid 356.289102 -276.797516)
					(end 355.908102 -277.178516)
				)
				(arc
					(start 355.908102 -278.321516)
					(mid 356.287832 -278.702514)
					(end 356.670102 -278.324056)
				)
				(arc
					(start 356.555802 -278.324056)
					(mid 356.289102 -278.588228)
					(end 356.022402 -278.324056)
				)
				(arc
					(start 356.022402 -278.321516)
					(mid 356.289102 -278.054816)
					(end 356.555802 -278.321516)
				)
				(xy 356.670102 -278.321516) (xy 356.670102 -277.181056)
				(arc
					(start 356.555802 -277.181056)
					(mid 356.289102 -277.445228)
					(end 356.022402 -277.181056)
				)
				(arc
					(start 356.022402 -277.178516)
					(mid 356.289102 -276.911816)
					(end 356.555802 -277.178516)
				)
			)
		)
	)
	(zone
		(layers "In2.Cu" "In4.Cu" "In7.Cu" "In9.Cu")
		(hatch none 0.5)
		(connect_pads
			(clearance 0)
		)
		(min_thickness 0.25)
		(keepout
			(tracks not_allowed)
			(vias allowed)
			(pads allowed)
			(copperpour not_allowed)
			(footprints allowed)
		)
		(placement
			(enabled no)
			(sheetname "")
		)
		(fill yes
			(thermal_gap 0.5)
			(thermal_bridge_width 0.5)
			(island_removal_mode 0)
		)
		(polygon
			(pts
				(arc
					(start 388.21995 -277.178516)
					(mid 387.83895 -276.797516)
					(end 387.45795 -277.178516)
				)
				(arc
					(start 387.45795 -278.321516)
					(mid 387.83768 -278.702514)
					(end 388.21995 -278.324056)
				)
				(arc
					(start 388.10565 -278.324056)
					(mid 387.83895 -278.588228)
					(end 387.57225 -278.324056)
				)
				(arc
					(start 387.57225 -278.321516)
					(mid 387.83895 -278.054816)
					(end 388.10565 -278.321516)
				)
				(xy 388.21995 -278.321516) (xy 388.21995 -277.181056)
				(arc
					(start 388.10565 -277.181056)
					(mid 387.83895 -277.445228)
					(end 387.57225 -277.181056)
				)
				(arc
					(start 387.57225 -277.178516)
					(mid 387.83895 -276.911816)
					(end 388.10565 -277.178516)
				)
			)
		)
	)
	(zone
		(layers "In2.Cu" "In4.Cu" "In7.Cu" "In9.Cu")
		(hatch none 0.5)
		(connect_pads
			(clearance 0)
		)
		(min_thickness 0.25)
		(keepout
			(tracks not_allowed)
			(vias allowed)
			(pads allowed)
			(copperpour not_allowed)
			(footprints allowed)
		)
		(placement
			(enabled no)
			(sheetname "")
		)
		(fill yes
			(thermal_gap 0.5)
			(thermal_bridge_width 0.5)
			(island_removal_mode 0)
		)
		(polygon
			(pts
				(arc
					(start 451.3199 -47.178468)
					(mid 450.9389 -46.797468)
					(end 450.5579 -47.178468)
				)
				(arc
					(start 450.5579 -48.321468)
					(mid 450.93763 -48.702466)
					(end 451.3199 -48.324008)
				)
				(arc
					(start 451.2056 -48.324008)
					(mid 450.9389 -48.58818)
					(end 450.6722 -48.324008)
				)
				(arc
					(start 450.6722 -48.321468)
					(mid 450.9389 -48.054768)
					(end 451.2056 -48.321468)
				)
				(xy 451.3199 -48.321468) (xy 451.3199 -47.181008)
				(arc
					(start 451.2056 -47.181008)
					(mid 450.9389 -47.44518)
					(end 450.6722 -47.181008)
				)
				(arc
					(start 450.6722 -47.178468)
					(mid 450.9389 -46.911768)
					(end 451.2056 -47.178468)
				)
			)
		)
	)
	(zone
		(net "GND")
		(layers "In2.Cu" "In4.Cu" "In7.Cu" "In9.Cu")
		(hatch none 0.5)
		(connect_pads
			(clearance 0.5)
		)
		(min_thickness 0.25)
		(fill yes
			(thermal_gap 0.5)
			(thermal_bridge_width 0.5)
			(island_removal_mode 0)
		)
		(polygon
			(pts
				(arc
					(start 202.032108 -374.000014)
					(mid 201.144056 -371.856068)
					(end 199.00011 -370.968016)
				)
				(xy 192.731898 -370.968016)
				(arc
					(start 192.731898 -350.19996)
					(mid 191.843846 -348.056014)
					(end 189.6999 -347.167962)
				)
				(xy 2.032 -347.167962) (xy 2.032 -2.032) (xy 99.96805 -2.032)
				(arc
					(start 99.96805 -13.999972)
					(mid 100.856102 -16.143918)
					(end 103.000048 -17.03197)
				)
				(xy 103.721154 -17.03197) (xy 103.721154 -15.762986)
				(arc
					(start 103.000048 -15.762986)
					(mid 101.753409 -15.246611)
					(end 101.237034 -13.999972)
				)
				(arc
					(start 101.237034 -0.999998)
					(mid 101.167624 -0.832426)
					(end 101.000052 -0.763016)
				)
				(arc
					(start 0.999998 -0.763016)
					(mid 0.832426 -0.832426)
					(end 0.763016 -0.999998)
				)
				(arc
					(start 0.763016 -348.199964)
					(mid 0.832426 -348.367536)
					(end 0.999998 -348.436946)
				)
				(arc
					(start 189.6999 -348.436946)
					(mid 190.946539 -348.953321)
					(end 191.462914 -350.19996)
				)
				(arc
					(start 191.462914 -372.000018)
					(mid 191.532324 -372.16759)
					(end 191.699896 -372.237)
				)
				(arc
					(start 199.00011 -372.237)
					(mid 200.246749 -372.753375)
					(end 200.763124 -374.000014)
				)
				(arc
					(start 200.763124 -420.200074)
					(mid 200.832534 -420.367646)
					(end 201.000106 -420.437056)
				)
				(xy 203.012548 -420.437056) (xy 203.012548 -419.168072) (xy 202.032108 -419.168072)
			)
		)
	)
	(zone
		(layers "In2.Cu" "In4.Cu" "In7.Cu" "In9.Cu")
		(hatch none 0.5)
		(connect_pads
			(clearance 0)
		)
		(min_thickness 0.25)
		(keepout
			(tracks not_allowed)
			(vias allowed)
			(pads allowed)
			(copperpour not_allowed)
			(footprints allowed)
		)
		(placement
			(enabled no)
			(sheetname "")
		)
		(fill yes
			(thermal_gap 0.5)
			(thermal_bridge_width 0.5)
			(island_removal_mode 0)
		)
		(polygon
			(pts
				(arc
					(start 271.970754 -308.721506)
					(mid 271.58696 -309.104919)
					(end 271.9705 -309.488586)
				)
				(arc
					(start 273.1135 -309.488586)
					(mid 273.383804 -309.377146)
					(end 273.49704 -309.107586)
				)
				(arc
					(start 273.3802 -309.107586)
					(mid 273.1135 -309.371758)
					(end 272.8468 -309.107586)
				)
				(arc
					(start 272.2372 -309.107586)
					(mid 271.9705 -309.371758)
					(end 271.7038 -309.107586)
				)
				(arc
					(start 271.7038 -309.105046)
					(mid 271.9705 -308.838346)
					(end 272.2372 -309.105046)
				)
				(arc
					(start 272.8468 -309.105046)
					(mid 273.1135 -308.838346)
					(end 273.3802 -309.105046)
				)
				(arc
					(start 273.49704 -309.105046)
					(mid 273.384704 -308.833842)
					(end 273.1135 -308.721506)
				)
			)
		)
	)
	(zone
		(layers "In2.Cu" "In4.Cu" "In7.Cu" "In9.Cu")
		(hatch none 0.5)
		(connect_pads
			(clearance 0)
		)
		(min_thickness 0.25)
		(keepout
			(tracks not_allowed)
			(vias allowed)
			(pads allowed)
			(copperpour not_allowed)
			(footprints allowed)
		)
		(placement
			(enabled no)
			(sheetname "")
		)
		(fill yes
			(thermal_gap 0.5)
			(thermal_bridge_width 0.5)
			(island_removal_mode 0)
		)
		(polygon
			(pts
				(arc
					(start 356.670102 -162.178492)
					(mid 356.289102 -161.797492)
					(end 355.908102 -162.178492)
				)
				(arc
					(start 355.908102 -163.321492)
					(mid 356.287832 -163.70249)
					(end 356.670102 -163.324032)
				)
				(arc
					(start 356.555802 -163.324032)
					(mid 356.289102 -163.588204)
					(end 356.022402 -163.324032)
				)
				(arc
					(start 356.022402 -163.321492)
					(mid 356.289102 -163.054792)
					(end 356.555802 -163.321492)
				)
				(xy 356.670102 -163.321492) (xy 356.670102 -162.181032)
				(arc
					(start 356.555802 -162.181032)
					(mid 356.289102 -162.445204)
					(end 356.022402 -162.181032)
				)
				(arc
					(start 356.022402 -162.178492)
					(mid 356.289102 -161.911792)
					(end 356.555802 -162.178492)
				)
			)
		)
	)
	(zone
		(layers "In2.Cu" "In4.Cu" "In7.Cu" "In9.Cu")
		(hatch none 0.5)
		(connect_pads
			(clearance 0)
		)
		(min_thickness 0.25)
		(keepout
			(tracks not_allowed)
			(vias allowed)
			(pads allowed)
			(copperpour not_allowed)
			(footprints allowed)
		)
		(placement
			(enabled no)
			(sheetname "")
		)
		(fill yes
			(thermal_gap 0.5)
			(thermal_bridge_width 0.5)
			(island_removal_mode 0)
		)
		(polygon
			(pts
				(arc
					(start 419.770052 -277.178516)
					(mid 419.389052 -276.797516)
					(end 419.008052 -277.178516)
				)
				(arc
					(start 419.008052 -278.321516)
					(mid 419.387782 -278.702514)
					(end 419.770052 -278.324056)
				)
				(arc
					(start 419.655752 -278.324056)
					(mid 419.389052 -278.588228)
					(end 419.122352 -278.324056)
				)
				(arc
					(start 419.122352 -278.321516)
					(mid 419.389052 -278.054816)
					(end 419.655752 -278.321516)
				)
				(xy 419.770052 -278.321516) (xy 419.770052 -277.181056)
				(arc
					(start 419.655752 -277.181056)
					(mid 419.389052 -277.445228)
					(end 419.122352 -277.181056)
				)
				(arc
					(start 419.122352 -277.178516)
					(mid 419.389052 -276.911816)
					(end 419.655752 -277.178516)
				)
			)
		)
	)
	(zone
		(layers "In2.Cu" "In4.Cu" "In7.Cu" "In9.Cu")
		(hatch none 0.5)
		(connect_pads
			(clearance 0)
		)
		(min_thickness 0.25)
		(keepout
			(tracks not_allowed)
			(vias allowed)
			(pads allowed)
			(copperpour not_allowed)
			(footprints allowed)
		)
		(placement
			(enabled no)
			(sheetname "")
		)
		(fill yes
			(thermal_gap 0.5)
			(thermal_bridge_width 0.5)
			(island_removal_mode 0)
		)
		(polygon
			(pts
				(arc
					(start 388.21995 -162.178492)
					(mid 387.83895 -161.797492)
					(end 387.45795 -162.178492)
				)
				(arc
					(start 387.45795 -163.321492)
					(mid 387.83768 -163.70249)
					(end 388.21995 -163.324032)
				)
				(arc
					(start 388.10565 -163.324032)
					(mid 387.83895 -163.588204)
					(end 387.57225 -163.324032)
				)
				(arc
					(start 387.57225 -163.321492)
					(mid 387.83895 -163.054792)
					(end 388.10565 -163.321492)
				)
				(xy 388.21995 -163.321492) (xy 388.21995 -162.181032)
				(arc
					(start 388.10565 -162.181032)
					(mid 387.83895 -162.445204)
					(end 387.57225 -162.181032)
				)
				(arc
					(start 387.57225 -162.178492)
					(mid 387.83895 -161.911792)
					(end 388.10565 -162.178492)
				)
			)
		)
	)
	(zone
		(layers "In2.Cu" "In4.Cu" "In7.Cu" "In9.Cu")
		(hatch none 0.5)
		(connect_pads
			(clearance 0)
		)
		(min_thickness 0.25)
		(keepout
			(tracks not_allowed)
			(vias allowed)
			(pads allowed)
			(copperpour not_allowed)
			(footprints allowed)
		)
		(placement
			(enabled no)
			(sheetname "")
		)
		(fill yes
			(thermal_gap 0.5)
			(thermal_bridge_width 0.5)
			(island_removal_mode 0)
		)
		(polygon
			(pts
				(arc
					(start 271.970754 -355.524054)
					(mid 271.5895 -355.904927)
					(end 271.9705 -356.286054)
				)
				(arc
					(start 273.1135 -356.286054)
					(mid 273.382008 -356.175358)
					(end 273.4945 -355.907594)
				)
				(arc
					(start 273.3802 -355.907594)
					(mid 273.1135 -356.171766)
					(end 272.8468 -355.907594)
				)
				(arc
					(start 272.2372 -355.907594)
					(mid 271.9705 -356.171766)
					(end 271.7038 -355.907594)
				)
				(arc
					(start 271.7038 -355.905054)
					(mid 271.9705 -355.638354)
					(end 272.2372 -355.905054)
				)
				(arc
					(start 272.8468 -355.905054)
					(mid 273.1135 -355.638354)
					(end 273.3802 -355.905054)
				)
				(arc
					(start 273.4945 -355.905054)
					(mid 273.382908 -355.635646)
					(end 273.1135 -355.524054)
				)
			)
		)
	)
	(zone
		(layers "In2.Cu" "In4.Cu" "In7.Cu" "In9.Cu")
		(hatch none 0.5)
		(connect_pads
			(clearance 0)
		)
		(min_thickness 0.25)
		(keepout
			(tracks not_allowed)
			(vias allowed)
			(pads allowed)
			(copperpour not_allowed)
			(footprints allowed)
		)
		(placement
			(enabled no)
			(sheetname "")
		)
		(fill yes
			(thermal_gap 0.5)
			(thermal_bridge_width 0.5)
			(island_removal_mode 0)
		)
		(polygon
			(pts
				(arc
					(start 271.970754 -312.321448)
					(mid 271.58696 -312.704861)
					(end 271.9705 -313.088528)
				)
				(arc
					(start 273.1135 -313.088528)
					(mid 273.383804 -312.977088)
					(end 273.49704 -312.707528)
				)
				(arc
					(start 273.3802 -312.707528)
					(mid 273.1135 -312.9717)
					(end 272.8468 -312.707528)
				)
				(arc
					(start 272.2372 -312.707528)
					(mid 271.9705 -312.9717)
					(end 271.7038 -312.707528)
				)
				(arc
					(start 271.7038 -312.704988)
					(mid 271.9705 -312.438288)
					(end 272.2372 -312.704988)
				)
				(arc
					(start 272.8468 -312.704988)
					(mid 273.1135 -312.438288)
					(end 273.3802 -312.704988)
				)
				(arc
					(start 273.49704 -312.704988)
					(mid 273.384704 -312.433784)
					(end 273.1135 -312.321448)
				)
			)
		)
	)
	(zone
		(layers "In2.Cu" "In4.Cu" "In7.Cu" "In9.Cu")
		(hatch none 0.5)
		(connect_pads
			(clearance 0)
		)
		(min_thickness 0.25)
		(keepout
			(tracks not_allowed)
			(vias allowed)
			(pads allowed)
			(copperpour not_allowed)
			(footprints allowed)
		)
		(placement
			(enabled no)
			(sheetname "")
		)
		(fill yes
			(thermal_gap 0.5)
			(thermal_bridge_width 0.5)
			(island_removal_mode 0)
		)
		(polygon
			(pts
				(arc
					(start 271.970754 -335.721452)
					(mid 271.58696 -336.104865)
					(end 271.9705 -336.488532)
				)
				(arc
					(start 273.1135 -336.488532)
					(mid 273.383804 -336.377092)
					(end 273.49704 -336.107532)
				)
				(arc
					(start 273.3802 -336.107532)
					(mid 273.1135 -336.371704)
					(end 272.8468 -336.107532)
				)
				(arc
					(start 272.2372 -336.107532)
					(mid 271.9705 -336.371704)
					(end 271.7038 -336.107532)
				)
				(arc
					(start 271.7038 -336.104992)
					(mid 271.9705 -335.838292)
					(end 272.2372 -336.104992)
				)
				(arc
					(start 272.8468 -336.104992)
					(mid 273.1135 -335.838292)
					(end 273.3802 -336.104992)
				)
				(arc
					(start 273.49704 -336.104992)
					(mid 273.384704 -335.833788)
					(end 273.1135 -335.721452)
				)
			)
		)
	)
	(zone
		(layers "In2.Cu" "In4.Cu" "In7.Cu" "In9.Cu")
		(hatch none 0.5)
		(connect_pads
			(clearance 0)
		)
		(min_thickness 0.25)
		(keepout
			(tracks not_allowed)
			(vias allowed)
			(pads allowed)
			(copperpour not_allowed)
			(footprints allowed)
		)
		(placement
			(enabled no)
			(sheetname "")
		)
		(fill yes
			(thermal_gap 0.5)
			(thermal_bridge_width 0.5)
			(island_removal_mode 0)
		)
		(polygon
			(pts
				(arc
					(start 271.970754 -314.121546)
					(mid 271.58696 -314.504959)
					(end 271.9705 -314.888626)
				)
				(arc
					(start 273.1135 -314.888626)
					(mid 273.383804 -314.777186)
					(end 273.49704 -314.507626)
				)
				(arc
					(start 273.3802 -314.507626)
					(mid 273.1135 -314.771798)
					(end 272.8468 -314.507626)
				)
				(arc
					(start 272.2372 -314.507626)
					(mid 271.9705 -314.771798)
					(end 271.7038 -314.507626)
				)
				(arc
					(start 271.7038 -314.505086)
					(mid 271.9705 -314.238386)
					(end 272.2372 -314.505086)
				)
				(arc
					(start 272.8468 -314.505086)
					(mid 273.1135 -314.238386)
					(end 273.3802 -314.505086)
				)
				(arc
					(start 273.49704 -314.505086)
					(mid 273.384704 -314.233882)
					(end 273.1135 -314.121546)
				)
			)
		)
	)
	(zone
		(layers "In2.Cu" "In4.Cu" "In7.Cu" "In9.Cu")
		(hatch none 0.5)
		(connect_pads
			(clearance 0)
		)
		(min_thickness 0.25)
		(keepout
			(tracks not_allowed)
			(vias allowed)
			(pads allowed)
			(copperpour not_allowed)
			(footprints allowed)
		)
		(placement
			(enabled no)
			(sheetname "")
		)
		(fill yes
			(thermal_gap 0.5)
			(thermal_bridge_width 0.5)
			(island_removal_mode 0)
		)
		(polygon
			(pts
				(arc
					(start 271.970754 -328.521568)
					(mid 271.58696 -328.904981)
					(end 271.9705 -329.288648)
				)
				(arc
					(start 273.1135 -329.288648)
					(mid 273.383804 -329.177208)
					(end 273.49704 -328.907648)
				)
				(arc
					(start 273.3802 -328.907648)
					(mid 273.1135 -329.17182)
					(end 272.8468 -328.907648)
				)
				(arc
					(start 272.2372 -328.907648)
					(mid 271.9705 -329.17182)
					(end 271.7038 -328.907648)
				)
				(arc
					(start 271.7038 -328.905108)
					(mid 271.9705 -328.638408)
					(end 272.2372 -328.905108)
				)
				(arc
					(start 272.8468 -328.905108)
					(mid 273.1135 -328.638408)
					(end 273.3802 -328.905108)
				)
				(arc
					(start 273.49704 -328.905108)
					(mid 273.384704 -328.633904)
					(end 273.1135 -328.521568)
				)
			)
		)
	)
	(zone
		(net "GND")
		(layers "In2.Cu" "In4.Cu" "In7.Cu" "In9.Cu")
		(hatch none 0.5)
		(connect_pads
			(clearance 0.5)
		)
		(min_thickness 0.25)
		(fill yes
			(thermal_gap 0.5)
			(thermal_bridge_width 0.5)
			(island_removal_mode 0)
		)
		(polygon
			(pts
				(arc
					(start 394.999972 -17.03197)
					(mid 397.143918 -16.143918)
					(end 398.03197 -13.999972)
				)
				(xy 398.03197 -2.032) (xy 489.418122 -2.032) (xy 489.418122 -347.167962)
				(arc
					(start 296.69994 -347.167962)
					(mid 294.555994 -348.056014)
					(end 293.667942 -350.19996)
				)
				(arc
					(start 293.667942 -373.000016)
					(mid 294.555994 -375.143962)
					(end 296.69994 -376.032014)
				)
				(xy 307.967888 -376.032014) (xy 307.967888 -419.168072) (xy 272.183606 -419.168072) (xy 272.183606 -420.437056)
				(arc
					(start 308.99989 -420.437056)
					(mid 309.167462 -420.367646)
					(end 309.236872 -420.200074)
				)
				(arc
					(start 309.236872 -375.000012)
					(mid 309.167462 -374.83244)
					(end 308.99989 -374.76303)
				)
				(arc
					(start 296.69994 -374.76303)
					(mid 295.453301 -374.246655)
					(end 294.936926 -373.000016)
				)
				(arc
					(start 294.936926 -350.19996)
					(mid 295.453301 -348.953321)
					(end 296.69994 -348.436946)
				)
				(arc
					(start 490.450124 -348.436946)
					(mid 490.617696 -348.367536)
					(end 490.687106 -348.199964)
				)
				(arc
					(start 490.687106 -0.999998)
					(mid 490.617696 -0.832426)
					(end 490.450124 -0.763016)
				)
				(arc
					(start 396.999968 -0.763016)
					(mid 396.832396 -0.832426)
					(end 396.762986 -0.999998)
				)
				(arc
					(start 396.762986 -13.999972)
					(mid 396.246611 -15.246611)
					(end 394.999972 -15.762986)
				)
				(xy 394.731494 -15.762986) (xy 394.731494 -17.03197)
			)
		)
	)
	(zone
		(layers "In2.Cu" "In4.Cu" "In7.Cu" "In9.Cu")
		(hatch none 0.5)
		(connect_pads
			(clearance 0)
		)
		(min_thickness 0.25)
		(keepout
			(tracks not_allowed)
			(vias allowed)
			(pads allowed)
			(copperpour not_allowed)
			(footprints allowed)
		)
		(placement
			(enabled no)
			(sheetname "")
		)
		(fill yes
			(thermal_gap 0.5)
			(thermal_bridge_width 0.5)
			(island_removal_mode 0)
		)
		(polygon
			(pts
				(arc
					(start 325.12 -162.178492)
					(mid 324.739 -161.797492)
					(end 324.358 -162.178492)
				)
				(arc
					(start 324.358 -163.321492)
					(mid 324.73773 -163.70249)
					(end 325.12 -163.324032)
				)
				(arc
					(start 325.0057 -163.324032)
					(mid 324.739 -163.588204)
					(end 324.4723 -163.324032)
				)
				(arc
					(start 324.4723 -163.321492)
					(mid 324.739 -163.054792)
					(end 325.0057 -163.321492)
				)
				(xy 325.12 -163.321492) (xy 325.12 -162.181032)
				(arc
					(start 325.0057 -162.181032)
					(mid 324.739 -162.445204)
					(end 324.4723 -162.181032)
				)
				(arc
					(start 324.4723 -162.178492)
					(mid 324.739 -161.911792)
					(end 325.0057 -162.178492)
				)
			)
		)
	)
	(zone
		(layers "In2.Cu" "In4.Cu" "In7.Cu" "In9.Cu")
		(hatch none 0.5)
		(connect_pads
			(clearance 0)
		)
		(min_thickness 0.25)
		(keepout
			(tracks not_allowed)
			(vias allowed)
			(pads allowed)
			(copperpour not_allowed)
			(footprints allowed)
		)
		(placement
			(enabled no)
			(sheetname "")
		)
		(fill yes
			(thermal_gap 0.5)
			(thermal_bridge_width 0.5)
			(island_removal_mode 0)
		)
		(polygon
			(pts
				(arc
					(start 271.970754 -359.123996)
					(mid 271.5895 -359.504869)
					(end 271.9705 -359.885996)
				)
				(arc
					(start 273.1135 -359.885996)
					(mid 273.382008 -359.7753)
					(end 273.4945 -359.507536)
				)
				(arc
					(start 273.3802 -359.507536)
					(mid 273.1135 -359.771708)
					(end 272.8468 -359.507536)
				)
				(arc
					(start 272.2372 -359.507536)
					(mid 271.9705 -359.771708)
					(end 271.7038 -359.507536)
				)
				(arc
					(start 271.7038 -359.504996)
					(mid 271.9705 -359.238296)
					(end 272.2372 -359.504996)
				)
				(arc
					(start 272.8468 -359.504996)
					(mid 273.1135 -359.238296)
					(end 273.3802 -359.504996)
				)
				(arc
					(start 273.4945 -359.504996)
					(mid 273.382908 -359.235588)
					(end 273.1135 -359.123996)
				)
			)
		)
	)
	(zone
		(layers "In2.Cu" "In4.Cu" "In7.Cu" "In9.Cu")
		(hatch none 0.5)
		(connect_pads
			(clearance 0)
		)
		(min_thickness 0.25)
		(keepout
			(tracks not_allowed)
			(vias allowed)
			(pads allowed)
			(copperpour not_allowed)
			(footprints allowed)
		)
		(placement
			(enabled no)
			(sheetname "")
		)
		(fill yes
			(thermal_gap 0.5)
			(thermal_bridge_width 0.5)
			(island_removal_mode 0)
		)
		(polygon
			(pts
				(arc
					(start 388.21995 -47.178468)
					(mid 387.83895 -46.797468)
					(end 387.45795 -47.178468)
				)
				(arc
					(start 387.45795 -48.321468)
					(mid 387.83768 -48.702466)
					(end 388.21995 -48.324008)
				)
				(arc
					(start 388.10565 -48.324008)
					(mid 387.83895 -48.58818)
					(end 387.57225 -48.324008)
				)
				(arc
					(start 387.57225 -48.321468)
					(mid 387.83895 -48.054768)
					(end 388.10565 -48.321468)
				)
				(xy 388.21995 -48.321468) (xy 388.21995 -47.181008)
				(arc
					(start 388.10565 -47.181008)
					(mid 387.83895 -47.44518)
					(end 387.57225 -47.181008)
				)
				(arc
					(start 387.57225 -47.178468)
					(mid 387.83895 -46.911768)
					(end 388.10565 -47.178468)
				)
			)
		)
	)
	(zone
		(layers "In2.Cu" "In4.Cu" "In7.Cu" "In9.Cu")
		(hatch none 0.5)
		(connect_pads
			(clearance 0)
		)
		(min_thickness 0.25)
		(keepout
			(tracks not_allowed)
			(vias allowed)
			(pads allowed)
			(copperpour not_allowed)
			(footprints allowed)
		)
		(placement
			(enabled no)
			(sheetname "")
		)
		(fill yes
			(thermal_gap 0.5)
			(thermal_bridge_width 0.5)
			(island_removal_mode 0)
		)
		(polygon
			(pts
				(arc
					(start 482.870002 -47.178468)
					(mid 482.489002 -46.797468)
					(end 482.108002 -47.178468)
				)
				(arc
					(start 482.108002 -48.321468)
					(mid 482.487732 -48.702466)
					(end 482.870002 -48.324008)
				)
				(arc
					(start 482.755702 -48.324008)
					(mid 482.489002 -48.58818)
					(end 482.222302 -48.324008)
				)
				(arc
					(start 482.222302 -48.321468)
					(mid 482.489002 -48.054768)
					(end 482.755702 -48.321468)
				)
				(xy 482.870002 -48.321468) (xy 482.870002 -47.181008)
				(arc
					(start 482.755702 -47.181008)
					(mid 482.489002 -47.44518)
					(end 482.222302 -47.181008)
				)
				(arc
					(start 482.222302 -47.178468)
					(mid 482.489002 -46.911768)
					(end 482.755702 -47.178468)
				)
			)
		)
	)
	(zone
		(layers "In2.Cu" "In4.Cu" "In7.Cu" "In9.Cu")
		(hatch none 0.5)
		(connect_pads
			(clearance 0)
		)
		(min_thickness 0.25)
		(keepout
			(tracks not_allowed)
			(vias allowed)
			(pads allowed)
			(copperpour not_allowed)
			(footprints allowed)
		)
		(placement
			(enabled no)
			(sheetname "")
		)
		(fill yes
			(thermal_gap 0.5)
			(thermal_bridge_width 0.5)
			(island_removal_mode 0)
		)
		(polygon
			(pts
				(arc
					(start 271.970754 -337.52155)
					(mid 271.58696 -337.904963)
					(end 271.9705 -338.28863)
				)
				(arc
					(start 273.1135 -338.28863)
					(mid 273.383804 -338.17719)
					(end 273.49704 -337.90763)
				)
				(arc
					(start 273.3802 -337.90763)
					(mid 273.1135 -338.171802)
					(end 272.8468 -337.90763)
				)
				(arc
					(start 272.2372 -337.90763)
					(mid 271.9705 -338.171802)
					(end 271.7038 -337.90763)
				)
				(arc
					(start 271.7038 -337.90509)
					(mid 271.9705 -337.63839)
					(end 272.2372 -337.90509)
				)
				(arc
					(start 272.8468 -337.90509)
					(mid 273.1135 -337.63839)
					(end 273.3802 -337.90509)
				)
				(arc
					(start 273.49704 -337.90509)
					(mid 273.384704 -337.633886)
					(end 273.1135 -337.52155)
				)
			)
		)
	)
	(zone
		(layers "In2.Cu" "In4.Cu" "In7.Cu" "In9.Cu")
		(hatch none 0.5)
		(connect_pads
			(clearance 0)
		)
		(min_thickness 0.25)
		(keepout
			(tracks not_allowed)
			(vias allowed)
			(pads allowed)
			(copperpour not_allowed)
			(footprints allowed)
		)
		(placement
			(enabled no)
			(sheetname "")
		)
		(fill yes
			(thermal_gap 0.5)
			(thermal_bridge_width 0.5)
			(island_removal_mode 0)
		)
		(polygon
			(pts
				(arc
					(start 271.970754 -330.321412)
					(mid 271.58696 -330.704825)
					(end 271.9705 -331.088492)
				)
				(arc
					(start 273.1135 -331.088492)
					(mid 273.383804 -330.977052)
					(end 273.49704 -330.707492)
				)
				(arc
					(start 273.3802 -330.707492)
					(mid 273.1135 -330.971664)
					(end 272.8468 -330.707492)
				)
				(arc
					(start 272.2372 -330.707492)
					(mid 271.9705 -330.971664)
					(end 271.7038 -330.707492)
				)
				(arc
					(start 271.7038 -330.704952)
					(mid 271.9705 -330.438252)
					(end 272.2372 -330.704952)
				)
				(arc
					(start 272.8468 -330.704952)
					(mid 273.1135 -330.438252)
					(end 273.3802 -330.704952)
				)
				(arc
					(start 273.49704 -330.704952)
					(mid 273.384704 -330.433748)
					(end 273.1135 -330.321412)
				)
			)
		)
	)
	(zone
		(layers "In2.Cu" "In4.Cu" "In7.Cu" "In9.Cu")
		(hatch none 0.5)
		(connect_pads
			(clearance 0)
		)
		(min_thickness 0.25)
		(keepout
			(tracks not_allowed)
			(vias allowed)
			(pads allowed)
			(copperpour not_allowed)
			(footprints allowed)
		)
		(placement
			(enabled no)
			(sheetname "")
		)
		(fill yes
			(thermal_gap 0.5)
			(thermal_bridge_width 0.5)
			(island_removal_mode 0)
		)
		(polygon
			(pts
				(arc
					(start 271.970754 -351.924112)
					(mid 271.5895 -352.304985)
					(end 271.9705 -352.686112)
				)
				(arc
					(start 273.1135 -352.686112)
					(mid 273.382008 -352.575416)
					(end 273.4945 -352.307652)
				)
				(arc
					(start 273.3802 -352.307652)
					(mid 273.1135 -352.571824)
					(end 272.8468 -352.307652)
				)
				(arc
					(start 272.2372 -352.307652)
					(mid 271.9705 -352.571824)
					(end 271.7038 -352.307652)
				)
				(arc
					(start 271.7038 -352.305112)
					(mid 271.9705 -352.038412)
					(end 272.2372 -352.305112)
				)
				(arc
					(start 272.8468 -352.305112)
					(mid 273.1135 -352.038412)
					(end 273.3802 -352.305112)
				)
				(arc
					(start 273.4945 -352.305112)
					(mid 273.382908 -352.035704)
					(end 273.1135 -351.924112)
				)
			)
		)
	)
	(zone
		(layers "In2.Cu" "In4.Cu" "In7.Cu" "In9.Cu")
		(hatch none 0.5)
		(connect_pads
			(clearance 0)
		)
		(min_thickness 0.25)
		(keepout
			(tracks not_allowed)
			(vias allowed)
			(pads allowed)
			(copperpour not_allowed)
			(footprints allowed)
		)
		(placement
			(enabled no)
			(sheetname "")
		)
		(fill yes
			(thermal_gap 0.5)
			(thermal_bridge_width 0.5)
			(island_removal_mode 0)
		)
		(polygon
			(pts
				(arc
					(start 271.970754 -333.921354)
					(mid 271.58696 -334.304767)
					(end 271.9705 -334.688434)
				)
				(arc
					(start 273.1135 -334.688434)
					(mid 273.383804 -334.576994)
					(end 273.49704 -334.307434)
				)
				(arc
					(start 273.3802 -334.307434)
					(mid 273.1135 -334.571606)
					(end 272.8468 -334.307434)
				)
				(arc
					(start 272.2372 -334.307434)
					(mid 271.9705 -334.571606)
					(end 271.7038 -334.307434)
				)
				(arc
					(start 271.7038 -334.304894)
					(mid 271.9705 -334.038194)
					(end 272.2372 -334.304894)
				)
				(arc
					(start 272.8468 -334.304894)
					(mid 273.1135 -334.038194)
					(end 273.3802 -334.304894)
				)
				(arc
					(start 273.49704 -334.304894)
					(mid 273.384704 -334.03369)
					(end 273.1135 -333.921354)
				)
			)
		)
	)
	(zone
		(layers "In2.Cu" "In4.Cu" "In7.Cu" "In9.Cu")
		(hatch none 0.5)
		(connect_pads
			(clearance 0)
		)
		(min_thickness 0.25)
		(keepout
			(tracks not_allowed)
			(vias allowed)
			(pads allowed)
			(copperpour not_allowed)
			(footprints allowed)
		)
		(placement
			(enabled no)
			(sheetname "")
		)
		(fill yes
			(thermal_gap 0.5)
			(thermal_bridge_width 0.5)
			(island_removal_mode 0)
		)
		(polygon
			(pts
				(arc
					(start 271.970754 -350.124014)
					(mid 271.5895 -350.504887)
					(end 271.9705 -350.886014)
				)
				(arc
					(start 273.1135 -350.886014)
					(mid 273.382008 -350.775318)
					(end 273.4945 -350.507554)
				)
				(arc
					(start 273.3802 -350.507554)
					(mid 273.1135 -350.771726)
					(end 272.8468 -350.507554)
				)
				(arc
					(start 272.2372 -350.507554)
					(mid 271.9705 -350.771726)
					(end 271.7038 -350.507554)
				)
				(arc
					(start 271.7038 -350.505014)
					(mid 271.9705 -350.238314)
					(end 272.2372 -350.505014)
				)
				(arc
					(start 272.8468 -350.505014)
					(mid 273.1135 -350.238314)
					(end 273.3802 -350.505014)
				)
				(arc
					(start 273.4945 -350.505014)
					(mid 273.382908 -350.235606)
					(end 273.1135 -350.124014)
				)
			)
		)
	)
	(zone
		(layers "In2.Cu" "In4.Cu" "In7.Cu" "In9.Cu")
		(hatch none 0.5)
		(connect_pads
			(clearance 0)
		)
		(min_thickness 0.25)
		(keepout
			(tracks not_allowed)
			(vias allowed)
			(pads allowed)
			(copperpour not_allowed)
			(footprints allowed)
		)
		(placement
			(enabled no)
			(sheetname "")
		)
		(fill yes
			(thermal_gap 0.5)
			(thermal_bridge_width 0.5)
			(island_removal_mode 0)
		)
		(polygon
			(pts
				(arc
					(start 271.970754 -332.12151)
					(mid 271.58696 -332.504923)
					(end 271.9705 -332.88859)
				)
				(arc
					(start 273.1135 -332.88859)
					(mid 273.383804 -332.77715)
					(end 273.49704 -332.50759)
				)
				(arc
					(start 273.3802 -332.50759)
					(mid 273.1135 -332.771762)
					(end 272.8468 -332.50759)
				)
				(arc
					(start 272.2372 -332.50759)
					(mid 271.9705 -332.771762)
					(end 271.7038 -332.50759)
				)
				(arc
					(start 271.7038 -332.50505)
					(mid 271.9705 -332.23835)
					(end 272.2372 -332.50505)
				)
				(arc
					(start 272.8468 -332.50505)
					(mid 273.1135 -332.23835)
					(end 273.3802 -332.50505)
				)
				(arc
					(start 273.49704 -332.50505)
					(mid 273.384704 -332.233846)
					(end 273.1135 -332.12151)
				)
			)
		)
	)
	(zone
		(net "GND")
		(layers "In2.Cu" "In4.Cu" "In7.Cu" "In9.Cu")
		(hatch none 0.5)
		(connect_pads
			(clearance 0.5)
		)
		(min_thickness 0.25)
		(fill yes
			(thermal_gap 0.5)
			(thermal_bridge_width 0.5)
			(island_removal_mode 0)
		)
		(polygon
			(pts
				(arc
					(start 148.999956 -17.03197)
					(mid 151.143902 -16.143918)
					(end 152.031954 -13.999972)
				)
				(xy 152.031954 -2.032)
				(arc
					(start 199.00011 -2.032)
					(mid 200.741362 -1.482149)
					(end 201.851006 -0.032004)
				)
				(xy 202.368658 -0.032004) (xy 202.368658 1.23698)
				(arc
					(start 201.000106 1.23698)
					(mid 200.832534 1.16757)
					(end 200.763124 0.999998)
				)
				(arc
					(start 200.763124 0.999998)
					(mid 200.246749 -0.246641)
					(end 199.00011 -0.763016)
				)
				(arc
					(start 150.999952 -0.763016)
					(mid 150.83238 -0.832426)
					(end 150.76297 -0.999998)
				)
				(arc
					(start 150.76297 -13.999972)
					(mid 150.246595 -15.246611)
					(end 148.999956 -15.762986)
				)
				(xy 148.719794 -15.762986) (xy 148.719794 -17.03197)
			)
		)
	)
	(zone
		(layers "In2.Cu" "In4.Cu" "In7.Cu" "In9.Cu")
		(hatch none 0.5)
		(connect_pads
			(clearance 0)
		)
		(min_thickness 0.25)
		(keepout
			(tracks not_allowed)
			(vias allowed)
			(pads allowed)
			(copperpour not_allowed)
			(footprints allowed)
		)
		(placement
			(enabled no)
			(sheetname "")
		)
		(fill yes
			(thermal_gap 0.5)
			(thermal_bridge_width 0.5)
			(island_removal_mode 0)
		)
		(polygon
			(pts
				(arc
					(start 419.770052 -47.178468)
					(mid 419.389052 -46.797468)
					(end 419.008052 -47.178468)
				)
				(arc
					(start 419.008052 -48.321468)
					(mid 419.387782 -48.702466)
					(end 419.770052 -48.324008)
				)
				(arc
					(start 419.655752 -48.324008)
					(mid 419.389052 -48.58818)
					(end 419.122352 -48.324008)
				)
				(arc
					(start 419.122352 -48.321468)
					(mid 419.389052 -48.054768)
					(end 419.655752 -48.321468)
				)
				(xy 419.770052 -48.321468) (xy 419.770052 -47.181008)
				(arc
					(start 419.655752 -47.181008)
					(mid 419.389052 -47.44518)
					(end 419.122352 -47.181008)
				)
				(arc
					(start 419.122352 -47.178468)
					(mid 419.389052 -46.911768)
					(end 419.655752 -47.178468)
				)
			)
		)
	)
	(zone
		(layers "In2.Cu" "In4.Cu" "In7.Cu" "In9.Cu")
		(hatch none 0.5)
		(connect_pads
			(clearance 0)
		)
		(min_thickness 0.25)
		(keepout
			(tracks not_allowed)
			(vias allowed)
			(pads allowed)
			(copperpour not_allowed)
			(footprints allowed)
		)
		(placement
			(enabled no)
			(sheetname "")
		)
		(fill yes
			(thermal_gap 0.5)
			(thermal_bridge_width 0.5)
			(island_removal_mode 0)
		)
		(polygon
			(pts
				(arc
					(start 375.147078 -28.080208)
					(mid 369.152678 -28.080208)
					(end 375.147078 -28.080208)
				)
			)
		)
	)
	(zone
		(layers "In2.Cu" "In4.Cu" "In7.Cu" "In9.Cu")
		(hatch none 0.5)
		(connect_pads
			(clearance 0)
		)
		(min_thickness 0.25)
		(keepout
			(tracks not_allowed)
			(vias allowed)
			(pads allowed)
			(copperpour not_allowed)
			(footprints allowed)
		)
		(placement
			(enabled no)
			(sheetname "")
		)
		(fill yes
			(thermal_gap 0.5)
			(thermal_bridge_width 0.5)
			(island_removal_mode 0)
		)
		(polygon
			(pts
				(arc
					(start 438.6199 -162.178492)
					(mid 438.2389 -161.797492)
					(end 437.8579 -162.178492)
				)
				(arc
					(start 437.8579 -163.321492)
					(mid 438.23763 -163.70249)
					(end 438.6199 -163.324032)
				)
				(arc
					(start 438.5056 -163.324032)
					(mid 438.2389 -163.588204)
					(end 437.9722 -163.324032)
				)
				(arc
					(start 437.9722 -163.321492)
					(mid 438.2389 -163.054792)
					(end 438.5056 -163.321492)
				)
				(xy 438.6199 -163.321492) (xy 438.6199 -162.181032)
				(arc
					(start 438.5056 -162.181032)
					(mid 438.2389 -162.445204)
					(end 437.9722 -162.181032)
				)
				(arc
					(start 437.9722 -162.178492)
					(mid 438.2389 -161.911792)
					(end 438.5056 -162.178492)
				)
			)
		)
	)
	(zone
		(layers "In2.Cu" "In4.Cu" "In7.Cu" "In9.Cu")
		(hatch none 0.5)
		(connect_pads
			(clearance 0)
		)
		(min_thickness 0.25)
		(keepout
			(tracks not_allowed)
			(vias allowed)
			(pads allowed)
			(copperpour not_allowed)
			(footprints allowed)
		)
		(placement
			(enabled no)
			(sheetname "")
		)
		(fill yes
			(thermal_gap 0.5)
			(thermal_bridge_width 0.5)
			(island_removal_mode 0)
		)
		(polygon
			(pts
				(arc
					(start 129.147062 -28.080208)
					(mid 123.152662 -28.080208)
					(end 129.147062 -28.080208)
				)
			)
		)
	)
	(zone
		(layers "In2.Cu" "In4.Cu" "In7.Cu" "In9.Cu")
		(hatch none 0.5)
		(connect_pads
			(clearance 0)
		)
		(min_thickness 0.25)
		(keepout
			(tracks not_allowed)
			(vias allowed)
			(pads allowed)
			(copperpour not_allowed)
			(footprints allowed)
		)
		(placement
			(enabled no)
			(sheetname "")
		)
		(fill yes
			(thermal_gap 0.5)
			(thermal_bridge_width 0.5)
			(island_removal_mode 0)
		)
		(polygon
			(pts
				(arc
					(start 451.3199 -277.178516)
					(mid 450.9389 -276.797516)
					(end 450.5579 -277.178516)
				)
				(arc
					(start 450.5579 -278.321516)
					(mid 450.93763 -278.702514)
					(end 451.3199 -278.324056)
				)
				(arc
					(start 451.2056 -278.324056)
					(mid 450.9389 -278.588228)
					(end 450.6722 -278.324056)
				)
				(arc
					(start 450.6722 -278.321516)
					(mid 450.9389 -278.054816)
					(end 451.2056 -278.321516)
				)
				(xy 451.3199 -278.321516) (xy 451.3199 -277.181056)
				(arc
					(start 451.2056 -277.181056)
					(mid 450.9389 -277.445228)
					(end 450.6722 -277.181056)
				)
				(arc
					(start 450.6722 -277.178516)
					(mid 450.9389 -276.911816)
					(end 451.2056 -277.178516)
				)
			)
		)
	)
	(zone
		(layers "In2.Cu" "In4.Cu" "In7.Cu" "In9.Cu")
		(hatch none 0.5)
		(connect_pads
			(clearance 0)
		)
		(min_thickness 0.25)
		(keepout
			(tracks not_allowed)
			(vias allowed)
			(pads allowed)
			(copperpour not_allowed)
			(footprints allowed)
		)
		(placement
			(enabled no)
			(sheetname "")
		)
		(fill yes
			(thermal_gap 0.5)
			(thermal_bridge_width 0.5)
			(island_removal_mode 0)
		)
		(polygon
			(pts
				(arc
					(start 271.970754 -315.92139)
					(mid 271.58696 -316.304803)
					(end 271.9705 -316.68847)
				)
				(arc
					(start 273.1135 -316.68847)
					(mid 273.383804 -316.57703)
					(end 273.49704 -316.30747)
				)
				(arc
					(start 273.3802 -316.30747)
					(mid 273.1135 -316.571642)
					(end 272.8468 -316.30747)
				)
				(arc
					(start 272.2372 -316.30747)
					(mid 271.9705 -316.571642)
					(end 271.7038 -316.30747)
				)
				(arc
					(start 271.7038 -316.30493)
					(mid 271.9705 -316.03823)
					(end 272.2372 -316.30493)
				)
				(arc
					(start 272.8468 -316.30493)
					(mid 273.1135 -316.03823)
					(end 273.3802 -316.30493)
				)
				(arc
					(start 273.49704 -316.30493)
					(mid 273.384704 -316.033726)
					(end 273.1135 -315.92139)
				)
			)
		)
	)
	(zone
		(layers "In2.Cu" "In4.Cu" "In7.Cu" "In9.Cu")
		(hatch none 0.5)
		(connect_pads
			(clearance 0)
		)
		(min_thickness 0.25)
		(keepout
			(tracks not_allowed)
			(vias allowed)
			(pads allowed)
			(copperpour not_allowed)
			(footprints allowed)
		)
		(placement
			(enabled no)
			(sheetname "")
		)
		(fill yes
			(thermal_gap 0.5)
			(thermal_bridge_width 0.5)
			(island_removal_mode 0)
		)
		(polygon
			(pts
				(arc
					(start 271.970754 -306.921408)
					(mid 271.58696 -307.304821)
					(end 271.9705 -307.688488)
				)
				(arc
					(start 273.1135 -307.688488)
					(mid 273.383804 -307.577048)
					(end 273.49704 -307.307488)
				)
				(arc
					(start 273.3802 -307.307488)
					(mid 273.1135 -307.57166)
					(end 272.8468 -307.307488)
				)
				(arc
					(start 272.2372 -307.307488)
					(mid 271.9705 -307.57166)
					(end 271.7038 -307.307488)
				)
				(arc
					(start 271.7038 -307.304948)
					(mid 271.9705 -307.038248)
					(end 272.2372 -307.304948)
				)
				(arc
					(start 272.8468 -307.304948)
					(mid 273.1135 -307.038248)
					(end 273.3802 -307.304948)
				)
				(arc
					(start 273.49704 -307.304948)
					(mid 273.384704 -307.033744)
					(end 273.1135 -306.921408)
				)
			)
		)
	)
	(zone
		(layers "In2.Cu" "In4.Cu" "In7.Cu" "In9.Cu")
		(hatch none 0.5)
		(connect_pads
			(clearance 0)
		)
		(min_thickness 0.25)
		(keepout
			(tracks not_allowed)
			(vias allowed)
			(pads allowed)
			(copperpour not_allowed)
			(footprints allowed)
		)
		(placement
			(enabled no)
			(sheetname "")
		)
		(fill yes
			(thermal_gap 0.5)
			(thermal_bridge_width 0.5)
			(island_removal_mode 0)
		)
		(polygon
			(pts
				(arc
					(start 271.970754 -310.52135)
					(mid 271.58696 -310.904763)
					(end 271.9705 -311.28843)
				)
				(arc
					(start 273.1135 -311.28843)
					(mid 273.383804 -311.17699)
					(end 273.49704 -310.90743)
				)
				(arc
					(start 273.3802 -310.90743)
					(mid 273.1135 -311.171602)
					(end 272.8468 -310.90743)
				)
				(arc
					(start 272.2372 -310.90743)
					(mid 271.9705 -311.171602)
					(end 271.7038 -310.90743)
				)
				(arc
					(start 271.7038 -310.90489)
					(mid 271.9705 -310.63819)
					(end 272.2372 -310.90489)
				)
				(arc
					(start 272.8468 -310.90489)
					(mid 273.1135 -310.63819)
					(end 273.3802 -310.90489)
				)
				(arc
					(start 273.49704 -310.90489)
					(mid 273.384704 -310.633686)
					(end 273.1135 -310.52135)
				)
			)
		)
	)
	(zone
		(layers "In2.Cu" "In4.Cu" "In7.Cu" "In9.Cu")
		(hatch none 0.5)
		(connect_pads
			(clearance 0)
		)
		(min_thickness 0.25)
		(keepout
			(tracks not_allowed)
			(vias allowed)
			(pads allowed)
			(copperpour not_allowed)
			(footprints allowed)
		)
		(placement
			(enabled no)
			(sheetname "")
		)
		(fill yes
			(thermal_gap 0.5)
			(thermal_bridge_width 0.5)
			(island_removal_mode 0)
		)
		(polygon
			(pts
				(arc
					(start 482.870002 -162.178492)
					(mid 482.489002 -161.797492)
					(end 482.108002 -162.178492)
				)
				(arc
					(start 482.108002 -163.321492)
					(mid 482.487732 -163.70249)
					(end 482.870002 -163.324032)
				)
				(arc
					(start 482.755702 -163.324032)
					(mid 482.489002 -163.588204)
					(end 482.222302 -163.324032)
				)
				(arc
					(start 482.222302 -163.321492)
					(mid 482.489002 -163.054792)
					(end 482.755702 -163.321492)
				)
				(xy 482.870002 -163.321492) (xy 482.870002 -162.181032)
				(arc
					(start 482.755702 -162.181032)
					(mid 482.489002 -162.445204)
					(end 482.222302 -162.181032)
				)
				(arc
					(start 482.222302 -162.178492)
					(mid 482.489002 -161.911792)
					(end 482.755702 -162.178492)
				)
			)
		)
	)
	(zone
		(layers "In2.Cu" "In4.Cu" "In7.Cu" "In9.Cu")
		(hatch none 0.5)
		(connect_pads
			(clearance 0)
		)
		(min_thickness 0.25)
		(keepout
			(tracks not_allowed)
			(vias allowed)
			(pads allowed)
			(copperpour not_allowed)
			(footprints allowed)
		)
		(placement
			(enabled no)
			(sheetname "")
		)
		(fill yes
			(thermal_gap 0.5)
			(thermal_bridge_width 0.5)
			(island_removal_mode 0)
		)
		(polygon
			(pts
				(arc
					(start 419.770052 -162.178492)
					(mid 419.389052 -161.797492)
					(end 419.008052 -162.178492)
				)
				(arc
					(start 419.008052 -163.321492)
					(mid 419.387782 -163.70249)
					(end 419.770052 -163.324032)
				)
				(arc
					(start 419.655752 -163.324032)
					(mid 419.389052 -163.588204)
					(end 419.122352 -163.324032)
				)
				(arc
					(start 419.122352 -163.321492)
					(mid 419.389052 -163.054792)
					(end 419.655752 -163.321492)
				)
				(xy 419.770052 -163.321492) (xy 419.770052 -162.181032)
				(arc
					(start 419.655752 -162.181032)
					(mid 419.389052 -162.445204)
					(end 419.122352 -162.181032)
				)
				(arc
					(start 419.122352 -162.178492)
					(mid 419.389052 -161.911792)
					(end 419.655752 -162.178492)
				)
			)
		)
	)
	(zone
		(layers "In2.Cu" "In4.Cu" "In7.Cu" "In9.Cu")
		(hatch none 0.5)
		(connect_pads
			(clearance 0)
		)
		(min_thickness 0.25)
		(keepout
			(tracks not_allowed)
			(vias allowed)
			(pads allowed)
			(copperpour not_allowed)
			(footprints allowed)
		)
		(placement
			(enabled no)
			(sheetname "")
		)
		(fill yes
			(thermal_gap 0.5)
			(thermal_bridge_width 0.5)
			(island_removal_mode 0)
		)
		(polygon
			(pts
				(arc
					(start 482.870002 -277.178516)
					(mid 482.489002 -276.797516)
					(end 482.108002 -277.178516)
				)
				(arc
					(start 482.108002 -278.321516)
					(mid 482.487732 -278.702514)
					(end 482.870002 -278.324056)
				)
				(arc
					(start 482.755702 -278.324056)
					(mid 482.489002 -278.588228)
					(end 482.222302 -278.324056)
				)
				(arc
					(start 482.222302 -278.321516)
					(mid 482.489002 -278.054816)
					(end 482.755702 -278.321516)
				)
				(xy 482.870002 -278.321516) (xy 482.870002 -277.181056)
				(arc
					(start 482.755702 -277.181056)
					(mid 482.489002 -277.445228)
					(end 482.222302 -277.181056)
				)
				(arc
					(start 482.222302 -277.178516)
					(mid 482.489002 -276.911816)
					(end 482.755702 -277.178516)
				)
			)
		)
	)
	(zone
		(layers "In2.Cu" "In4.Cu" "In7.Cu" "In9.Cu")
		(hatch none 0.5)
		(connect_pads
			(clearance 0)
		)
		(min_thickness 0.25)
		(keepout
			(tracks not_allowed)
			(vias allowed)
			(pads allowed)
			(copperpour not_allowed)
			(footprints allowed)
		)
		(placement
			(enabled no)
			(sheetname "")
		)
		(fill yes
			(thermal_gap 0.5)
			(thermal_bridge_width 0.5)
			(island_removal_mode 0)
		)
		(polygon
			(pts
				(arc
					(start 271.970754 -353.723956)
					(mid 271.5895 -354.104829)
					(end 271.9705 -354.485956)
				)
				(arc
					(start 273.1135 -354.485956)
					(mid 273.382008 -354.37526)
					(end 273.4945 -354.107496)
				)
				(arc
					(start 273.3802 -354.107496)
					(mid 273.1135 -354.371668)
					(end 272.8468 -354.107496)
				)
				(arc
					(start 272.2372 -354.107496)
					(mid 271.9705 -354.371668)
					(end 271.7038 -354.107496)
				)
				(arc
					(start 271.7038 -354.104956)
					(mid 271.9705 -353.838256)
					(end 272.2372 -354.104956)
				)
				(arc
					(start 272.8468 -354.104956)
					(mid 273.1135 -353.838256)
					(end 273.3802 -354.104956)
				)
				(arc
					(start 273.4945 -354.104956)
					(mid 273.382908 -353.835548)
					(end 273.1135 -353.723956)
				)
			)
		)
	)
	(zone
		(layers "In3.Cu" "In5.Cu" "In6.Cu" "In8.Cu" "In10.Cu")
		(hatch none 0.5)
		(connect_pads
			(clearance 0)
		)
		(min_thickness 0.25)
		(keepout
			(tracks not_allowed)
			(vias allowed)
			(pads allowed)
			(copperpour not_allowed)
			(footprints allowed)
		)
		(placement
			(enabled no)
			(sheetname "")
		)
		(fill yes
			(thermal_gap 0.5)
			(thermal_bridge_width 0.5)
			(island_removal_mode 0)
		)
		(polygon
			(pts
				(arc
					(start 283.576014 -106.847894)
					(mid 282.59786 -107.173776)
					(end 282.923742 -108.15193)
				)
				(arc
					(start 284.923738 -109.151928)
					(mid 285.901892 -108.826046)
					(end 285.57601 -107.847892)
				)
			)
		)
	)
	(zone
		(layers "In3.Cu" "In5.Cu" "In6.Cu" "In8.Cu" "In10.Cu")
		(hatch none 0.5)
		(connect_pads
			(clearance 0)
		)
		(min_thickness 0.25)
		(keepout
			(tracks not_allowed)
			(vias allowed)
			(pads allowed)
			(copperpour not_allowed)
			(footprints allowed)
		)
		(placement
			(enabled no)
			(sheetname "")
		)
		(fill yes
			(thermal_gap 0.5)
			(thermal_bridge_width 0.5)
			(island_removal_mode 0)
		)
		(polygon
			(pts
				(arc
					(start 240.874804 -106.85018)
					(mid 239.900206 -107.175046)
					(end 240.225072 -108.149644)
				)
				(xy 240.223802 -108.15193) (xy 242.223798 -109.151928) (xy 242.224052 -109.151674)
				(arc
					(start 242.225068 -109.149642)
					(mid 243.199666 -108.824776)
					(end 242.8748 -107.850178)
				)
				(xy 242.87607 -107.847892) (xy 240.876074 -106.847894)
			)
		)
	)
	(zone
		(layers "In3.Cu" "In5.Cu" "In6.Cu" "In8.Cu" "In10.Cu")
		(hatch none 0.5)
		(connect_pads
			(clearance 0)
		)
		(min_thickness 0.25)
		(keepout
			(tracks not_allowed)
			(vias allowed)
			(pads allowed)
			(copperpour not_allowed)
			(footprints allowed)
		)
		(placement
			(enabled no)
			(sheetname "")
		)
		(fill yes
			(thermal_gap 0.5)
			(thermal_bridge_width 0.5)
			(island_removal_mode 0)
		)
		(polygon
			(pts
				(arc
					(start 240.874804 -134.850124)
					(mid 239.900206 -135.17499)
					(end 240.225072 -136.149588)
				)
				(xy 240.223802 -136.151874) (xy 242.223798 -137.151872) (xy 242.224052 -137.151618)
				(arc
					(start 242.225068 -137.149586)
					(mid 243.199666 -136.82472)
					(end 242.8748 -135.850122)
				)
				(xy 242.87607 -135.847836) (xy 240.876074 -134.847838)
			)
		)
	)
	(zone
		(net "GND")
		(layers "In3.Cu" "In8.Cu" "In10.Cu")
		(hatch none 0.5)
		(connect_pads
			(clearance 0.5)
		)
		(min_thickness 0.25)
		(fill yes
			(thermal_gap 0.5)
			(thermal_bridge_width 0.5)
			(island_removal_mode 0)
		)
		(polygon
			(pts
				(arc
					(start 221.000066 38.037008)
					(mid 220.832494 37.967598)
					(end 220.763084 37.800026)
				)
				(arc
					(start 220.763084 2.999994)
					(mid 220.246709 1.753355)
					(end 219.00007 1.23698)
				)
				(arc
					(start 201.000106 1.23698)
					(mid 200.832534 1.16757)
					(end 200.763124 0.999998)
				)
				(arc
					(start 200.763124 0.999998)
					(mid 200.246749 -0.246641)
					(end 199.00011 -0.763016)
				)
				(arc
					(start 150.999952 -0.763016)
					(mid 150.83238 -0.832426)
					(end 150.76297 -0.999998)
				)
				(arc
					(start 150.76297 -13.999972)
					(mid 150.246595 -15.246611)
					(end 148.999956 -15.762986)
				)
				(arc
					(start 103.000048 -15.762986)
					(mid 101.753409 -15.246611)
					(end 101.237034 -13.999972)
				)
				(arc
					(start 101.237034 -0.999998)
					(mid 101.167624 -0.832426)
					(end 101.000052 -0.763016)
				)
				(arc
					(start 0.999998 -0.763016)
					(mid 0.832426 -0.832426)
					(end 0.763016 -0.999998)
				)
				(arc
					(start 0.763016 -348.199964)
					(mid 0.832426 -348.367536)
					(end 0.999998 -348.436946)
				)
				(arc
					(start 189.6999 -348.436946)
					(mid 190.946539 -348.953321)
					(end 191.462914 -350.19996)
				)
				(arc
					(start 191.462914 -372.000018)
					(mid 191.532324 -372.16759)
					(end 191.699896 -372.237)
				)
				(arc
					(start 199.00011 -372.237)
					(mid 200.246749 -372.753375)
					(end 200.763124 -374.000014)
				)
				(arc
					(start 200.763124 -420.200074)
					(mid 200.832534 -420.367646)
					(end 201.000106 -420.437056)
				)
				(arc
					(start 308.99989 -420.437056)
					(mid 309.167462 -420.367646)
					(end 309.236872 -420.200074)
				)
				(arc
					(start 309.236872 -375.000012)
					(mid 309.167462 -374.83244)
					(end 308.99989 -374.76303)
				)
				(arc
					(start 296.69994 -374.76303)
					(mid 295.453301 -374.246655)
					(end 294.936926 -373.000016)
				)
				(arc
					(start 294.936926 -350.19996)
					(mid 295.453301 -348.953321)
					(end 296.69994 -348.436946)
				)
				(arc
					(start 490.450124 -348.436946)
					(mid 490.617696 -348.367536)
					(end 490.687106 -348.199964)
				)
				(arc
					(start 490.687106 -0.999998)
					(mid 490.617696 -0.832426)
					(end 490.450124 -0.763016)
				)
				(arc
					(start 396.999968 -0.763016)
					(mid 396.832396 -0.832426)
					(end 396.762986 -0.999998)
				)
				(arc
					(start 396.762986 -13.999972)
					(mid 396.246611 -15.246611)
					(end 394.999972 -15.762986)
				)
				(arc
					(start 349.000064 -15.762986)
					(mid 347.753425 -15.246611)
					(end 347.23705 -13.999972)
				)
				(arc
					(start 347.23705 -0.999998)
					(mid 347.16764 -0.832426)
					(end 347.000068 -0.763016)
				)
				(arc
					(start 300.999906 -0.763016)
					(mid 299.753267 -0.246641)
					(end 299.236892 0.999998)
				)
				(arc
					(start 299.236892 37.800026)
					(mid 299.167482 37.967598)
					(end 298.99991 38.037008)
				)
			)
		)
		(polygon
			(pts
				(arc
					(start 223.148652 -416.799776)
					(mid 222.599885 -416.25139)
					(end 222.051372 -416.80003)
				)
				(arc
					(start 222.051372 -418.200078)
					(mid 222.600012 -418.748718)
					(end 223.148652 -418.200078)
				)
			)
		)
		(polygon
			(pts
				(arc
					(start 219.54871 -416.799776)
					(mid 218.999943 -416.25139)
					(end 218.45143 -416.80003)
				)
				(arc
					(start 218.45143 -418.200078)
					(mid 219.00007 -418.748718)
					(end 219.54871 -418.200078)
				)
			)
		)
		(polygon
			(pts
				(arc
					(start 215.948768 -416.799776)
					(mid 215.400001 -416.25139)
					(end 214.851488 -416.80003)
				)
				(arc
					(start 214.851488 -418.200078)
					(mid 215.400128 -418.748718)
					(end 215.948768 -418.200078)
				)
			)
		)
		(polygon
			(pts
				(arc
					(start 212.348826 -416.799776)
					(mid 211.800059 -416.25139)
					(end 211.251546 -416.80003)
				)
				(arc
					(start 211.251546 -418.200078)
					(mid 211.800186 -418.748718)
					(end 212.348826 -418.200078)
				)
			)
		)
		(polygon
			(pts
				(arc
					(start 221.348808 -414.199832)
					(mid 220.800041 -413.651446)
					(end 220.251528 -414.200086)
				)
				(arc
					(start 220.251528 -415.600134)
					(mid 220.800168 -416.148774)
					(end 221.348808 -415.600134)
				)
			)
		)
		(polygon
			(pts
				(arc
					(start 217.748612 -414.199832)
					(mid 217.199845 -413.651446)
					(end 216.651332 -414.200086)
				)
				(arc
					(start 216.651332 -415.600134)
					(mid 217.199972 -416.148774)
					(end 217.748612 -415.600134)
				)
			)
		)
		(polygon
			(pts
				(arc
					(start 214.14867 -414.199832)
					(mid 213.599903 -413.651446)
					(end 213.05139 -414.200086)
				)
				(arc
					(start 213.05139 -415.600134)
					(mid 213.60003 -416.148774)
					(end 214.14867 -415.600134)
				)
			)
		)
		(polygon
			(pts
				(arc
					(start 210.548728 -414.199832)
					(mid 209.999961 -413.651446)
					(end 209.451448 -414.200086)
				)
				(arc
					(start 209.451448 -415.600134)
					(mid 210.000088 -416.148774)
					(end 210.548728 -415.600134)
				)
			)
		)
		(polygon
			(pts
				(arc
					(start 210.548728 -410.59989)
					(mid 209.999961 -410.051504)
					(end 209.451448 -410.600144)
				)
				(arc
					(start 209.451448 -412.000192)
					(mid 210.000088 -412.548832)
					(end 210.548728 -412.000192)
				)
			)
		)
		(polygon
			(pts
				(arc
					(start 221.348808 -406.999948)
					(mid 220.800041 -406.451562)
					(end 220.251528 -407.000202)
				)
				(arc
					(start 220.251528 -408.399996)
					(mid 220.800168 -408.948636)
					(end 221.348808 -408.399996)
				)
			)
		)
		(polygon
			(pts
				(arc
					(start 217.748612 -406.999948)
					(mid 217.199845 -406.451562)
					(end 216.651332 -407.000202)
				)
				(arc
					(start 216.651332 -408.399996)
					(mid 217.199972 -408.948636)
					(end 217.748612 -408.399996)
				)
			)
		)
		(polygon
			(pts
				(arc
					(start 214.14867 -406.999948)
					(mid 213.599903 -406.451562)
					(end 213.05139 -407.000202)
				)
				(arc
					(start 213.05139 -408.399996)
					(mid 213.60003 -408.948636)
					(end 214.14867 -408.399996)
				)
			)
		)
		(polygon
			(pts
				(arc
					(start 210.548728 -406.999948)
					(mid 209.999961 -406.451562)
					(end 209.451448 -407.000202)
				)
				(arc
					(start 209.451448 -408.399996)
					(mid 210.000088 -408.948636)
					(end 210.548728 -408.399996)
				)
			)
		)
		(polygon
			(pts
				(arc
					(start 223.148652 -405.999696)
					(mid 222.599885 -405.45131)
					(end 222.051372 -405.99995)
				)
				(arc
					(start 222.051372 -407.399998)
					(mid 222.600012 -407.948638)
					(end 223.148652 -407.399998)
				)
			)
		)
		(polygon
			(pts
				(arc
					(start 219.54871 -405.999696)
					(mid 218.999943 -405.45131)
					(end 218.45143 -405.99995)
				)
				(arc
					(start 218.45143 -407.399998)
					(mid 219.00007 -407.948638)
					(end 219.54871 -407.399998)
				)
			)
		)
		(polygon
			(pts
				(arc
					(start 215.948768 -405.999696)
					(mid 215.400001 -405.45131)
					(end 214.851488 -405.99995)
				)
				(arc
					(start 214.851488 -407.399998)
					(mid 215.400128 -407.948638)
					(end 215.948768 -407.399998)
				)
			)
		)
		(polygon
			(pts
				(arc
					(start 212.348826 -405.999696)
					(mid 211.800059 -405.45131)
					(end 211.251546 -405.99995)
				)
				(arc
					(start 211.251546 -407.399998)
					(mid 211.800186 -407.948638)
					(end 212.348826 -407.399998)
				)
			)
		)
		(polygon
			(pts
				(arc
					(start 273.1135 -359.885996)
					(mid 273.4945 -359.504996)
					(end 273.1135 -359.123996)
				)
				(arc
					(start 271.970246 -359.123996)
					(mid 271.5895 -359.505123)
					(end 271.9705 -359.885996)
				)
			)
		)
		(polygon
			(pts
				(arc
					(start 273.1135 -358.085898)
					(mid 273.4945 -357.704898)
					(end 273.1135 -357.323898)
				)
				(arc
					(start 271.970246 -357.323898)
					(mid 271.5895 -357.705025)
					(end 271.9705 -358.085898)
				)
			)
		)
		(polygon
			(pts
				(arc
					(start 280.636726 -358.253792)
					(mid 281.185366 -357.705152)
					(end 280.636726 -357.156512)
				)
				(arc
					(start 279.236678 -357.156512)
					(mid 278.688038 -357.705152)
					(end 279.236678 -358.253792)
				)
			)
		)
		(polygon
			(pts
				(arc
					(start 287.83661 -358.256332)
					(mid 288.38779 -357.705152)
					(end 287.83661 -357.153972)
				)
				(arc
					(start 286.436562 -357.153972)
					(mid 285.885382 -357.705152)
					(end 286.436562 -358.256332)
				)
			)
		)
		(polygon
			(pts
				(arc
					(start 273.1135 -356.286054)
					(mid 273.4945 -355.905054)
					(end 273.1135 -355.524054)
				)
				(arc
					(start 271.970246 -355.524054)
					(mid 271.5895 -355.905181)
					(end 271.9705 -356.286054)
				)
			)
		)
		(polygon
			(pts
				(arc
					(start 279.636728 -356.453694)
					(mid 280.185368 -355.905054)
					(end 279.636728 -355.356414)
				)
				(arc
					(start 278.23668 -355.356414)
					(mid 277.68804 -355.905054)
					(end 278.23668 -356.453694)
				)
			)
		)
		(polygon
			(pts
				(arc
					(start 286.836612 -356.456234)
					(mid 287.387792 -355.905054)
					(end 286.836612 -355.353874)
				)
				(arc
					(start 285.436564 -355.353874)
					(mid 284.885384 -355.905054)
					(end 285.436564 -356.456234)
				)
			)
		)
		(polygon
			(pts
				(arc
					(start 273.1135 -354.485956)
					(mid 273.4945 -354.104956)
					(end 273.1135 -353.723956)
				)
				(arc
					(start 271.970246 -353.723956)
					(mid 271.5895 -354.105083)
					(end 271.9705 -354.485956)
				)
			)
		)
		(polygon
			(pts
				(arc
					(start 280.636726 -354.65385)
					(mid 281.185366 -354.10521)
					(end 280.636726 -353.55657)
				)
				(arc
					(start 279.236678 -353.55657)
					(mid 278.688038 -354.10521)
					(end 279.236678 -354.65385)
				)
			)
		)
		(polygon
			(pts
				(arc
					(start 287.83661 -354.65639)
					(mid 288.38779 -354.10521)
					(end 287.83661 -353.55403)
				)
				(arc
					(start 286.436562 -353.55403)
					(mid 285.885382 -354.10521)
					(end 286.436562 -354.65639)
				)
			)
		)
		(polygon
			(pts
				(arc
					(start 273.1135 -352.686112)
					(mid 273.4945 -352.305112)
					(end 273.1135 -351.924112)
				)
				(arc
					(start 271.970246 -351.924112)
					(mid 271.5895 -352.305239)
					(end 271.9705 -352.686112)
				)
			)
		)
		(polygon
			(pts
				(arc
					(start 279.636728 -352.853752)
					(mid 280.185368 -352.305112)
					(end 279.636728 -351.756472)
				)
				(arc
					(start 278.23668 -351.756472)
					(mid 277.68804 -352.305112)
					(end 278.23668 -352.853752)
				)
			)
		)
		(polygon
			(pts
				(arc
					(start 286.836612 -352.856292)
					(mid 287.387792 -352.305112)
					(end 286.836612 -351.753932)
				)
				(arc
					(start 285.436564 -351.753932)
					(mid 284.885384 -352.305112)
					(end 285.436564 -352.856292)
				)
			)
		)
		(polygon
			(pts
				(arc
					(start 273.1135 -350.886014)
					(mid 273.4945 -350.505014)
					(end 273.1135 -350.124014)
				)
				(arc
					(start 271.970246 -350.124014)
					(mid 271.5895 -350.505141)
					(end 271.9705 -350.886014)
				)
			)
		)
		(polygon
			(pts
				(arc
					(start 280.636726 -351.053908)
					(mid 281.185366 -350.505268)
					(end 280.636726 -349.956628)
				)
				(arc
					(start 279.236678 -349.956628)
					(mid 278.688038 -350.505268)
					(end 279.236678 -351.053908)
				)
			)
		)
		(polygon
			(pts
				(arc
					(start 287.83661 -351.056448)
					(mid 288.38779 -350.505268)
					(end 287.83661 -349.954088)
				)
				(arc
					(start 286.436562 -349.954088)
					(mid 285.885382 -350.505268)
					(end 286.436562 -351.056448)
				)
			)
		)
		(polygon
			(pts
				(arc
					(start 279.636728 -349.25381)
					(mid 280.185368 -348.70517)
					(end 279.636728 -348.15653)
				)
				(arc
					(start 278.23668 -348.15653)
					(mid 277.68804 -348.70517)
					(end 278.23668 -349.25381)
				)
			)
		)
		(polygon
			(pts
				(arc
					(start 286.836612 -349.25635)
					(mid 287.387792 -348.70517)
					(end 286.836612 -348.15399)
				)
				(arc
					(start 285.436564 -348.15399)
					(mid 284.885384 -348.70517)
					(end 285.436564 -349.25635)
				)
			)
		)
		(polygon
			(pts
				(arc
					(start 287.83661 -347.453712)
					(mid 288.38525 -346.905072)
					(end 287.83661 -346.356432)
				)
				(arc
					(start 286.436562 -346.356432)
					(mid 285.887922 -346.905072)
					(end 286.436562 -347.453712)
				)
			)
		)
		(polygon
			(pts
				(arc
					(start 280.636726 -347.453712)
					(mid 281.185366 -346.905072)
					(end 280.636726 -346.356432)
				)
				(arc
					(start 279.236678 -346.356432)
					(mid 278.688038 -346.905072)
					(end 279.236678 -347.453712)
				)
			)
		)
		(polygon
			(pts
				(arc
					(start 286.836612 -345.653868)
					(mid 287.385252 -345.105228)
					(end 286.836612 -344.556588)
				)
				(arc
					(start 285.436564 -344.556588)
					(mid 284.887924 -345.105228)
					(end 285.436564 -345.653868)
				)
			)
		)
		(polygon
			(pts
				(arc
					(start 279.636728 -345.653868)
					(mid 280.185368 -345.105228)
					(end 279.636728 -344.556588)
				)
				(arc
					(start 278.23668 -344.556588)
					(mid 277.68804 -345.105228)
					(end 278.23668 -345.653868)
				)
			)
		)
		(polygon
			(pts
				(arc
					(start 287.83661 -343.85377)
					(mid 288.38525 -343.30513)
					(end 287.83661 -342.75649)
				)
				(arc
					(start 286.436562 -342.75649)
					(mid 285.887922 -343.30513)
					(end 286.436562 -343.85377)
				)
			)
		)
		(polygon
			(pts
				(arc
					(start 280.636726 -343.85377)
					(mid 281.185366 -343.30513)
					(end 280.636726 -342.75649)
				)
				(arc
					(start 279.236678 -342.75649)
					(mid 278.688038 -343.30513)
					(end 279.236678 -343.85377)
				)
			)
		)
		(polygon
			(pts
				(arc
					(start 286.836612 -342.053672)
					(mid 287.385252 -341.505032)
					(end 286.836612 -340.956392)
				)
				(arc
					(start 285.436564 -340.956392)
					(mid 284.887924 -341.505032)
					(end 285.436564 -342.053672)
				)
			)
		)
		(polygon
			(pts
				(arc
					(start 279.636728 -342.053672)
					(mid 280.185368 -341.505032)
					(end 279.636728 -340.956392)
				)
				(arc
					(start 278.23668 -340.956392)
					(mid 277.68804 -341.505032)
					(end 278.23668 -342.053672)
				)
			)
		)
		(polygon
			(pts
				(arc
					(start 287.83661 -340.253828)
					(mid 288.38525 -339.705188)
					(end 287.83661 -339.156548)
				)
				(arc
					(start 286.436562 -339.156548)
					(mid 285.887922 -339.705188)
					(end 286.436562 -340.253828)
				)
			)
		)
		(polygon
			(pts
				(arc
					(start 280.636726 -340.253828)
					(mid 281.185366 -339.705188)
					(end 280.636726 -339.156548)
				)
				(arc
					(start 279.236678 -339.156548)
					(mid 278.688038 -339.705188)
					(end 279.236678 -340.253828)
				)
			)
		)
		(polygon
			(pts
				(arc
					(start 273.1135 -338.28863)
					(mid 273.49704 -337.90509)
					(end 273.1135 -337.52155)
				)
				(arc
					(start 271.970246 -337.52155)
					(mid 271.58696 -337.905217)
					(end 271.9705 -338.28863)
				)
			)
		)
		(polygon
			(pts
				(arc
					(start 286.836612 -338.45373)
					(mid 287.385252 -337.90509)
					(end 286.836612 -337.35645)
				)
				(arc
					(start 285.436564 -337.35645)
					(mid 284.887924 -337.90509)
					(end 285.436564 -338.45373)
				)
			)
		)
		(polygon
			(pts
				(arc
					(start 279.636728 -338.45373)
					(mid 280.185368 -337.90509)
					(end 279.636728 -337.35645)
				)
				(arc
					(start 278.23668 -337.35645)
					(mid 277.68804 -337.90509)
					(end 278.23668 -338.45373)
				)
			)
		)
		(polygon
			(pts
				(arc
					(start 273.1135 -336.488532)
					(mid 273.49704 -336.104992)
					(end 273.1135 -335.721452)
				)
				(arc
					(start 271.970246 -335.721452)
					(mid 271.58696 -336.105119)
					(end 271.9705 -336.488532)
				)
			)
		)
		(polygon
			(pts
				(arc
					(start 280.636726 -336.653886)
					(mid 281.185366 -336.105246)
					(end 280.636726 -335.556606)
				)
				(arc
					(start 279.236678 -335.556606)
					(mid 278.688038 -336.105246)
					(end 279.236678 -336.653886)
				)
			)
		)
		(polygon
			(pts
				(arc
					(start 287.83661 -336.656426)
					(mid 288.38779 -336.105246)
					(end 287.83661 -335.554066)
				)
				(arc
					(start 286.436562 -335.554066)
					(mid 285.885382 -336.105246)
					(end 286.436562 -336.656426)
				)
			)
		)
		(polygon
			(pts
				(arc
					(start 273.1135 -334.688434)
					(mid 273.49704 -334.304894)
					(end 273.1135 -333.921354)
				)
				(arc
					(start 271.970246 -333.921354)
					(mid 271.58696 -334.305021)
					(end 271.9705 -334.688434)
				)
			)
		)
		(polygon
			(pts
				(arc
					(start 279.636728 -334.853788)
					(mid 280.185368 -334.305148)
					(end 279.636728 -333.756508)
				)
				(arc
					(start 278.23668 -333.756508)
					(mid 277.68804 -334.305148)
					(end 278.23668 -334.853788)
				)
			)
		)
		(polygon
			(pts
				(arc
					(start 286.836612 -334.856328)
					(mid 287.387792 -334.305148)
					(end 286.836612 -333.753968)
				)
				(arc
					(start 285.436564 -333.753968)
					(mid 284.885384 -334.305148)
					(end 285.436564 -334.856328)
				)
			)
		)
		(polygon
			(pts
				(arc
					(start 273.1135 -332.88859)
					(mid 273.49704 -332.50505)
					(end 273.1135 -332.12151)
				)
				(arc
					(start 271.970246 -332.12151)
					(mid 271.58696 -332.505177)
					(end 271.9705 -332.88859)
				)
			)
		)
		(polygon
			(pts
				(arc
					(start 280.636726 -333.05369)
					(mid 281.185366 -332.50505)
					(end 280.636726 -331.95641)
				)
				(arc
					(start 279.236678 -331.95641)
					(mid 278.688038 -332.50505)
					(end 279.236678 -333.05369)
				)
			)
		)
		(polygon
			(pts
				(arc
					(start 287.83661 -333.05623)
					(mid 288.38779 -332.50505)
					(end 287.83661 -331.95387)
				)
				(arc
					(start 286.436562 -331.95387)
					(mid 285.885382 -332.50505)
					(end 286.436562 -333.05623)
				)
			)
		)
		(polygon
			(pts
				(arc
					(start 273.1135 -331.088492)
					(mid 273.49704 -330.704952)
					(end 273.1135 -330.321412)
				)
				(arc
					(start 271.970246 -330.321412)
					(mid 271.58696 -330.705079)
					(end 271.9705 -331.088492)
				)
			)
		)
		(polygon
			(pts
				(arc
					(start 279.636728 -331.253846)
					(mid 280.185368 -330.705206)
					(end 279.636728 -330.156566)
				)
				(arc
					(start 278.23668 -330.156566)
					(mid 277.68804 -330.705206)
					(end 278.23668 -331.253846)
				)
			)
		)
		(polygon
			(pts
				(arc
					(start 286.836612 -331.256386)
					(mid 287.387792 -330.705206)
					(end 286.836612 -330.154026)
				)
				(arc
					(start 285.436564 -330.154026)
					(mid 284.885384 -330.705206)
					(end 285.436564 -331.256386)
				)
			)
		)
		(polygon
			(pts
				(arc
					(start 273.1135 -329.288648)
					(mid 273.49704 -328.905108)
					(end 273.1135 -328.521568)
				)
				(arc
					(start 271.970246 -328.521568)
					(mid 271.58696 -328.905235)
					(end 271.9705 -329.288648)
				)
			)
		)
		(polygon
			(pts
				(arc
					(start 280.636726 -329.453748)
					(mid 281.185366 -328.905108)
					(end 280.636726 -328.356468)
				)
				(arc
					(start 279.236678 -328.356468)
					(mid 278.688038 -328.905108)
					(end 279.236678 -329.453748)
				)
			)
		)
		(polygon
			(pts
				(arc
					(start 287.83661 -329.456288)
					(mid 288.38779 -328.905108)
					(end 287.83661 -328.353928)
				)
				(arc
					(start 286.436562 -328.353928)
					(mid 285.885382 -328.905108)
					(end 286.436562 -329.456288)
				)
			)
		)
		(polygon
			(pts
				(arc
					(start 279.636728 -327.653904)
					(mid 280.185368 -327.105264)
					(end 279.636728 -326.556624)
				)
				(arc
					(start 278.23668 -326.556624)
					(mid 277.68804 -327.105264)
					(end 278.23668 -327.653904)
				)
			)
		)
		(polygon
			(pts
				(arc
					(start 286.836612 -327.656444)
					(mid 287.387792 -327.105264)
					(end 286.836612 -326.554084)
				)
				(arc
					(start 285.436564 -326.554084)
					(mid 284.885384 -327.105264)
					(end 285.436564 -327.656444)
				)
			)
		)
		(polygon
			(pts
				(arc
					(start 287.83661 -325.853806)
					(mid 288.38525 -325.305166)
					(end 287.83661 -324.756526)
				)
				(arc
					(start 286.436562 -324.756526)
					(mid 285.887922 -325.305166)
					(end 286.436562 -325.853806)
				)
			)
		)
		(polygon
			(pts
				(arc
					(start 280.636726 -325.853806)
					(mid 281.185366 -325.305166)
					(end 280.636726 -324.756526)
				)
				(arc
					(start 279.236678 -324.756526)
					(mid 278.688038 -325.305166)
					(end 279.236678 -325.853806)
				)
			)
		)
		(polygon
			(pts
				(arc
					(start 286.836612 -324.053708)
					(mid 287.385252 -323.505068)
					(end 286.836612 -322.956428)
				)
				(arc
					(start 285.436564 -322.956428)
					(mid 284.887924 -323.505068)
					(end 285.436564 -324.053708)
				)
			)
		)
		(polygon
			(pts
				(arc
					(start 279.636728 -324.053708)
					(mid 280.185368 -323.505068)
					(end 279.636728 -322.956428)
				)
				(arc
					(start 278.23668 -322.956428)
					(mid 277.68804 -323.505068)
					(end 278.23668 -324.053708)
				)
			)
		)
		(polygon
			(pts
				(arc
					(start 287.83661 -322.253864)
					(mid 288.38525 -321.705224)
					(end 287.83661 -321.156584)
				)
				(arc
					(start 286.436562 -321.156584)
					(mid 285.887922 -321.705224)
					(end 286.436562 -322.253864)
				)
			)
		)
		(polygon
			(pts
				(arc
					(start 280.636726 -322.253864)
					(mid 281.185366 -321.705224)
					(end 280.636726 -321.156584)
				)
				(arc
					(start 279.236678 -321.156584)
					(mid 278.688038 -321.705224)
					(end 279.236678 -322.253864)
				)
			)
		)
		(polygon
			(pts
				(arc
					(start 286.836612 -320.453766)
					(mid 287.385252 -319.905126)
					(end 286.836612 -319.356486)
				)
				(arc
					(start 285.436564 -319.356486)
					(mid 284.887924 -319.905126)
					(end 285.436564 -320.453766)
				)
			)
		)
		(polygon
			(pts
				(arc
					(start 279.636728 -320.453766)
					(mid 280.185368 -319.905126)
					(end 279.636728 -319.356486)
				)
				(arc
					(start 278.23668 -319.356486)
					(mid 277.68804 -319.905126)
					(end 278.23668 -320.453766)
				)
			)
		)
		(polygon
			(pts
				(arc
					(start 287.83661 -318.653668)
					(mid 288.38525 -318.105028)
					(end 287.83661 -317.556388)
				)
				(arc
					(start 286.436562 -317.556388)
					(mid 285.887922 -318.105028)
					(end 286.436562 -318.653668)
				)
			)
		)
		(polygon
			(pts
				(arc
					(start 280.636726 -318.653668)
					(mid 281.185366 -318.105028)
					(end 280.636726 -317.556388)
				)
				(arc
					(start 279.236678 -317.556388)
					(mid 278.688038 -318.105028)
					(end 279.236678 -318.653668)
				)
			)
		)
		(polygon
			(pts
				(arc
					(start 273.1135 -316.68847)
					(mid 273.49704 -316.30493)
					(end 273.1135 -315.92139)
				)
				(arc
					(start 271.970246 -315.92139)
					(mid 271.58696 -316.305057)
					(end 271.9705 -316.68847)
				)
			)
		)
		(polygon
			(pts
				(arc
					(start 286.836612 -316.853824)
					(mid 287.385252 -316.305184)
					(end 286.836612 -315.756544)
				)
				(arc
					(start 285.436564 -315.756544)
					(mid 284.887924 -316.305184)
					(end 285.436564 -316.853824)
				)
			)
		)
		(polygon
			(pts
				(arc
					(start 279.636728 -316.853824)
					(mid 280.185368 -316.305184)
					(end 279.636728 -315.756544)
				)
				(arc
					(start 278.23668 -315.756544)
					(mid 277.68804 -316.305184)
					(end 278.23668 -316.853824)
				)
			)
		)
		(polygon
			(pts
				(arc
					(start 273.1135 -314.888626)
					(mid 273.49704 -314.505086)
					(end 273.1135 -314.121546)
				)
				(arc
					(start 271.970246 -314.121546)
					(mid 271.58696 -314.505213)
					(end 271.9705 -314.888626)
				)
			)
		)
		(polygon
			(pts
				(arc
					(start 280.636726 -315.053726)
					(mid 281.185366 -314.505086)
					(end 280.636726 -313.956446)
				)
				(arc
					(start 279.236678 -313.956446)
					(mid 278.688038 -314.505086)
					(end 279.236678 -315.053726)
				)
			)
		)
		(polygon
			(pts
				(arc
					(start 287.83661 -315.056266)
					(mid 288.38779 -314.505086)
					(end 287.83661 -313.953906)
				)
				(arc
					(start 286.436562 -313.953906)
					(mid 285.885382 -314.505086)
					(end 286.436562 -315.056266)
				)
			)
		)
		(polygon
			(pts
				(arc
					(start 273.1135 -313.088528)
					(mid 273.49704 -312.704988)
					(end 273.1135 -312.321448)
				)
				(arc
					(start 271.970246 -312.321448)
					(mid 271.58696 -312.705115)
					(end 271.9705 -313.088528)
				)
			)
		)
		(polygon
			(pts
				(arc
					(start 279.636728 -313.253882)
					(mid 280.185368 -312.705242)
					(end 279.636728 -312.156602)
				)
				(arc
					(start 278.23668 -312.156602)
					(mid 277.68804 -312.705242)
					(end 278.23668 -313.253882)
				)
			)
		)
		(polygon
			(pts
				(arc
					(start 286.836612 -313.256422)
					(mid 287.387792 -312.705242)
					(end 286.836612 -312.154062)
				)
				(arc
					(start 285.436564 -312.154062)
					(mid 284.885384 -312.705242)
					(end 285.436564 -313.256422)
				)
			)
		)
		(polygon
			(pts
				(arc
					(start 273.1135 -311.28843)
					(mid 273.49704 -310.90489)
					(end 273.1135 -310.52135)
				)
				(arc
					(start 271.970246 -310.52135)
					(mid 271.58696 -310.905017)
					(end 271.9705 -311.28843)
				)
			)
		)
		(polygon
			(pts
				(arc
					(start 280.636726 -311.453784)
					(mid 281.185366 -310.905144)
					(end 280.636726 -310.356504)
				)
				(arc
					(start 279.236678 -310.356504)
					(mid 278.688038 -310.905144)
					(end 279.236678 -311.453784)
				)
			)
		)
		(polygon
			(pts
				(arc
					(start 287.83661 -311.456324)
					(mid 288.38779 -310.905144)
					(end 287.83661 -310.353964)
				)
				(arc
					(start 286.436562 -310.353964)
					(mid 285.885382 -310.905144)
					(end 286.436562 -311.456324)
				)
			)
		)
		(polygon
			(pts
				(arc
					(start 273.1135 -309.488586)
					(mid 273.49704 -309.105046)
					(end 273.1135 -308.721506)
				)
				(arc
					(start 271.970246 -308.721506)
					(mid 271.58696 -309.105173)
					(end 271.9705 -309.488586)
				)
			)
		)
		(polygon
			(pts
				(arc
					(start 279.636728 -309.653686)
					(mid 280.185368 -309.105046)
					(end 279.636728 -308.556406)
				)
				(arc
					(start 278.23668 -308.556406)
					(mid 277.68804 -309.105046)
					(end 278.23668 -309.653686)
				)
			)
		)
		(polygon
			(pts
				(arc
					(start 286.836612 -309.656226)
					(mid 287.387792 -309.105046)
					(end 286.836612 -308.553866)
				)
				(arc
					(start 285.436564 -308.553866)
					(mid 284.885384 -309.105046)
					(end 285.436564 -309.656226)
				)
			)
		)
		(polygon
			(pts
				(arc
					(start 273.1135 -307.688488)
					(mid 273.49704 -307.304948)
					(end 273.1135 -306.921408)
				)
				(arc
					(start 271.970246 -306.921408)
					(mid 271.58696 -307.305075)
					(end 271.9705 -307.688488)
				)
			)
		)
		(polygon
			(pts
				(arc
					(start 280.636726 -307.853842)
					(mid 281.185366 -307.305202)
					(end 280.636726 -306.756562)
				)
				(arc
					(start 279.236678 -306.756562)
					(mid 278.688038 -307.305202)
					(end 279.236678 -307.853842)
				)
			)
		)
		(polygon
			(pts
				(arc
					(start 287.83661 -307.856382)
					(mid 288.38779 -307.305202)
					(end 287.83661 -306.754022)
				)
				(arc
					(start 286.436562 -306.754022)
					(mid 285.885382 -307.305202)
					(end 286.436562 -307.856382)
				)
			)
		)
		(polygon
			(pts
				(arc
					(start 279.636728 -306.053744)
					(mid 280.185368 -305.505104)
					(end 279.636728 -304.956464)
				)
				(arc
					(start 278.23668 -304.956464)
					(mid 277.68804 -305.505104)
					(end 278.23668 -306.053744)
				)
			)
		)
		(polygon
			(pts
				(arc
					(start 286.836612 -306.056284)
					(mid 287.387792 -305.505104)
					(end 286.836612 -304.953924)
				)
				(arc
					(start 285.436564 -304.953924)
					(mid 284.885384 -305.505104)
					(end 285.436564 -306.056284)
				)
			)
		)
		(polygon
			(pts
				(arc
					(start 287.83661 -304.2539)
					(mid 288.38525 -303.70526)
					(end 287.83661 -303.15662)
				)
				(arc
					(start 286.436562 -303.15662)
					(mid 285.887922 -303.70526)
					(end 286.436562 -304.2539)
				)
			)
		)
		(polygon
			(pts
				(arc
					(start 280.636726 -304.2539)
					(mid 281.185366 -303.70526)
					(end 280.636726 -303.15662)
				)
				(arc
					(start 279.236678 -303.15662)
					(mid 278.688038 -303.70526)
					(end 279.236678 -304.2539)
				)
			)
		)
		(polygon
			(pts
				(arc
					(start 286.836612 -302.453802)
					(mid 287.385252 -301.905162)
					(end 286.836612 -301.356522)
				)
				(arc
					(start 285.436564 -301.356522)
					(mid 284.887924 -301.905162)
					(end 285.436564 -302.453802)
				)
			)
		)
		(polygon
			(pts
				(arc
					(start 279.636728 -302.453802)
					(mid 280.185368 -301.905162)
					(end 279.636728 -301.356522)
				)
				(arc
					(start 278.23668 -301.356522)
					(mid 277.68804 -301.905162)
					(end 278.23668 -302.453802)
				)
			)
		)
		(polygon
			(pts
				(arc
					(start 287.83661 -300.653704)
					(mid 288.38525 -300.105064)
					(end 287.83661 -299.556424)
				)
				(arc
					(start 286.436562 -299.556424)
					(mid 285.887922 -300.105064)
					(end 286.436562 -300.653704)
				)
			)
		)
		(polygon
			(pts
				(arc
					(start 280.636726 -300.653704)
					(mid 281.185366 -300.105064)
					(end 280.636726 -299.556424)
				)
				(arc
					(start 279.236678 -299.556424)
					(mid 278.688038 -300.105064)
					(end 279.236678 -300.653704)
				)
			)
		)
		(polygon
			(pts
				(arc
					(start 286.836612 -298.85386)
					(mid 287.385252 -298.30522)
					(end 286.836612 -297.75658)
				)
				(arc
					(start 285.436564 -297.75658)
					(mid 284.887924 -298.30522)
					(end 285.436564 -298.85386)
				)
			)
		)
		(polygon
			(pts
				(arc
					(start 279.636728 -298.85386)
					(mid 280.185368 -298.30522)
					(end 279.636728 -297.75658)
				)
				(arc
					(start 278.23668 -297.75658)
					(mid 277.68804 -298.30522)
					(end 278.23668 -298.85386)
				)
			)
		)
		(polygon
			(pts
				(arc
					(start 280.636726 -297.053762)
					(mid 281.185366 -296.505122)
					(end 280.636726 -295.956482)
				)
				(arc
					(start 279.236678 -295.956482)
					(mid 278.688038 -296.505122)
					(end 279.236678 -297.053762)
				)
			)
		)
		(polygon
			(pts
				(arc
					(start 287.83661 -297.056302)
					(mid 288.38779 -296.505122)
					(end 287.83661 -295.953942)
				)
				(arc
					(start 286.436562 -295.953942)
					(mid 285.885382 -296.505122)
					(end 286.436562 -297.056302)
				)
			)
		)
		(polygon
			(pts
				(arc
					(start 279.636728 -295.253918)
					(mid 280.185368 -294.705278)
					(end 279.636728 -294.156638)
				)
				(arc
					(start 278.23668 -294.156638)
					(mid 277.68804 -294.705278)
					(end 278.23668 -295.253918)
				)
			)
		)
		(polygon
			(pts
				(arc
					(start 286.836612 -295.256458)
					(mid 287.387792 -294.705278)
					(end 286.836612 -294.154098)
				)
				(arc
					(start 285.436564 -294.154098)
					(mid 284.885384 -294.705278)
					(end 285.436564 -295.256458)
				)
			)
		)
		(polygon
			(pts
				(arc
					(start 482.870002 -277.178262)
					(mid 482.488875 -276.797516)
					(end 482.108002 -277.178516)
				)
				(arc
					(start 482.108002 -278.321516)
					(mid 482.489002 -278.702516)
					(end 482.870002 -278.321516)
				)
			)
		)
		(polygon
			(pts
				(arc
					(start 451.3199 -277.178262)
					(mid 450.938773 -276.797516)
					(end 450.5579 -277.178516)
				)
				(arc
					(start 450.5579 -278.321516)
					(mid 450.9389 -278.702516)
					(end 451.3199 -278.321516)
				)
			)
		)
		(polygon
			(pts
				(arc
					(start 419.770052 -277.178262)
					(mid 419.388925 -276.797516)
					(end 419.008052 -277.178516)
				)
				(arc
					(start 419.008052 -278.321516)
					(mid 419.389052 -278.702516)
					(end 419.770052 -278.321516)
				)
			)
		)
		(polygon
			(pts
				(arc
					(start 388.21995 -277.178262)
					(mid 387.838823 -276.797516)
					(end 387.45795 -277.178516)
				)
				(arc
					(start 387.45795 -278.321516)
					(mid 387.83895 -278.702516)
					(end 388.21995 -278.321516)
				)
			)
		)
		(polygon
			(pts
				(arc
					(start 356.670102 -277.178262)
					(mid 356.288975 -276.797516)
					(end 355.908102 -277.178516)
				)
				(arc
					(start 355.908102 -278.321516)
					(mid 356.289102 -278.702516)
					(end 356.670102 -278.321516)
				)
			)
		)
		(polygon
			(pts
				(arc
					(start 325.12 -277.178262)
					(mid 324.738873 -276.797516)
					(end 324.358 -277.178516)
				)
				(arc
					(start 324.358 -278.321516)
					(mid 324.739 -278.702516)
					(end 325.12 -278.321516)
				)
			)
		)
		(polygon
			(pts
				(arc
					(start 190.639954 -277.178262)
					(mid 190.258827 -276.797516)
					(end 189.877954 -277.178516)
				)
				(arc
					(start 189.877954 -278.321516)
					(mid 190.258954 -278.702516)
					(end 190.639954 -278.321516)
				)
			)
		)
		(polygon
			(pts
				(arc
					(start 159.089852 -277.178262)
					(mid 158.708725 -276.797516)
					(end 158.327852 -277.178516)
				)
				(arc
					(start 158.327852 -278.321516)
					(mid 158.708852 -278.702516)
					(end 159.089852 -278.321516)
				)
			)
		)
		(polygon
			(pts
				(arc
					(start 127.53975 -277.178262)
					(mid 127.158623 -276.797516)
					(end 126.77775 -277.178516)
				)
				(arc
					(start 126.77775 -278.321516)
					(mid 127.15875 -278.702516)
					(end 127.53975 -278.321516)
				)
			)
		)
		(polygon
			(pts
				(arc
					(start 95.989902 -277.178262)
					(mid 95.608775 -276.797516)
					(end 95.227902 -277.178516)
				)
				(arc
					(start 95.227902 -278.321516)
					(mid 95.608902 -278.702516)
					(end 95.989902 -278.321516)
				)
			)
		)
		(polygon
			(pts
				(arc
					(start 64.4398 -277.178262)
					(mid 64.058673 -276.797516)
					(end 63.6778 -277.178516)
				)
				(arc
					(start 63.6778 -278.321516)
					(mid 64.0588 -278.702516)
					(end 64.4398 -278.321516)
				)
			)
		)
		(polygon
			(pts
				(arc
					(start 32.889952 -277.178262)
					(mid 32.508825 -276.797516)
					(end 32.127952 -277.178516)
				)
				(arc
					(start 32.127952 -278.321516)
					(mid 32.508952 -278.702516)
					(end 32.889952 -278.321516)
				)
			)
		)
		(polygon
			(pts
				(arc
					(start 478.120202 -273.368516)
					(mid 477.739202 -272.987516)
					(end 477.358202 -273.368516)
				)
				(arc
					(start 477.358202 -274.51177)
					(mid 477.739329 -274.892516)
					(end 478.120202 -274.511516)
				)
			)
		)
		(polygon
			(pts
				(arc
					(start 446.5701 -273.368516)
					(mid 446.1891 -272.987516)
					(end 445.8081 -273.368516)
				)
				(arc
					(start 445.8081 -274.51177)
					(mid 446.189227 -274.892516)
					(end 446.5701 -274.511516)
				)
			)
		)
		(polygon
			(pts
				(arc
					(start 415.020252 -273.368516)
					(mid 414.639252 -272.987516)
					(end 414.258252 -273.368516)
				)
				(arc
					(start 414.258252 -274.51177)
					(mid 414.639379 -274.892516)
					(end 415.020252 -274.511516)
				)
			)
		)
		(polygon
			(pts
				(arc
					(start 383.47015 -273.368516)
					(mid 383.08915 -272.987516)
					(end 382.70815 -273.368516)
				)
				(arc
					(start 382.70815 -274.51177)
					(mid 383.089277 -274.892516)
					(end 383.47015 -274.511516)
				)
			)
		)
		(polygon
			(pts
				(arc
					(start 351.920302 -273.368516)
					(mid 351.539302 -272.987516)
					(end 351.158302 -273.368516)
				)
				(arc
					(start 351.158302 -274.51177)
					(mid 351.539429 -274.892516)
					(end 351.920302 -274.511516)
				)
			)
		)
		(polygon
			(pts
				(arc
					(start 320.41084 -273.368262)
					(mid 319.989073 -272.946876)
					(end 319.56756 -273.368516)
				)
				(arc
					(start 319.56756 -274.511516)
					(mid 319.9892 -274.933156)
					(end 320.41084 -274.511516)
				)
			)
		)
		(polygon
			(pts
				(arc
					(start 284.236668 -264.250932)
					(mid 284.785308 -263.702292)
					(end 284.236668 -263.153652)
				)
				(arc
					(start 282.83662 -263.153652)
					(mid 282.28798 -263.702292)
					(end 282.83662 -264.250932)
				)
			)
		)
		(polygon
			(pts
				(arc
					(start 287.83661 -264.253472)
					(mid 288.38779 -263.702292)
					(end 287.83661 -263.151112)
				)
				(arc
					(start 286.436562 -263.151112)
					(mid 285.885382 -263.702292)
					(end 286.436562 -264.253472)
				)
			)
		)
		(polygon
			(pts
				(arc
					(start 280.636726 -264.253472)
					(mid 281.187906 -263.702292)
					(end 280.636726 -263.151112)
				)
				(arc
					(start 279.236678 -263.151112)
					(mid 278.685498 -263.702292)
					(end 279.236678 -264.253472)
				)
			)
		)
		(polygon
			(pts
				(arc
					(start 286.836612 -262.453374)
					(mid 287.387792 -261.902194)
					(end 286.836612 -261.351014)
				)
				(arc
					(start 285.436564 -261.351014)
					(mid 284.885384 -261.902194)
					(end 285.436564 -262.453374)
				)
			)
		)
		(polygon
			(pts
				(arc
					(start 279.636728 -262.453374)
					(mid 280.187908 -261.902194)
					(end 279.636728 -261.351014)
				)
				(arc
					(start 278.23668 -261.351014)
					(mid 277.6855 -261.902194)
					(end 278.23668 -262.453374)
				)
			)
		)
		(polygon
			(pts
				(arc
					(start 287.83661 -260.65353)
					(mid 288.38779 -260.10235)
					(end 287.83661 -259.55117)
				)
				(arc
					(start 286.436562 -259.55117)
					(mid 285.885382 -260.10235)
					(end 286.436562 -260.65353)
				)
			)
		)
		(polygon
			(pts
				(arc
					(start 280.636726 -260.65353)
					(mid 281.187906 -260.10235)
					(end 280.636726 -259.55117)
				)
				(arc
					(start 279.236678 -259.55117)
					(mid 278.685498 -260.10235)
					(end 279.236678 -260.65353)
				)
			)
		)
		(polygon
			(pts
				(arc
					(start 286.836612 -258.853432)
					(mid 287.387792 -258.302252)
					(end 286.836612 -257.751072)
				)
				(arc
					(start 285.436564 -257.751072)
					(mid 284.885384 -258.302252)
					(end 285.436564 -258.853432)
				)
			)
		)
		(polygon
			(pts
				(arc
					(start 279.636728 -258.853432)
					(mid 280.187908 -258.302252)
					(end 279.636728 -257.751072)
				)
				(arc
					(start 278.23668 -257.751072)
					(mid 277.6855 -258.302252)
					(end 278.23668 -258.853432)
				)
			)
		)
		(polygon
			(pts
				(arc
					(start 287.83661 -257.053588)
					(mid 288.38779 -256.502408)
					(end 287.83661 -255.951228)
				)
				(arc
					(start 286.436562 -255.951228)
					(mid 285.885382 -256.502408)
					(end 286.436562 -257.053588)
				)
			)
		)
		(polygon
			(pts
				(arc
					(start 280.636726 -257.053588)
					(mid 281.187906 -256.502408)
					(end 280.636726 -255.951228)
				)
				(arc
					(start 279.236678 -255.951228)
					(mid 278.685498 -256.502408)
					(end 279.236678 -257.053588)
				)
			)
		)
		(polygon
			(pts
				(arc
					(start 286.836612 -255.25349)
					(mid 287.387792 -254.70231)
					(end 286.836612 -254.15113)
				)
				(arc
					(start 285.436564 -254.15113)
					(mid 284.885384 -254.70231)
					(end 285.436564 -255.25349)
				)
			)
		)
		(polygon
			(pts
				(arc
					(start 279.636728 -255.25349)
					(mid 280.187908 -254.70231)
					(end 279.636728 -254.15113)
				)
				(arc
					(start 278.23668 -254.15113)
					(mid 277.6855 -254.70231)
					(end 278.23668 -255.25349)
				)
			)
		)
		(polygon
			(pts
				(arc
					(start 287.83661 -253.453392)
					(mid 288.38779 -252.902212)
					(end 287.83661 -252.351032)
				)
				(arc
					(start 286.436562 -252.351032)
					(mid 285.885382 -252.902212)
					(end 286.436562 -253.453392)
				)
			)
		)
		(polygon
			(pts
				(arc
					(start 280.636726 -253.453392)
					(mid 281.187906 -252.902212)
					(end 280.636726 -252.351032)
				)
				(arc
					(start 279.236678 -252.351032)
					(mid 278.685498 -252.902212)
					(end 279.236678 -253.453392)
				)
			)
		)
		(polygon
			(pts
				(arc
					(start 286.836612 -251.653548)
					(mid 287.387792 -251.102368)
					(end 286.836612 -250.551188)
				)
				(arc
					(start 285.436564 -250.551188)
					(mid 284.885384 -251.102368)
					(end 285.436564 -251.653548)
				)
			)
		)
		(polygon
			(pts
				(arc
					(start 279.636728 -251.653548)
					(mid 280.187908 -251.102368)
					(end 279.636728 -250.551188)
				)
				(arc
					(start 278.23668 -250.551188)
					(mid 277.6855 -251.102368)
					(end 278.23668 -251.653548)
				)
			)
		)
		(polygon
			(pts
				(arc
					(start 240.871756 -178.87696)
					(mid 239.92498 -179.182145)
					(end 240.236502 -180.126894)
				)
				(arc
					(start 242.236498 -181.126892)
					(mid 243.17706 -180.813202)
					(end 242.86337 -179.87264)
				)
			)
		)
		(polygon
			(pts
				(arc
					(start 283.563314 -178.872642)
					(mid 282.622752 -179.186332)
					(end 282.936442 -180.126894)
				)
				(arc
					(start 284.928056 -181.122574)
					(mid 285.874832 -180.817389)
					(end 285.56331 -179.87264)
				)
			)
		)
		(polygon
			(pts
				(arc
					(start 281.074876 -178.149504)
					(mid 281.399742 -177.174906)
					(end 280.425144 -176.85004)
				)
				(xy 280.423874 -176.847754) (xy 278.424132 -177.847752) (xy 278.424132 -177.848006)
				(arc
					(start 278.425148 -177.850038)
					(mid 278.100282 -178.824636)
					(end 279.07488 -179.149502)
				)
				(xy 279.07615 -179.151788) (xy 281.076146 -178.15179)
			)
		)
		(polygon
			(pts
				(arc
					(start 238.374936 -178.149504)
					(mid 238.699802 -177.174906)
					(end 237.725204 -176.85004)
				)
				(xy 237.723934 -176.847754) (xy 235.724192 -177.847752) (xy 235.724192 -177.848006)
				(arc
					(start 235.725208 -177.850038)
					(mid 235.400342 -178.824636)
					(end 236.37494 -179.149502)
				)
				(xy 236.37621 -179.151788) (xy 238.376206 -178.15179)
			)
		)
		(polygon
			(pts
				(arc
					(start 240.871756 -174.876968)
					(mid 239.92498 -175.182153)
					(end 240.236502 -176.126902)
				)
				(arc
					(start 242.236498 -177.1269)
					(mid 243.17706 -176.81321)
					(end 242.86337 -175.872648)
				)
			)
		)
		(polygon
			(pts
				(arc
					(start 283.563314 -174.87265)
					(mid 282.622752 -175.18634)
					(end 282.936442 -176.126902)
				)
				(arc
					(start 284.928056 -177.122582)
					(mid 285.874832 -176.817397)
					(end 285.56331 -175.872648)
				)
			)
		)
		(polygon
			(pts
				(arc
					(start 281.074876 -174.149512)
					(mid 281.399742 -173.174914)
					(end 280.425144 -172.850048)
				)
				(xy 280.423874 -172.847762) (xy 278.424132 -173.84776) (xy 278.424132 -173.848014)
				(arc
					(start 278.425148 -173.850046)
					(mid 278.100282 -174.824644)
					(end 279.07488 -175.14951)
				)
				(xy 279.07615 -175.151796) (xy 281.076146 -174.151798)
			)
		)
		(polygon
			(pts
				(arc
					(start 238.374936 -174.149512)
					(mid 238.699802 -173.174914)
					(end 237.725204 -172.850048)
				)
				(xy 237.723934 -172.847762) (xy 235.724192 -173.84776) (xy 235.724192 -173.848014)
				(arc
					(start 235.725208 -173.850046)
					(mid 235.400342 -174.824644)
					(end 236.37494 -175.14951)
				)
				(xy 236.37621 -175.151796) (xy 238.376206 -174.151798)
			)
		)
		(polygon
			(pts
				(arc
					(start 240.871756 -170.876976)
					(mid 239.92498 -171.182161)
					(end 240.236502 -172.12691)
				)
				(arc
					(start 242.236498 -173.126908)
					(mid 243.17706 -172.813218)
					(end 242.86337 -171.872656)
				)
			)
		)
		(polygon
			(pts
				(arc
					(start 283.563314 -170.872658)
					(mid 282.622752 -171.186348)
					(end 282.936442 -172.12691)
				)
				(arc
					(start 284.928056 -173.12259)
					(mid 285.874832 -172.817405)
					(end 285.56331 -171.872656)
				)
			)
		)
		(polygon
			(pts
				(arc
					(start 281.074876 -170.14952)
					(mid 281.399742 -169.174922)
					(end 280.425144 -168.850056)
				)
				(xy 280.423874 -168.84777) (xy 278.424132 -169.847768) (xy 278.424132 -169.848022)
				(arc
					(start 278.425148 -169.850054)
					(mid 278.100282 -170.824652)
					(end 279.07488 -171.149518)
				)
				(xy 279.07615 -171.151804) (xy 281.076146 -170.151806)
			)
		)
		(polygon
			(pts
				(arc
					(start 238.374936 -170.14952)
					(mid 238.699802 -169.174922)
					(end 237.725204 -168.850056)
				)
				(xy 237.723934 -168.84777) (xy 235.724192 -169.847768) (xy 235.724192 -169.848022)
				(arc
					(start 235.725208 -169.850054)
					(mid 235.400342 -170.824652)
					(end 236.37494 -171.149518)
				)
				(xy 236.37621 -171.151804) (xy 238.376206 -170.151806)
			)
		)
		(polygon
			(pts
				(arc
					(start 240.871756 -166.876984)
					(mid 239.92498 -167.182169)
					(end 240.236502 -168.126918)
				)
				(arc
					(start 242.236498 -169.126916)
					(mid 243.17706 -168.813226)
					(end 242.86337 -167.872664)
				)
			)
		)
		(polygon
			(pts
				(arc
					(start 283.563314 -166.872666)
					(mid 282.622752 -167.186356)
					(end 282.936442 -168.126918)
				)
				(arc
					(start 284.928056 -169.122598)
					(mid 285.874832 -168.817413)
					(end 285.56331 -167.872664)
				)
			)
		)
		(polygon
			(pts
				(arc
					(start 281.074876 -166.149528)
					(mid 281.399742 -165.17493)
					(end 280.425144 -164.850064)
				)
				(xy 280.423874 -164.847778) (xy 278.424132 -165.847776) (xy 278.424132 -165.84803)
				(arc
					(start 278.425148 -165.850062)
					(mid 278.100282 -166.82466)
					(end 279.07488 -167.149526)
				)
				(xy 279.07615 -167.151812) (xy 281.076146 -166.151814)
			)
		)
		(polygon
			(pts
				(arc
					(start 238.374936 -166.149528)
					(mid 238.699802 -165.17493)
					(end 237.725204 -164.850064)
				)
				(xy 237.723934 -164.847778) (xy 235.724192 -165.847776) (xy 235.724192 -165.84803)
				(arc
					(start 235.725208 -165.850062)
					(mid 235.400342 -166.82466)
					(end 236.37494 -167.149526)
				)
				(xy 236.37621 -167.151812) (xy 238.376206 -166.151814)
			)
		)
		(polygon
			(pts
				(arc
					(start 283.563314 -162.872674)
					(mid 282.622752 -163.186364)
					(end 282.936442 -164.126926)
				)
				(arc
					(start 284.928056 -165.122606)
					(mid 285.874832 -164.817421)
					(end 285.56331 -163.872672)
				)
			)
		)
		(polygon
			(pts
				(arc
					(start 240.877344 -162.845496)
					(mid 239.895939 -163.172546)
					(end 240.222786 -164.154104)
				)
				(arc
					(start 242.222782 -165.154102)
					(mid 243.204238 -164.82695)
					(end 242.877086 -163.845494)
				)
			)
		)
		(polygon
			(pts
				(arc
					(start 482.870002 -162.178238)
					(mid 482.488875 -161.797492)
					(end 482.108002 -162.178492)
				)
				(arc
					(start 482.108002 -163.321492)
					(mid 482.489002 -163.702492)
					(end 482.870002 -163.321492)
				)
			)
		)
		(polygon
			(pts
				(arc
					(start 438.6199 -162.178238)
					(mid 438.238773 -161.797492)
					(end 437.8579 -162.178492)
				)
				(arc
					(start 437.8579 -163.321492)
					(mid 438.2389 -163.702492)
					(end 438.6199 -163.321492)
				)
			)
		)
		(polygon
			(pts
				(arc
					(start 419.770052 -162.178238)
					(mid 419.388925 -161.797492)
					(end 419.008052 -162.178492)
				)
				(arc
					(start 419.008052 -163.321492)
					(mid 419.389052 -163.702492)
					(end 419.770052 -163.321492)
				)
			)
		)
		(polygon
			(pts
				(arc
					(start 388.21995 -162.178238)
					(mid 387.838823 -161.797492)
					(end 387.45795 -162.178492)
				)
				(arc
					(start 387.45795 -163.321492)
					(mid 387.83895 -163.702492)
					(end 388.21995 -163.321492)
				)
			)
		)
		(polygon
			(pts
				(arc
					(start 356.670102 -162.178238)
					(mid 356.288975 -161.797492)
					(end 355.908102 -162.178492)
				)
				(arc
					(start 355.908102 -163.321492)
					(mid 356.289102 -163.702492)
					(end 356.670102 -163.321492)
				)
			)
		)
		(polygon
			(pts
				(arc
					(start 325.12 -162.178238)
					(mid 324.738873 -161.797492)
					(end 324.358 -162.178492)
				)
				(arc
					(start 324.358 -163.321492)
					(mid 324.739 -163.702492)
					(end 325.12 -163.321492)
				)
			)
		)
		(polygon
			(pts
				(arc
					(start 190.639954 -162.178238)
					(mid 190.258827 -161.797492)
					(end 189.877954 -162.178492)
				)
				(arc
					(start 189.877954 -163.321492)
					(mid 190.258954 -163.702492)
					(end 190.639954 -163.321492)
				)
			)
		)
		(polygon
			(pts
				(arc
					(start 159.089852 -162.178238)
					(mid 158.708725 -161.797492)
					(end 158.327852 -162.178492)
				)
				(arc
					(start 158.327852 -163.321492)
					(mid 158.708852 -163.702492)
					(end 159.089852 -163.321492)
				)
			)
		)
		(polygon
			(pts
				(arc
					(start 127.53975 -162.178238)
					(mid 127.158623 -161.797492)
					(end 126.77775 -162.178492)
				)
				(arc
					(start 126.77775 -163.321492)
					(mid 127.15875 -163.702492)
					(end 127.53975 -163.321492)
				)
			)
		)
		(polygon
			(pts
				(arc
					(start 95.989902 -162.178238)
					(mid 95.608775 -161.797492)
					(end 95.227902 -162.178492)
				)
				(arc
					(start 95.227902 -163.321492)
					(mid 95.608902 -163.702492)
					(end 95.989902 -163.321492)
				)
			)
		)
		(polygon
			(pts
				(arc
					(start 64.4398 -162.178238)
					(mid 64.058673 -161.797492)
					(end 63.6778 -162.178492)
				)
				(arc
					(start 63.6778 -163.321492)
					(mid 64.0588 -163.702492)
					(end 64.4398 -163.321492)
				)
			)
		)
		(polygon
			(pts
				(arc
					(start 32.889952 -162.178238)
					(mid 32.508825 -161.797492)
					(end 32.127952 -162.178492)
				)
				(arc
					(start 32.127952 -163.321492)
					(mid 32.508952 -163.702492)
					(end 32.889952 -163.321492)
				)
			)
		)
		(polygon
			(pts
				(arc
					(start 281.07386 -162.14725)
					(mid 281.397456 -161.175954)
					(end 280.42616 -160.852358)
				)
				(xy 278.426418 -161.852102)
				(arc
					(start 278.426418 -161.852356)
					(mid 278.102619 -162.8235)
					(end 279.073864 -163.147248)
				)
			)
		)
		(polygon
			(pts
				(arc
					(start 238.377222 -162.154108)
					(mid 238.704374 -161.172652)
					(end 237.722918 -160.8455)
				)
				(arc
					(start 235.733844 -161.840164)
					(mid 235.393447 -162.821194)
					(end 236.377226 -163.154106)
				)
			)
		)
		(polygon
			(pts
				(arc
					(start 283.571696 -158.877)
					(mid 282.62492 -159.182185)
					(end 282.936442 -160.126934)
				)
				(arc
					(start 284.936438 -161.126932)
					(mid 285.877 -160.813242)
					(end 285.56331 -159.87268)
				)
			)
		)
		(polygon
			(pts
				(arc
					(start 240.87709 -158.845504)
					(mid 239.895634 -159.172656)
					(end 240.222786 -160.154112)
				)
				(arc
					(start 242.222528 -161.15411)
					(mid 243.204289 -160.82711)
					(end 242.877086 -159.845502)
				)
			)
		)
		(polygon
			(pts
				(arc
					(start 478.120202 -158.368492)
					(mid 477.739202 -157.987492)
					(end 477.358202 -158.368492)
				)
				(arc
					(start 477.358202 -159.511746)
					(mid 477.739329 -159.892492)
					(end 478.120202 -159.511492)
				)
			)
		)
		(polygon
			(pts
				(arc
					(start 440.2201 -158.368492)
					(mid 439.8391 -157.987492)
					(end 439.4581 -158.368492)
				)
				(arc
					(start 439.4581 -159.511746)
					(mid 439.839227 -159.892492)
					(end 440.2201 -159.511492)
				)
			)
		)
		(polygon
			(pts
				(arc
					(start 415.020252 -158.368492)
					(mid 414.639252 -157.987492)
					(end 414.258252 -158.368492)
				)
				(arc
					(start 414.258252 -159.511746)
					(mid 414.639379 -159.892492)
					(end 415.020252 -159.511492)
				)
			)
		)
		(polygon
			(pts
				(arc
					(start 383.47015 -158.368492)
					(mid 383.08915 -157.987492)
					(end 382.70815 -158.368492)
				)
				(arc
					(start 382.70815 -159.511746)
					(mid 383.089277 -159.892492)
					(end 383.47015 -159.511492)
				)
			)
		)
		(polygon
			(pts
				(arc
					(start 351.920302 -158.368492)
					(mid 351.539302 -157.987492)
					(end 351.158302 -158.368492)
				)
				(arc
					(start 351.158302 -159.511746)
					(mid 351.539429 -159.892492)
					(end 351.920302 -159.511492)
				)
			)
		)
		(polygon
			(pts
				(arc
					(start 320.3702 -158.368492)
					(mid 319.9892 -157.987492)
					(end 319.6082 -158.368492)
				)
				(arc
					(start 319.6082 -159.511746)
					(mid 319.989327 -159.892492)
					(end 320.3702 -159.511492)
				)
			)
		)
		(polygon
			(pts
				(arc
					(start 281.07386 -158.147258)
					(mid 281.397456 -157.175962)
					(end 280.42616 -156.852366)
				)
				(xy 278.426418 -157.85211)
				(arc
					(start 278.426418 -157.852364)
					(mid 278.102619 -158.823508)
					(end 279.073864 -159.147256)
				)
			)
		)
		(polygon
			(pts
				(arc
					(start 238.377222 -158.154116)
					(mid 238.704374 -157.17266)
					(end 237.722918 -156.845508)
				)
				(arc
					(start 235.733844 -157.840172)
					(mid 235.393447 -158.821202)
					(end 236.377226 -159.154114)
				)
			)
		)
		(polygon
			(pts
				(arc
					(start 283.563314 -154.87269)
					(mid 282.622752 -155.18638)
					(end 282.936442 -156.126942)
				)
				(arc
					(start 284.928056 -157.122622)
					(mid 285.874832 -156.817437)
					(end 285.56331 -155.872688)
				)
			)
		)
		(polygon
			(pts
				(arc
					(start 240.87709 -154.845512)
					(mid 239.895634 -155.172664)
					(end 240.222786 -156.15412)
				)
				(arc
					(start 242.222528 -157.154118)
					(mid 243.204289 -156.827118)
					(end 242.877086 -155.84551)
				)
			)
		)
		(polygon
			(pts
				(arc
					(start 281.07386 -154.147266)
					(mid 281.397456 -153.17597)
					(end 280.42616 -152.852374)
				)
				(xy 278.426418 -153.852118)
				(arc
					(start 278.426418 -153.852372)
					(mid 278.102619 -154.823516)
					(end 279.073864 -155.147264)
				)
			)
		)
		(polygon
			(pts
				(arc
					(start 238.377222 -154.154124)
					(mid 238.704374 -153.172668)
					(end 237.722918 -152.845516)
				)
				(arc
					(start 235.733844 -153.84018)
					(mid 235.393447 -154.82121)
					(end 236.377226 -155.154122)
				)
			)
		)
		(polygon
			(pts
				(arc
					(start 283.563314 -150.872698)
					(mid 282.622752 -151.186388)
					(end 282.936442 -152.12695)
				)
				(arc
					(start 284.928056 -153.12263)
					(mid 285.874832 -152.817445)
					(end 285.56331 -151.872696)
				)
			)
		)
		(polygon
			(pts
				(arc
					(start 240.877344 -150.84552)
					(mid 239.895939 -151.17257)
					(end 240.222786 -152.154128)
				)
				(arc
					(start 242.222782 -153.154126)
					(mid 243.204238 -152.826974)
					(end 242.877086 -151.845518)
				)
			)
		)
		(polygon
			(pts
				(arc
					(start 281.07386 -150.147274)
					(mid 281.397456 -149.175978)
					(end 280.42616 -148.852382)
				)
				(xy 278.426418 -149.852126)
				(arc
					(start 278.426418 -149.85238)
					(mid 278.102619 -150.823524)
					(end 279.073864 -151.147272)
				)
			)
		)
		(polygon
			(pts
				(arc
					(start 238.377222 -150.154132)
					(mid 238.704374 -149.172676)
					(end 237.722918 -148.845524)
				)
				(arc
					(start 235.733844 -149.840188)
					(mid 235.393447 -150.821218)
					(end 236.377226 -151.15413)
				)
			)
		)
		(polygon
			(pts
				(arc
					(start 281.074876 -138.149584)
					(mid 281.399742 -137.174986)
					(end 280.425144 -136.85012)
				)
				(xy 280.423874 -136.847834) (xy 278.424132 -137.847832) (xy 278.424132 -137.848086)
				(arc
					(start 278.425148 -137.850118)
					(mid 278.100282 -138.824716)
					(end 279.07488 -139.149582)
				)
				(xy 279.07615 -139.151868) (xy 281.076146 -138.15187)
			)
		)
		(polygon
			(pts
				(arc
					(start 238.374936 -138.149584)
					(mid 238.699802 -137.174986)
					(end 237.725204 -136.85012)
				)
				(xy 237.723934 -136.847834) (xy 235.724192 -137.847832) (xy 235.724192 -137.848086)
				(arc
					(start 235.725208 -137.850118)
					(mid 235.400342 -138.824716)
					(end 236.37494 -139.149582)
				)
				(xy 236.37621 -139.151868) (xy 238.376206 -138.15187)
			)
		)
		(polygon
			(pts
				(arc
					(start 283.574744 -134.850124)
					(mid 282.600146 -135.17499)
					(end 282.925012 -136.149588)
				)
				(xy 282.923742 -136.151874) (xy 284.923738 -137.151872) (xy 284.923992 -137.151618)
				(arc
					(start 284.925008 -137.149586)
					(mid 285.899606 -136.82472)
					(end 285.57474 -135.850122)
				)
				(xy 285.57601 -135.847836) (xy 283.576014 -134.847838)
			)
		)
		(polygon
			(pts
				(arc
					(start 240.874804 -134.850124)
					(mid 239.900206 -135.17499)
					(end 240.225072 -136.149588)
				)
				(xy 240.223802 -136.151874) (xy 242.223798 -137.151872) (xy 242.224052 -137.151618)
				(arc
					(start 242.225068 -137.149586)
					(mid 243.199666 -136.82472)
					(end 242.8748 -135.850122)
				)
				(xy 242.87607 -135.847836) (xy 240.876074 -134.847838)
			)
		)
		(polygon
			(pts
				(arc
					(start 281.07386 -130.147314)
					(mid 281.397456 -129.176018)
					(end 280.42616 -128.852422)
				)
				(xy 278.426418 -129.852166)
				(arc
					(start 278.426418 -129.85242)
					(mid 278.102619 -130.823564)
					(end 279.073864 -131.147312)
				)
			)
		)
		(polygon
			(pts
				(arc
					(start 238.377222 -130.154172)
					(mid 238.704374 -129.172716)
					(end 237.722918 -128.845564)
				)
				(arc
					(start 235.733844 -129.840228)
					(mid 235.393447 -130.821258)
					(end 236.377226 -131.15417)
				)
			)
		)
		(polygon
			(pts
				(arc
					(start 283.563314 -126.872746)
					(mid 282.622752 -127.186436)
					(end 282.936442 -128.126998)
				)
				(arc
					(start 284.928056 -129.122678)
					(mid 285.874832 -128.817493)
					(end 285.56331 -127.872744)
				)
			)
		)
		(polygon
			(pts
				(arc
					(start 240.891822 -126.844552)
					(mid 239.891674 -127.163691)
					(end 240.219484 -128.161034)
				)
				(arc
					(start 242.21948 -129.161032)
					(mid 243.211096 -128.830324)
					(end 242.880388 -127.838708)
				)
			)
		)
		(polygon
			(pts
				(arc
					(start 281.07386 -126.147322)
					(mid 281.397456 -125.176026)
					(end 280.42616 -124.85243)
				)
				(xy 278.426418 -125.852174)
				(arc
					(start 278.426418 -125.852428)
					(mid 278.102619 -126.823572)
					(end 279.073864 -127.14732)
				)
			)
		)
		(polygon
			(pts
				(arc
					(start 238.377222 -126.15418)
					(mid 238.704374 -125.172724)
					(end 237.722918 -124.845572)
				)
				(arc
					(start 235.733844 -125.840236)
					(mid 235.393447 -126.821266)
					(end 236.377226 -127.154178)
				)
			)
		)
		(polygon
			(pts
				(arc
					(start 283.563314 -122.872754)
					(mid 282.622752 -123.186444)
					(end 282.936442 -124.127006)
				)
				(arc
					(start 284.928056 -125.122686)
					(mid 285.874832 -124.817501)
					(end 285.56331 -123.872752)
				)
			)
		)
		(polygon
			(pts
				(arc
					(start 240.880392 -122.838718)
					(mid 239.888776 -123.169426)
					(end 240.219484 -124.161042)
				)
				(arc
					(start 242.20805 -125.155198)
					(mid 243.208198 -124.836059)
					(end 242.880388 -123.838716)
				)
			)
		)
		(polygon
			(pts
				(arc
					(start 281.07386 -122.14733)
					(mid 281.397456 -121.176034)
					(end 280.42616 -120.852438)
				)
				(xy 278.426418 -121.852182)
				(arc
					(start 278.426418 -121.852436)
					(mid 278.102619 -122.82358)
					(end 279.073864 -123.147328)
				)
			)
		)
		(polygon
			(pts
				(arc
					(start 238.3663 -122.159522)
					(mid 238.706697 -121.178492)
					(end 237.722918 -120.84558)
				)
				(arc
					(start 235.722922 -121.845578)
					(mid 235.39577 -122.827034)
					(end 236.377226 -123.154186)
				)
			)
		)
		(polygon
			(pts
				(arc
					(start 283.563314 -118.872762)
					(mid 282.622752 -119.186452)
					(end 282.936442 -120.127014)
				)
				(arc
					(start 284.928056 -121.122694)
					(mid 285.874832 -120.817509)
					(end 285.56331 -119.87276)
				)
			)
		)
		(polygon
			(pts
				(arc
					(start 240.87709 -118.845584)
					(mid 239.895634 -119.172736)
					(end 240.222786 -120.154192)
				)
				(arc
					(start 242.222528 -121.15419)
					(mid 243.204289 -120.82719)
					(end 242.877086 -119.845582)
				)
			)
		)
		(polygon
			(pts
				(arc
					(start 281.07386 -118.147338)
					(mid 281.397456 -117.176042)
					(end 280.42616 -116.852446)
				)
				(xy 278.426418 -117.85219)
				(arc
					(start 278.426418 -117.852444)
					(mid 278.102619 -118.823588)
					(end 279.073864 -119.147336)
				)
			)
		)
		(polygon
			(pts
				(arc
					(start 238.377222 -118.154196)
					(mid 238.704374 -117.17274)
					(end 237.722918 -116.845588)
				)
				(arc
					(start 235.733844 -117.840252)
					(mid 235.393447 -118.821282)
					(end 236.377226 -119.154194)
				)
			)
		)
		(polygon
			(pts
				(arc
					(start 283.563314 -114.87277)
					(mid 282.622752 -115.18646)
					(end 282.936442 -116.127022)
				)
				(arc
					(start 284.928056 -117.122702)
					(mid 285.874832 -116.817517)
					(end 285.56331 -115.872768)
				)
			)
		)
		(polygon
			(pts
				(arc
					(start 240.877344 -114.845592)
					(mid 239.895939 -115.172642)
					(end 240.222786 -116.1542)
				)
				(arc
					(start 242.222782 -117.154198)
					(mid 243.204238 -116.827046)
					(end 242.877086 -115.84559)
				)
			)
		)
		(polygon
			(pts
				(arc
					(start 281.063446 -114.127026)
					(mid 281.377136 -113.186464)
					(end 280.436574 -112.872774)
				)
				(arc
					(start 278.44496 -113.868708)
					(mid 278.120865 -114.809139)
					(end 279.06345 -115.127024)
				)
			)
		)
		(polygon
			(pts
				(arc
					(start 238.377222 -114.154204)
					(mid 238.704374 -113.172748)
					(end 237.722918 -112.845596)
				)
				(arc
					(start 235.733844 -113.84026)
					(mid 235.393447 -114.82129)
					(end 236.377226 -115.154202)
				)
			)
		)
		(polygon
			(pts
				(arc
					(start 240.874804 -106.85018)
					(mid 239.900206 -107.175046)
					(end 240.225072 -108.149644)
				)
				(xy 240.223802 -108.15193) (xy 242.223798 -109.151928) (xy 242.224052 -109.151674)
				(arc
					(start 242.225068 -109.149642)
					(mid 243.199666 -108.824776)
					(end 242.8748 -107.850178)
				)
				(xy 242.87607 -107.847892) (xy 240.876074 -106.847894)
			)
		)
		(polygon
			(pts
				(arc
					(start 283.576014 -106.847894)
					(mid 282.59786 -107.173776)
					(end 282.923742 -108.15193)
				)
				(arc
					(start 284.923738 -109.151928)
					(mid 285.901892 -108.826046)
					(end 285.57601 -107.847892)
				)
			)
		)
		(polygon
			(pts
				(arc
					(start 240.871756 -82.577178)
					(mid 239.92498 -82.882363)
					(end 240.236502 -83.827112)
				)
				(arc
					(start 242.236498 -84.82711)
					(mid 243.17706 -84.51342)
					(end 242.86337 -83.572858)
				)
			)
		)
		(polygon
			(pts
				(arc
					(start 283.563314 -82.57286)
					(mid 282.622752 -82.88655)
					(end 282.936442 -83.827112)
				)
				(arc
					(start 284.928056 -84.822792)
					(mid 285.874832 -84.517607)
					(end 285.56331 -83.572858)
				)
			)
		)
		(polygon
			(pts
				(arc
					(start 281.074876 -81.849722)
					(mid 281.399742 -80.875124)
					(end 280.425144 -80.550258)
				)
				(xy 280.423874 -80.547972) (xy 278.424132 -81.54797) (xy 278.424132 -81.548224)
				(arc
					(start 278.425148 -81.550256)
					(mid 278.100282 -82.524854)
					(end 279.07488 -82.84972)
				)
				(xy 279.07615 -82.852006) (xy 281.076146 -81.852008)
			)
		)
		(polygon
			(pts
				(arc
					(start 238.374936 -81.849722)
					(mid 238.699802 -80.875124)
					(end 237.725204 -80.550258)
				)
				(xy 237.723934 -80.547972) (xy 235.724192 -81.54797) (xy 235.724192 -81.548224)
				(arc
					(start 235.725208 -81.550256)
					(mid 235.400342 -82.524854)
					(end 236.37494 -82.84972)
				)
				(xy 236.37621 -82.852006) (xy 238.376206 -81.852008)
			)
		)
		(polygon
			(pts
				(arc
					(start 283.563314 -78.572868)
					(mid 282.622752 -78.886558)
					(end 282.936442 -79.82712)
				)
				(arc
					(start 284.928056 -80.8228)
					(mid 285.874832 -80.517615)
					(end 285.56331 -79.572866)
				)
			)
		)
		(polygon
			(pts
				(arc
					(start 240.863374 -78.572868)
					(mid 239.922812 -78.886558)
					(end 240.236502 -79.82712)
				)
				(arc
					(start 242.228116 -80.8228)
					(mid 243.174892 -80.517615)
					(end 242.86337 -79.572866)
				)
			)
		)
		(polygon
			(pts
				(arc
					(start 281.074876 -77.84973)
					(mid 281.399742 -76.875132)
					(end 280.425144 -76.550266)
				)
				(xy 280.423874 -76.54798) (xy 278.424132 -77.547978) (xy 278.424132 -77.548232)
				(arc
					(start 278.425148 -77.550264)
					(mid 278.100282 -78.524862)
					(end 279.07488 -78.849728)
				)
				(xy 279.07615 -78.852014) (xy 281.076146 -77.852016)
			)
		)
		(polygon
			(pts
				(arc
					(start 238.374936 -77.84973)
					(mid 238.699802 -76.875132)
					(end 237.725204 -76.550266)
				)
				(xy 237.723934 -76.54798) (xy 235.724192 -77.547978) (xy 235.724192 -77.548232)
				(arc
					(start 235.725208 -77.550264)
					(mid 235.400342 -78.524862)
					(end 236.37494 -78.849728)
				)
				(xy 236.37621 -78.852014) (xy 238.376206 -77.852016)
			)
		)
		(polygon
			(pts
				(arc
					(start 283.563314 -74.572876)
					(mid 282.622752 -74.886566)
					(end 282.936442 -75.827128)
				)
				(arc
					(start 284.928056 -76.822808)
					(mid 285.874832 -76.517623)
					(end 285.56331 -75.572874)
				)
			)
		)
		(polygon
			(pts
				(arc
					(start 240.863374 -74.572876)
					(mid 239.922812 -74.886566)
					(end 240.236502 -75.827128)
				)
				(arc
					(start 242.228116 -76.822808)
					(mid 243.174892 -76.517623)
					(end 242.86337 -75.572874)
				)
			)
		)
		(polygon
			(pts
				(arc
					(start 281.074876 -73.849738)
					(mid 281.399742 -72.87514)
					(end 280.425144 -72.550274)
				)
				(xy 280.423874 -72.547988) (xy 278.424132 -73.547986) (xy 278.424132 -73.54824)
				(arc
					(start 278.425148 -73.550272)
					(mid 278.100282 -74.52487)
					(end 279.07488 -74.849736)
				)
				(xy 279.07615 -74.852022) (xy 281.076146 -73.852024)
			)
		)
		(polygon
			(pts
				(arc
					(start 238.374936 -73.849738)
					(mid 238.699802 -72.87514)
					(end 237.725204 -72.550274)
				)
				(xy 237.723934 -72.547988) (xy 235.724192 -73.547986) (xy 235.724192 -73.54824)
				(arc
					(start 235.725208 -73.550272)
					(mid 235.400342 -74.52487)
					(end 236.37494 -74.849736)
				)
				(xy 236.37621 -74.852022) (xy 238.376206 -73.852024)
			)
		)
		(polygon
			(pts
				(arc
					(start 283.563314 -70.572884)
					(mid 282.622752 -70.886574)
					(end 282.936442 -71.827136)
				)
				(arc
					(start 284.928056 -72.822816)
					(mid 285.874832 -72.517631)
					(end 285.56331 -71.572882)
				)
			)
		)
		(polygon
			(pts
				(arc
					(start 240.863374 -70.572884)
					(mid 239.922812 -70.886574)
					(end 240.236502 -71.827136)
				)
				(arc
					(start 242.228116 -72.822816)
					(mid 243.174892 -72.517631)
					(end 242.86337 -71.572882)
				)
			)
		)
		(polygon
			(pts
				(arc
					(start 281.074876 -69.849746)
					(mid 281.399742 -68.875148)
					(end 280.425144 -68.550282)
				)
				(xy 280.423874 -68.547996) (xy 278.424132 -69.547994) (xy 278.424132 -69.548248)
				(arc
					(start 278.425148 -69.55028)
					(mid 278.100282 -70.524878)
					(end 279.07488 -70.849744)
				)
				(xy 279.07615 -70.85203) (xy 281.076146 -69.852032)
			)
		)
		(polygon
			(pts
				(arc
					(start 238.374936 -69.849746)
					(mid 238.699802 -68.875148)
					(end 237.725204 -68.550282)
				)
				(xy 237.723934 -68.547996) (xy 235.724192 -69.547994) (xy 235.724192 -69.548248)
				(arc
					(start 235.725208 -69.55028)
					(mid 235.400342 -70.524878)
					(end 236.37494 -70.849744)
				)
				(xy 236.37621 -70.85203) (xy 238.376206 -69.852032)
			)
		)
		(polygon
			(pts
				(arc
					(start 240.871756 -66.57721)
					(mid 239.92498 -66.882395)
					(end 240.236502 -67.827144)
				)
				(arc
					(start 242.236498 -68.827142)
					(mid 243.17706 -68.513452)
					(end 242.86337 -67.57289)
				)
			)
		)
		(polygon
			(pts
				(arc
					(start 283.563314 -66.572892)
					(mid 282.622752 -66.886582)
					(end 282.936442 -67.827144)
				)
				(arc
					(start 284.928056 -68.822824)
					(mid 285.874832 -68.517639)
					(end 285.56331 -67.57289)
				)
			)
		)
		(polygon
			(pts
				(arc
					(start 281.074876 -65.849754)
					(mid 281.399742 -64.875156)
					(end 280.425144 -64.55029)
				)
				(xy 280.423874 -64.548004) (xy 278.424132 -65.548002) (xy 278.424132 -65.548256)
				(arc
					(start 278.425148 -65.550288)
					(mid 278.100282 -66.524886)
					(end 279.07488 -66.849752)
				)
				(xy 279.07615 -66.852038) (xy 281.076146 -65.85204)
			)
		)
		(polygon
			(pts
				(arc
					(start 238.374936 -65.849754)
					(mid 238.699802 -64.875156)
					(end 237.725204 -64.55029)
				)
				(xy 237.723934 -64.548004) (xy 235.723938 -65.548002)
				(arc
					(start 235.725208 -65.550288)
					(mid 235.400342 -66.524886)
					(end 236.37494 -66.849752)
				)
				(xy 236.37621 -66.852038) (xy 238.375952 -65.85204) (xy 238.375952 -65.851786)
			)
		)
		(polygon
			(pts
				(arc
					(start 240.871756 -62.577218)
					(mid 239.92498 -62.882403)
					(end 240.236502 -63.827152)
				)
				(arc
					(start 242.236498 -64.82715)
					(mid 243.17706 -64.51346)
					(end 242.86337 -63.572898)
				)
			)
		)
		(polygon
			(pts
				(arc
					(start 283.563314 -62.5729)
					(mid 282.622752 -62.88659)
					(end 282.936442 -63.827152)
				)
				(arc
					(start 284.928056 -64.822832)
					(mid 285.874832 -64.517647)
					(end 285.56331 -63.572898)
				)
			)
		)
		(polygon
			(pts
				(arc
					(start 281.074876 -61.849762)
					(mid 281.399742 -60.875164)
					(end 280.425144 -60.550298)
				)
				(xy 280.423874 -60.548012) (xy 278.424132 -61.54801) (xy 278.424132 -61.548264)
				(arc
					(start 278.425148 -61.550296)
					(mid 278.100282 -62.524894)
					(end 279.07488 -62.84976)
				)
				(xy 279.07615 -62.852046) (xy 281.076146 -61.852048)
			)
		)
		(polygon
			(pts
				(arc
					(start 238.374936 -61.849762)
					(mid 238.699802 -60.875164)
					(end 237.725204 -60.550298)
				)
				(xy 237.723934 -60.548012) (xy 235.724192 -61.54801) (xy 235.724192 -61.548264)
				(arc
					(start 235.725208 -61.550296)
					(mid 235.400342 -62.524894)
					(end 236.37494 -62.84976)
				)
				(xy 236.37621 -62.852046) (xy 238.376206 -61.852048)
			)
		)
		(polygon
			(pts
				(arc
					(start 240.871756 -58.577226)
					(mid 239.92498 -58.882411)
					(end 240.236502 -59.82716)
				)
				(arc
					(start 242.236498 -60.827158)
					(mid 243.17706 -60.513468)
					(end 242.86337 -59.572906)
				)
			)
		)
		(polygon
			(pts
				(arc
					(start 283.563314 -58.572908)
					(mid 282.622752 -58.886598)
					(end 282.936442 -59.82716)
				)
				(arc
					(start 284.928056 -60.82284)
					(mid 285.874832 -60.517655)
					(end 285.56331 -59.572906)
				)
			)
		)
		(polygon
			(pts
				(arc
					(start 281.074876 -57.84977)
					(mid 281.399742 -56.875172)
					(end 280.425144 -56.550306)
				)
				(xy 280.423874 -56.54802) (xy 278.424132 -57.548018) (xy 278.424132 -57.548272)
				(arc
					(start 278.425148 -57.550304)
					(mid 278.100282 -58.524902)
					(end 279.07488 -58.849768)
				)
				(xy 279.07615 -58.852054) (xy 281.076146 -57.852056)
			)
		)
		(polygon
			(pts
				(arc
					(start 238.374936 -57.84977)
					(mid 238.699802 -56.875172)
					(end 237.725204 -56.550306)
				)
				(xy 237.723934 -56.54802) (xy 235.724192 -57.548018) (xy 235.724192 -57.548272)
				(arc
					(start 235.725208 -57.550304)
					(mid 235.400342 -58.524902)
					(end 236.37494 -58.849768)
				)
				(xy 236.37621 -58.852054) (xy 238.376206 -57.852056)
			)
		)
		(polygon
			(pts
				(arc
					(start 240.871756 -54.577234)
					(mid 239.92498 -54.882419)
					(end 240.236502 -55.827168)
				)
				(arc
					(start 242.236498 -56.827166)
					(mid 243.17706 -56.513476)
					(end 242.86337 -55.572914)
				)
			)
		)
		(polygon
			(pts
				(arc
					(start 283.563314 -54.572916)
					(mid 282.622752 -54.886606)
					(end 282.936442 -55.827168)
				)
				(arc
					(start 284.928056 -56.822848)
					(mid 285.874832 -56.517663)
					(end 285.56331 -55.572914)
				)
			)
		)
		(polygon
			(pts
				(arc
					(start 281.074876 -53.849778)
					(mid 281.399742 -52.87518)
					(end 280.425144 -52.550314)
				)
				(xy 280.423874 -52.548028) (xy 278.424132 -53.548026) (xy 278.424132 -53.54828)
				(arc
					(start 278.425148 -53.550312)
					(mid 278.100282 -54.52491)
					(end 279.07488 -54.849776)
				)
				(xy 279.07615 -54.852062) (xy 281.076146 -53.852064)
			)
		)
		(polygon
			(pts
				(arc
					(start 238.374936 -53.849778)
					(mid 238.699802 -52.87518)
					(end 237.725204 -52.550314)
				)
				(xy 237.723934 -52.548028) (xy 235.724192 -53.548026) (xy 235.724192 -53.54828)
				(arc
					(start 235.725208 -53.550312)
					(mid 235.400342 -54.52491)
					(end 236.37494 -54.849776)
				)
				(xy 236.37621 -54.852062) (xy 238.376206 -53.852064)
			)
		)
		(polygon
			(pts
				(arc
					(start 283.563314 -50.572924)
					(mid 282.622752 -50.886614)
					(end 282.936442 -51.827176)
				)
				(arc
					(start 284.928056 -52.822856)
					(mid 285.874832 -52.517671)
					(end 285.56331 -51.572922)
				)
			)
		)
		(polygon
			(pts
				(arc
					(start 240.863374 -50.572924)
					(mid 239.922812 -50.886614)
					(end 240.236502 -51.827176)
				)
				(arc
					(start 242.228116 -52.822856)
					(mid 243.174892 -52.517671)
					(end 242.86337 -51.572922)
				)
			)
		)
		(polygon
			(pts
				(arc
					(start 281.074876 -49.849786)
					(mid 281.399742 -48.875188)
					(end 280.425144 -48.550322)
				)
				(xy 280.423874 -48.548036) (xy 278.424132 -49.548034) (xy 278.424132 -49.548288)
				(arc
					(start 278.425148 -49.55032)
					(mid 278.100282 -50.524918)
					(end 279.07488 -50.849784)
				)
				(xy 279.07615 -50.85207) (xy 281.076146 -49.852072)
			)
		)
		(polygon
			(pts
				(arc
					(start 238.374936 -49.849786)
					(mid 238.699802 -48.875188)
					(end 237.725204 -48.550322)
				)
				(xy 237.723934 -48.548036) (xy 235.724192 -49.548034) (xy 235.724192 -49.548288)
				(arc
					(start 235.725208 -49.55032)
					(mid 235.400342 -50.524918)
					(end 236.37494 -50.849784)
				)
				(xy 236.37621 -50.85207) (xy 238.376206 -49.852072)
			)
		)
		(polygon
			(pts
				(arc
					(start 482.870002 -47.178214)
					(mid 482.488875 -46.797468)
					(end 482.108002 -47.178468)
				)
				(arc
					(start 482.108002 -48.321468)
					(mid 482.489002 -48.702468)
					(end 482.870002 -48.321468)
				)
			)
		)
		(polygon
			(pts
				(arc
					(start 451.3199 -47.178214)
					(mid 450.938773 -46.797468)
					(end 450.5579 -47.178468)
				)
				(arc
					(start 450.5579 -48.321468)
					(mid 450.9389 -48.702468)
					(end 451.3199 -48.321468)
				)
			)
		)
		(polygon
			(pts
				(arc
					(start 419.770052 -47.178214)
					(mid 419.388925 -46.797468)
					(end 419.008052 -47.178468)
				)
				(arc
					(start 419.008052 -48.321468)
					(mid 419.389052 -48.702468)
					(end 419.770052 -48.321468)
				)
			)
		)
		(polygon
			(pts
				(arc
					(start 388.21995 -47.178214)
					(mid 387.838823 -46.797468)
					(end 387.45795 -47.178468)
				)
				(arc
					(start 387.45795 -48.321468)
					(mid 387.83895 -48.702468)
					(end 388.21995 -48.321468)
				)
			)
		)
		(polygon
			(pts
				(arc
					(start 190.639954 -47.178214)
					(mid 190.258827 -46.797468)
					(end 189.877954 -47.178468)
				)
				(arc
					(start 189.877954 -48.321468)
					(mid 190.258954 -48.702468)
					(end 190.639954 -48.321468)
				)
			)
		)
		(polygon
			(pts
				(arc
					(start 159.089852 -47.178214)
					(mid 158.708725 -46.797468)
					(end 158.327852 -47.178468)
				)
				(arc
					(start 158.327852 -48.321468)
					(mid 158.708852 -48.702468)
					(end 159.089852 -48.321468)
				)
			)
		)
		(polygon
			(pts
				(arc
					(start 127.53975 -47.178214)
					(mid 127.158623 -46.797468)
					(end 126.77775 -47.178468)
				)
				(arc
					(start 126.77775 -48.321468)
					(mid 127.15875 -48.702468)
					(end 127.53975 -48.321468)
				)
			)
		)
		(polygon
			(pts
				(arc
					(start 95.989902 -47.178214)
					(mid 95.608775 -46.797468)
					(end 95.227902 -47.178468)
				)
				(arc
					(start 95.227902 -48.321468)
					(mid 95.608902 -48.702468)
					(end 95.989902 -48.321468)
				)
			)
		)
		(polygon
			(pts
				(arc
					(start 64.4398 -47.178214)
					(mid 64.058673 -46.797468)
					(end 63.6778 -47.178468)
				)
				(arc
					(start 63.6778 -48.321468)
					(mid 64.0588 -48.702468)
					(end 64.4398 -48.321468)
				)
			)
		)
		(polygon
			(pts
				(arc
					(start 32.889952 -47.178214)
					(mid 32.508825 -46.797468)
					(end 32.127952 -47.178468)
				)
				(arc
					(start 32.127952 -48.321468)
					(mid 32.508952 -48.702468)
					(end 32.889952 -48.321468)
				)
			)
		)
		(polygon
			(pts
				(arc
					(start 356.675182 -47.178214)
					(mid 356.288975 -46.792388)
					(end 355.903022 -47.178468)
				)
				(arc
					(start 355.903022 -48.321468)
					(mid 356.289102 -48.707548)
					(end 356.675182 -48.321468)
				)
			)
		)
		(polygon
			(pts
				(arc
					(start 240.871756 -46.57725)
					(mid 239.92498 -46.882435)
					(end 240.236502 -47.827184)
				)
				(arc
					(start 242.236498 -48.827182)
					(mid 243.17706 -48.513492)
					(end 242.86337 -47.57293)
				)
			)
		)
		(polygon
			(pts
				(arc
					(start 283.563314 -46.572932)
					(mid 282.622752 -46.886622)
					(end 282.936442 -47.827184)
				)
				(arc
					(start 284.928056 -48.822864)
					(mid 285.874832 -48.517679)
					(end 285.56331 -47.57293)
				)
			)
		)
		(polygon
			(pts
				(arc
					(start 323.824854 -46.818042)
					(mid 324.2056 -46.436915)
					(end 323.8246 -46.056042)
				)
				(arc
					(start 322.6816 -46.056042)
					(mid 322.3006 -46.437042)
					(end 322.6816 -46.818042)
				)
			)
		)
		(polygon
			(pts
				(arc
					(start 383.908554 -46.5328)
					(mid 384.2893 -46.151673)
					(end 383.9083 -45.7708)
				)
				(arc
					(start 382.7653 -45.7708)
					(mid 382.3843 -46.1518)
					(end 382.7653 -46.5328)
				)
			)
		)
		(polygon
			(pts
				(arc
					(start 281.074876 -45.849794)
					(mid 281.399742 -44.875196)
					(end 280.425144 -44.55033)
				)
				(xy 280.423874 -44.548044) (xy 278.424132 -45.548042) (xy 278.424132 -45.548296)
				(arc
					(start 278.425148 -45.550328)
					(mid 278.100282 -46.524926)
					(end 279.07488 -46.849792)
				)
				(xy 279.07615 -46.852078) (xy 281.076146 -45.85208)
			)
		)
		(polygon
			(pts
				(arc
					(start 238.374936 -45.849794)
					(mid 238.699802 -44.875196)
					(end 237.725204 -44.55033)
				)
				(xy 237.723934 -44.548044) (xy 235.724192 -45.548042) (xy 235.724192 -45.548296)
				(arc
					(start 235.725208 -45.550328)
					(mid 235.400342 -46.524926)
					(end 236.37494 -46.849792)
				)
				(xy 236.37621 -46.852078) (xy 238.376206 -45.85208)
			)
		)
		(polygon
			(pts
				(arc
					(start 478.120202 -43.368468)
					(mid 477.739202 -42.987468)
					(end 477.358202 -43.368468)
				)
				(arc
					(start 477.358202 -44.511722)
					(mid 477.739329 -44.892468)
					(end 478.120202 -44.511468)
				)
			)
		)
		(polygon
			(pts
				(arc
					(start 446.5701 -43.368468)
					(mid 446.1891 -42.987468)
					(end 445.8081 -43.368468)
				)
				(arc
					(start 445.8081 -44.511722)
					(mid 446.189227 -44.892468)
					(end 446.5701 -44.511468)
				)
			)
		)
		(polygon
			(pts
				(arc
					(start 415.020252 -43.368468)
					(mid 414.639252 -42.987468)
					(end 414.258252 -43.368468)
				)
				(arc
					(start 414.258252 -44.511722)
					(mid 414.639379 -44.892468)
					(end 415.020252 -44.511468)
				)
			)
		)
		(polygon
			(pts
				(arc
					(start 240.871756 -42.577258)
					(mid 239.92498 -42.882443)
					(end 240.236502 -43.827192)
				)
				(arc
					(start 242.236498 -44.82719)
					(mid 243.17706 -44.5135)
					(end 242.86337 -43.572938)
				)
			)
		)
		(polygon
			(pts
				(arc
					(start 283.563314 -42.57294)
					(mid 282.622752 -42.88663)
					(end 282.936442 -43.827192)
				)
				(arc
					(start 284.928056 -44.822872)
					(mid 285.874832 -44.517687)
					(end 285.56331 -43.572938)
				)
			)
		)
		(polygon
			(pts
				(arc
					(start 320.3575 -43.008042)
					(mid 320.7385 -42.627042)
					(end 320.3575 -42.246042)
				)
				(arc
					(start 319.214246 -42.246042)
					(mid 318.8335 -42.627169)
					(end 319.2145 -43.008042)
				)
			)
		)
		(polygon
			(pts
				(arc
					(start 351.907602 -43.013122)
					(mid 352.293682 -42.627042)
					(end 351.907602 -42.240962)
				)
				(arc
					(start 350.764348 -42.240962)
					(mid 350.378522 -42.627169)
					(end 350.764602 -43.013122)
				)
			)
		)
		(polygon
			(pts
				(arc
					(start 281.074876 -41.849802)
					(mid 281.399742 -40.875204)
					(end 280.425144 -40.550338)
				)
				(xy 280.423874 -40.548052) (xy 278.424132 -41.54805) (xy 278.424132 -41.548304)
				(arc
					(start 278.425148 -41.550336)
					(mid 278.100282 -42.524934)
					(end 279.07488 -42.8498)
				)
				(xy 279.07615 -42.852086) (xy 281.076146 -41.852088)
			)
		)
		(polygon
			(pts
				(arc
					(start 238.374936 -41.849802)
					(mid 238.699802 -40.875204)
					(end 237.725204 -40.550338)
				)
				(xy 237.723934 -40.548052) (xy 235.724192 -41.54805) (xy 235.724192 -41.548304)
				(arc
					(start 235.725208 -41.550336)
					(mid 235.400342 -42.524934)
					(end 236.37494 -42.8498)
				)
				(xy 236.37621 -42.852086) (xy 238.376206 -41.852088)
			)
		)
		(polygon
			(pts
				(arc
					(start 240.871756 -38.577266)
					(mid 239.92498 -38.882451)
					(end 240.236502 -39.8272)
				)
				(arc
					(start 242.236498 -40.827198)
					(mid 243.17706 -40.513508)
					(end 242.86337 -39.572946)
				)
			)
		)
		(polygon
			(pts
				(arc
					(start 283.563314 -38.572948)
					(mid 282.622752 -38.886638)
					(end 282.936442 -39.8272)
				)
				(arc
					(start 284.928056 -40.82288)
					(mid 285.874832 -40.517695)
					(end 285.56331 -39.572946)
				)
			)
		)
		(polygon
			(pts
				(arc
					(start 281.074876 -37.84981)
					(mid 281.399742 -36.875212)
					(end 280.425144 -36.550346)
				)
				(xy 280.423874 -36.54806) (xy 278.424132 -37.548058) (xy 278.424132 -37.548312)
				(arc
					(start 278.425148 -37.550344)
					(mid 278.100282 -38.524942)
					(end 279.07488 -38.849808)
				)
				(xy 279.07615 -38.852094) (xy 281.076146 -37.852096)
			)
		)
		(polygon
			(pts
				(arc
					(start 238.374936 -37.84981)
					(mid 238.699802 -36.875212)
					(end 237.725204 -36.550346)
				)
				(xy 237.723934 -36.54806) (xy 235.724192 -37.548058) (xy 235.724192 -37.548312)
				(arc
					(start 235.725208 -37.550344)
					(mid 235.400342 -38.524942)
					(end 236.37494 -38.849808)
				)
				(xy 236.37621 -38.852094) (xy 238.376206 -37.852096)
			)
		)
		(polygon
			(pts
				(arc
					(start 240.876074 -34.548064)
					(mid 239.89792 -34.873946)
					(end 240.223802 -35.8521)
				)
				(arc
					(start 242.223798 -36.852098)
					(mid 243.201952 -36.526216)
					(end 242.87607 -35.548062)
				)
			)
		)
		(polygon
			(pts
				(arc
					(start 283.57703 -34.545778)
					(mid 282.595574 -34.87293)
					(end 282.922726 -35.854386)
				)
				(arc
					(start 284.922468 -36.854384)
					(mid 285.904229 -36.527384)
					(end 285.577026 -35.545776)
				)
			)
		)
		(polygon
			(pts
				(arc
					(start 389.898636 -29.149802)
					(mid 389.349869 -28.601416)
					(end 388.801356 -29.150056)
				)
				(arc
					(start 388.801356 -30.550104)
					(mid 389.349996 -31.098744)
					(end 389.898636 -30.550104)
				)
			)
		)
		(polygon
			(pts
				(arc
					(start 143.89862 -29.149802)
					(mid 143.349853 -28.601416)
					(end 142.80134 -29.150056)
				)
				(arc
					(start 142.80134 -30.550104)
					(mid 143.34998 -31.098744)
					(end 143.89862 -30.550104)
				)
			)
		)
		(polygon
			(pts
				(arc
					(start 136.698736 -29.149802)
					(mid 136.149969 -28.601416)
					(end 135.601456 -29.150056)
				)
				(arc
					(start 135.601456 -30.550104)
					(mid 136.150096 -31.098744)
					(end 136.698736 -30.550104)
				)
			)
		)
		(polygon
			(pts
				(arc
					(start 368.30127 -29.150056)
					(mid 367.75009 -28.598876)
					(end 367.19891 -29.150056)
				)
				(arc
					(start 367.19891 -30.550358)
					(mid 367.750217 -31.101284)
					(end 368.30127 -30.550104)
				)
			)
		)
		(polygon
			(pts
				(arc
					(start 122.301254 -29.150056)
					(mid 121.750074 -28.598876)
					(end 121.198894 -29.150056)
				)
				(arc
					(start 121.198894 -30.550358)
					(mid 121.750201 -31.101284)
					(end 122.301254 -30.550104)
				)
			)
		)
		(polygon
			(pts
				(arc
					(start 382.701292 -29.149802)
					(mid 382.149985 -28.598876)
					(end 381.598932 -29.150056)
				)
				(arc
					(start 381.598932 -30.550104)
					(mid 382.150112 -31.101284)
					(end 382.701292 -30.550104)
				)
			)
		)
		(polygon
			(pts
				(arc
					(start 362.89869 -28.149804)
					(mid 362.349923 -27.601418)
					(end 361.80141 -28.150058)
				)
				(arc
					(start 361.80141 -29.550106)
					(mid 362.35005 -30.098746)
					(end 362.89869 -29.550106)
				)
			)
		)
		(polygon
			(pts
				(arc
					(start 116.898674 -28.149804)
					(mid 116.349907 -27.601418)
					(end 115.801394 -28.150058)
				)
				(arc
					(start 115.801394 -29.550106)
					(mid 116.350034 -30.098746)
					(end 116.898674 -29.550106)
				)
			)
		)
		(polygon
			(pts
				(arc
					(start 389.898636 -21.949918)
					(mid 389.349869 -21.401532)
					(end 388.801356 -21.950172)
				)
				(arc
					(start 388.801356 -23.35022)
					(mid 389.349996 -23.89886)
					(end 389.898636 -23.35022)
				)
			)
		)
		(polygon
			(pts
				(arc
					(start 386.298694 -21.949918)
					(mid 385.749927 -21.401532)
					(end 385.201414 -21.950172)
				)
				(arc
					(start 385.201414 -23.35022)
					(mid 385.750054 -23.89886)
					(end 386.298694 -23.35022)
				)
			)
		)
		(polygon
			(pts
				(arc
					(start 382.698752 -21.949918)
					(mid 382.149985 -21.401532)
					(end 381.601472 -21.950172)
				)
				(arc
					(start 381.601472 -23.35022)
					(mid 382.150112 -23.89886)
					(end 382.698752 -23.35022)
				)
			)
		)
		(polygon
			(pts
				(arc
					(start 379.098556 -21.949918)
					(mid 378.549789 -21.401532)
					(end 378.001276 -21.950172)
				)
				(arc
					(start 378.001276 -23.35022)
					(mid 378.549916 -23.89886)
					(end 379.098556 -23.35022)
				)
			)
		)
		(polygon
			(pts
				(arc
					(start 368.29873 -21.949918)
					(mid 367.749963 -21.401532)
					(end 367.20145 -21.950172)
				)
				(arc
					(start 367.20145 -23.35022)
					(mid 367.75009 -23.89886)
					(end 368.29873 -23.35022)
				)
			)
		)
		(polygon
			(pts
				(arc
					(start 364.698534 -21.949918)
					(mid 364.149767 -21.401532)
					(end 363.601254 -21.950172)
				)
				(arc
					(start 363.601254 -23.35022)
					(mid 364.149894 -23.89886)
					(end 364.698534 -23.35022)
				)
			)
		)
		(polygon
			(pts
				(arc
					(start 361.098592 -21.949918)
					(mid 360.549825 -21.401532)
					(end 360.001312 -21.950172)
				)
				(arc
					(start 360.001312 -23.35022)
					(mid 360.549952 -23.89886)
					(end 361.098592 -23.35022)
				)
			)
		)
		(polygon
			(pts
				(arc
					(start 357.49865 -21.949918)
					(mid 356.949883 -21.401532)
					(end 356.40137 -21.950172)
				)
				(arc
					(start 356.40137 -23.35022)
					(mid 356.95001 -23.89886)
					(end 357.49865 -23.35022)
				)
			)
		)
		(polygon
			(pts
				(arc
					(start 143.89862 -21.949918)
					(mid 143.349853 -21.401532)
					(end 142.80134 -21.950172)
				)
				(arc
					(start 142.80134 -23.35022)
					(mid 143.34998 -23.89886)
					(end 143.89862 -23.35022)
				)
			)
		)
		(polygon
			(pts
				(arc
					(start 140.298678 -21.949918)
					(mid 139.749911 -21.401532)
					(end 139.201398 -21.950172)
				)
				(arc
					(start 139.201398 -23.35022)
					(mid 139.750038 -23.89886)
					(end 140.298678 -23.35022)
				)
			)
		)
		(polygon
			(pts
				(arc
					(start 136.698736 -21.949918)
					(mid 136.149969 -21.401532)
					(end 135.601456 -21.950172)
				)
				(arc
					(start 135.601456 -23.35022)
					(mid 136.150096 -23.89886)
					(end 136.698736 -23.35022)
				)
			)
		)
		(polygon
			(pts
				(arc
					(start 133.09854 -21.949918)
					(mid 132.549773 -21.401532)
					(end 132.00126 -21.950172)
				)
				(arc
					(start 132.00126 -23.35022)
					(mid 132.5499 -23.89886)
					(end 133.09854 -23.35022)
				)
			)
		)
		(polygon
			(pts
				(arc
					(start 122.298714 -21.949918)
					(mid 121.749947 -21.401532)
					(end 121.201434 -21.950172)
				)
				(arc
					(start 121.201434 -23.35022)
					(mid 121.750074 -23.89886)
					(end 122.298714 -23.35022)
				)
			)
		)
		(polygon
			(pts
				(arc
					(start 118.698518 -21.949918)
					(mid 118.149751 -21.401532)
					(end 117.601238 -21.950172)
				)
				(arc
					(start 117.601238 -23.35022)
					(mid 118.149878 -23.89886)
					(end 118.698518 -23.35022)
				)
			)
		)
		(polygon
			(pts
				(arc
					(start 115.098576 -21.949918)
					(mid 114.549809 -21.401532)
					(end 114.001296 -21.950172)
				)
				(arc
					(start 114.001296 -23.35022)
					(mid 114.549936 -23.89886)
					(end 115.098576 -23.35022)
				)
			)
		)
		(polygon
			(pts
				(arc
					(start 111.498634 -21.949918)
					(mid 110.949867 -21.401532)
					(end 110.401354 -21.950172)
				)
				(arc
					(start 110.401354 -23.35022)
					(mid 110.949994 -23.89886)
					(end 111.498634 -23.35022)
				)
			)
		)
		(polygon
			(pts
				(arc
					(start 388.098538 -20.94992)
					(mid 387.549771 -20.401534)
					(end 387.001258 -20.950174)
				)
				(arc
					(start 387.001258 -22.350222)
					(mid 387.549898 -22.898862)
					(end 388.098538 -22.350222)
				)
			)
		)
		(polygon
			(pts
				(arc
					(start 384.498596 -20.94992)
					(mid 383.949829 -20.401534)
					(end 383.401316 -20.950174)
				)
				(arc
					(start 383.401316 -22.350222)
					(mid 383.949956 -22.898862)
					(end 384.498596 -22.350222)
				)
			)
		)
		(polygon
			(pts
				(arc
					(start 380.898654 -20.94992)
					(mid 380.349887 -20.401534)
					(end 379.801374 -20.950174)
				)
				(arc
					(start 379.801374 -22.350222)
					(mid 380.350014 -22.898862)
					(end 380.898654 -22.350222)
				)
			)
		)
		(polygon
			(pts
				(arc
					(start 377.298712 -20.94992)
					(mid 376.749945 -20.401534)
					(end 376.201432 -20.950174)
				)
				(arc
					(start 376.201432 -22.350222)
					(mid 376.750072 -22.898862)
					(end 377.298712 -22.350222)
				)
			)
		)
		(polygon
			(pts
				(arc
					(start 366.498632 -20.94992)
					(mid 365.949865 -20.401534)
					(end 365.401352 -20.950174)
				)
				(arc
					(start 365.401352 -22.350222)
					(mid 365.949992 -22.898862)
					(end 366.498632 -22.350222)
				)
			)
		)
		(polygon
			(pts
				(arc
					(start 362.89869 -20.94992)
					(mid 362.349923 -20.401534)
					(end 361.80141 -20.950174)
				)
				(arc
					(start 361.80141 -22.350222)
					(mid 362.35005 -22.898862)
					(end 362.89869 -22.350222)
				)
			)
		)
		(polygon
			(pts
				(arc
					(start 359.298748 -20.94992)
					(mid 358.749981 -20.401534)
					(end 358.201468 -20.950174)
				)
				(arc
					(start 358.201468 -22.350222)
					(mid 358.750108 -22.898862)
					(end 359.298748 -22.350222)
				)
			)
		)
		(polygon
			(pts
				(arc
					(start 355.698552 -20.94992)
					(mid 355.149785 -20.401534)
					(end 354.601272 -20.950174)
				)
				(arc
					(start 354.601272 -22.350222)
					(mid 355.149912 -22.898862)
					(end 355.698552 -22.350222)
				)
			)
		)
		(polygon
			(pts
				(arc
					(start 142.098522 -20.94992)
					(mid 141.549755 -20.401534)
					(end 141.001242 -20.950174)
				)
				(arc
					(start 141.001242 -22.350222)
					(mid 141.549882 -22.898862)
					(end 142.098522 -22.350222)
				)
			)
		)
		(polygon
			(pts
				(arc
					(start 138.49858 -20.94992)
					(mid 137.949813 -20.401534)
					(end 137.4013 -20.950174)
				)
				(arc
					(start 137.4013 -22.350222)
					(mid 137.94994 -22.898862)
					(end 138.49858 -22.350222)
				)
			)
		)
		(polygon
			(pts
				(arc
					(start 134.898638 -20.94992)
					(mid 134.349871 -20.401534)
					(end 133.801358 -20.950174)
				)
				(arc
					(start 133.801358 -22.350222)
					(mid 134.349998 -22.898862)
					(end 134.898638 -22.350222)
				)
			)
		)
		(polygon
			(pts
				(arc
					(start 131.298696 -20.94992)
					(mid 130.749929 -20.401534)
					(end 130.201416 -20.950174)
				)
				(arc
					(start 130.201416 -22.350222)
					(mid 130.750056 -22.898862)
					(end 131.298696 -22.350222)
				)
			)
		)
		(polygon
			(pts
				(arc
					(start 120.498616 -20.94992)
					(mid 119.949849 -20.401534)
					(end 119.401336 -20.950174)
				)
				(arc
					(start 119.401336 -22.350222)
					(mid 119.949976 -22.898862)
					(end 120.498616 -22.350222)
				)
			)
		)
		(polygon
			(pts
				(arc
					(start 116.898674 -20.94992)
					(mid 116.349907 -20.401534)
					(end 115.801394 -20.950174)
				)
				(arc
					(start 115.801394 -22.350222)
					(mid 116.350034 -22.898862)
					(end 116.898674 -22.350222)
				)
			)
		)
		(polygon
			(pts
				(arc
					(start 113.298732 -20.94992)
					(mid 112.749965 -20.401534)
					(end 112.201452 -20.950174)
				)
				(arc
					(start 112.201452 -22.350222)
					(mid 112.750092 -22.898862)
					(end 113.298732 -22.350222)
				)
			)
		)
		(polygon
			(pts
				(arc
					(start 109.698536 -20.94992)
					(mid 109.149769 -20.401534)
					(end 108.601256 -20.950174)
				)
				(arc
					(start 108.601256 -22.350222)
					(mid 109.149896 -22.898862)
					(end 109.698536 -22.350222)
				)
			)
		)
		(polygon
			(pts
				(arc
					(start 133.09854 -18.35023)
					(mid 132.5499 -17.80159)
					(end 132.00126 -18.35023)
				)
				(arc
					(start 132.00126 -19.750278)
					(mid 132.550027 -20.298664)
					(end 133.09854 -19.750024)
				)
			)
		)
		(polygon
			(pts
				(arc
					(start 389.898636 -18.349976)
					(mid 389.349869 -17.80159)
					(end 388.801356 -18.35023)
				)
				(arc
					(start 388.801356 -19.750024)
					(mid 389.349996 -20.298664)
					(end 389.898636 -19.750024)
				)
			)
		)
		(polygon
			(pts
				(arc
					(start 386.298694 -18.349976)
					(mid 385.749927 -17.80159)
					(end 385.201414 -18.35023)
				)
				(arc
					(start 385.201414 -19.750024)
					(mid 385.750054 -20.298664)
					(end 386.298694 -19.750024)
				)
			)
		)
		(polygon
			(pts
				(arc
					(start 382.698752 -18.349976)
					(mid 382.149985 -17.80159)
					(end 381.601472 -18.35023)
				)
				(arc
					(start 381.601472 -19.750024)
					(mid 382.150112 -20.298664)
					(end 382.698752 -19.750024)
				)
			)
		)
		(polygon
			(pts
				(arc
					(start 379.098556 -18.349976)
					(mid 378.549789 -17.80159)
					(end 378.001276 -18.35023)
				)
				(arc
					(start 378.001276 -19.750024)
					(mid 378.549916 -20.298664)
					(end 379.098556 -19.750024)
				)
			)
		)
		(polygon
			(pts
				(arc
					(start 368.29873 -18.349976)
					(mid 367.749963 -17.80159)
					(end 367.20145 -18.35023)
				)
				(arc
					(start 367.20145 -19.750024)
					(mid 367.75009 -20.298664)
					(end 368.29873 -19.750024)
				)
			)
		)
		(polygon
			(pts
				(arc
					(start 364.698534 -18.349976)
					(mid 364.149767 -17.80159)
					(end 363.601254 -18.35023)
				)
				(arc
					(start 363.601254 -19.750024)
					(mid 364.149894 -20.298664)
					(end 364.698534 -19.750024)
				)
			)
		)
		(polygon
			(pts
				(arc
					(start 361.098592 -18.349976)
					(mid 360.549825 -17.80159)
					(end 360.001312 -18.35023)
				)
				(arc
					(start 360.001312 -19.750024)
					(mid 360.549952 -20.298664)
					(end 361.098592 -19.750024)
				)
			)
		)
		(polygon
			(pts
				(arc
					(start 357.49865 -18.349976)
					(mid 356.949883 -17.80159)
					(end 356.40137 -18.35023)
				)
				(arc
					(start 356.40137 -19.750024)
					(mid 356.95001 -20.298664)
					(end 357.49865 -19.750024)
				)
			)
		)
		(polygon
			(pts
				(arc
					(start 143.89862 -18.349976)
					(mid 143.349853 -17.80159)
					(end 142.80134 -18.35023)
				)
				(arc
					(start 142.80134 -19.750024)
					(mid 143.34998 -20.298664)
					(end 143.89862 -19.750024)
				)
			)
		)
		(polygon
			(pts
				(arc
					(start 140.298678 -18.349976)
					(mid 139.749911 -17.80159)
					(end 139.201398 -18.35023)
				)
				(arc
					(start 139.201398 -19.750024)
					(mid 139.750038 -20.298664)
					(end 140.298678 -19.750024)
				)
			)
		)
		(polygon
			(pts
				(arc
					(start 136.698736 -18.349976)
					(mid 136.149969 -17.80159)
					(end 135.601456 -18.35023)
				)
				(arc
					(start 135.601456 -19.750024)
					(mid 136.150096 -20.298664)
					(end 136.698736 -19.750024)
				)
			)
		)
		(polygon
			(pts
				(arc
					(start 122.298714 -18.349976)
					(mid 121.749947 -17.80159)
					(end 121.201434 -18.35023)
				)
				(arc
					(start 121.201434 -19.750024)
					(mid 121.750074 -20.298664)
					(end 122.298714 -19.750024)
				)
			)
		)
		(polygon
			(pts
				(arc
					(start 118.698518 -18.349976)
					(mid 118.149751 -17.80159)
					(end 117.601238 -18.35023)
				)
				(arc
					(start 117.601238 -19.750024)
					(mid 118.149878 -20.298664)
					(end 118.698518 -19.750024)
				)
			)
		)
		(polygon
			(pts
				(arc
					(start 115.098576 -18.349976)
					(mid 114.549809 -17.80159)
					(end 114.001296 -18.35023)
				)
				(arc
					(start 114.001296 -19.750024)
					(mid 114.549936 -20.298664)
					(end 115.098576 -19.750024)
				)
			)
		)
		(polygon
			(pts
				(arc
					(start 111.498634 -18.349976)
					(mid 110.949867 -17.80159)
					(end 110.401354 -18.35023)
				)
				(arc
					(start 110.401354 -19.750024)
					(mid 110.949994 -20.298664)
					(end 111.498634 -19.750024)
				)
			)
		)
		(polygon
			(pts
				(arc
					(start 388.098538 -17.349724)
					(mid 387.549771 -16.801338)
					(end 387.001258 -17.349978)
				)
				(arc
					(start 387.001258 -18.750026)
					(mid 387.549898 -19.298666)
					(end 388.098538 -18.750026)
				)
			)
		)
		(polygon
			(pts
				(arc
					(start 384.498596 -17.349724)
					(mid 383.949829 -16.801338)
					(end 383.401316 -17.349978)
				)
				(arc
					(start 383.401316 -18.750026)
					(mid 383.949956 -19.298666)
					(end 384.498596 -18.750026)
				)
			)
		)
		(polygon
			(pts
				(arc
					(start 380.898654 -17.349724)
					(mid 380.349887 -16.801338)
					(end 379.801374 -17.349978)
				)
				(arc
					(start 379.801374 -18.750026)
					(mid 380.350014 -19.298666)
					(end 380.898654 -18.750026)
				)
			)
		)
		(polygon
			(pts
				(arc
					(start 377.298712 -17.349724)
					(mid 376.749945 -16.801338)
					(end 376.201432 -17.349978)
				)
				(arc
					(start 376.201432 -18.750026)
					(mid 376.750072 -19.298666)
					(end 377.298712 -18.750026)
				)
			)
		)
		(polygon
			(pts
				(arc
					(start 366.498632 -17.349724)
					(mid 365.949865 -16.801338)
					(end 365.401352 -17.349978)
				)
				(arc
					(start 365.401352 -18.750026)
					(mid 365.949992 -19.298666)
					(end 366.498632 -18.750026)
				)
			)
		)
		(polygon
			(pts
				(arc
					(start 362.89869 -17.349724)
					(mid 362.349923 -16.801338)
					(end 361.80141 -17.349978)
				)
				(arc
					(start 361.80141 -18.750026)
					(mid 362.35005 -19.298666)
					(end 362.89869 -18.750026)
				)
			)
		)
		(polygon
			(pts
				(arc
					(start 359.298748 -17.349724)
					(mid 358.749981 -16.801338)
					(end 358.201468 -17.349978)
				)
				(arc
					(start 358.201468 -18.750026)
					(mid 358.750108 -19.298666)
					(end 359.298748 -18.750026)
				)
			)
		)
		(polygon
			(pts
				(arc
					(start 355.698552 -17.349724)
					(mid 355.149785 -16.801338)
					(end 354.601272 -17.349978)
				)
				(arc
					(start 354.601272 -18.750026)
					(mid 355.149912 -19.298666)
					(end 355.698552 -18.750026)
				)
			)
		)
		(polygon
			(pts
				(arc
					(start 142.098522 -17.349724)
					(mid 141.549755 -16.801338)
					(end 141.001242 -17.349978)
				)
				(arc
					(start 141.001242 -18.750026)
					(mid 141.549882 -19.298666)
					(end 142.098522 -18.750026)
				)
			)
		)
		(polygon
			(pts
				(arc
					(start 138.49858 -17.349724)
					(mid 137.949813 -16.801338)
					(end 137.4013 -17.349978)
				)
				(arc
					(start 137.4013 -18.750026)
					(mid 137.94994 -19.298666)
					(end 138.49858 -18.750026)
				)
			)
		)
		(polygon
			(pts
				(arc
					(start 134.898638 -17.349724)
					(mid 134.349871 -16.801338)
					(end 133.801358 -17.349978)
				)
				(arc
					(start 133.801358 -18.750026)
					(mid 134.349998 -19.298666)
					(end 134.898638 -18.750026)
				)
			)
		)
		(polygon
			(pts
				(arc
					(start 131.298696 -17.349724)
					(mid 130.749929 -16.801338)
					(end 130.201416 -17.349978)
				)
				(arc
					(start 130.201416 -18.750026)
					(mid 130.750056 -19.298666)
					(end 131.298696 -18.750026)
				)
			)
		)
		(polygon
			(pts
				(arc
					(start 120.498616 -17.349724)
					(mid 119.949849 -16.801338)
					(end 119.401336 -17.349978)
				)
				(arc
					(start 119.401336 -18.750026)
					(mid 119.949976 -19.298666)
					(end 120.498616 -18.750026)
				)
			)
		)
		(polygon
			(pts
				(arc
					(start 116.898674 -17.349724)
					(mid 116.349907 -16.801338)
					(end 115.801394 -17.349978)
				)
				(arc
					(start 115.801394 -18.750026)
					(mid 116.350034 -19.298666)
					(end 116.898674 -18.750026)
				)
			)
		)
		(polygon
			(pts
				(arc
					(start 113.298732 -17.349724)
					(mid 112.749965 -16.801338)
					(end 112.201452 -17.349978)
				)
				(arc
					(start 112.201452 -18.750026)
					(mid 112.750092 -19.298666)
					(end 113.298732 -18.750026)
				)
			)
		)
		(polygon
			(pts
				(arc
					(start 109.698536 -17.349724)
					(mid 109.149769 -16.801338)
					(end 108.601256 -17.349978)
				)
				(arc
					(start 108.601256 -18.750026)
					(mid 109.149896 -19.298666)
					(end 109.698536 -18.750026)
				)
			)
		)
		(polygon
			(pts
				(arc
					(start 281.074876 -17.84985)
					(mid 281.399742 -16.875252)
					(end 280.425144 -16.550386)
				)
				(xy 280.423874 -16.5481) (xy 278.424132 -17.548098) (xy 278.424132 -17.548352)
				(arc
					(start 278.425148 -17.550384)
					(mid 278.100282 -18.524982)
					(end 279.07488 -18.849848)
				)
				(xy 279.07615 -18.852134) (xy 281.076146 -17.852136)
			)
		)
		(polygon
			(pts
				(arc
					(start 238.374936 -17.84985)
					(mid 238.699802 -16.875252)
					(end 237.725204 -16.550386)
				)
				(xy 237.723934 -16.5481) (xy 235.724192 -17.548098) (xy 235.724192 -17.548352)
				(arc
					(start 235.725208 -17.550384)
					(mid 235.400342 -18.524982)
					(end 236.37494 -18.849848)
				)
				(xy 236.37621 -18.852134) (xy 238.376206 -17.852136)
			)
		)
		(polygon
			(pts
				(arc
					(start 281.077162 -11.854434)
					(mid 281.404314 -10.872978)
					(end 280.422858 -10.545826)
				)
				(arc
					(start 278.433784 -11.54049)
					(mid 278.037097 -12.362161)
					(end 278.750268 -12.931394)
				)
				(arc
					(start 278.750268 -12.931394)
					(mid 278.918191 -12.911919)
					(end 279.077166 -12.854432)
				)
			)
		)
		(polygon
			(pts
				(arc
					(start 238.377222 -11.854434)
					(mid 238.704374 -10.872978)
					(end 237.722918 -10.545826)
				)
				(arc
					(start 235.733844 -11.54049)
					(mid 235.393447 -12.52152)
					(end 236.377226 -12.854432)
				)
			)
		)
	)
	(zone
		(layer "In4.Cu")
		(hatch none 0.5)
		(connect_pads
			(clearance 0)
		)
		(min_thickness 0.25)
		(keepout
			(tracks not_allowed)
			(vias allowed)
			(pads allowed)
			(copperpour not_allowed)
			(footprints allowed)
		)
		(placement
			(enabled no)
			(sheetname "")
		)
		(fill
			(thermal_gap 0.5)
			(thermal_bridge_width 0.5)
			(island_removal_mode 0)
		)
		(polygon
			(pts
				(xy 204.387196 -420.437056) (xy 204.387196 -419.514274) (xy 229.14864 -419.514274) (xy 229.768146 -420.13378)
				(xy 232.002584 -420.13378) (xy 232.62209 -419.514274) (xy 272.003266 -419.514274) (xy 272.003266 -420.437056)
			)
		)
	)
	(zone
		(net "P12V_A")
		(layer "In4.Cu")
		(hatch none 0.5)
		(connect_pads
			(clearance 0.5)
		)
		(min_thickness 0.25)
		(fill yes
			(thermal_gap 0.5)
			(thermal_bridge_width 0.5)
			(island_removal_mode 0)
		)
		(polygon
			(pts
				(xy 274.828 -381.742188) (xy 274.828 -408.836622) (xy 276.026626 -410.035248) (xy 288.656776 -410.035248)
				(xy 289.047428 -410.035248) (xy 291.079682 -408.002994) (xy 291.079682 -407.612342) (xy 291.079682 -380.007622)
				(xy 291.079682 -375.029222) (xy 291.079682 -370.775738) (xy 289.744404 -369.44046) (xy 289.74288 -369.44046)
				(xy 288.83356 -368.53114) (xy 254.929894 -368.53114) (xy 254.020574 -369.44046) (xy 252.598682 -370.862352)
				(xy 252.598682 -377.09348) (xy 252.839982 -377.33478) (xy 274.31492 -377.33478) (xy 274.828 -377.84786)
				(xy 274.828 -378.841)
			)
		)
	)
	(zone
		(net "MB3_P12V_IN_R")
		(layer "In4.Cu")
		(hatch none 0.5)
		(connect_pads
			(clearance 0.5)
		)
		(min_thickness 0.25)
		(fill yes
			(thermal_gap 0.5)
			(thermal_bridge_width 0.5)
			(island_removal_mode 0)
		)
		(polygon
			(pts
				(xy 253.111 -390.15416) (xy 265.951208 -390.15416) (xy 273.92884 -390.15416) (xy 274.465542 -389.617458)
				(xy 274.465542 -386.81025) (xy 274.465542 -381.720598) (xy 274.465542 -379.113542) (xy 274.4597 -379.1077)
				(xy 274.4597 -378.0536) (xy 274.22348 -377.81738) (xy 253.27102 -377.81738) (xy 252.983492 -377.81738)
				(xy 252.552708 -378.248164) (xy 252.552708 -389.780018) (xy 252.92685 -390.15416)
			)
		)
	)
	(zone
		(net "GND")
		(layer "In4.Cu")
		(hatch none 0.5)
		(connect_pads
			(clearance 0.5)
		)
		(min_thickness 0.25)
		(fill yes
			(thermal_gap 0.5)
			(thermal_bridge_width 0.5)
			(island_removal_mode 0)
		)
		(polygon
			(pts
				(arc
					(start 349.000064 -15.762986)
					(mid 347.753425 -15.246611)
					(end 347.23705 -13.999972)
				)
				(arc
					(start 347.23705 -0.999998)
					(mid 347.16764 -0.832426)
					(end 347.000068 -0.763016)
				)
				(arc
					(start 300.999906 -0.763016)
					(mid 299.753267 -0.246641)
					(end 299.236892 0.999998)
				)
				(xy 299.236892 2.402332) (xy 297.967908 2.402332)
				(arc
					(start 297.967908 0.999998)
					(mid 298.85596 -1.143948)
					(end 300.999906 -2.032)
				)
				(xy 345.968066 -2.032)
				(arc
					(start 345.968066 -13.999972)
					(mid 346.856118 -16.143918)
					(end 349.000064 -17.03197)
				)
				(xy 349.743776 -17.03197) (xy 349.743776 -15.762986)
			)
		)
	)
	(zone
		(net "GND")
		(layer "In4.Cu")
		(hatch none 0.5)
		(connect_pads
			(clearance 0.5)
		)
		(min_thickness 0.25)
		(fill yes
			(thermal_gap 0.5)
			(thermal_bridge_width 0.5)
			(island_removal_mode 0)
		)
		(polygon
			(pts
				(arc
					(start 221.000066 38.037008)
					(mid 220.832494 37.967598)
					(end 220.763084 37.800026)
				)
				(xy 220.763084 4.156964) (xy 222.032068 4.156964) (xy 222.032068 36.768024) (xy 297.967908 36.768024)
				(xy 297.967908 2.719324) (xy 299.236892 2.719324)
				(arc
					(start 299.236892 37.800026)
					(mid 299.167482 37.967598)
					(end 298.99991 38.037008)
				)
			)
		)
	)
	(zone
		(net "P12V_IN")
		(layer "In5.Cu")
		(hatch none 0.5)
		(connect_pads
			(clearance 0.5)
		)
		(min_thickness 0.25)
		(fill yes
			(thermal_gap 0.5)
			(thermal_bridge_width 0.5)
			(island_removal_mode 0)
		)
		(polygon
			(pts
				(xy 253.059946 -390.5885) (xy 253.05893 -390.589516) (xy 253.025402 -390.589516) (xy 252.4887 -391.126218)
				(xy 252.4887 -397.030194) (xy 251.08408 -398.434814) (xy 244.340888 -398.434814) (xy 243.21262 -399.563082)
				(xy 243.21262 -419.930072) (xy 273.815048 -419.930072) (xy 273.815048 -401.682458) (xy 275.0185 -400.479006)
				(xy 275.0185 -396.379446) (xy 273.815048 -395.175994) (xy 273.815048 -391.008108) (xy 273.39544 -390.5885)
			)
		)
	)
	(zone
		(net "P12V_A")
		(layer "In5.Cu")
		(hatch none 0.5)
		(connect_pads
			(clearance 0.5)
		)
		(min_thickness 0.25)
		(fill yes
			(thermal_gap 0.5)
			(thermal_bridge_width 0.5)
			(island_removal_mode 0)
		)
		(polygon
			(pts
				(xy 221.270068 37.530024)
				(arc
					(start 221.270068 2.999994)
					(mid 220.605201 1.394863)
					(end 219.00007 0.729996)
				)
				(arc
					(start 201.254106 0.729996)
					(mid 200.506839 -0.697991)
					(end 199.00011 -1.27)
				)
				(xy 151.269954 -1.27)
				(arc
					(start 151.269954 -13.999972)
					(mid 150.777824 -15.411381)
					(end 149.514814 -16.210788)
				)
				(xy 149.514814 -35.531044) (xy 148.846794 -36.199064) (xy 134.267448 -36.199064) (xy 133.46303 -35.394646)
				(xy 133.46303 -25.13076) (xy 132.59689 -24.26462) (xy 131.902454 -24.26462) (xy 130.892296 -23.254462)
				(xy 126.374144 -23.254462) (xy 124.747274 -24.881332) (xy 124.747274 -35.38855) (xy 123.93676 -36.199064)
				(xy 103.696516 -36.199064) (xy 103.015288 -35.517836) (xy 103.015288 -16.26997)
				(arc
					(start 103.000048 -16.26997)
					(mid 101.394917 -15.605103)
					(end 100.73005 -13.999972)
				)
				(xy 100.73005 -1.27) (xy 1.27 -1.27) (xy 1.27 -347.929962)
				(arc
					(start 189.6999 -347.929962)
					(mid 191.305031 -348.594829)
					(end 191.969898 -350.19996)
				)
				(xy 191.969898 -371.730016)
				(arc
					(start 199.00011 -371.730016)
					(mid 200.605241 -372.394883)
					(end 201.270108 -374.000014)
				)
				(xy 201.270108 -419.930072) (xy 242.83162 -419.930072) (xy 242.83162 -399.405094) (xy 244.1829 -398.053814)
				(xy 250.926092 -398.053814) (xy 252.1077 -396.872206) (xy 252.1077 -378.152406) (xy 252.879606 -377.3805)
				(xy 274.322794 -377.3805) (xy 274.8407 -377.898406) (xy 274.8407 -378.983748) (xy 274.8407 -379.003306)
				(xy 274.8407 -389.791194) (xy 274.196048 -390.435846) (xy 274.196048 -395.018006) (xy 275.3995 -396.221458)
				(xy 275.3995 -400.636994) (xy 274.196048 -401.840446) (xy 274.196048 -419.930072) (xy 308.729888 -419.930072)
				(xy 308.729888 -375.270014)
				(arc
					(start 296.69994 -375.270014)
					(mid 295.094809 -374.605147)
					(end 294.429942 -373.000016)
				)
				(xy 294.429942 -360.503724) (xy 275.69668 -360.503724) (xy 275.197062 -360.004106) (xy 275.197062 -292.078918)
				(xy 275.893022 -291.382958) (xy 290.707572 -291.382958) (xy 291.403024 -292.07841) (xy 291.403024 -347.729302)
				(xy 293.683182 -350.00946)
				(arc
					(start 294.43807 -350.00946)
					(mid 295.163722 -348.528919)
					(end 296.69994 -347.929962)
				)
				(xy 490.180122 -347.929962) (xy 490.180122 -1.27) (xy 397.26997 -1.27)
				(arc
					(start 397.26997 -13.999972)
					(mid 396.77784 -15.411381)
					(end 395.51483 -16.210788)
				)
				(xy 395.51483 -35.531044) (xy 394.84681 -36.199064) (xy 349.696532 -36.199064) (xy 349.015304 -35.517836)
				(xy 349.015304 -16.26997)
				(arc
					(start 349.000064 -16.26997)
					(mid 347.394933 -15.605103)
					(end 346.730066 -13.999972)
				)
				(xy 346.730066 -1.27)
				(arc
					(start 300.999906 -1.27)
					(mid 299.394775 -0.605133)
					(end 298.729908 0.999998)
				)
				(xy 298.729908 37.530024)
			)
		)
		(polygon
			(pts
				(arc
					(start 223.148652 -416.799776)
					(mid 222.599885 -416.25139)
					(end 222.051372 -416.80003)
				)
				(arc
					(start 222.051372 -418.200078)
					(mid 222.600012 -418.748718)
					(end 223.148652 -418.200078)
				)
			)
		)
		(polygon
			(pts
				(arc
					(start 219.54871 -416.799776)
					(mid 218.999943 -416.25139)
					(end 218.45143 -416.80003)
				)
				(arc
					(start 218.45143 -418.200078)
					(mid 219.00007 -418.748718)
					(end 219.54871 -418.200078)
				)
			)
		)
		(polygon
			(pts
				(arc
					(start 215.948768 -416.799776)
					(mid 215.400001 -416.25139)
					(end 214.851488 -416.80003)
				)
				(arc
					(start 214.851488 -418.200078)
					(mid 215.400128 -418.748718)
					(end 215.948768 -418.200078)
				)
			)
		)
		(polygon
			(pts
				(arc
					(start 212.348826 -416.799776)
					(mid 211.800059 -416.25139)
					(end 211.251546 -416.80003)
				)
				(arc
					(start 211.251546 -418.200078)
					(mid 211.800186 -418.748718)
					(end 212.348826 -418.200078)
				)
			)
		)
		(polygon
			(pts
				(arc
					(start 221.348808 -414.199832)
					(mid 220.800041 -413.651446)
					(end 220.251528 -414.200086)
				)
				(arc
					(start 220.251528 -415.600134)
					(mid 220.800168 -416.148774)
					(end 221.348808 -415.600134)
				)
			)
		)
		(polygon
			(pts
				(arc
					(start 217.748612 -414.199832)
					(mid 217.199845 -413.651446)
					(end 216.651332 -414.200086)
				)
				(arc
					(start 216.651332 -415.600134)
					(mid 217.199972 -416.148774)
					(end 217.748612 -415.600134)
				)
			)
		)
		(polygon
			(pts
				(arc
					(start 214.14867 -414.199832)
					(mid 213.599903 -413.651446)
					(end 213.05139 -414.200086)
				)
				(arc
					(start 213.05139 -415.600134)
					(mid 213.60003 -416.148774)
					(end 214.14867 -415.600134)
				)
			)
		)
		(polygon
			(pts
				(arc
					(start 210.548728 -414.199832)
					(mid 209.999961 -413.651446)
					(end 209.451448 -414.200086)
				)
				(arc
					(start 209.451448 -415.600134)
					(mid 210.000088 -416.148774)
					(end 210.548728 -415.600134)
				)
			)
		)
		(polygon
			(pts
				(arc
					(start 210.548728 -410.59989)
					(mid 209.999961 -410.051504)
					(end 209.451448 -410.600144)
				)
				(arc
					(start 209.451448 -412.000192)
					(mid 210.000088 -412.548832)
					(end 210.548728 -412.000192)
				)
			)
		)
		(polygon
			(pts
				(arc
					(start 221.348808 -406.999948)
					(mid 220.800041 -406.451562)
					(end 220.251528 -407.000202)
				)
				(arc
					(start 220.251528 -408.399996)
					(mid 220.800168 -408.948636)
					(end 221.348808 -408.399996)
				)
			)
		)
		(polygon
			(pts
				(arc
					(start 217.748612 -406.999948)
					(mid 217.199845 -406.451562)
					(end 216.651332 -407.000202)
				)
				(arc
					(start 216.651332 -408.399996)
					(mid 217.199972 -408.948636)
					(end 217.748612 -408.399996)
				)
			)
		)
		(polygon
			(pts
				(arc
					(start 214.14867 -406.999948)
					(mid 213.599903 -406.451562)
					(end 213.05139 -407.000202)
				)
				(arc
					(start 213.05139 -408.399996)
					(mid 213.60003 -408.948636)
					(end 214.14867 -408.399996)
				)
			)
		)
		(polygon
			(pts
				(arc
					(start 210.548728 -406.999948)
					(mid 209.999961 -406.451562)
					(end 209.451448 -407.000202)
				)
				(arc
					(start 209.451448 -408.399996)
					(mid 210.000088 -408.948636)
					(end 210.548728 -408.399996)
				)
			)
		)
		(polygon
			(pts
				(arc
					(start 223.148652 -405.999696)
					(mid 222.599885 -405.45131)
					(end 222.051372 -405.99995)
				)
				(arc
					(start 222.051372 -407.399998)
					(mid 222.600012 -407.948638)
					(end 223.148652 -407.399998)
				)
			)
		)
		(polygon
			(pts
				(arc
					(start 219.54871 -405.999696)
					(mid 218.999943 -405.45131)
					(end 218.45143 -405.99995)
				)
				(arc
					(start 218.45143 -407.399998)
					(mid 219.00007 -407.948638)
					(end 219.54871 -407.399998)
				)
			)
		)
		(polygon
			(pts
				(arc
					(start 215.948768 -405.999696)
					(mid 215.400001 -405.45131)
					(end 214.851488 -405.99995)
				)
				(arc
					(start 214.851488 -407.399998)
					(mid 215.400128 -407.948638)
					(end 215.948768 -407.399998)
				)
			)
		)
		(polygon
			(pts
				(arc
					(start 212.348826 -405.999696)
					(mid 211.800059 -405.45131)
					(end 211.251546 -405.99995)
				)
				(arc
					(start 211.251546 -407.399998)
					(mid 211.800186 -407.948638)
					(end 212.348826 -407.399998)
				)
			)
		)
		(polygon
			(pts
				(arc
					(start 273.1135 -359.885996)
					(mid 273.4945 -359.504996)
					(end 273.1135 -359.123996)
				)
				(arc
					(start 271.970246 -359.123996)
					(mid 271.5895 -359.505123)
					(end 271.9705 -359.885996)
				)
			)
		)
		(polygon
			(pts
				(arc
					(start 273.1135 -358.085898)
					(mid 273.4945 -357.704898)
					(end 273.1135 -357.323898)
				)
				(arc
					(start 271.970246 -357.323898)
					(mid 271.5895 -357.705025)
					(end 271.9705 -358.085898)
				)
			)
		)
		(polygon
			(pts
				(arc
					(start 273.1135 -356.286054)
					(mid 273.4945 -355.905054)
					(end 273.1135 -355.524054)
				)
				(arc
					(start 271.970246 -355.524054)
					(mid 271.5895 -355.905181)
					(end 271.9705 -356.286054)
				)
			)
		)
		(polygon
			(pts
				(arc
					(start 273.1135 -354.485956)
					(mid 273.4945 -354.104956)
					(end 273.1135 -353.723956)
				)
				(arc
					(start 271.970246 -353.723956)
					(mid 271.5895 -354.105083)
					(end 271.9705 -354.485956)
				)
			)
		)
		(polygon
			(pts
				(arc
					(start 273.1135 -352.686112)
					(mid 273.4945 -352.305112)
					(end 273.1135 -351.924112)
				)
				(arc
					(start 271.970246 -351.924112)
					(mid 271.5895 -352.305239)
					(end 271.9705 -352.686112)
				)
			)
		)
		(polygon
			(pts
				(arc
					(start 273.1135 -350.886014)
					(mid 273.4945 -350.505014)
					(end 273.1135 -350.124014)
				)
				(arc
					(start 271.970246 -350.124014)
					(mid 271.5895 -350.505141)
					(end 271.9705 -350.886014)
				)
			)
		)
		(polygon
			(pts
				(arc
					(start 273.1135 -338.28863)
					(mid 273.49704 -337.90509)
					(end 273.1135 -337.52155)
				)
				(arc
					(start 271.970246 -337.52155)
					(mid 271.58696 -337.905217)
					(end 271.9705 -338.28863)
				)
			)
		)
		(polygon
			(pts
				(arc
					(start 273.1135 -336.488532)
					(mid 273.49704 -336.104992)
					(end 273.1135 -335.721452)
				)
				(arc
					(start 271.970246 -335.721452)
					(mid 271.58696 -336.105119)
					(end 271.9705 -336.488532)
				)
			)
		)
		(polygon
			(pts
				(arc
					(start 273.1135 -334.688434)
					(mid 273.49704 -334.304894)
					(end 273.1135 -333.921354)
				)
				(arc
					(start 271.970246 -333.921354)
					(mid 271.58696 -334.305021)
					(end 271.9705 -334.688434)
				)
			)
		)
		(polygon
			(pts
				(arc
					(start 273.1135 -332.88859)
					(mid 273.49704 -332.50505)
					(end 273.1135 -332.12151)
				)
				(arc
					(start 271.970246 -332.12151)
					(mid 271.58696 -332.505177)
					(end 271.9705 -332.88859)
				)
			)
		)
		(polygon
			(pts
				(arc
					(start 273.1135 -331.088492)
					(mid 273.49704 -330.704952)
					(end 273.1135 -330.321412)
				)
				(arc
					(start 271.970246 -330.321412)
					(mid 271.58696 -330.705079)
					(end 271.9705 -331.088492)
				)
			)
		)
		(polygon
			(pts
				(arc
					(start 273.1135 -329.288648)
					(mid 273.49704 -328.905108)
					(end 273.1135 -328.521568)
				)
				(arc
					(start 271.970246 -328.521568)
					(mid 271.58696 -328.905235)
					(end 271.9705 -329.288648)
				)
			)
		)
		(polygon
			(pts
				(arc
					(start 273.1135 -316.68847)
					(mid 273.49704 -316.30493)
					(end 273.1135 -315.92139)
				)
				(arc
					(start 271.970246 -315.92139)
					(mid 271.58696 -316.305057)
					(end 271.9705 -316.68847)
				)
			)
		)
		(polygon
			(pts
				(arc
					(start 273.1135 -314.888626)
					(mid 273.49704 -314.505086)
					(end 273.1135 -314.121546)
				)
				(arc
					(start 271.970246 -314.121546)
					(mid 271.58696 -314.505213)
					(end 271.9705 -314.888626)
				)
			)
		)
		(polygon
			(pts
				(arc
					(start 273.1135 -313.088528)
					(mid 273.49704 -312.704988)
					(end 273.1135 -312.321448)
				)
				(arc
					(start 271.970246 -312.321448)
					(mid 271.58696 -312.705115)
					(end 271.9705 -313.088528)
				)
			)
		)
		(polygon
			(pts
				(arc
					(start 273.1135 -311.28843)
					(mid 273.49704 -310.90489)
					(end 273.1135 -310.52135)
				)
				(arc
					(start 271.970246 -310.52135)
					(mid 271.58696 -310.905017)
					(end 271.9705 -311.28843)
				)
			)
		)
		(polygon
			(pts
				(arc
					(start 273.1135 -309.488586)
					(mid 273.49704 -309.105046)
					(end 273.1135 -308.721506)
				)
				(arc
					(start 271.970246 -308.721506)
					(mid 271.58696 -309.105173)
					(end 271.9705 -309.488586)
				)
			)
		)
		(polygon
			(pts
				(arc
					(start 273.1135 -307.688488)
					(mid 273.49704 -307.304948)
					(end 273.1135 -306.921408)
				)
				(arc
					(start 271.970246 -306.921408)
					(mid 271.58696 -307.305075)
					(end 271.9705 -307.688488)
				)
			)
		)
		(polygon
			(pts
				(arc
					(start 482.870002 -277.178262)
					(mid 482.488875 -276.797516)
					(end 482.108002 -277.178516)
				)
				(arc
					(start 482.108002 -278.321516)
					(mid 482.489002 -278.702516)
					(end 482.870002 -278.321516)
				)
			)
		)
		(polygon
			(pts
				(arc
					(start 451.3199 -277.178262)
					(mid 450.938773 -276.797516)
					(end 450.5579 -277.178516)
				)
				(arc
					(start 450.5579 -278.321516)
					(mid 450.9389 -278.702516)
					(end 451.3199 -278.321516)
				)
			)
		)
		(polygon
			(pts
				(arc
					(start 419.770052 -277.178262)
					(mid 419.388925 -276.797516)
					(end 419.008052 -277.178516)
				)
				(arc
					(start 419.008052 -278.321516)
					(mid 419.389052 -278.702516)
					(end 419.770052 -278.321516)
				)
			)
		)
		(polygon
			(pts
				(arc
					(start 388.21995 -277.178262)
					(mid 387.838823 -276.797516)
					(end 387.45795 -277.178516)
				)
				(arc
					(start 387.45795 -278.321516)
					(mid 387.83895 -278.702516)
					(end 388.21995 -278.321516)
				)
			)
		)
		(polygon
			(pts
				(arc
					(start 356.670102 -277.178262)
					(mid 356.288975 -276.797516)
					(end 355.908102 -277.178516)
				)
				(arc
					(start 355.908102 -278.321516)
					(mid 356.289102 -278.702516)
					(end 356.670102 -278.321516)
				)
			)
		)
		(polygon
			(pts
				(arc
					(start 325.12 -277.178262)
					(mid 324.738873 -276.797516)
					(end 324.358 -277.178516)
				)
				(arc
					(start 324.358 -278.321516)
					(mid 324.739 -278.702516)
					(end 325.12 -278.321516)
				)
			)
		)
		(polygon
			(pts
				(arc
					(start 190.639954 -277.178262)
					(mid 190.258827 -276.797516)
					(end 189.877954 -277.178516)
				)
				(arc
					(start 189.877954 -278.321516)
					(mid 190.258954 -278.702516)
					(end 190.639954 -278.321516)
				)
			)
		)
		(polygon
			(pts
				(arc
					(start 159.089852 -277.178262)
					(mid 158.708725 -276.797516)
					(end 158.327852 -277.178516)
				)
				(arc
					(start 158.327852 -278.321516)
					(mid 158.708852 -278.702516)
					(end 159.089852 -278.321516)
				)
			)
		)
		(polygon
			(pts
				(arc
					(start 127.53975 -277.178262)
					(mid 127.158623 -276.797516)
					(end 126.77775 -277.178516)
				)
				(arc
					(start 126.77775 -278.321516)
					(mid 127.15875 -278.702516)
					(end 127.53975 -278.321516)
				)
			)
		)
		(polygon
			(pts
				(arc
					(start 95.989902 -277.178262)
					(mid 95.608775 -276.797516)
					(end 95.227902 -277.178516)
				)
				(arc
					(start 95.227902 -278.321516)
					(mid 95.608902 -278.702516)
					(end 95.989902 -278.321516)
				)
			)
		)
		(polygon
			(pts
				(arc
					(start 64.4398 -277.178262)
					(mid 64.058673 -276.797516)
					(end 63.6778 -277.178516)
				)
				(arc
					(start 63.6778 -278.321516)
					(mid 64.0588 -278.702516)
					(end 64.4398 -278.321516)
				)
			)
		)
		(polygon
			(pts
				(arc
					(start 32.889952 -277.178262)
					(mid 32.508825 -276.797516)
					(end 32.127952 -277.178516)
				)
				(arc
					(start 32.127952 -278.321516)
					(mid 32.508952 -278.702516)
					(end 32.889952 -278.321516)
				)
			)
		)
		(polygon
			(pts
				(arc
					(start 478.120202 -273.368516)
					(mid 477.739202 -272.987516)
					(end 477.358202 -273.368516)
				)
				(arc
					(start 477.358202 -274.51177)
					(mid 477.739329 -274.892516)
					(end 478.120202 -274.511516)
				)
			)
		)
		(polygon
			(pts
				(arc
					(start 446.5701 -273.368516)
					(mid 446.1891 -272.987516)
					(end 445.8081 -273.368516)
				)
				(arc
					(start 445.8081 -274.51177)
					(mid 446.189227 -274.892516)
					(end 446.5701 -274.511516)
				)
			)
		)
		(polygon
			(pts
				(arc
					(start 415.020252 -273.368516)
					(mid 414.639252 -272.987516)
					(end 414.258252 -273.368516)
				)
				(arc
					(start 414.258252 -274.51177)
					(mid 414.639379 -274.892516)
					(end 415.020252 -274.511516)
				)
			)
		)
		(polygon
			(pts
				(arc
					(start 383.47015 -273.368516)
					(mid 383.08915 -272.987516)
					(end 382.70815 -273.368516)
				)
				(arc
					(start 382.70815 -274.51177)
					(mid 383.089277 -274.892516)
					(end 383.47015 -274.511516)
				)
			)
		)
		(polygon
			(pts
				(arc
					(start 351.920302 -273.368516)
					(mid 351.539302 -272.987516)
					(end 351.158302 -273.368516)
				)
				(arc
					(start 351.158302 -274.51177)
					(mid 351.539429 -274.892516)
					(end 351.920302 -274.511516)
				)
			)
		)
		(polygon
			(pts
				(arc
					(start 320.41084 -273.368262)
					(mid 319.989073 -272.946876)
					(end 319.56756 -273.368516)
				)
				(arc
					(start 319.56756 -274.511516)
					(mid 319.9892 -274.933156)
					(end 320.41084 -274.511516)
				)
			)
		)
		(polygon
			(pts
				(xy 290.482782 -248.59869) (xy 274.429474 -248.59869) (xy 273.734022 -249.294142) (xy 273.734022 -263.665716)
				(xy 276.857206 -266.7889) (xy 290.726368 -266.7889) (xy 291.422328 -266.09294) (xy 291.422328 -249.538236)
			)
		)
		(polygon
			(pts
				(arc
					(start 482.870002 -162.178238)
					(mid 482.488875 -161.797492)
					(end 482.108002 -162.178492)
				)
				(arc
					(start 482.108002 -163.321492)
					(mid 482.489002 -163.702492)
					(end 482.870002 -163.321492)
				)
			)
		)
		(polygon
			(pts
				(arc
					(start 438.6199 -162.178238)
					(mid 438.238773 -161.797492)
					(end 437.8579 -162.178492)
				)
				(arc
					(start 437.8579 -163.321492)
					(mid 438.2389 -163.702492)
					(end 438.6199 -163.321492)
				)
			)
		)
		(polygon
			(pts
				(arc
					(start 419.770052 -162.178238)
					(mid 419.388925 -161.797492)
					(end 419.008052 -162.178492)
				)
				(arc
					(start 419.008052 -163.321492)
					(mid 419.389052 -163.702492)
					(end 419.770052 -163.321492)
				)
			)
		)
		(polygon
			(pts
				(arc
					(start 388.21995 -162.178238)
					(mid 387.838823 -161.797492)
					(end 387.45795 -162.178492)
				)
				(arc
					(start 387.45795 -163.321492)
					(mid 387.83895 -163.702492)
					(end 388.21995 -163.321492)
				)
			)
		)
		(polygon
			(pts
				(arc
					(start 356.670102 -162.178238)
					(mid 356.288975 -161.797492)
					(end 355.908102 -162.178492)
				)
				(arc
					(start 355.908102 -163.321492)
					(mid 356.289102 -163.702492)
					(end 356.670102 -163.321492)
				)
			)
		)
		(polygon
			(pts
				(arc
					(start 325.12 -162.178238)
					(mid 324.738873 -161.797492)
					(end 324.358 -162.178492)
				)
				(arc
					(start 324.358 -163.321492)
					(mid 324.739 -163.702492)
					(end 325.12 -163.321492)
				)
			)
		)
		(polygon
			(pts
				(arc
					(start 190.639954 -162.178238)
					(mid 190.258827 -161.797492)
					(end 189.877954 -162.178492)
				)
				(arc
					(start 189.877954 -163.321492)
					(mid 190.258954 -163.702492)
					(end 190.639954 -163.321492)
				)
			)
		)
		(polygon
			(pts
				(arc
					(start 159.089852 -162.178238)
					(mid 158.708725 -161.797492)
					(end 158.327852 -162.178492)
				)
				(arc
					(start 158.327852 -163.321492)
					(mid 158.708852 -163.702492)
					(end 159.089852 -163.321492)
				)
			)
		)
		(polygon
			(pts
				(arc
					(start 127.53975 -162.178238)
					(mid 127.158623 -161.797492)
					(end 126.77775 -162.178492)
				)
				(arc
					(start 126.77775 -163.321492)
					(mid 127.15875 -163.702492)
					(end 127.53975 -163.321492)
				)
			)
		)
		(polygon
			(pts
				(arc
					(start 95.989902 -162.178238)
					(mid 95.608775 -161.797492)
					(end 95.227902 -162.178492)
				)
				(arc
					(start 95.227902 -163.321492)
					(mid 95.608902 -163.702492)
					(end 95.989902 -163.321492)
				)
			)
		)
		(polygon
			(pts
				(arc
					(start 64.4398 -162.178238)
					(mid 64.058673 -161.797492)
					(end 63.6778 -162.178492)
				)
				(arc
					(start 63.6778 -163.321492)
					(mid 64.0588 -163.702492)
					(end 64.4398 -163.321492)
				)
			)
		)
		(polygon
			(pts
				(arc
					(start 32.889952 -162.178238)
					(mid 32.508825 -161.797492)
					(end 32.127952 -162.178492)
				)
				(arc
					(start 32.127952 -163.321492)
					(mid 32.508952 -163.702492)
					(end 32.889952 -163.321492)
				)
			)
		)
		(polygon
			(pts
				(arc
					(start 478.120202 -158.368492)
					(mid 477.739202 -157.987492)
					(end 477.358202 -158.368492)
				)
				(arc
					(start 477.358202 -159.511746)
					(mid 477.739329 -159.892492)
					(end 478.120202 -159.511492)
				)
			)
		)
		(polygon
			(pts
				(arc
					(start 440.2201 -158.368492)
					(mid 439.8391 -157.987492)
					(end 439.4581 -158.368492)
				)
				(arc
					(start 439.4581 -159.511746)
					(mid 439.839227 -159.892492)
					(end 440.2201 -159.511492)
				)
			)
		)
		(polygon
			(pts
				(arc
					(start 415.020252 -158.368492)
					(mid 414.639252 -157.987492)
					(end 414.258252 -158.368492)
				)
				(arc
					(start 414.258252 -159.511746)
					(mid 414.639379 -159.892492)
					(end 415.020252 -159.511492)
				)
			)
		)
		(polygon
			(pts
				(arc
					(start 383.47015 -158.368492)
					(mid 383.08915 -157.987492)
					(end 382.70815 -158.368492)
				)
				(arc
					(start 382.70815 -159.511746)
					(mid 383.089277 -159.892492)
					(end 383.47015 -159.511492)
				)
			)
		)
		(polygon
			(pts
				(arc
					(start 351.920302 -158.368492)
					(mid 351.539302 -157.987492)
					(end 351.158302 -158.368492)
				)
				(arc
					(start 351.158302 -159.511746)
					(mid 351.539429 -159.892492)
					(end 351.920302 -159.511492)
				)
			)
		)
		(polygon
			(pts
				(arc
					(start 320.3702 -158.368492)
					(mid 319.9892 -157.987492)
					(end 319.6082 -158.368492)
				)
				(arc
					(start 319.6082 -159.511746)
					(mid 319.989327 -159.892492)
					(end 320.3702 -159.511492)
				)
			)
		)
		(polygon
			(pts
				(arc
					(start 482.870002 -47.178214)
					(mid 482.488875 -46.797468)
					(end 482.108002 -47.178468)
				)
				(arc
					(start 482.108002 -48.321468)
					(mid 482.489002 -48.702468)
					(end 482.870002 -48.321468)
				)
			)
		)
		(polygon
			(pts
				(arc
					(start 451.3199 -47.178214)
					(mid 450.938773 -46.797468)
					(end 450.5579 -47.178468)
				)
				(arc
					(start 450.5579 -48.321468)
					(mid 450.9389 -48.702468)
					(end 451.3199 -48.321468)
				)
			)
		)
		(polygon
			(pts
				(arc
					(start 419.770052 -47.178214)
					(mid 419.388925 -46.797468)
					(end 419.008052 -47.178468)
				)
				(arc
					(start 419.008052 -48.321468)
					(mid 419.389052 -48.702468)
					(end 419.770052 -48.321468)
				)
			)
		)
		(polygon
			(pts
				(arc
					(start 388.21995 -47.178214)
					(mid 387.838823 -46.797468)
					(end 387.45795 -47.178468)
				)
				(arc
					(start 387.45795 -48.321468)
					(mid 387.83895 -48.702468)
					(end 388.21995 -48.321468)
				)
			)
		)
		(polygon
			(pts
				(arc
					(start 190.639954 -47.178214)
					(mid 190.258827 -46.797468)
					(end 189.877954 -47.178468)
				)
				(arc
					(start 189.877954 -48.321468)
					(mid 190.258954 -48.702468)
					(end 190.639954 -48.321468)
				)
			)
		)
		(polygon
			(pts
				(arc
					(start 159.089852 -47.178214)
					(mid 158.708725 -46.797468)
					(end 158.327852 -47.178468)
				)
				(arc
					(start 158.327852 -48.321468)
					(mid 158.708852 -48.702468)
					(end 159.089852 -48.321468)
				)
			)
		)
		(polygon
			(pts
				(arc
					(start 127.53975 -47.178214)
					(mid 127.158623 -46.797468)
					(end 126.77775 -47.178468)
				)
				(arc
					(start 126.77775 -48.321468)
					(mid 127.15875 -48.702468)
					(end 127.53975 -48.321468)
				)
			)
		)
		(polygon
			(pts
				(arc
					(start 95.989902 -47.178214)
					(mid 95.608775 -46.797468)
					(end 95.227902 -47.178468)
				)
				(arc
					(start 95.227902 -48.321468)
					(mid 95.608902 -48.702468)
					(end 95.989902 -48.321468)
				)
			)
		)
		(polygon
			(pts
				(arc
					(start 64.4398 -47.178214)
					(mid 64.058673 -46.797468)
					(end 63.6778 -47.178468)
				)
				(arc
					(start 63.6778 -48.321468)
					(mid 64.0588 -48.702468)
					(end 64.4398 -48.321468)
				)
			)
		)
		(polygon
			(pts
				(arc
					(start 32.889952 -47.178214)
					(mid 32.508825 -46.797468)
					(end 32.127952 -47.178468)
				)
				(arc
					(start 32.127952 -48.321468)
					(mid 32.508952 -48.702468)
					(end 32.889952 -48.321468)
				)
			)
		)
		(polygon
			(pts
				(arc
					(start 356.675182 -47.178214)
					(mid 356.288975 -46.792388)
					(end 355.903022 -47.178468)
				)
				(arc
					(start 355.903022 -48.321468)
					(mid 356.289102 -48.707548)
					(end 356.675182 -48.321468)
				)
			)
		)
		(polygon
			(pts
				(arc
					(start 323.824854 -46.818042)
					(mid 324.2056 -46.436915)
					(end 323.8246 -46.056042)
				)
				(arc
					(start 322.6816 -46.056042)
					(mid 322.3006 -46.437042)
					(end 322.6816 -46.818042)
				)
			)
		)
		(polygon
			(pts
				(arc
					(start 383.908554 -46.5328)
					(mid 384.2893 -46.151673)
					(end 383.9083 -45.7708)
				)
				(arc
					(start 382.7653 -45.7708)
					(mid 382.3843 -46.1518)
					(end 382.7653 -46.5328)
				)
			)
		)
		(polygon
			(pts
				(arc
					(start 478.120202 -43.368468)
					(mid 477.739202 -42.987468)
					(end 477.358202 -43.368468)
				)
				(arc
					(start 477.358202 -44.511722)
					(mid 477.739329 -44.892468)
					(end 478.120202 -44.511468)
				)
			)
		)
		(polygon
			(pts
				(arc
					(start 446.5701 -43.368468)
					(mid 446.1891 -42.987468)
					(end 445.8081 -43.368468)
				)
				(arc
					(start 445.8081 -44.511722)
					(mid 446.189227 -44.892468)
					(end 446.5701 -44.511468)
				)
			)
		)
		(polygon
			(pts
				(arc
					(start 415.020252 -43.368468)
					(mid 414.639252 -42.987468)
					(end 414.258252 -43.368468)
				)
				(arc
					(start 414.258252 -44.511722)
					(mid 414.639379 -44.892468)
					(end 415.020252 -44.511468)
				)
			)
		)
		(polygon
			(pts
				(arc
					(start 320.3575 -43.008042)
					(mid 320.7385 -42.627042)
					(end 320.3575 -42.246042)
				)
				(arc
					(start 319.214246 -42.246042)
					(mid 318.8335 -42.627169)
					(end 319.2145 -43.008042)
				)
			)
		)
		(polygon
			(pts
				(arc
					(start 351.907602 -43.013122)
					(mid 352.293682 -42.627042)
					(end 351.907602 -42.240962)
				)
				(arc
					(start 350.764348 -42.240962)
					(mid 350.378522 -42.627169)
					(end 350.764602 -43.013122)
				)
			)
		)
		(polygon
			(pts
				(xy 247.733312 1.005332) (xy 226.54641 1.005332) (xy 213.7537 -11.787378) (xy 213.7537 -80.693006)
				(xy 208.175606 -86.2711) (xy 187.982606 -86.2711) (xy 183.1721 -91.081606) (xy 183.1721 -130.27152)
				(xy 181.847998 -131.595622) (xy 159.407098 -131.595622) (xy 158.68396 -132.31876) (xy 158.68396 -155.833064)
				(xy 159.475932 -156.625036) (xy 174.099474 -156.625036) (xy 174.552356 -156.172154) (xy 174.552356 -149.995636)
				(xy 175.30064 -149.247352) (xy 182.823866 -149.247352) (xy 183.175402 -149.598888) (xy 183.175402 -155.948634)
				(xy 183.851804 -156.625036) (xy 209.619342 -156.625036) (xy 211.8741 -158.879794) (xy 211.8741 -190.553594)
				(xy 219.351606 -198.0311) (xy 246.077994 -198.0311) (xy 249.5677 -194.541394) (xy 249.5677 -0.829056)
			)
		)
		(polygon
			(pts
				(xy 292.432994 6.4897) (xy 266.570206 6.4897) (xy 262.6487 2.568194) (xy 262.6487 -193.220594) (xy 267.637006 -198.2089)
				(xy 293.931594 -198.2089) (xy 297.5991 -194.541394) (xy 297.5991 -175.135794) (xy 326.214994 -146.5199)
				(xy 351.489772 -146.5199) (xy 353.487228 -144.522444) (xy 353.487228 -122.458734) (xy 350.090994 -119.0625)
				(xy 326.545194 -119.0625) (xy 296.9641 -89.481406) (xy 296.9641 1.958594)
			)
		)
	)
	(zone
		(net "GND")
		(layer "In5.Cu")
		(hatch none 0.5)
		(connect_pads
			(clearance 0.5)
		)
		(min_thickness 0.25)
		(fill yes
			(thermal_gap 0.5)
			(thermal_bridge_width 0.5)
			(island_removal_mode 0)
		)
		(polygon
			(pts
				(xy 276.05101 -291.763958) (xy 275.578062 -292.236906) (xy 275.578062 -359.846118) (xy 275.854668 -360.122724)
				(xy 294.429942 -360.122724) (xy 294.429942 -350.39046) (xy 293.525194 -350.39046) (xy 291.022024 -347.88729)
				(xy 291.022024 -292.236398) (xy 290.549584 -291.763958)
			)
		)
		(polygon
			(pts
				(arc
					(start 280.636726 -358.253792)
					(mid 281.185366 -357.705152)
					(end 280.636726 -357.156512)
				)
				(arc
					(start 279.236678 -357.156512)
					(mid 278.688038 -357.705152)
					(end 279.236678 -358.253792)
				)
			)
		)
		(polygon
			(pts
				(arc
					(start 287.83661 -358.256332)
					(mid 288.38779 -357.705152)
					(end 287.83661 -357.153972)
				)
				(arc
					(start 286.436562 -357.153972)
					(mid 285.885382 -357.705152)
					(end 286.436562 -358.256332)
				)
			)
		)
		(polygon
			(pts
				(arc
					(start 279.636728 -356.453694)
					(mid 280.185368 -355.905054)
					(end 279.636728 -355.356414)
				)
				(arc
					(start 278.23668 -355.356414)
					(mid 277.68804 -355.905054)
					(end 278.23668 -356.453694)
				)
			)
		)
		(polygon
			(pts
				(arc
					(start 286.836612 -356.456234)
					(mid 287.387792 -355.905054)
					(end 286.836612 -355.353874)
				)
				(arc
					(start 285.436564 -355.353874)
					(mid 284.885384 -355.905054)
					(end 285.436564 -356.456234)
				)
			)
		)
		(polygon
			(pts
				(arc
					(start 280.636726 -354.65385)
					(mid 281.185366 -354.10521)
					(end 280.636726 -353.55657)
				)
				(arc
					(start 279.236678 -353.55657)
					(mid 278.688038 -354.10521)
					(end 279.236678 -354.65385)
				)
			)
		)
		(polygon
			(pts
				(arc
					(start 287.83661 -354.65639)
					(mid 288.38779 -354.10521)
					(end 287.83661 -353.55403)
				)
				(arc
					(start 286.436562 -353.55403)
					(mid 285.885382 -354.10521)
					(end 286.436562 -354.65639)
				)
			)
		)
		(polygon
			(pts
				(arc
					(start 279.636728 -352.853752)
					(mid 280.185368 -352.305112)
					(end 279.636728 -351.756472)
				)
				(arc
					(start 278.23668 -351.756472)
					(mid 277.68804 -352.305112)
					(end 278.23668 -352.853752)
				)
			)
		)
		(polygon
			(pts
				(arc
					(start 286.836612 -352.856292)
					(mid 287.387792 -352.305112)
					(end 286.836612 -351.753932)
				)
				(arc
					(start 285.436564 -351.753932)
					(mid 284.885384 -352.305112)
					(end 285.436564 -352.856292)
				)
			)
		)
		(polygon
			(pts
				(arc
					(start 280.636726 -351.053908)
					(mid 281.185366 -350.505268)
					(end 280.636726 -349.956628)
				)
				(arc
					(start 279.236678 -349.956628)
					(mid 278.688038 -350.505268)
					(end 279.236678 -351.053908)
				)
			)
		)
		(polygon
			(pts
				(arc
					(start 287.83661 -351.056448)
					(mid 288.38779 -350.505268)
					(end 287.83661 -349.954088)
				)
				(arc
					(start 286.436562 -349.954088)
					(mid 285.885382 -350.505268)
					(end 286.436562 -351.056448)
				)
			)
		)
		(polygon
			(pts
				(arc
					(start 279.636728 -349.25381)
					(mid 280.185368 -348.70517)
					(end 279.636728 -348.15653)
				)
				(arc
					(start 278.23668 -348.15653)
					(mid 277.68804 -348.70517)
					(end 278.23668 -349.25381)
				)
			)
		)
		(polygon
			(pts
				(arc
					(start 286.836612 -349.25635)
					(mid 287.387792 -348.70517)
					(end 286.836612 -348.15399)
				)
				(arc
					(start 285.436564 -348.15399)
					(mid 284.885384 -348.70517)
					(end 285.436564 -349.25635)
				)
			)
		)
		(polygon
			(pts
				(arc
					(start 287.83661 -347.453712)
					(mid 288.38525 -346.905072)
					(end 287.83661 -346.356432)
				)
				(arc
					(start 286.436562 -346.356432)
					(mid 285.887922 -346.905072)
					(end 286.436562 -347.453712)
				)
			)
		)
		(polygon
			(pts
				(arc
					(start 280.636726 -347.453712)
					(mid 281.185366 -346.905072)
					(end 280.636726 -346.356432)
				)
				(arc
					(start 279.236678 -346.356432)
					(mid 278.688038 -346.905072)
					(end 279.236678 -347.453712)
				)
			)
		)
		(polygon
			(pts
				(arc
					(start 286.836612 -345.653868)
					(mid 287.385252 -345.105228)
					(end 286.836612 -344.556588)
				)
				(arc
					(start 285.436564 -344.556588)
					(mid 284.887924 -345.105228)
					(end 285.436564 -345.653868)
				)
			)
		)
		(polygon
			(pts
				(arc
					(start 279.636728 -345.653868)
					(mid 280.185368 -345.105228)
					(end 279.636728 -344.556588)
				)
				(arc
					(start 278.23668 -344.556588)
					(mid 277.68804 -345.105228)
					(end 278.23668 -345.653868)
				)
			)
		)
		(polygon
			(pts
				(arc
					(start 287.83661 -343.85377)
					(mid 288.38525 -343.30513)
					(end 287.83661 -342.75649)
				)
				(arc
					(start 286.436562 -342.75649)
					(mid 285.887922 -343.30513)
					(end 286.436562 -343.85377)
				)
			)
		)
		(polygon
			(pts
				(arc
					(start 280.636726 -343.85377)
					(mid 281.185366 -343.30513)
					(end 280.636726 -342.75649)
				)
				(arc
					(start 279.236678 -342.75649)
					(mid 278.688038 -343.30513)
					(end 279.236678 -343.85377)
				)
			)
		)
		(polygon
			(pts
				(arc
					(start 286.836612 -342.053672)
					(mid 287.385252 -341.505032)
					(end 286.836612 -340.956392)
				)
				(arc
					(start 285.436564 -340.956392)
					(mid 284.887924 -341.505032)
					(end 285.436564 -342.053672)
				)
			)
		)
		(polygon
			(pts
				(arc
					(start 279.636728 -342.053672)
					(mid 280.185368 -341.505032)
					(end 279.636728 -340.956392)
				)
				(arc
					(start 278.23668 -340.956392)
					(mid 277.68804 -341.505032)
					(end 278.23668 -342.053672)
				)
			)
		)
		(polygon
			(pts
				(arc
					(start 287.83661 -340.253828)
					(mid 288.38525 -339.705188)
					(end 287.83661 -339.156548)
				)
				(arc
					(start 286.436562 -339.156548)
					(mid 285.887922 -339.705188)
					(end 286.436562 -340.253828)
				)
			)
		)
		(polygon
			(pts
				(arc
					(start 280.636726 -340.253828)
					(mid 281.185366 -339.705188)
					(end 280.636726 -339.156548)
				)
				(arc
					(start 279.236678 -339.156548)
					(mid 278.688038 -339.705188)
					(end 279.236678 -340.253828)
				)
			)
		)
		(polygon
			(pts
				(arc
					(start 286.836612 -338.45373)
					(mid 287.385252 -337.90509)
					(end 286.836612 -337.35645)
				)
				(arc
					(start 285.436564 -337.35645)
					(mid 284.887924 -337.90509)
					(end 285.436564 -338.45373)
				)
			)
		)
		(polygon
			(pts
				(arc
					(start 279.636728 -338.45373)
					(mid 280.185368 -337.90509)
					(end 279.636728 -337.35645)
				)
				(arc
					(start 278.23668 -337.35645)
					(mid 277.68804 -337.90509)
					(end 278.23668 -338.45373)
				)
			)
		)
		(polygon
			(pts
				(arc
					(start 280.636726 -336.653886)
					(mid 281.185366 -336.105246)
					(end 280.636726 -335.556606)
				)
				(arc
					(start 279.236678 -335.556606)
					(mid 278.688038 -336.105246)
					(end 279.236678 -336.653886)
				)
			)
		)
		(polygon
			(pts
				(arc
					(start 287.83661 -336.656426)
					(mid 288.38779 -336.105246)
					(end 287.83661 -335.554066)
				)
				(arc
					(start 286.436562 -335.554066)
					(mid 285.885382 -336.105246)
					(end 286.436562 -336.656426)
				)
			)
		)
		(polygon
			(pts
				(arc
					(start 279.636728 -334.853788)
					(mid 280.185368 -334.305148)
					(end 279.636728 -333.756508)
				)
				(arc
					(start 278.23668 -333.756508)
					(mid 277.68804 -334.305148)
					(end 278.23668 -334.853788)
				)
			)
		)
		(polygon
			(pts
				(arc
					(start 286.836612 -334.856328)
					(mid 287.387792 -334.305148)
					(end 286.836612 -333.753968)
				)
				(arc
					(start 285.436564 -333.753968)
					(mid 284.885384 -334.305148)
					(end 285.436564 -334.856328)
				)
			)
		)
		(polygon
			(pts
				(arc
					(start 280.636726 -333.05369)
					(mid 281.185366 -332.50505)
					(end 280.636726 -331.95641)
				)
				(arc
					(start 279.236678 -331.95641)
					(mid 278.688038 -332.50505)
					(end 279.236678 -333.05369)
				)
			)
		)
		(polygon
			(pts
				(arc
					(start 287.83661 -333.05623)
					(mid 288.38779 -332.50505)
					(end 287.83661 -331.95387)
				)
				(arc
					(start 286.436562 -331.95387)
					(mid 285.885382 -332.50505)
					(end 286.436562 -333.05623)
				)
			)
		)
		(polygon
			(pts
				(arc
					(start 279.636728 -331.253846)
					(mid 280.185368 -330.705206)
					(end 279.636728 -330.156566)
				)
				(arc
					(start 278.23668 -330.156566)
					(mid 277.68804 -330.705206)
					(end 278.23668 -331.253846)
				)
			)
		)
		(polygon
			(pts
				(arc
					(start 286.836612 -331.256386)
					(mid 287.387792 -330.705206)
					(end 286.836612 -330.154026)
				)
				(arc
					(start 285.436564 -330.154026)
					(mid 284.885384 -330.705206)
					(end 285.436564 -331.256386)
				)
			)
		)
		(polygon
			(pts
				(arc
					(start 280.636726 -329.453748)
					(mid 281.185366 -328.905108)
					(end 280.636726 -328.356468)
				)
				(arc
					(start 279.236678 -328.356468)
					(mid 278.688038 -328.905108)
					(end 279.236678 -329.453748)
				)
			)
		)
		(polygon
			(pts
				(arc
					(start 287.83661 -329.456288)
					(mid 288.38779 -328.905108)
					(end 287.83661 -328.353928)
				)
				(arc
					(start 286.436562 -328.353928)
					(mid 285.885382 -328.905108)
					(end 286.436562 -329.456288)
				)
			)
		)
		(polygon
			(pts
				(arc
					(start 279.636728 -327.653904)
					(mid 280.185368 -327.105264)
					(end 279.636728 -326.556624)
				)
				(arc
					(start 278.23668 -326.556624)
					(mid 277.68804 -327.105264)
					(end 278.23668 -327.653904)
				)
			)
		)
		(polygon
			(pts
				(arc
					(start 286.836612 -327.656444)
					(mid 287.387792 -327.105264)
					(end 286.836612 -326.554084)
				)
				(arc
					(start 285.436564 -326.554084)
					(mid 284.885384 -327.105264)
					(end 285.436564 -327.656444)
				)
			)
		)
		(polygon
			(pts
				(arc
					(start 287.83661 -325.853806)
					(mid 288.38525 -325.305166)
					(end 287.83661 -324.756526)
				)
				(arc
					(start 286.436562 -324.756526)
					(mid 285.887922 -325.305166)
					(end 286.436562 -325.853806)
				)
			)
		)
		(polygon
			(pts
				(arc
					(start 280.636726 -325.853806)
					(mid 281.185366 -325.305166)
					(end 280.636726 -324.756526)
				)
				(arc
					(start 279.236678 -324.756526)
					(mid 278.688038 -325.305166)
					(end 279.236678 -325.853806)
				)
			)
		)
		(polygon
			(pts
				(arc
					(start 286.836612 -324.053708)
					(mid 287.385252 -323.505068)
					(end 286.836612 -322.956428)
				)
				(arc
					(start 285.436564 -322.956428)
					(mid 284.887924 -323.505068)
					(end 285.436564 -324.053708)
				)
			)
		)
		(polygon
			(pts
				(arc
					(start 279.636728 -324.053708)
					(mid 280.185368 -323.505068)
					(end 279.636728 -322.956428)
				)
				(arc
					(start 278.23668 -322.956428)
					(mid 277.68804 -323.505068)
					(end 278.23668 -324.053708)
				)
			)
		)
		(polygon
			(pts
				(arc
					(start 287.83661 -322.253864)
					(mid 288.38525 -321.705224)
					(end 287.83661 -321.156584)
				)
				(arc
					(start 286.436562 -321.156584)
					(mid 285.887922 -321.705224)
					(end 286.436562 -322.253864)
				)
			)
		)
		(polygon
			(pts
				(arc
					(start 280.636726 -322.253864)
					(mid 281.185366 -321.705224)
					(end 280.636726 -321.156584)
				)
				(arc
					(start 279.236678 -321.156584)
					(mid 278.688038 -321.705224)
					(end 279.236678 -322.253864)
				)
			)
		)
		(polygon
			(pts
				(arc
					(start 286.836612 -320.453766)
					(mid 287.385252 -319.905126)
					(end 286.836612 -319.356486)
				)
				(arc
					(start 285.436564 -319.356486)
					(mid 284.887924 -319.905126)
					(end 285.436564 -320.453766)
				)
			)
		)
		(polygon
			(pts
				(arc
					(start 279.636728 -320.453766)
					(mid 280.185368 -319.905126)
					(end 279.636728 -319.356486)
				)
				(arc
					(start 278.23668 -319.356486)
					(mid 277.68804 -319.905126)
					(end 278.23668 -320.453766)
				)
			)
		)
		(polygon
			(pts
				(arc
					(start 287.83661 -318.653668)
					(mid 288.38525 -318.105028)
					(end 287.83661 -317.556388)
				)
				(arc
					(start 286.436562 -317.556388)
					(mid 285.887922 -318.105028)
					(end 286.436562 -318.653668)
				)
			)
		)
		(polygon
			(pts
				(arc
					(start 280.636726 -318.653668)
					(mid 281.185366 -318.105028)
					(end 280.636726 -317.556388)
				)
				(arc
					(start 279.236678 -317.556388)
					(mid 278.688038 -318.105028)
					(end 279.236678 -318.653668)
				)
			)
		)
		(polygon
			(pts
				(arc
					(start 286.836612 -316.853824)
					(mid 287.385252 -316.305184)
					(end 286.836612 -315.756544)
				)
				(arc
					(start 285.436564 -315.756544)
					(mid 284.887924 -316.305184)
					(end 285.436564 -316.853824)
				)
			)
		)
		(polygon
			(pts
				(arc
					(start 279.636728 -316.853824)
					(mid 280.185368 -316.305184)
					(end 279.636728 -315.756544)
				)
				(arc
					(start 278.23668 -315.756544)
					(mid 277.68804 -316.305184)
					(end 278.23668 -316.853824)
				)
			)
		)
		(polygon
			(pts
				(arc
					(start 280.636726 -315.053726)
					(mid 281.185366 -314.505086)
					(end 280.636726 -313.956446)
				)
				(arc
					(start 279.236678 -313.956446)
					(mid 278.688038 -314.505086)
					(end 279.236678 -315.053726)
				)
			)
		)
		(polygon
			(pts
				(arc
					(start 287.83661 -315.056266)
					(mid 288.38779 -314.505086)
					(end 287.83661 -313.953906)
				)
				(arc
					(start 286.436562 -313.953906)
					(mid 285.885382 -314.505086)
					(end 286.436562 -315.056266)
				)
			)
		)
		(polygon
			(pts
				(arc
					(start 279.636728 -313.253882)
					(mid 280.185368 -312.705242)
					(end 279.636728 -312.156602)
				)
				(arc
					(start 278.23668 -312.156602)
					(mid 277.68804 -312.705242)
					(end 278.23668 -313.253882)
				)
			)
		)
		(polygon
			(pts
				(arc
					(start 286.836612 -313.256422)
					(mid 287.387792 -312.705242)
					(end 286.836612 -312.154062)
				)
				(arc
					(start 285.436564 -312.154062)
					(mid 284.885384 -312.705242)
					(end 285.436564 -313.256422)
				)
			)
		)
		(polygon
			(pts
				(arc
					(start 280.636726 -311.453784)
					(mid 281.185366 -310.905144)
					(end 280.636726 -310.356504)
				)
				(arc
					(start 279.236678 -310.356504)
					(mid 278.688038 -310.905144)
					(end 279.236678 -311.453784)
				)
			)
		)
		(polygon
			(pts
				(arc
					(start 287.83661 -311.456324)
					(mid 288.38779 -310.905144)
					(end 287.83661 -310.353964)
				)
				(arc
					(start 286.436562 -310.353964)
					(mid 285.885382 -310.905144)
					(end 286.436562 -311.456324)
				)
			)
		)
		(polygon
			(pts
				(arc
					(start 279.636728 -309.653686)
					(mid 280.185368 -309.105046)
					(end 279.636728 -308.556406)
				)
				(arc
					(start 278.23668 -308.556406)
					(mid 277.68804 -309.105046)
					(end 278.23668 -309.653686)
				)
			)
		)
		(polygon
			(pts
				(arc
					(start 286.836612 -309.656226)
					(mid 287.387792 -309.105046)
					(end 286.836612 -308.553866)
				)
				(arc
					(start 285.436564 -308.553866)
					(mid 284.885384 -309.105046)
					(end 285.436564 -309.656226)
				)
			)
		)
		(polygon
			(pts
				(arc
					(start 280.636726 -307.853842)
					(mid 281.185366 -307.305202)
					(end 280.636726 -306.756562)
				)
				(arc
					(start 279.236678 -306.756562)
					(mid 278.688038 -307.305202)
					(end 279.236678 -307.853842)
				)
			)
		)
		(polygon
			(pts
				(arc
					(start 287.83661 -307.856382)
					(mid 288.38779 -307.305202)
					(end 287.83661 -306.754022)
				)
				(arc
					(start 286.436562 -306.754022)
					(mid 285.885382 -307.305202)
					(end 286.436562 -307.856382)
				)
			)
		)
		(polygon
			(pts
				(arc
					(start 279.636728 -306.053744)
					(mid 280.185368 -305.505104)
					(end 279.636728 -304.956464)
				)
				(arc
					(start 278.23668 -304.956464)
					(mid 277.68804 -305.505104)
					(end 278.23668 -306.053744)
				)
			)
		)
		(polygon
			(pts
				(arc
					(start 286.836612 -306.056284)
					(mid 287.387792 -305.505104)
					(end 286.836612 -304.953924)
				)
				(arc
					(start 285.436564 -304.953924)
					(mid 284.885384 -305.505104)
					(end 285.436564 -306.056284)
				)
			)
		)
		(polygon
			(pts
				(arc
					(start 287.83661 -304.2539)
					(mid 288.38525 -303.70526)
					(end 287.83661 -303.15662)
				)
				(arc
					(start 286.436562 -303.15662)
					(mid 285.887922 -303.70526)
					(end 286.436562 -304.2539)
				)
			)
		)
		(polygon
			(pts
				(arc
					(start 280.636726 -304.2539)
					(mid 281.185366 -303.70526)
					(end 280.636726 -303.15662)
				)
				(arc
					(start 279.236678 -303.15662)
					(mid 278.688038 -303.70526)
					(end 279.236678 -304.2539)
				)
			)
		)
		(polygon
			(pts
				(arc
					(start 286.836612 -302.453802)
					(mid 287.385252 -301.905162)
					(end 286.836612 -301.356522)
				)
				(arc
					(start 285.436564 -301.356522)
					(mid 284.887924 -301.905162)
					(end 285.436564 -302.453802)
				)
			)
		)
		(polygon
			(pts
				(arc
					(start 279.636728 -302.453802)
					(mid 280.185368 -301.905162)
					(end 279.636728 -301.356522)
				)
				(arc
					(start 278.23668 -301.356522)
					(mid 277.68804 -301.905162)
					(end 278.23668 -302.453802)
				)
			)
		)
		(polygon
			(pts
				(arc
					(start 287.83661 -300.653704)
					(mid 288.38525 -300.105064)
					(end 287.83661 -299.556424)
				)
				(arc
					(start 286.436562 -299.556424)
					(mid 285.887922 -300.105064)
					(end 286.436562 -300.653704)
				)
			)
		)
		(polygon
			(pts
				(arc
					(start 280.636726 -300.653704)
					(mid 281.185366 -300.105064)
					(end 280.636726 -299.556424)
				)
				(arc
					(start 279.236678 -299.556424)
					(mid 278.688038 -300.105064)
					(end 279.236678 -300.653704)
				)
			)
		)
		(polygon
			(pts
				(arc
					(start 286.836612 -298.85386)
					(mid 287.385252 -298.30522)
					(end 286.836612 -297.75658)
				)
				(arc
					(start 285.436564 -297.75658)
					(mid 284.887924 -298.30522)
					(end 285.436564 -298.85386)
				)
			)
		)
		(polygon
			(pts
				(arc
					(start 279.636728 -298.85386)
					(mid 280.185368 -298.30522)
					(end 279.636728 -297.75658)
				)
				(arc
					(start 278.23668 -297.75658)
					(mid 277.68804 -298.30522)
					(end 278.23668 -298.85386)
				)
			)
		)
		(polygon
			(pts
				(arc
					(start 280.636726 -297.053762)
					(mid 281.185366 -296.505122)
					(end 280.636726 -295.956482)
				)
				(arc
					(start 279.236678 -295.956482)
					(mid 278.688038 -296.505122)
					(end 279.236678 -297.053762)
				)
			)
		)
		(polygon
			(pts
				(arc
					(start 287.83661 -297.056302)
					(mid 288.38779 -296.505122)
					(end 287.83661 -295.953942)
				)
				(arc
					(start 286.436562 -295.953942)
					(mid 285.885382 -296.505122)
					(end 286.436562 -297.056302)
				)
			)
		)
		(polygon
			(pts
				(arc
					(start 279.636728 -295.253918)
					(mid 280.185368 -294.705278)
					(end 279.636728 -294.156638)
				)
				(arc
					(start 278.23668 -294.156638)
					(mid 277.68804 -294.705278)
					(end 278.23668 -295.253918)
				)
			)
		)
		(polygon
			(pts
				(arc
					(start 286.836612 -295.256458)
					(mid 287.387792 -294.705278)
					(end 286.836612 -294.154098)
				)
				(arc
					(start 285.436564 -294.154098)
					(mid 284.885384 -294.705278)
					(end 285.436564 -295.256458)
				)
			)
		)
	)
	(zone
		(net "MB3_P12V_IN_R")
		(layer "In5.Cu")
		(hatch none 0.5)
		(connect_pads
			(clearance 0.5)
		)
		(min_thickness 0.25)
		(fill yes
			(thermal_gap 0.5)
			(thermal_bridge_width 0.5)
			(island_removal_mode 0)
		)
		(polygon
			(pts
				(xy 253.037594 -377.7615) (xy 252.4887 -378.310394) (xy 252.4887 -389.72109) (xy 252.97511 -390.2075)
				(xy 273.885406 -390.2075) (xy 274.4597 -389.633206)
				(arc
					(start 274.4597 -379.010672)
					(mid 274.45894 -378.993528)
					(end 274.4597 -378.976382)
				)
				(xy 274.4597 -378.056394) (xy 274.164806 -377.7615)
			)
		)
	)
	(zone
		(net "GND")
		(layer "In5.Cu")
		(hatch none 0.5)
		(connect_pads
			(clearance 0.5)
		)
		(min_thickness 0.25)
		(fill yes
			(thermal_gap 0.5)
			(thermal_bridge_width 0.5)
			(island_removal_mode 0)
		)
		(polygon
			(pts
				(xy 242.242086 -101.68128) (xy 241.193828 -102.729538) (xy 237.399576 -102.729538) (xy 236.403134 -101.733096)
				(xy 235.552996 -101.733096) (xy 234.738418 -102.547674) (xy 234.738418 -180.898292) (xy 235.144818 -181.304692)
				(xy 235.854748 -181.304692) (xy 237.221014 -179.938426) (xy 238.317024 -179.938426) (xy 238.396018 -179.938426)
				(xy 241.900456 -183.442864) (xy 244.244114 -183.442864) (xy 244.7798 -182.907178) (xy 244.7798 -103.005636)
				(xy 243.455444 -101.68128)
			)
		)
		(polygon
			(pts
				(arc
					(start 240.871756 -178.87696)
					(mid 239.92498 -179.182145)
					(end 240.236502 -180.126894)
				)
				(arc
					(start 242.236498 -181.126892)
					(mid 243.17706 -180.813202)
					(end 242.86337 -179.87264)
				)
			)
		)
		(polygon
			(pts
				(arc
					(start 238.374936 -178.149504)
					(mid 238.699802 -177.174906)
					(end 237.725204 -176.85004)
				)
				(xy 237.723934 -176.847754) (xy 235.724192 -177.847752) (xy 235.724192 -177.848006)
				(arc
					(start 235.725208 -177.850038)
					(mid 235.400342 -178.824636)
					(end 236.37494 -179.149502)
				)
				(xy 236.37621 -179.151788) (xy 238.376206 -178.15179)
			)
		)
		(polygon
			(pts
				(arc
					(start 240.871756 -174.876968)
					(mid 239.92498 -175.182153)
					(end 240.236502 -176.126902)
				)
				(arc
					(start 242.236498 -177.1269)
					(mid 243.17706 -176.81321)
					(end 242.86337 -175.872648)
				)
			)
		)
		(polygon
			(pts
				(arc
					(start 238.374936 -174.149512)
					(mid 238.699802 -173.174914)
					(end 237.725204 -172.850048)
				)
				(xy 237.723934 -172.847762) (xy 235.724192 -173.84776) (xy 235.724192 -173.848014)
				(arc
					(start 235.725208 -173.850046)
					(mid 235.400342 -174.824644)
					(end 236.37494 -175.14951)
				)
				(xy 236.37621 -175.151796) (xy 238.376206 -174.151798)
			)
		)
		(polygon
			(pts
				(arc
					(start 240.871756 -170.876976)
					(mid 239.92498 -171.182161)
					(end 240.236502 -172.12691)
				)
				(arc
					(start 242.236498 -173.126908)
					(mid 243.17706 -172.813218)
					(end 242.86337 -171.872656)
				)
			)
		)
		(polygon
			(pts
				(arc
					(start 238.374936 -170.14952)
					(mid 238.699802 -169.174922)
					(end 237.725204 -168.850056)
				)
				(xy 237.723934 -168.84777) (xy 235.724192 -169.847768) (xy 235.724192 -169.848022)
				(arc
					(start 235.725208 -169.850054)
					(mid 235.400342 -170.824652)
					(end 236.37494 -171.149518)
				)
				(xy 236.37621 -171.151804) (xy 238.376206 -170.151806)
			)
		)
		(polygon
			(pts
				(arc
					(start 240.871756 -166.876984)
					(mid 239.92498 -167.182169)
					(end 240.236502 -168.126918)
				)
				(arc
					(start 242.236498 -169.126916)
					(mid 243.17706 -168.813226)
					(end 242.86337 -167.872664)
				)
			)
		)
		(polygon
			(pts
				(arc
					(start 238.374936 -166.149528)
					(mid 238.699802 -165.17493)
					(end 237.725204 -164.850064)
				)
				(xy 237.723934 -164.847778) (xy 235.724192 -165.847776) (xy 235.724192 -165.84803)
				(arc
					(start 235.725208 -165.850062)
					(mid 235.400342 -166.82466)
					(end 236.37494 -167.149526)
				)
				(xy 236.37621 -167.151812) (xy 238.376206 -166.151814)
			)
		)
		(polygon
			(pts
				(arc
					(start 240.877344 -162.845496)
					(mid 239.895939 -163.172546)
					(end 240.222786 -164.154104)
				)
				(arc
					(start 242.222782 -165.154102)
					(mid 243.204238 -164.82695)
					(end 242.877086 -163.845494)
				)
			)
		)
		(polygon
			(pts
				(arc
					(start 238.377222 -162.154108)
					(mid 238.704374 -161.172652)
					(end 237.722918 -160.8455)
				)
				(arc
					(start 235.733844 -161.840164)
					(mid 235.393447 -162.821194)
					(end 236.377226 -163.154106)
				)
			)
		)
		(polygon
			(pts
				(arc
					(start 240.87709 -158.845504)
					(mid 239.895634 -159.172656)
					(end 240.222786 -160.154112)
				)
				(arc
					(start 242.222528 -161.15411)
					(mid 243.204289 -160.82711)
					(end 242.877086 -159.845502)
				)
			)
		)
		(polygon
			(pts
				(arc
					(start 238.377222 -158.154116)
					(mid 238.704374 -157.17266)
					(end 237.722918 -156.845508)
				)
				(arc
					(start 235.733844 -157.840172)
					(mid 235.393447 -158.821202)
					(end 236.377226 -159.154114)
				)
			)
		)
		(polygon
			(pts
				(arc
					(start 240.87709 -154.845512)
					(mid 239.895634 -155.172664)
					(end 240.222786 -156.15412)
				)
				(arc
					(start 242.222528 -157.154118)
					(mid 243.204289 -156.827118)
					(end 242.877086 -155.84551)
				)
			)
		)
		(polygon
			(pts
				(arc
					(start 238.377222 -154.154124)
					(mid 238.704374 -153.172668)
					(end 237.722918 -152.845516)
				)
				(arc
					(start 235.733844 -153.84018)
					(mid 235.393447 -154.82121)
					(end 236.377226 -155.154122)
				)
			)
		)
		(polygon
			(pts
				(arc
					(start 240.877344 -150.84552)
					(mid 239.895939 -151.17257)
					(end 240.222786 -152.154128)
				)
				(arc
					(start 242.222782 -153.154126)
					(mid 243.204238 -152.826974)
					(end 242.877086 -151.845518)
				)
			)
		)
		(polygon
			(pts
				(arc
					(start 238.377222 -150.154132)
					(mid 238.704374 -149.172676)
					(end 237.722918 -148.845524)
				)
				(arc
					(start 235.733844 -149.840188)
					(mid 235.393447 -150.821218)
					(end 236.377226 -151.15413)
				)
			)
		)
		(polygon
			(pts
				(arc
					(start 238.374936 -138.149584)
					(mid 238.699802 -137.174986)
					(end 237.725204 -136.85012)
				)
				(xy 237.723934 -136.847834) (xy 235.724192 -137.847832) (xy 235.724192 -137.848086)
				(arc
					(start 235.725208 -137.850118)
					(mid 235.400342 -138.824716)
					(end 236.37494 -139.149582)
				)
				(xy 236.37621 -139.151868) (xy 238.376206 -138.15187)
			)
		)
		(polygon
			(pts
				(arc
					(start 240.874804 -134.850124)
					(mid 239.900206 -135.17499)
					(end 240.225072 -136.149588)
				)
				(xy 240.223802 -136.151874) (xy 242.223798 -137.151872) (xy 242.224052 -137.151618)
				(arc
					(start 242.225068 -137.149586)
					(mid 243.199666 -136.82472)
					(end 242.8748 -135.850122)
				)
				(xy 242.87607 -135.847836) (xy 240.876074 -134.847838)
			)
		)
		(polygon
			(pts
				(arc
					(start 238.377222 -130.154172)
					(mid 238.704374 -129.172716)
					(end 237.722918 -128.845564)
				)
				(arc
					(start 235.733844 -129.840228)
					(mid 235.393447 -130.821258)
					(end 236.377226 -131.15417)
				)
			)
		)
		(polygon
			(pts
				(arc
					(start 240.891822 -126.844552)
					(mid 239.891674 -127.163691)
					(end 240.219484 -128.161034)
				)
				(arc
					(start 242.21948 -129.161032)
					(mid 243.211096 -128.830324)
					(end 242.880388 -127.838708)
				)
			)
		)
		(polygon
			(pts
				(arc
					(start 238.377222 -126.15418)
					(mid 238.704374 -125.172724)
					(end 237.722918 -124.845572)
				)
				(arc
					(start 235.733844 -125.840236)
					(mid 235.393447 -126.821266)
					(end 236.377226 -127.154178)
				)
			)
		)
		(polygon
			(pts
				(arc
					(start 240.880392 -122.838718)
					(mid 239.888776 -123.169426)
					(end 240.219484 -124.161042)
				)
				(arc
					(start 242.20805 -125.155198)
					(mid 243.208198 -124.836059)
					(end 242.880388 -123.838716)
				)
			)
		)
		(polygon
			(pts
				(arc
					(start 238.3663 -122.159522)
					(mid 238.706697 -121.178492)
					(end 237.722918 -120.84558)
				)
				(arc
					(start 235.722922 -121.845578)
					(mid 235.39577 -122.827034)
					(end 236.377226 -123.154186)
				)
			)
		)
		(polygon
			(pts
				(arc
					(start 240.87709 -118.845584)
					(mid 239.895634 -119.172736)
					(end 240.222786 -120.154192)
				)
				(arc
					(start 242.222528 -121.15419)
					(mid 243.204289 -120.82719)
					(end 242.877086 -119.845582)
				)
			)
		)
		(polygon
			(pts
				(arc
					(start 238.377222 -118.154196)
					(mid 238.704374 -117.17274)
					(end 237.722918 -116.845588)
				)
				(arc
					(start 235.733844 -117.840252)
					(mid 235.393447 -118.821282)
					(end 236.377226 -119.154194)
				)
			)
		)
		(polygon
			(pts
				(arc
					(start 240.877344 -114.845592)
					(mid 239.895939 -115.172642)
					(end 240.222786 -116.1542)
				)
				(arc
					(start 242.222782 -117.154198)
					(mid 243.204238 -116.827046)
					(end 242.877086 -115.84559)
				)
			)
		)
		(polygon
			(pts
				(arc
					(start 238.377222 -114.154204)
					(mid 238.704374 -113.172748)
					(end 237.722918 -112.845596)
				)
				(arc
					(start 235.733844 -113.84026)
					(mid 235.393447 -114.82129)
					(end 236.377226 -115.154202)
				)
			)
		)
		(polygon
			(pts
				(arc
					(start 240.874804 -106.85018)
					(mid 239.900206 -107.175046)
					(end 240.225072 -108.149644)
				)
				(xy 240.223802 -108.15193) (xy 242.223798 -109.151928) (xy 242.224052 -109.151674)
				(arc
					(start 242.225068 -109.149642)
					(mid 243.199666 -108.824776)
					(end 242.8748 -107.850178)
				)
				(xy 242.87607 -107.847892) (xy 240.876074 -106.847894)
			)
		)
	)
	(zone
		(net "P12V_A_COMP")
		(layer "In5.Cu")
		(hatch none 0.5)
		(connect_pads
			(clearance 0.5)
		)
		(min_thickness 0.25)
		(fill yes
			(thermal_gap 0.5)
			(thermal_bridge_width 0.5)
			(island_removal_mode 0)
		)
		(polygon
			(pts
				(xy 226.704398 0.624332) (xy 214.1347 -11.945366) (xy 214.1347 -80.850994) (xy 208.333594 -86.6521)
				(xy 188.140594 -86.6521) (xy 183.5531 -91.239594) (xy 183.5531 -130.429508) (xy 182.005986 -131.976622)
				(xy 159.565086 -131.976622) (xy 159.06496 -132.476748) (xy 159.06496 -155.675076) (xy 159.63392 -156.244036)
				(xy 173.941486 -156.244036) (xy 174.171356 -156.014166) (xy 174.171356 -149.837648) (xy 175.142652 -148.866352)
				(xy 182.981854 -148.866352) (xy 183.556402 -149.4409) (xy 183.556402 -155.790646) (xy 184.009792 -156.244036)
				(xy 209.698336 -156.244036) (xy 209.77733 -156.244036) (xy 212.2551 -158.721806) (xy 212.2551 -190.395606)
				(xy 219.509594 -197.6501) (xy 245.920006 -197.6501) (xy 249.1867 -194.383406) (xy 249.1867 -0.987044)
				(xy 247.575324 0.624332)
			)
		)
		(polygon
			(pts
				(xy 243.613432 -101.30028) (xy 242.084098 -101.30028) (xy 241.03584 -102.348538) (xy 237.557564 -102.348538)
				(xy 236.561122 -101.352096) (xy 235.395008 -101.352096) (xy 234.357418 -102.389686) (xy 234.357418 -181.05628)
				(xy 234.413044 -181.111906) (xy 234.413298 -181.111906) (xy 234.98683 -181.685692) (xy 236.012736 -181.685692)
				(xy 237.379002 -180.319426) (xy 238.23803 -180.319426) (xy 241.742468 -183.823864) (xy 244.402102 -183.823864)
				(xy 245.1608 -183.065166) (xy 245.1608 -102.847648)
			)
		)
		(polygon
			(pts
				(xy 243.613432 -5.000498) (xy 242.084098 -5.000498) (xy 241.03584 -6.048756) (xy 237.557564 -6.048756)
				(xy 236.561122 -5.052314) (xy 235.395008 -5.052314) (xy 234.357418 -6.089904) (xy 234.357418 -84.756498)
				(xy 234.98683 -85.38591) (xy 236.012736 -85.38591) (xy 237.379002 -84.019644) (xy 238.23803 -84.019644)
				(xy 241.742468 -87.524082) (xy 244.402102 -87.524082) (xy 245.1608 -86.765384) (xy 245.1608 -6.547866)
			)
		)
	)
	(zone
		(net "GND")
		(layer "In5.Cu")
		(hatch none 0.5)
		(connect_pads
			(clearance 0.5)
		)
		(min_thickness 0.25)
		(fill yes
			(thermal_gap 0.5)
			(thermal_bridge_width 0.5)
			(island_removal_mode 0)
		)
		(polygon
			(pts
				(xy 284.942026 -101.68128) (xy 283.893768 -102.729538) (xy 280.099516 -102.729538) (xy 279.103074 -101.733096)
				(xy 278.252936 -101.733096) (xy 277.438358 -102.547674) (xy 277.438358 -180.898292) (xy 277.844758 -181.304692)
				(xy 278.554688 -181.304692) (xy 279.920954 -179.938426) (xy 281.095958 -179.938426) (xy 284.600396 -183.442864)
				(xy 286.944054 -183.442864) (xy 287.47974 -182.907178) (xy 287.47974 -103.005636) (xy 286.155384 -101.68128)
			)
		)
		(polygon
			(pts
				(arc
					(start 283.563314 -178.872642)
					(mid 282.622752 -179.186332)
					(end 282.936442 -180.126894)
				)
				(arc
					(start 284.928056 -181.122574)
					(mid 285.874832 -180.817389)
					(end 285.56331 -179.87264)
				)
			)
		)
		(polygon
			(pts
				(arc
					(start 281.074876 -178.149504)
					(mid 281.399742 -177.174906)
					(end 280.425144 -176.85004)
				)
				(xy 280.423874 -176.847754) (xy 278.424132 -177.847752) (xy 278.424132 -177.848006)
				(arc
					(start 278.425148 -177.850038)
					(mid 278.100282 -178.824636)
					(end 279.07488 -179.149502)
				)
				(xy 279.07615 -179.151788) (xy 281.076146 -178.15179)
			)
		)
		(polygon
			(pts
				(arc
					(start 283.563314 -174.87265)
					(mid 282.622752 -175.18634)
					(end 282.936442 -176.126902)
				)
				(arc
					(start 284.928056 -177.122582)
					(mid 285.874832 -176.817397)
					(end 285.56331 -175.872648)
				)
			)
		)
		(polygon
			(pts
				(arc
					(start 281.074876 -174.149512)
					(mid 281.399742 -173.174914)
					(end 280.425144 -172.850048)
				)
				(xy 280.423874 -172.847762) (xy 278.424132 -173.84776) (xy 278.424132 -173.848014)
				(arc
					(start 278.425148 -173.850046)
					(mid 278.100282 -174.824644)
					(end 279.07488 -175.14951)
				)
				(xy 279.07615 -175.151796) (xy 281.076146 -174.151798)
			)
		)
		(polygon
			(pts
				(arc
					(start 283.563314 -170.872658)
					(mid 282.622752 -171.186348)
					(end 282.936442 -172.12691)
				)
				(arc
					(start 284.928056 -173.12259)
					(mid 285.874832 -172.817405)
					(end 285.56331 -171.872656)
				)
			)
		)
		(polygon
			(pts
				(arc
					(start 281.074876 -170.14952)
					(mid 281.399742 -169.174922)
					(end 280.425144 -168.850056)
				)
				(xy 280.423874 -168.84777) (xy 278.424132 -169.847768) (xy 278.424132 -169.848022)
				(arc
					(start 278.425148 -169.850054)
					(mid 278.100282 -170.824652)
					(end 279.07488 -171.149518)
				)
				(xy 279.07615 -171.151804) (xy 281.076146 -170.151806)
			)
		)
		(polygon
			(pts
				(arc
					(start 283.563314 -166.872666)
					(mid 282.622752 -167.186356)
					(end 282.936442 -168.126918)
				)
				(arc
					(start 284.928056 -169.122598)
					(mid 285.874832 -168.817413)
					(end 285.56331 -167.872664)
				)
			)
		)
		(polygon
			(pts
				(arc
					(start 281.074876 -166.149528)
					(mid 281.399742 -165.17493)
					(end 280.425144 -164.850064)
				)
				(xy 280.423874 -164.847778) (xy 278.424132 -165.847776) (xy 278.424132 -165.84803)
				(arc
					(start 278.425148 -165.850062)
					(mid 278.100282 -166.82466)
					(end 279.07488 -167.149526)
				)
				(xy 279.07615 -167.151812) (xy 281.076146 -166.151814)
			)
		)
		(polygon
			(pts
				(arc
					(start 283.563314 -162.872674)
					(mid 282.622752 -163.186364)
					(end 282.936442 -164.126926)
				)
				(arc
					(start 284.928056 -165.122606)
					(mid 285.874832 -164.817421)
					(end 285.56331 -163.872672)
				)
			)
		)
		(polygon
			(pts
				(arc
					(start 281.07386 -162.14725)
					(mid 281.397456 -161.175954)
					(end 280.42616 -160.852358)
				)
				(xy 278.426418 -161.852102)
				(arc
					(start 278.426418 -161.852356)
					(mid 278.102619 -162.8235)
					(end 279.073864 -163.147248)
				)
			)
		)
		(polygon
			(pts
				(arc
					(start 283.571696 -158.877)
					(mid 282.62492 -159.182185)
					(end 282.936442 -160.126934)
				)
				(arc
					(start 284.936438 -161.126932)
					(mid 285.877 -160.813242)
					(end 285.56331 -159.87268)
				)
			)
		)
		(polygon
			(pts
				(arc
					(start 281.07386 -158.147258)
					(mid 281.397456 -157.175962)
					(end 280.42616 -156.852366)
				)
				(xy 278.426418 -157.85211)
				(arc
					(start 278.426418 -157.852364)
					(mid 278.102619 -158.823508)
					(end 279.073864 -159.147256)
				)
			)
		)
		(polygon
			(pts
				(arc
					(start 283.563314 -154.87269)
					(mid 282.622752 -155.18638)
					(end 282.936442 -156.126942)
				)
				(arc
					(start 284.928056 -157.122622)
					(mid 285.874832 -156.817437)
					(end 285.56331 -155.872688)
				)
			)
		)
		(polygon
			(pts
				(arc
					(start 281.07386 -154.147266)
					(mid 281.397456 -153.17597)
					(end 280.42616 -152.852374)
				)
				(xy 278.426418 -153.852118)
				(arc
					(start 278.426418 -153.852372)
					(mid 278.102619 -154.823516)
					(end 279.073864 -155.147264)
				)
			)
		)
		(polygon
			(pts
				(arc
					(start 283.563314 -150.872698)
					(mid 282.622752 -151.186388)
					(end 282.936442 -152.12695)
				)
				(arc
					(start 284.928056 -153.12263)
					(mid 285.874832 -152.817445)
					(end 285.56331 -151.872696)
				)
			)
		)
		(polygon
			(pts
				(arc
					(start 281.07386 -150.147274)
					(mid 281.397456 -149.175978)
					(end 280.42616 -148.852382)
				)
				(xy 278.426418 -149.852126)
				(arc
					(start 278.426418 -149.85238)
					(mid 278.102619 -150.823524)
					(end 279.073864 -151.147272)
				)
			)
		)
		(polygon
			(pts
				(arc
					(start 281.074876 -138.149584)
					(mid 281.399742 -137.174986)
					(end 280.425144 -136.85012)
				)
				(xy 280.423874 -136.847834) (xy 278.424132 -137.847832) (xy 278.424132 -137.848086)
				(arc
					(start 278.425148 -137.850118)
					(mid 278.100282 -138.824716)
					(end 279.07488 -139.149582)
				)
				(xy 279.07615 -139.151868) (xy 281.076146 -138.15187)
			)
		)
		(polygon
			(pts
				(arc
					(start 283.574744 -134.850124)
					(mid 282.600146 -135.17499)
					(end 282.925012 -136.149588)
				)
				(xy 282.923742 -136.151874) (xy 284.923738 -137.151872) (xy 284.923992 -137.151618)
				(arc
					(start 284.925008 -137.149586)
					(mid 285.899606 -136.82472)
					(end 285.57474 -135.850122)
				)
				(xy 285.57601 -135.847836) (xy 283.576014 -134.847838)
			)
		)
		(polygon
			(pts
				(arc
					(start 281.07386 -130.147314)
					(mid 281.397456 -129.176018)
					(end 280.42616 -128.852422)
				)
				(xy 278.426418 -129.852166)
				(arc
					(start 278.426418 -129.85242)
					(mid 278.102619 -130.823564)
					(end 279.073864 -131.147312)
				)
			)
		)
		(polygon
			(pts
				(arc
					(start 283.563314 -126.872746)
					(mid 282.622752 -127.186436)
					(end 282.936442 -128.126998)
				)
				(arc
					(start 284.928056 -129.122678)
					(mid 285.874832 -128.817493)
					(end 285.56331 -127.872744)
				)
			)
		)
		(polygon
			(pts
				(arc
					(start 281.07386 -126.147322)
					(mid 281.397456 -125.176026)
					(end 280.42616 -124.85243)
				)
				(xy 278.426418 -125.852174)
				(arc
					(start 278.426418 -125.852428)
					(mid 278.102619 -126.823572)
					(end 279.073864 -127.14732)
				)
			)
		)
		(polygon
			(pts
				(arc
					(start 283.563314 -122.872754)
					(mid 282.622752 -123.186444)
					(end 282.936442 -124.127006)
				)
				(arc
					(start 284.928056 -125.122686)
					(mid 285.874832 -124.817501)
					(end 285.56331 -123.872752)
				)
			)
		)
		(polygon
			(pts
				(arc
					(start 281.07386 -122.14733)
					(mid 281.397456 -121.176034)
					(end 280.42616 -120.852438)
				)
				(xy 278.426418 -121.852182)
				(arc
					(start 278.426418 -121.852436)
					(mid 278.102619 -122.82358)
					(end 279.073864 -123.147328)
				)
			)
		)
		(polygon
			(pts
				(arc
					(start 283.563314 -118.872762)
					(mid 282.622752 -119.186452)
					(end 282.936442 -120.127014)
				)
				(arc
					(start 284.928056 -121.122694)
					(mid 285.874832 -120.817509)
					(end 285.56331 -119.87276)
				)
			)
		)
		(polygon
			(pts
				(arc
					(start 281.07386 -118.147338)
					(mid 281.397456 -117.176042)
					(end 280.42616 -116.852446)
				)
				(xy 278.426418 -117.85219)
				(arc
					(start 278.426418 -117.852444)
					(mid 278.102619 -118.823588)
					(end 279.073864 -119.147336)
				)
			)
		)
		(polygon
			(pts
				(arc
					(start 283.563314 -114.87277)
					(mid 282.622752 -115.18646)
					(end 282.936442 -116.127022)
				)
				(arc
					(start 284.928056 -117.122702)
					(mid 285.874832 -116.817517)
					(end 285.56331 -115.872768)
				)
			)
		)
		(polygon
			(pts
				(arc
					(start 281.063446 -114.127026)
					(mid 281.377136 -113.186464)
					(end 280.436574 -112.872774)
				)
				(arc
					(start 278.44496 -113.868708)
					(mid 278.120865 -114.809139)
					(end 279.06345 -115.127024)
				)
			)
		)
		(polygon
			(pts
				(arc
					(start 283.576014 -106.847894)
					(mid 282.59786 -107.173776)
					(end 282.923742 -108.15193)
				)
				(arc
					(start 284.923738 -109.151928)
					(mid 285.901892 -108.826046)
					(end 285.57601 -107.847892)
				)
			)
		)
	)
	(zone
		(net "GND")
		(layer "In5.Cu")
		(hatch none 0.5)
		(connect_pads
			(clearance 0.5)
		)
		(min_thickness 0.25)
		(fill yes
			(thermal_gap 0.5)
			(thermal_bridge_width 0.5)
			(island_removal_mode 0)
		)
		(polygon
			(pts
				(xy 274.587462 -248.97969) (xy 274.115022 -249.45213) (xy 274.115022 -263.507728) (xy 277.015194 -266.4079)
				(xy 290.56838 -266.4079) (xy 291.041328 -265.934952) (xy 291.041328 -249.696224) (xy 290.324794 -248.97969)
			)
		)
		(polygon
			(pts
				(arc
					(start 284.236668 -264.250932)
					(mid 284.785308 -263.702292)
					(end 284.236668 -263.153652)
				)
				(arc
					(start 282.83662 -263.153652)
					(mid 282.28798 -263.702292)
					(end 282.83662 -264.250932)
				)
			)
		)
		(polygon
			(pts
				(arc
					(start 287.83661 -264.253472)
					(mid 288.38779 -263.702292)
					(end 287.83661 -263.151112)
				)
				(arc
					(start 286.436562 -263.151112)
					(mid 285.885382 -263.702292)
					(end 286.436562 -264.253472)
				)
			)
		)
		(polygon
			(pts
				(arc
					(start 280.636726 -264.253472)
					(mid 281.187906 -263.702292)
					(end 280.636726 -263.151112)
				)
				(arc
					(start 279.236678 -263.151112)
					(mid 278.685498 -263.702292)
					(end 279.236678 -264.253472)
				)
			)
		)
		(polygon
			(pts
				(arc
					(start 286.836612 -262.453374)
					(mid 287.387792 -261.902194)
					(end 286.836612 -261.351014)
				)
				(arc
					(start 285.436564 -261.351014)
					(mid 284.885384 -261.902194)
					(end 285.436564 -262.453374)
				)
			)
		)
		(polygon
			(pts
				(arc
					(start 279.636728 -262.453374)
					(mid 280.187908 -261.902194)
					(end 279.636728 -261.351014)
				)
				(arc
					(start 278.23668 -261.351014)
					(mid 277.6855 -261.902194)
					(end 278.23668 -262.453374)
				)
			)
		)
		(polygon
			(pts
				(arc
					(start 287.83661 -260.65353)
					(mid 288.38779 -260.10235)
					(end 287.83661 -259.55117)
				)
				(arc
					(start 286.436562 -259.55117)
					(mid 285.885382 -260.10235)
					(end 286.436562 -260.65353)
				)
			)
		)
		(polygon
			(pts
				(arc
					(start 280.636726 -260.65353)
					(mid 281.187906 -260.10235)
					(end 280.636726 -259.55117)
				)
				(arc
					(start 279.236678 -259.55117)
					(mid 278.685498 -260.10235)
					(end 279.236678 -260.65353)
				)
			)
		)
		(polygon
			(pts
				(arc
					(start 286.836612 -258.853432)
					(mid 287.387792 -258.302252)
					(end 286.836612 -257.751072)
				)
				(arc
					(start 285.436564 -257.751072)
					(mid 284.885384 -258.302252)
					(end 285.436564 -258.853432)
				)
			)
		)
		(polygon
			(pts
				(arc
					(start 279.636728 -258.853432)
					(mid 280.187908 -258.302252)
					(end 279.636728 -257.751072)
				)
				(arc
					(start 278.23668 -257.751072)
					(mid 277.6855 -258.302252)
					(end 278.23668 -258.853432)
				)
			)
		)
		(polygon
			(pts
				(arc
					(start 287.83661 -257.053588)
					(mid 288.38779 -256.502408)
					(end 287.83661 -255.951228)
				)
				(arc
					(start 286.436562 -255.951228)
					(mid 285.885382 -256.502408)
					(end 286.436562 -257.053588)
				)
			)
		)
		(polygon
			(pts
				(arc
					(start 280.636726 -257.053588)
					(mid 281.187906 -256.502408)
					(end 280.636726 -255.951228)
				)
				(arc
					(start 279.236678 -255.951228)
					(mid 278.685498 -256.502408)
					(end 279.236678 -257.053588)
				)
			)
		)
		(polygon
			(pts
				(arc
					(start 286.836612 -255.25349)
					(mid 287.387792 -254.70231)
					(end 286.836612 -254.15113)
				)
				(arc
					(start 285.436564 -254.15113)
					(mid 284.885384 -254.70231)
					(end 285.436564 -255.25349)
				)
			)
		)
		(polygon
			(pts
				(arc
					(start 279.636728 -255.25349)
					(mid 280.187908 -254.70231)
					(end 279.636728 -254.15113)
				)
				(arc
					(start 278.23668 -254.15113)
					(mid 277.6855 -254.70231)
					(end 278.23668 -255.25349)
				)
			)
		)
		(polygon
			(pts
				(arc
					(start 287.83661 -253.453392)
					(mid 288.38779 -252.902212)
					(end 287.83661 -252.351032)
				)
				(arc
					(start 286.436562 -252.351032)
					(mid 285.885382 -252.902212)
					(end 286.436562 -253.453392)
				)
			)
		)
		(polygon
			(pts
				(arc
					(start 280.636726 -253.453392)
					(mid 281.187906 -252.902212)
					(end 280.636726 -252.351032)
				)
				(arc
					(start 279.236678 -252.351032)
					(mid 278.685498 -252.902212)
					(end 279.236678 -253.453392)
				)
			)
		)
		(polygon
			(pts
				(arc
					(start 286.836612 -251.653548)
					(mid 287.387792 -251.102368)
					(end 286.836612 -250.551188)
				)
				(arc
					(start 285.436564 -250.551188)
					(mid 284.885384 -251.102368)
					(end 285.436564 -251.653548)
				)
			)
		)
		(polygon
			(pts
				(arc
					(start 279.636728 -251.653548)
					(mid 280.187908 -251.102368)
					(end 279.636728 -250.551188)
				)
				(arc
					(start 278.23668 -250.551188)
					(mid 277.6855 -251.102368)
					(end 278.23668 -251.653548)
				)
			)
		)
	)
	(zone
		(net "GND")
		(layer "In5.Cu")
		(hatch none 0.5)
		(connect_pads
			(clearance 0.5)
		)
		(min_thickness 0.25)
		(fill yes
			(thermal_gap 0.5)
			(thermal_bridge_width 0.5)
			(island_removal_mode 0)
		)
		(polygon
			(pts
				(arc
					(start 395.13383 -16.265906)
					(mid 395.066931 -16.268928)
					(end 394.999972 -16.26997)
				)
				(xy 349.396304 -16.26997) (xy 349.396304 -35.359848) (xy 349.85452 -35.818064) (xy 394.688822 -35.818064)
				(xy 395.13383 -35.373056)
			)
		)
		(polygon
			(pts
				(arc
					(start 389.898636 -29.149802)
					(mid 389.349869 -28.601416)
					(end 388.801356 -29.150056)
				)
				(arc
					(start 388.801356 -30.550104)
					(mid 389.349996 -31.098744)
					(end 389.898636 -30.550104)
				)
			)
		)
		(polygon
			(pts
				(arc
					(start 368.30127 -29.150056)
					(mid 367.75009 -28.598876)
					(end 367.19891 -29.150056)
				)
				(arc
					(start 367.19891 -30.550358)
					(mid 367.750217 -31.101284)
					(end 368.30127 -30.550104)
				)
			)
		)
		(polygon
			(pts
				(arc
					(start 382.701292 -29.149802)
					(mid 382.149985 -28.598876)
					(end 381.598932 -29.150056)
				)
				(arc
					(start 381.598932 -30.550104)
					(mid 382.150112 -31.101284)
					(end 382.701292 -30.550104)
				)
			)
		)
		(polygon
			(pts
				(arc
					(start 362.89869 -28.149804)
					(mid 362.349923 -27.601418)
					(end 361.80141 -28.150058)
				)
				(arc
					(start 361.80141 -29.550106)
					(mid 362.35005 -30.098746)
					(end 362.89869 -29.550106)
				)
			)
		)
		(polygon
			(pts
				(arc
					(start 389.898636 -21.949918)
					(mid 389.349869 -21.401532)
					(end 388.801356 -21.950172)
				)
				(arc
					(start 388.801356 -23.35022)
					(mid 389.349996 -23.89886)
					(end 389.898636 -23.35022)
				)
			)
		)
		(polygon
			(pts
				(arc
					(start 386.298694 -21.949918)
					(mid 385.749927 -21.401532)
					(end 385.201414 -21.950172)
				)
				(arc
					(start 385.201414 -23.35022)
					(mid 385.750054 -23.89886)
					(end 386.298694 -23.35022)
				)
			)
		)
		(polygon
			(pts
				(arc
					(start 382.698752 -21.949918)
					(mid 382.149985 -21.401532)
					(end 381.601472 -21.950172)
				)
				(arc
					(start 381.601472 -23.35022)
					(mid 382.150112 -23.89886)
					(end 382.698752 -23.35022)
				)
			)
		)
		(polygon
			(pts
				(arc
					(start 379.098556 -21.949918)
					(mid 378.549789 -21.401532)
					(end 378.001276 -21.950172)
				)
				(arc
					(start 378.001276 -23.35022)
					(mid 378.549916 -23.89886)
					(end 379.098556 -23.35022)
				)
			)
		)
		(polygon
			(pts
				(arc
					(start 368.29873 -21.949918)
					(mid 367.749963 -21.401532)
					(end 367.20145 -21.950172)
				)
				(arc
					(start 367.20145 -23.35022)
					(mid 367.75009 -23.89886)
					(end 368.29873 -23.35022)
				)
			)
		)
		(polygon
			(pts
				(arc
					(start 364.698534 -21.949918)
					(mid 364.149767 -21.401532)
					(end 363.601254 -21.950172)
				)
				(arc
					(start 363.601254 -23.35022)
					(mid 364.149894 -23.89886)
					(end 364.698534 -23.35022)
				)
			)
		)
		(polygon
			(pts
				(arc
					(start 361.098592 -21.949918)
					(mid 360.549825 -21.401532)
					(end 360.001312 -21.950172)
				)
				(arc
					(start 360.001312 -23.35022)
					(mid 360.549952 -23.89886)
					(end 361.098592 -23.35022)
				)
			)
		)
		(polygon
			(pts
				(arc
					(start 357.49865 -21.949918)
					(mid 356.949883 -21.401532)
					(end 356.40137 -21.950172)
				)
				(arc
					(start 356.40137 -23.35022)
					(mid 356.95001 -23.89886)
					(end 357.49865 -23.35022)
				)
			)
		)
		(polygon
			(pts
				(arc
					(start 388.098538 -20.94992)
					(mid 387.549771 -20.401534)
					(end 387.001258 -20.950174)
				)
				(arc
					(start 387.001258 -22.350222)
					(mid 387.549898 -22.898862)
					(end 388.098538 -22.350222)
				)
			)
		)
		(polygon
			(pts
				(arc
					(start 384.498596 -20.94992)
					(mid 383.949829 -20.401534)
					(end 383.401316 -20.950174)
				)
				(arc
					(start 383.401316 -22.350222)
					(mid 383.949956 -22.898862)
					(end 384.498596 -22.350222)
				)
			)
		)
		(polygon
			(pts
				(arc
					(start 380.898654 -20.94992)
					(mid 380.349887 -20.401534)
					(end 379.801374 -20.950174)
				)
				(arc
					(start 379.801374 -22.350222)
					(mid 380.350014 -22.898862)
					(end 380.898654 -22.350222)
				)
			)
		)
		(polygon
			(pts
				(arc
					(start 377.298712 -20.94992)
					(mid 376.749945 -20.401534)
					(end 376.201432 -20.950174)
				)
				(arc
					(start 376.201432 -22.350222)
					(mid 376.750072 -22.898862)
					(end 377.298712 -22.350222)
				)
			)
		)
		(polygon
			(pts
				(arc
					(start 366.498632 -20.94992)
					(mid 365.949865 -20.401534)
					(end 365.401352 -20.950174)
				)
				(arc
					(start 365.401352 -22.350222)
					(mid 365.949992 -22.898862)
					(end 366.498632 -22.350222)
				)
			)
		)
		(polygon
			(pts
				(arc
					(start 362.89869 -20.94992)
					(mid 362.349923 -20.401534)
					(end 361.80141 -20.950174)
				)
				(arc
					(start 361.80141 -22.350222)
					(mid 362.35005 -22.898862)
					(end 362.89869 -22.350222)
				)
			)
		)
		(polygon
			(pts
				(arc
					(start 359.298748 -20.94992)
					(mid 358.749981 -20.401534)
					(end 358.201468 -20.950174)
				)
				(arc
					(start 358.201468 -22.350222)
					(mid 358.750108 -22.898862)
					(end 359.298748 -22.350222)
				)
			)
		)
		(polygon
			(pts
				(arc
					(start 355.698552 -20.94992)
					(mid 355.149785 -20.401534)
					(end 354.601272 -20.950174)
				)
				(arc
					(start 354.601272 -22.350222)
					(mid 355.149912 -22.898862)
					(end 355.698552 -22.350222)
				)
			)
		)
		(polygon
			(pts
				(arc
					(start 389.898636 -18.349976)
					(mid 389.349869 -17.80159)
					(end 388.801356 -18.35023)
				)
				(arc
					(start 388.801356 -19.750024)
					(mid 389.349996 -20.298664)
					(end 389.898636 -19.750024)
				)
			)
		)
		(polygon
			(pts
				(arc
					(start 386.298694 -18.349976)
					(mid 385.749927 -17.80159)
					(end 385.201414 -18.35023)
				)
				(arc
					(start 385.201414 -19.750024)
					(mid 385.750054 -20.298664)
					(end 386.298694 -19.750024)
				)
			)
		)
		(polygon
			(pts
				(arc
					(start 382.698752 -18.349976)
					(mid 382.149985 -17.80159)
					(end 381.601472 -18.35023)
				)
				(arc
					(start 381.601472 -19.750024)
					(mid 382.150112 -20.298664)
					(end 382.698752 -19.750024)
				)
			)
		)
		(polygon
			(pts
				(arc
					(start 379.098556 -18.349976)
					(mid 378.549789 -17.80159)
					(end 378.001276 -18.35023)
				)
				(arc
					(start 378.001276 -19.750024)
					(mid 378.549916 -20.298664)
					(end 379.098556 -19.750024)
				)
			)
		)
		(polygon
			(pts
				(arc
					(start 368.29873 -18.349976)
					(mid 367.749963 -17.80159)
					(end 367.20145 -18.35023)
				)
				(arc
					(start 367.20145 -19.750024)
					(mid 367.75009 -20.298664)
					(end 368.29873 -19.750024)
				)
			)
		)
		(polygon
			(pts
				(arc
					(start 364.698534 -18.349976)
					(mid 364.149767 -17.80159)
					(end 363.601254 -18.35023)
				)
				(arc
					(start 363.601254 -19.750024)
					(mid 364.149894 -20.298664)
					(end 364.698534 -19.750024)
				)
			)
		)
		(polygon
			(pts
				(arc
					(start 361.098592 -18.349976)
					(mid 360.549825 -17.80159)
					(end 360.001312 -18.35023)
				)
				(arc
					(start 360.001312 -19.750024)
					(mid 360.549952 -20.298664)
					(end 361.098592 -19.750024)
				)
			)
		)
		(polygon
			(pts
				(arc
					(start 357.49865 -18.349976)
					(mid 356.949883 -17.80159)
					(end 356.40137 -18.35023)
				)
				(arc
					(start 356.40137 -19.750024)
					(mid 356.95001 -20.298664)
					(end 357.49865 -19.750024)
				)
			)
		)
		(polygon
			(pts
				(arc
					(start 388.098538 -17.349724)
					(mid 387.549771 -16.801338)
					(end 387.001258 -17.349978)
				)
				(arc
					(start 387.001258 -18.750026)
					(mid 387.549898 -19.298666)
					(end 388.098538 -18.750026)
				)
			)
		)
		(polygon
			(pts
				(arc
					(start 384.498596 -17.349724)
					(mid 383.949829 -16.801338)
					(end 383.401316 -17.349978)
				)
				(arc
					(start 383.401316 -18.750026)
					(mid 383.949956 -19.298666)
					(end 384.498596 -18.750026)
				)
			)
		)
		(polygon
			(pts
				(arc
					(start 380.898654 -17.349724)
					(mid 380.349887 -16.801338)
					(end 379.801374 -17.349978)
				)
				(arc
					(start 379.801374 -18.750026)
					(mid 380.350014 -19.298666)
					(end 380.898654 -18.750026)
				)
			)
		)
		(polygon
			(pts
				(arc
					(start 377.298712 -17.349724)
					(mid 376.749945 -16.801338)
					(end 376.201432 -17.349978)
				)
				(arc
					(start 376.201432 -18.750026)
					(mid 376.750072 -19.298666)
					(end 377.298712 -18.750026)
				)
			)
		)
		(polygon
			(pts
				(arc
					(start 366.498632 -17.349724)
					(mid 365.949865 -16.801338)
					(end 365.401352 -17.349978)
				)
				(arc
					(start 365.401352 -18.750026)
					(mid 365.949992 -19.298666)
					(end 366.498632 -18.750026)
				)
			)
		)
		(polygon
			(pts
				(arc
					(start 362.89869 -17.349724)
					(mid 362.349923 -16.801338)
					(end 361.80141 -17.349978)
				)
				(arc
					(start 361.80141 -18.750026)
					(mid 362.35005 -19.298666)
					(end 362.89869 -18.750026)
				)
			)
		)
		(polygon
			(pts
				(arc
					(start 359.298748 -17.349724)
					(mid 358.749981 -16.801338)
					(end 358.201468 -17.349978)
				)
				(arc
					(start 358.201468 -18.750026)
					(mid 358.750108 -19.298666)
					(end 359.298748 -18.750026)
				)
			)
		)
		(polygon
			(pts
				(arc
					(start 355.698552 -17.349724)
					(mid 355.149785 -16.801338)
					(end 354.601272 -17.349978)
				)
				(arc
					(start 354.601272 -18.750026)
					(mid 355.149912 -19.298666)
					(end 355.698552 -18.750026)
				)
			)
		)
	)
	(zone
		(net "P12V_B_COMP")
		(layer "In5.Cu")
		(hatch none 0.5)
		(connect_pads
			(clearance 0.5)
		)
		(min_thickness 0.25)
		(fill yes
			(thermal_gap 0.5)
			(thermal_bridge_width 0.5)
			(island_removal_mode 0)
		)
		(polygon
			(pts
				(xy 266.728194 6.1087) (xy 263.0297 2.410206) (xy 263.0297 -193.062606) (xy 267.794994 -197.8279)
				(xy 293.773606 -197.8279) (xy 297.2181 -194.383406) (xy 297.2181 -174.977806) (xy 326.057006 -146.1389)
				(xy 351.331784 -146.1389) (xy 353.106228 -144.364456) (xy 353.106228 -122.616722) (xy 349.933006 -119.4435)
				(xy 326.387206 -119.4435) (xy 296.5831 -89.639394) (xy 296.5831 1.800606) (xy 292.275006 6.1087)
			)
		)
		(polygon
			(pts
				(xy 286.313372 -101.30028) (xy 284.784038 -101.30028) (xy 283.73578 -102.348538) (xy 280.257504 -102.348538)
				(xy 279.261062 -101.352096) (xy 278.094948 -101.352096) (xy 277.057358 -102.389686) (xy 277.057358 -181.05628)
				(xy 277.68677 -181.685692) (xy 278.712676 -181.685692) (xy 280.078942 -180.319426) (xy 280.93797 -180.319426)
				(xy 284.442408 -183.823864) (xy 287.102042 -183.823864) (xy 287.86074 -183.065166) (xy 287.86074 -102.847648)
			)
		)
		(polygon
			(pts
				(xy 286.313372 -5.000498) (xy 284.784038 -5.000498) (xy 283.73578 -6.048756) (xy 280.257504 -6.048756)
				(xy 279.261062 -5.052314) (xy 278.094948 -5.052314) (xy 277.057358 -6.089904) (xy 277.057358 -84.756498)
				(xy 277.68677 -85.38591) (xy 278.712676 -85.38591) (xy 280.078942 -84.019644) (xy 280.93797 -84.019644)
				(xy 284.442408 -87.524082) (xy 287.102042 -87.524082) (xy 287.86074 -86.765384) (xy 287.86074 -6.547866)
			)
		)
	)
	(zone
		(net "GND")
		(layer "In5.Cu")
		(hatch none 0.5)
		(connect_pads
			(clearance 0.5)
		)
		(min_thickness 0.25)
		(fill yes
			(thermal_gap 0.5)
			(thermal_bridge_width 0.5)
			(island_removal_mode 0)
		)
		(polygon
			(pts
				(xy 284.942026 -5.381498) (xy 283.893768 -6.429756) (xy 280.099516 -6.429756) (xy 279.103074 -5.433314)
				(xy 278.252936 -5.433314) (xy 277.438358 -6.247892) (xy 277.438358 -84.59851) (xy 277.844758 -85.00491)
				(xy 278.554688 -85.00491) (xy 279.920954 -83.638644) (xy 281.095958 -83.638644) (xy 284.600396 -87.143082)
				(xy 286.944054 -87.143082) (xy 287.47974 -86.607396) (xy 287.47974 -6.705854) (xy 286.155384 -5.381498)
			)
		)
		(polygon
			(pts
				(arc
					(start 283.563314 -82.57286)
					(mid 282.622752 -82.88655)
					(end 282.936442 -83.827112)
				)
				(arc
					(start 284.928056 -84.822792)
					(mid 285.874832 -84.517607)
					(end 285.56331 -83.572858)
				)
			)
		)
		(polygon
			(pts
				(arc
					(start 281.074876 -81.849722)
					(mid 281.399742 -80.875124)
					(end 280.425144 -80.550258)
				)
				(xy 280.423874 -80.547972) (xy 278.424132 -81.54797) (xy 278.424132 -81.548224)
				(arc
					(start 278.425148 -81.550256)
					(mid 278.100282 -82.524854)
					(end 279.07488 -82.84972)
				)
				(xy 279.07615 -82.852006) (xy 281.076146 -81.852008)
			)
		)
		(polygon
			(pts
				(arc
					(start 283.563314 -78.572868)
					(mid 282.622752 -78.886558)
					(end 282.936442 -79.82712)
				)
				(arc
					(start 284.928056 -80.8228)
					(mid 285.874832 -80.517615)
					(end 285.56331 -79.572866)
				)
			)
		)
		(polygon
			(pts
				(arc
					(start 281.074876 -77.84973)
					(mid 281.399742 -76.875132)
					(end 280.425144 -76.550266)
				)
				(xy 280.423874 -76.54798) (xy 278.424132 -77.547978) (xy 278.424132 -77.548232)
				(arc
					(start 278.425148 -77.550264)
					(mid 278.100282 -78.524862)
					(end 279.07488 -78.849728)
				)
				(xy 279.07615 -78.852014) (xy 281.076146 -77.852016)
			)
		)
		(polygon
			(pts
				(arc
					(start 283.563314 -74.572876)
					(mid 282.622752 -74.886566)
					(end 282.936442 -75.827128)
				)
				(arc
					(start 284.928056 -76.822808)
					(mid 285.874832 -76.517623)
					(end 285.56331 -75.572874)
				)
			)
		)
		(polygon
			(pts
				(arc
					(start 281.074876 -73.849738)
					(mid 281.399742 -72.87514)
					(end 280.425144 -72.550274)
				)
				(xy 280.423874 -72.547988) (xy 278.424132 -73.547986) (xy 278.424132 -73.54824)
				(arc
					(start 278.425148 -73.550272)
					(mid 278.100282 -74.52487)
					(end 279.07488 -74.849736)
				)
				(xy 279.07615 -74.852022) (xy 281.076146 -73.852024)
			)
		)
		(polygon
			(pts
				(arc
					(start 283.563314 -70.572884)
					(mid 282.622752 -70.886574)
					(end 282.936442 -71.827136)
				)
				(arc
					(start 284.928056 -72.822816)
					(mid 285.874832 -72.517631)
					(end 285.56331 -71.572882)
				)
			)
		)
		(polygon
			(pts
				(arc
					(start 281.074876 -69.849746)
					(mid 281.399742 -68.875148)
					(end 280.425144 -68.550282)
				)
				(xy 280.423874 -68.547996) (xy 278.424132 -69.547994) (xy 278.424132 -69.548248)
				(arc
					(start 278.425148 -69.55028)
					(mid 278.100282 -70.524878)
					(end 279.07488 -70.849744)
				)
				(xy 279.07615 -70.85203) (xy 281.076146 -69.852032)
			)
		)
		(polygon
			(pts
				(arc
					(start 283.563314 -66.572892)
					(mid 282.622752 -66.886582)
					(end 282.936442 -67.827144)
				)
				(arc
					(start 284.928056 -68.822824)
					(mid 285.874832 -68.517639)
					(end 285.56331 -67.57289)
				)
			)
		)
		(polygon
			(pts
				(arc
					(start 281.074876 -65.849754)
					(mid 281.399742 -64.875156)
					(end 280.425144 -64.55029)
				)
				(xy 280.423874 -64.548004) (xy 278.424132 -65.548002) (xy 278.424132 -65.548256)
				(arc
					(start 278.425148 -65.550288)
					(mid 278.100282 -66.524886)
					(end 279.07488 -66.849752)
				)
				(xy 279.07615 -66.852038) (xy 281.076146 -65.85204)
			)
		)
		(polygon
			(pts
				(arc
					(start 283.563314 -62.5729)
					(mid 282.622752 -62.88659)
					(end 282.936442 -63.827152)
				)
				(arc
					(start 284.928056 -64.822832)
					(mid 285.874832 -64.517647)
					(end 285.56331 -63.572898)
				)
			)
		)
		(polygon
			(pts
				(arc
					(start 281.074876 -61.849762)
					(mid 281.399742 -60.875164)
					(end 280.425144 -60.550298)
				)
				(xy 280.423874 -60.548012) (xy 278.424132 -61.54801) (xy 278.424132 -61.548264)
				(arc
					(start 278.425148 -61.550296)
					(mid 278.100282 -62.524894)
					(end 279.07488 -62.84976)
				)
				(xy 279.07615 -62.852046) (xy 281.076146 -61.852048)
			)
		)
		(polygon
			(pts
				(arc
					(start 283.563314 -58.572908)
					(mid 282.622752 -58.886598)
					(end 282.936442 -59.82716)
				)
				(arc
					(start 284.928056 -60.82284)
					(mid 285.874832 -60.517655)
					(end 285.56331 -59.572906)
				)
			)
		)
		(polygon
			(pts
				(arc
					(start 281.074876 -57.84977)
					(mid 281.399742 -56.875172)
					(end 280.425144 -56.550306)
				)
				(xy 280.423874 -56.54802) (xy 278.424132 -57.548018) (xy 278.424132 -57.548272)
				(arc
					(start 278.425148 -57.550304)
					(mid 278.100282 -58.524902)
					(end 279.07488 -58.849768)
				)
				(xy 279.07615 -58.852054) (xy 281.076146 -57.852056)
			)
		)
		(polygon
			(pts
				(arc
					(start 283.563314 -54.572916)
					(mid 282.622752 -54.886606)
					(end 282.936442 -55.827168)
				)
				(arc
					(start 284.928056 -56.822848)
					(mid 285.874832 -56.517663)
					(end 285.56331 -55.572914)
				)
			)
		)
		(polygon
			(pts
				(arc
					(start 281.074876 -53.849778)
					(mid 281.399742 -52.87518)
					(end 280.425144 -52.550314)
				)
				(xy 280.423874 -52.548028) (xy 278.424132 -53.548026) (xy 278.424132 -53.54828)
				(arc
					(start 278.425148 -53.550312)
					(mid 278.100282 -54.52491)
					(end 279.07488 -54.849776)
				)
				(xy 279.07615 -54.852062) (xy 281.076146 -53.852064)
			)
		)
		(polygon
			(pts
				(arc
					(start 283.563314 -50.572924)
					(mid 282.622752 -50.886614)
					(end 282.936442 -51.827176)
				)
				(arc
					(start 284.928056 -52.822856)
					(mid 285.874832 -52.517671)
					(end 285.56331 -51.572922)
				)
			)
		)
		(polygon
			(pts
				(arc
					(start 281.074876 -49.849786)
					(mid 281.399742 -48.875188)
					(end 280.425144 -48.550322)
				)
				(xy 280.423874 -48.548036) (xy 278.424132 -49.548034) (xy 278.424132 -49.548288)
				(arc
					(start 278.425148 -49.55032)
					(mid 278.100282 -50.524918)
					(end 279.07488 -50.849784)
				)
				(xy 279.07615 -50.85207) (xy 281.076146 -49.852072)
			)
		)
		(polygon
			(pts
				(arc
					(start 283.563314 -46.572932)
					(mid 282.622752 -46.886622)
					(end 282.936442 -47.827184)
				)
				(arc
					(start 284.928056 -48.822864)
					(mid 285.874832 -48.517679)
					(end 285.56331 -47.57293)
				)
			)
		)
		(polygon
			(pts
				(arc
					(start 281.074876 -45.849794)
					(mid 281.399742 -44.875196)
					(end 280.425144 -44.55033)
				)
				(xy 280.423874 -44.548044) (xy 278.424132 -45.548042) (xy 278.424132 -45.548296)
				(arc
					(start 278.425148 -45.550328)
					(mid 278.100282 -46.524926)
					(end 279.07488 -46.849792)
				)
				(xy 279.07615 -46.852078) (xy 281.076146 -45.85208)
			)
		)
		(polygon
			(pts
				(arc
					(start 283.563314 -42.57294)
					(mid 282.622752 -42.88663)
					(end 282.936442 -43.827192)
				)
				(arc
					(start 284.928056 -44.822872)
					(mid 285.874832 -44.517687)
					(end 285.56331 -43.572938)
				)
			)
		)
		(polygon
			(pts
				(arc
					(start 281.074876 -41.849802)
					(mid 281.399742 -40.875204)
					(end 280.425144 -40.550338)
				)
				(xy 280.423874 -40.548052) (xy 278.424132 -41.54805) (xy 278.424132 -41.548304)
				(arc
					(start 278.425148 -41.550336)
					(mid 278.100282 -42.524934)
					(end 279.07488 -42.8498)
				)
				(xy 279.07615 -42.852086) (xy 281.076146 -41.852088)
			)
		)
		(polygon
			(pts
				(arc
					(start 283.563314 -38.572948)
					(mid 282.622752 -38.886638)
					(end 282.936442 -39.8272)
				)
				(arc
					(start 284.928056 -40.82288)
					(mid 285.874832 -40.517695)
					(end 285.56331 -39.572946)
				)
			)
		)
		(polygon
			(pts
				(arc
					(start 281.074876 -37.84981)
					(mid 281.399742 -36.875212)
					(end 280.425144 -36.550346)
				)
				(xy 280.423874 -36.54806) (xy 278.424132 -37.548058) (xy 278.424132 -37.548312)
				(arc
					(start 278.425148 -37.550344)
					(mid 278.100282 -38.524942)
					(end 279.07488 -38.849808)
				)
				(xy 279.07615 -38.852094) (xy 281.076146 -37.852096)
			)
		)
		(polygon
			(pts
				(arc
					(start 283.57703 -34.545778)
					(mid 282.595574 -34.87293)
					(end 282.922726 -35.854386)
				)
				(arc
					(start 284.922468 -36.854384)
					(mid 285.904229 -36.527384)
					(end 285.577026 -35.545776)
				)
			)
		)
		(polygon
			(pts
				(arc
					(start 281.074876 -17.84985)
					(mid 281.399742 -16.875252)
					(end 280.425144 -16.550386)
				)
				(xy 280.423874 -16.5481) (xy 278.424132 -17.548098) (xy 278.424132 -17.548352)
				(arc
					(start 278.425148 -17.550384)
					(mid 278.100282 -18.524982)
					(end 279.07488 -18.849848)
				)
				(xy 279.07615 -18.852134) (xy 281.076146 -17.852136)
			)
		)
		(polygon
			(pts
				(arc
					(start 281.077162 -11.854434)
					(mid 281.404314 -10.872978)
					(end 280.422858 -10.545826)
				)
				(arc
					(start 278.433784 -11.54049)
					(mid 278.093387 -12.52152)
					(end 279.077166 -12.854432)
				)
			)
		)
	)
	(zone
		(net "GND")
		(layer "In5.Cu")
		(hatch none 0.5)
		(connect_pads
			(clearance 0.5)
		)
		(min_thickness 0.25)
		(fill yes
			(thermal_gap 0.5)
			(thermal_bridge_width 0.5)
			(island_removal_mode 0)
		)
		(polygon
			(pts
				(xy 242.242086 -5.381498) (xy 241.193828 -6.429756) (xy 237.399576 -6.429756) (xy 236.403134 -5.433314)
				(xy 235.552996 -5.433314) (xy 234.738418 -6.247892) (xy 234.738418 -84.59851) (xy 235.144818 -85.00491)
				(xy 235.854748 -85.00491) (xy 237.221014 -83.638644) (xy 238.396018 -83.638644) (xy 241.900456 -87.143082)
				(xy 244.244114 -87.143082) (xy 244.7798 -86.607396) (xy 244.7798 -6.705854) (xy 243.455444 -5.381498)
			)
		)
		(polygon
			(pts
				(arc
					(start 240.871756 -82.577178)
					(mid 239.92498 -82.882363)
					(end 240.236502 -83.827112)
				)
				(arc
					(start 242.236498 -84.82711)
					(mid 243.17706 -84.51342)
					(end 242.86337 -83.572858)
				)
			)
		)
		(polygon
			(pts
				(arc
					(start 238.374936 -81.849722)
					(mid 238.699802 -80.875124)
					(end 237.725204 -80.550258)
				)
				(xy 237.723934 -80.547972) (xy 235.724192 -81.54797) (xy 235.724192 -81.548224)
				(arc
					(start 235.725208 -81.550256)
					(mid 235.400342 -82.524854)
					(end 236.37494 -82.84972)
				)
				(xy 236.37621 -82.852006) (xy 238.376206 -81.852008)
			)
		)
		(polygon
			(pts
				(arc
					(start 240.863374 -78.572868)
					(mid 239.922812 -78.886558)
					(end 240.236502 -79.82712)
				)
				(arc
					(start 242.228116 -80.8228)
					(mid 243.174892 -80.517615)
					(end 242.86337 -79.572866)
				)
			)
		)
		(polygon
			(pts
				(arc
					(start 238.374936 -77.84973)
					(mid 238.699802 -76.875132)
					(end 237.725204 -76.550266)
				)
				(xy 237.723934 -76.54798) (xy 235.724192 -77.547978) (xy 235.724192 -77.548232)
				(arc
					(start 235.725208 -77.550264)
					(mid 235.400342 -78.524862)
					(end 236.37494 -78.849728)
				)
				(xy 236.37621 -78.852014) (xy 238.376206 -77.852016)
			)
		)
		(polygon
			(pts
				(arc
					(start 240.863374 -74.572876)
					(mid 239.922812 -74.886566)
					(end 240.236502 -75.827128)
				)
				(arc
					(start 242.228116 -76.822808)
					(mid 243.174892 -76.517623)
					(end 242.86337 -75.572874)
				)
			)
		)
		(polygon
			(pts
				(arc
					(start 238.374936 -73.849738)
					(mid 238.699802 -72.87514)
					(end 237.725204 -72.550274)
				)
				(xy 237.723934 -72.547988) (xy 235.724192 -73.547986) (xy 235.724192 -73.54824)
				(arc
					(start 235.725208 -73.550272)
					(mid 235.400342 -74.52487)
					(end 236.37494 -74.849736)
				)
				(xy 236.37621 -74.852022) (xy 238.376206 -73.852024)
			)
		)
		(polygon
			(pts
				(arc
					(start 240.863374 -70.572884)
					(mid 239.922812 -70.886574)
					(end 240.236502 -71.827136)
				)
				(arc
					(start 242.228116 -72.822816)
					(mid 243.174892 -72.517631)
					(end 242.86337 -71.572882)
				)
			)
		)
		(polygon
			(pts
				(arc
					(start 238.374936 -69.849746)
					(mid 238.699802 -68.875148)
					(end 237.725204 -68.550282)
				)
				(xy 237.723934 -68.547996) (xy 235.724192 -69.547994) (xy 235.724192 -69.548248)
				(arc
					(start 235.725208 -69.55028)
					(mid 235.400342 -70.524878)
					(end 236.37494 -70.849744)
				)
				(xy 236.37621 -70.85203) (xy 238.376206 -69.852032)
			)
		)
		(polygon
			(pts
				(arc
					(start 240.871756 -66.57721)
					(mid 239.92498 -66.882395)
					(end 240.236502 -67.827144)
				)
				(arc
					(start 242.236498 -68.827142)
					(mid 243.17706 -68.513452)
					(end 242.86337 -67.57289)
				)
			)
		)
		(polygon
			(pts
				(arc
					(start 238.374936 -65.849754)
					(mid 238.699802 -64.875156)
					(end 237.725204 -64.55029)
				)
				(xy 237.723934 -64.548004) (xy 235.723938 -65.548002)
				(arc
					(start 235.725208 -65.550288)
					(mid 235.400342 -66.524886)
					(end 236.37494 -66.849752)
				)
				(xy 236.37621 -66.852038) (xy 238.375952 -65.85204) (xy 238.375952 -65.851786)
			)
		)
		(polygon
			(pts
				(arc
					(start 240.871756 -62.577218)
					(mid 239.92498 -62.882403)
					(end 240.236502 -63.827152)
				)
				(arc
					(start 242.236498 -64.82715)
					(mid 243.17706 -64.51346)
					(end 242.86337 -63.572898)
				)
			)
		)
		(polygon
			(pts
				(arc
					(start 238.374936 -61.849762)
					(mid 238.699802 -60.875164)
					(end 237.725204 -60.550298)
				)
				(xy 237.723934 -60.548012) (xy 235.724192 -61.54801) (xy 235.724192 -61.548264)
				(arc
					(start 235.725208 -61.550296)
					(mid 235.400342 -62.524894)
					(end 236.37494 -62.84976)
				)
				(xy 236.37621 -62.852046) (xy 238.376206 -61.852048)
			)
		)
		(polygon
			(pts
				(arc
					(start 240.871756 -58.577226)
					(mid 239.92498 -58.882411)
					(end 240.236502 -59.82716)
				)
				(arc
					(start 242.236498 -60.827158)
					(mid 243.17706 -60.513468)
					(end 242.86337 -59.572906)
				)
			)
		)
		(polygon
			(pts
				(arc
					(start 238.374936 -57.84977)
					(mid 238.699802 -56.875172)
					(end 237.725204 -56.550306)
				)
				(xy 237.723934 -56.54802) (xy 235.724192 -57.548018) (xy 235.724192 -57.548272)
				(arc
					(start 235.725208 -57.550304)
					(mid 235.400342 -58.524902)
					(end 236.37494 -58.849768)
				)
				(xy 236.37621 -58.852054) (xy 238.376206 -57.852056)
			)
		)
		(polygon
			(pts
				(arc
					(start 240.871756 -54.577234)
					(mid 239.92498 -54.882419)
					(end 240.236502 -55.827168)
				)
				(arc
					(start 242.236498 -56.827166)
					(mid 243.17706 -56.513476)
					(end 242.86337 -55.572914)
				)
			)
		)
		(polygon
			(pts
				(arc
					(start 238.374936 -53.849778)
					(mid 238.699802 -52.87518)
					(end 237.725204 -52.550314)
				)
				(xy 237.723934 -52.548028) (xy 235.724192 -53.548026) (xy 235.724192 -53.54828)
				(arc
					(start 235.725208 -53.550312)
					(mid 235.400342 -54.52491)
					(end 236.37494 -54.849776)
				)
				(xy 236.37621 -54.852062) (xy 238.376206 -53.852064)
			)
		)
		(polygon
			(pts
				(arc
					(start 240.863374 -50.572924)
					(mid 239.922812 -50.886614)
					(end 240.236502 -51.827176)
				)
				(arc
					(start 242.228116 -52.822856)
					(mid 243.174892 -52.517671)
					(end 242.86337 -51.572922)
				)
			)
		)
		(polygon
			(pts
				(arc
					(start 238.374936 -49.849786)
					(mid 238.699802 -48.875188)
					(end 237.725204 -48.550322)
				)
				(xy 237.723934 -48.548036) (xy 235.724192 -49.548034) (xy 235.724192 -49.548288)
				(arc
					(start 235.725208 -49.55032)
					(mid 235.400342 -50.524918)
					(end 236.37494 -50.849784)
				)
				(xy 236.37621 -50.85207) (xy 238.376206 -49.852072)
			)
		)
		(polygon
			(pts
				(arc
					(start 240.871756 -46.57725)
					(mid 239.92498 -46.882435)
					(end 240.236502 -47.827184)
				)
				(arc
					(start 242.236498 -48.827182)
					(mid 243.17706 -48.513492)
					(end 242.86337 -47.57293)
				)
			)
		)
		(polygon
			(pts
				(arc
					(start 238.374936 -45.849794)
					(mid 238.699802 -44.875196)
					(end 237.725204 -44.55033)
				)
				(xy 237.723934 -44.548044) (xy 235.724192 -45.548042) (xy 235.724192 -45.548296)
				(arc
					(start 235.725208 -45.550328)
					(mid 235.400342 -46.524926)
					(end 236.37494 -46.849792)
				)
				(xy 236.37621 -46.852078) (xy 238.376206 -45.85208)
			)
		)
		(polygon
			(pts
				(arc
					(start 240.871756 -42.577258)
					(mid 239.92498 -42.882443)
					(end 240.236502 -43.827192)
				)
				(arc
					(start 242.236498 -44.82719)
					(mid 243.17706 -44.5135)
					(end 242.86337 -43.572938)
				)
			)
		)
		(polygon
			(pts
				(arc
					(start 238.374936 -41.849802)
					(mid 238.699802 -40.875204)
					(end 237.725204 -40.550338)
				)
				(xy 237.723934 -40.548052) (xy 235.724192 -41.54805) (xy 235.724192 -41.548304)
				(arc
					(start 235.725208 -41.550336)
					(mid 235.400342 -42.524934)
					(end 236.37494 -42.8498)
				)
				(xy 236.37621 -42.852086) (xy 238.376206 -41.852088)
			)
		)
		(polygon
			(pts
				(arc
					(start 240.871756 -38.577266)
					(mid 239.92498 -38.882451)
					(end 240.236502 -39.8272)
				)
				(arc
					(start 242.236498 -40.827198)
					(mid 243.17706 -40.513508)
					(end 242.86337 -39.572946)
				)
			)
		)
		(polygon
			(pts
				(arc
					(start 238.374936 -37.84981)
					(mid 238.699802 -36.875212)
					(end 237.725204 -36.550346)
				)
				(xy 237.723934 -36.54806) (xy 235.724192 -37.548058) (xy 235.724192 -37.548312)
				(arc
					(start 235.725208 -37.550344)
					(mid 235.400342 -38.524942)
					(end 236.37494 -38.849808)
				)
				(xy 236.37621 -38.852094) (xy 238.376206 -37.852096)
			)
		)
		(polygon
			(pts
				(arc
					(start 240.876074 -34.548064)
					(mid 239.89792 -34.873946)
					(end 240.223802 -35.8521)
				)
				(arc
					(start 242.223798 -36.852098)
					(mid 243.201952 -36.526216)
					(end 242.87607 -35.548062)
				)
			)
		)
		(polygon
			(pts
				(arc
					(start 238.374936 -17.84985)
					(mid 238.699802 -16.875252)
					(end 237.725204 -16.550386)
				)
				(xy 237.723934 -16.5481) (xy 235.724192 -17.548098) (xy 235.724192 -17.548352)
				(arc
					(start 235.725208 -17.550384)
					(mid 235.400342 -18.524982)
					(end 236.37494 -18.849848)
				)
				(xy 236.37621 -18.852134) (xy 238.376206 -17.852136)
			)
		)
		(polygon
			(pts
				(arc
					(start 238.377222 -11.854434)
					(mid 238.704374 -10.872978)
					(end 237.722918 -10.545826)
				)
				(arc
					(start 235.733844 -11.54049)
					(mid 235.393447 -12.52152)
					(end 236.377226 -12.854432)
				)
			)
		)
	)
	(zone
		(net "GND")
		(layer "In5.Cu")
		(hatch none 0.5)
		(connect_pads
			(clearance 0.5)
		)
		(min_thickness 0.25)
		(fill yes
			(thermal_gap 0.5)
			(thermal_bridge_width 0.5)
			(island_removal_mode 0)
		)
		(polygon
			(pts
				(arc
					(start 149.133814 -16.265906)
					(mid 149.066915 -16.268928)
					(end 148.999956 -16.26997)
				)
				(xy 103.396288 -16.26997) (xy 103.396288 -35.359848) (xy 103.854504 -35.818064) (xy 123.778772 -35.818064)
				(xy 124.366274 -35.230562) (xy 124.366274 -24.723344) (xy 126.216156 -22.873462)
				(arc
					(start 130.584956 -22.873462)
					(mid 130.30755 -22.674608)
					(end 130.201416 -22.350222)
				)
				(arc
					(start 130.201416 -20.950174)
					(mid 130.749929 -20.401534)
					(end 131.298696 -20.94992)
				)
				(arc
					(start 131.298696 -22.350222)
					(mid 131.192538 -22.674591)
					(end 130.915156 -22.873462)
				)
				(xy 131.050284 -22.873462) (xy 132.060442 -23.88362)
				(arc
					(start 132.421376 -23.88362)
					(mid 132.118883 -23.689718)
					(end 132.00126 -23.35022)
				)
				(arc
					(start 132.00126 -21.950172)
					(mid 132.549773 -21.401532)
					(end 133.09854 -21.949918)
				)
				(arc
					(start 133.09854 -23.35022)
					(mid 132.980896 -23.689702)
					(end 132.678424 -23.88362)
				)
				(xy 132.754878 -23.88362) (xy 133.84403 -24.972772) (xy 133.84403 -35.236658) (xy 134.425436 -35.818064)
				(xy 148.688806 -35.818064) (xy 149.133814 -35.373056)
			)
		)
		(polygon
			(pts
				(arc
					(start 143.89862 -29.149802)
					(mid 143.349853 -28.601416)
					(end 142.80134 -29.150056)
				)
				(arc
					(start 142.80134 -30.550104)
					(mid 143.34998 -31.098744)
					(end 143.89862 -30.550104)
				)
			)
		)
		(polygon
			(pts
				(arc
					(start 136.698736 -29.149802)
					(mid 136.149969 -28.601416)
					(end 135.601456 -29.150056)
				)
				(arc
					(start 135.601456 -30.550104)
					(mid 136.150096 -31.098744)
					(end 136.698736 -30.550104)
				)
			)
		)
		(polygon
			(pts
				(arc
					(start 122.301254 -29.150056)
					(mid 121.750074 -28.598876)
					(end 121.198894 -29.150056)
				)
				(arc
					(start 121.198894 -30.550358)
					(mid 121.750201 -31.101284)
					(end 122.301254 -30.550104)
				)
			)
		)
		(polygon
			(pts
				(arc
					(start 116.898674 -28.149804)
					(mid 116.349907 -27.601418)
					(end 115.801394 -28.150058)
				)
				(arc
					(start 115.801394 -29.550106)
					(mid 116.350034 -30.098746)
					(end 116.898674 -29.550106)
				)
			)
		)
		(polygon
			(pts
				(arc
					(start 143.89862 -21.949918)
					(mid 143.349853 -21.401532)
					(end 142.80134 -21.950172)
				)
				(arc
					(start 142.80134 -23.35022)
					(mid 143.34998 -23.89886)
					(end 143.89862 -23.35022)
				)
			)
		)
		(polygon
			(pts
				(arc
					(start 140.298678 -21.949918)
					(mid 139.749911 -21.401532)
					(end 139.201398 -21.950172)
				)
				(arc
					(start 139.201398 -23.35022)
					(mid 139.750038 -23.89886)
					(end 140.298678 -23.35022)
				)
			)
		)
		(polygon
			(pts
				(arc
					(start 136.698736 -21.949918)
					(mid 136.149969 -21.401532)
					(end 135.601456 -21.950172)
				)
				(arc
					(start 135.601456 -23.35022)
					(mid 136.150096 -23.89886)
					(end 136.698736 -23.35022)
				)
			)
		)
		(polygon
			(pts
				(arc
					(start 122.298714 -21.949918)
					(mid 121.749947 -21.401532)
					(end 121.201434 -21.950172)
				)
				(arc
					(start 121.201434 -23.35022)
					(mid 121.750074 -23.89886)
					(end 122.298714 -23.35022)
				)
			)
		)
		(polygon
			(pts
				(arc
					(start 118.698518 -21.949918)
					(mid 118.149751 -21.401532)
					(end 117.601238 -21.950172)
				)
				(arc
					(start 117.601238 -23.35022)
					(mid 118.149878 -23.89886)
					(end 118.698518 -23.35022)
				)
			)
		)
		(polygon
			(pts
				(arc
					(start 115.098576 -21.949918)
					(mid 114.549809 -21.401532)
					(end 114.001296 -21.950172)
				)
				(arc
					(start 114.001296 -23.35022)
					(mid 114.549936 -23.89886)
					(end 115.098576 -23.35022)
				)
			)
		)
		(polygon
			(pts
				(arc
					(start 111.498634 -21.949918)
					(mid 110.949867 -21.401532)
					(end 110.401354 -21.950172)
				)
				(arc
					(start 110.401354 -23.35022)
					(mid 110.949994 -23.89886)
					(end 111.498634 -23.35022)
				)
			)
		)
		(polygon
			(pts
				(arc
					(start 142.098522 -20.94992)
					(mid 141.549755 -20.401534)
					(end 141.001242 -20.950174)
				)
				(arc
					(start 141.001242 -22.350222)
					(mid 141.549882 -22.898862)
					(end 142.098522 -22.350222)
				)
			)
		)
		(polygon
			(pts
				(arc
					(start 138.49858 -20.94992)
					(mid 137.949813 -20.401534)
					(end 137.4013 -20.950174)
				)
				(arc
					(start 137.4013 -22.350222)
					(mid 137.94994 -22.898862)
					(end 138.49858 -22.350222)
				)
			)
		)
		(polygon
			(pts
				(arc
					(start 134.898638 -20.94992)
					(mid 134.349871 -20.401534)
					(end 133.801358 -20.950174)
				)
				(arc
					(start 133.801358 -22.350222)
					(mid 134.349998 -22.898862)
					(end 134.898638 -22.350222)
				)
			)
		)
		(polygon
			(pts
				(arc
					(start 120.498616 -20.94992)
					(mid 119.949849 -20.401534)
					(end 119.401336 -20.950174)
				)
				(arc
					(start 119.401336 -22.350222)
					(mid 119.949976 -22.898862)
					(end 120.498616 -22.350222)
				)
			)
		)
		(polygon
			(pts
				(arc
					(start 116.898674 -20.94992)
					(mid 116.349907 -20.401534)
					(end 115.801394 -20.950174)
				)
				(arc
					(start 115.801394 -22.350222)
					(mid 116.350034 -22.898862)
					(end 116.898674 -22.350222)
				)
			)
		)
		(polygon
			(pts
				(arc
					(start 113.298732 -20.94992)
					(mid 112.749965 -20.401534)
					(end 112.201452 -20.950174)
				)
				(arc
					(start 112.201452 -22.350222)
					(mid 112.750092 -22.898862)
					(end 113.298732 -22.350222)
				)
			)
		)
		(polygon
			(pts
				(arc
					(start 109.698536 -20.94992)
					(mid 109.149769 -20.401534)
					(end 108.601256 -20.950174)
				)
				(arc
					(start 108.601256 -22.350222)
					(mid 109.149896 -22.898862)
					(end 109.698536 -22.350222)
				)
			)
		)
		(polygon
			(pts
				(arc
					(start 133.09854 -18.35023)
					(mid 132.5499 -17.80159)
					(end 132.00126 -18.35023)
				)
				(arc
					(start 132.00126 -19.750278)
					(mid 132.550027 -20.298664)
					(end 133.09854 -19.750024)
				)
			)
		)
		(polygon
			(pts
				(arc
					(start 143.89862 -18.349976)
					(mid 143.349853 -17.80159)
					(end 142.80134 -18.35023)
				)
				(arc
					(start 142.80134 -19.750024)
					(mid 143.34998 -20.298664)
					(end 143.89862 -19.750024)
				)
			)
		)
		(polygon
			(pts
				(arc
					(start 140.298678 -18.349976)
					(mid 139.749911 -17.80159)
					(end 139.201398 -18.35023)
				)
				(arc
					(start 139.201398 -19.750024)
					(mid 139.750038 -20.298664)
					(end 140.298678 -19.750024)
				)
			)
		)
		(polygon
			(pts
				(arc
					(start 136.698736 -18.349976)
					(mid 136.149969 -17.80159)
					(end 135.601456 -18.35023)
				)
				(arc
					(start 135.601456 -19.750024)
					(mid 136.150096 -20.298664)
					(end 136.698736 -19.750024)
				)
			)
		)
		(polygon
			(pts
				(arc
					(start 122.298714 -18.349976)
					(mid 121.749947 -17.80159)
					(end 121.201434 -18.35023)
				)
				(arc
					(start 121.201434 -19.750024)
					(mid 121.750074 -20.298664)
					(end 122.298714 -19.750024)
				)
			)
		)
		(polygon
			(pts
				(arc
					(start 118.698518 -18.349976)
					(mid 118.149751 -17.80159)
					(end 117.601238 -18.35023)
				)
				(arc
					(start 117.601238 -19.750024)
					(mid 118.149878 -20.298664)
					(end 118.698518 -19.750024)
				)
			)
		)
		(polygon
			(pts
				(arc
					(start 115.098576 -18.349976)
					(mid 114.549809 -17.80159)
					(end 114.001296 -18.35023)
				)
				(arc
					(start 114.001296 -19.750024)
					(mid 114.549936 -20.298664)
					(end 115.098576 -19.750024)
				)
			)
		)
		(polygon
			(pts
				(arc
					(start 111.498634 -18.349976)
					(mid 110.949867 -17.80159)
					(end 110.401354 -18.35023)
				)
				(arc
					(start 110.401354 -19.750024)
					(mid 110.949994 -20.298664)
					(end 111.498634 -19.750024)
				)
			)
		)
		(polygon
			(pts
				(arc
					(start 142.098522 -17.349724)
					(mid 141.549755 -16.801338)
					(end 141.001242 -17.349978)
				)
				(arc
					(start 141.001242 -18.750026)
					(mid 141.549882 -19.298666)
					(end 142.098522 -18.750026)
				)
			)
		)
		(polygon
			(pts
				(arc
					(start 138.49858 -17.349724)
					(mid 137.949813 -16.801338)
					(end 137.4013 -17.349978)
				)
				(arc
					(start 137.4013 -18.750026)
					(mid 137.94994 -19.298666)
					(end 138.49858 -18.750026)
				)
			)
		)
		(polygon
			(pts
				(arc
					(start 134.898638 -17.349724)
					(mid 134.349871 -16.801338)
					(end 133.801358 -17.349978)
				)
				(arc
					(start 133.801358 -18.750026)
					(mid 134.349998 -19.298666)
					(end 134.898638 -18.750026)
				)
			)
		)
		(polygon
			(pts
				(arc
					(start 131.298696 -17.349724)
					(mid 130.749929 -16.801338)
					(end 130.201416 -17.349978)
				)
				(arc
					(start 130.201416 -18.750026)
					(mid 130.750056 -19.298666)
					(end 131.298696 -18.750026)
				)
			)
		)
		(polygon
			(pts
				(arc
					(start 120.498616 -17.349724)
					(mid 119.949849 -16.801338)
					(end 119.401336 -17.349978)
				)
				(arc
					(start 119.401336 -18.750026)
					(mid 119.949976 -19.298666)
					(end 120.498616 -18.750026)
				)
			)
		)
		(polygon
			(pts
				(arc
					(start 116.898674 -17.349724)
					(mid 116.349907 -16.801338)
					(end 115.801394 -17.349978)
				)
				(arc
					(start 115.801394 -18.750026)
					(mid 116.350034 -19.298666)
					(end 116.898674 -18.750026)
				)
			)
		)
		(polygon
			(pts
				(arc
					(start 113.298732 -17.349724)
					(mid 112.749965 -16.801338)
					(end 112.201452 -17.349978)
				)
				(arc
					(start 112.201452 -18.750026)
					(mid 112.750092 -19.298666)
					(end 113.298732 -18.750026)
				)
			)
		)
		(polygon
			(pts
				(arc
					(start 109.698536 -17.349724)
					(mid 109.149769 -16.801338)
					(end 108.601256 -17.349978)
				)
				(arc
					(start 108.601256 -18.750026)
					(mid 109.149896 -19.298666)
					(end 109.698536 -18.750026)
				)
			)
		)
	)
	(zone
		(net "P5V_A_3")
		(layer "In6.Cu")
		(hatch none 0.5)
		(connect_pads
			(clearance 0.5)
		)
		(min_thickness 0.25)
		(fill yes
			(thermal_gap 0.5)
			(thermal_bridge_width 0.5)
			(island_removal_mode 0)
		)
		(polygon
			(pts
				(xy 338.702904 -164.126418) (xy 338.307426 -164.521896) (xy 338.307426 -264.932668) (xy 336.1055 -267.134594)
				(xy 336.1055 -272.310606) (xy 338.307426 -274.512532) (xy 338.307426 -285.813754) (xy 338.79409 -286.300418)
				(xy 398.12087 -286.300418) (xy 401.48129 -282.939998) (xy 413.822388 -282.939998) (xy 417.182808 -286.300418)
				(xy 475.451932 -286.300418) (xy 480.039426 -281.712924) (xy 480.039426 -264.022332) (xy 475.628716 -259.611622)
				(xy 475.628716 -244.68582) (xy 474.373194 -243.430298) (xy 410.556964 -243.430298) (xy 403.077426 -235.95076)
				(xy 403.077426 -165.157912) (xy 402.045932 -164.126418) (xy 371.34292 -164.126418) (xy 369.315238 -166.1541)
				(xy 352.041206 -166.1541) (xy 350.013524 -164.126418)
			)
		)
		(polygon
			(pts
				(arc
					(start 451.3199 -277.178262)
					(mid 450.938773 -276.797516)
					(end 450.5579 -277.178516)
				)
				(arc
					(start 450.5579 -278.321516)
					(mid 450.9389 -278.702516)
					(end 451.3199 -278.321516)
				)
			)
		)
		(polygon
			(pts
				(arc
					(start 419.770052 -277.178262)
					(mid 419.388925 -276.797516)
					(end 419.008052 -277.178516)
				)
				(arc
					(start 419.008052 -278.321516)
					(mid 419.389052 -278.702516)
					(end 419.770052 -278.321516)
				)
			)
		)
		(polygon
			(pts
				(arc
					(start 388.21995 -277.178262)
					(mid 387.838823 -276.797516)
					(end 387.45795 -277.178516)
				)
				(arc
					(start 387.45795 -278.321516)
					(mid 387.83895 -278.702516)
					(end 388.21995 -278.321516)
				)
			)
		)
		(polygon
			(pts
				(arc
					(start 356.670102 -277.178262)
					(mid 356.288975 -276.797516)
					(end 355.908102 -277.178516)
				)
				(arc
					(start 355.908102 -278.321516)
					(mid 356.289102 -278.702516)
					(end 356.670102 -278.321516)
				)
			)
		)
		(polygon
			(pts
				(arc
					(start 478.120202 -273.368516)
					(mid 477.739202 -272.987516)
					(end 477.358202 -273.368516)
				)
				(arc
					(start 477.358202 -274.51177)
					(mid 477.739329 -274.892516)
					(end 478.120202 -274.511516)
				)
			)
		)
		(polygon
			(pts
				(arc
					(start 446.5701 -273.368516)
					(mid 446.1891 -272.987516)
					(end 445.8081 -273.368516)
				)
				(arc
					(start 445.8081 -274.51177)
					(mid 446.189227 -274.892516)
					(end 446.5701 -274.511516)
				)
			)
		)
		(polygon
			(pts
				(arc
					(start 415.020252 -273.368516)
					(mid 414.639252 -272.987516)
					(end 414.258252 -273.368516)
				)
				(arc
					(start 414.258252 -274.51177)
					(mid 414.639379 -274.892516)
					(end 415.020252 -274.511516)
				)
			)
		)
		(polygon
			(pts
				(arc
					(start 383.47015 -273.368516)
					(mid 383.08915 -272.987516)
					(end 382.70815 -273.368516)
				)
				(arc
					(start 382.70815 -274.51177)
					(mid 383.089277 -274.892516)
					(end 383.47015 -274.511516)
				)
			)
		)
		(polygon
			(pts
				(arc
					(start 351.920302 -273.368516)
					(mid 351.539302 -272.987516)
					(end 351.158302 -273.368516)
				)
				(arc
					(start 351.158302 -274.51177)
					(mid 351.539429 -274.892516)
					(end 351.920302 -274.511516)
				)
			)
		)
	)
	(zone
		(net "P3V3_STBY_B")
		(layer "In6.Cu")
		(hatch none 0.5)
		(connect_pads
			(clearance 0.5)
		)
		(min_thickness 0.25)
		(fill yes
			(thermal_gap 0.5)
			(thermal_bridge_width 0.5)
			(island_removal_mode 0)
		)
		(polygon
			(pts
				(xy 261.452106 37.530024) (xy 261.452106 24.064722) (xy 261.932674 23.584154) (xy 267.51534 23.584154)
				(xy 273.3675 17.731994) (xy 273.3675 8.176006) (xy 263.5885 -1.602994) (xy 263.5885 -188.800994)
				(xy 231.5845 -220.804994) (xy 231.5845 -353.138994) (xy 229.64775 -355.075744) (xy 229.64775 -357.020622)
				(xy 227.459286 -359.209086) (xy 225.514408 -359.209086) (xy 220.6625 -364.060994) (xy 220.6625 -374.444006)
				(xy 234.298236 -388.079742) (xy 234.298236 -403.943312) (xy 232.687368 -405.55418) (xy 230.852472 -405.55418)
				(xy 230.488236 -405.918416) (xy 230.488236 -419.484556) (xy 230.933752 -419.930072) (xy 244.010434 -419.930072)
				(xy 244.43309 -419.507416) (xy 244.43309 -385.735068) (xy 251.43079 -378.737368) (xy 251.43079 -218.758516)
				(xy 280.2001 -189.989206) (xy 280.2001 -188.242194) (xy 279.752806 -187.7949) (xy 277.854664 -187.7949)
				(xy 277.057358 -186.997594) (xy 277.057358 -102.389686) (xy 278.094948 -101.352096) (xy 279.261062 -101.352096)
				(xy 280.257504 -102.348538) (xy 283.73578 -102.348538) (xy 284.784038 -101.30028) (xy 286.313372 -101.30028)
				(xy 287.67024 -102.657148) (xy 310.323484 -80.003904) (xy 310.323484 -38.022022) (xy 314.592208 -33.753298)
				(xy 348.489524 -33.753298) (xy 349.015304 -33.227264) (xy 349.015304 -16.569182)
				(arc
					(start 348.695772 -16.249396)
					(mid 347.290793 -15.493589)
					(end 346.730066 -13.999972)
				)
				(xy 346.730066 -1.27)
				(arc
					(start 300.999906 -1.27)
					(mid 299.394775 -0.605133)
					(end 298.729908 0.999998)
				)
				(xy 298.729908 37.530024)
			)
		)
		(polygon
			(pts
				(xy 286.336994 -5.0165) (xy 284.756606 -5.0165) (xy 283.740606 -6.0325) (xy 280.240994 -6.0325)
				(xy 279.250394 -5.0419) (xy 278.101806 -5.0419) (xy 277.0505 -6.093206) (xy 277.0505 -84.737194)
				(xy 277.695406 -85.3821) (xy 279.402794 -85.3821) (xy 280.139394 -84.6455) (xy 281.022806 -84.6455)
				(xy 283.893006 -87.5157) (xy 286.799274 -87.5157) (xy 287.86074 -86.454234) (xy 287.86074 -6.540246)
			)
		)
	)
	(zone
		(net "GND")
		(layer "In6.Cu")
		(hatch none 0.5)
		(connect_pads
			(clearance 0.5)
		)
		(min_thickness 0.25)
		(fill yes
			(thermal_gap 0.5)
			(thermal_bridge_width 0.5)
			(island_removal_mode 0)
		)
		(polygon
			(pts
				(xy 270.621506 -286.681418) (xy 270.216884 -287.08604) (xy 270.216884 -359.558082) (xy 271.261078 -360.602276)
				(xy 287.615122 -360.602276) (xy 289.6235 -358.593898) (xy 289.6235 -301.927006) (xy 304.595276 -286.95523)
				(xy 304.595276 -286.798512) (xy 304.478182 -286.681418)
			)
		)
		(polygon
			(pts
				(arc
					(start 273.1135 -359.885996)
					(mid 273.4945 -359.504996)
					(end 273.1135 -359.123996)
				)
				(arc
					(start 271.970246 -359.123996)
					(mid 271.5895 -359.505123)
					(end 271.9705 -359.885996)
				)
			)
		)
		(polygon
			(pts
				(arc
					(start 273.1135 -358.085898)
					(mid 273.4945 -357.704898)
					(end 273.1135 -357.323898)
				)
				(arc
					(start 271.970246 -357.323898)
					(mid 271.5895 -357.705025)
					(end 271.9705 -358.085898)
				)
			)
		)
		(polygon
			(pts
				(arc
					(start 280.636726 -358.253792)
					(mid 281.185366 -357.705152)
					(end 280.636726 -357.156512)
				)
				(arc
					(start 279.236678 -357.156512)
					(mid 278.688038 -357.705152)
					(end 279.236678 -358.253792)
				)
			)
		)
		(polygon
			(pts
				(arc
					(start 287.83661 -358.256332)
					(mid 288.38779 -357.705152)
					(end 287.83661 -357.153972)
				)
				(arc
					(start 286.436562 -357.153972)
					(mid 285.885382 -357.705152)
					(end 286.436562 -358.256332)
				)
			)
		)
		(polygon
			(pts
				(arc
					(start 273.1135 -356.286054)
					(mid 273.4945 -355.905054)
					(end 273.1135 -355.524054)
				)
				(arc
					(start 271.970246 -355.524054)
					(mid 271.5895 -355.905181)
					(end 271.9705 -356.286054)
				)
			)
		)
		(polygon
			(pts
				(arc
					(start 279.636728 -356.453694)
					(mid 280.185368 -355.905054)
					(end 279.636728 -355.356414)
				)
				(arc
					(start 278.23668 -355.356414)
					(mid 277.68804 -355.905054)
					(end 278.23668 -356.453694)
				)
			)
		)
		(polygon
			(pts
				(arc
					(start 286.836612 -356.456234)
					(mid 287.387792 -355.905054)
					(end 286.836612 -355.353874)
				)
				(arc
					(start 285.436564 -355.353874)
					(mid 284.885384 -355.905054)
					(end 285.436564 -356.456234)
				)
			)
		)
		(polygon
			(pts
				(arc
					(start 273.1135 -354.485956)
					(mid 273.4945 -354.104956)
					(end 273.1135 -353.723956)
				)
				(arc
					(start 271.970246 -353.723956)
					(mid 271.5895 -354.105083)
					(end 271.9705 -354.485956)
				)
			)
		)
		(polygon
			(pts
				(arc
					(start 280.636726 -354.65385)
					(mid 281.185366 -354.10521)
					(end 280.636726 -353.55657)
				)
				(arc
					(start 279.236678 -353.55657)
					(mid 278.688038 -354.10521)
					(end 279.236678 -354.65385)
				)
			)
		)
		(polygon
			(pts
				(arc
					(start 287.83661 -354.65639)
					(mid 288.38779 -354.10521)
					(end 287.83661 -353.55403)
				)
				(arc
					(start 286.436562 -353.55403)
					(mid 285.885382 -354.10521)
					(end 286.436562 -354.65639)
				)
			)
		)
		(polygon
			(pts
				(arc
					(start 273.1135 -352.686112)
					(mid 273.4945 -352.305112)
					(end 273.1135 -351.924112)
				)
				(arc
					(start 271.970246 -351.924112)
					(mid 271.5895 -352.305239)
					(end 271.9705 -352.686112)
				)
			)
		)
		(polygon
			(pts
				(arc
					(start 279.636728 -352.853752)
					(mid 280.185368 -352.305112)
					(end 279.636728 -351.756472)
				)
				(arc
					(start 278.23668 -351.756472)
					(mid 277.68804 -352.305112)
					(end 278.23668 -352.853752)
				)
			)
		)
		(polygon
			(pts
				(arc
					(start 286.836612 -352.856292)
					(mid 287.387792 -352.305112)
					(end 286.836612 -351.753932)
				)
				(arc
					(start 285.436564 -351.753932)
					(mid 284.885384 -352.305112)
					(end 285.436564 -352.856292)
				)
			)
		)
		(polygon
			(pts
				(arc
					(start 273.1135 -350.886014)
					(mid 273.4945 -350.505014)
					(end 273.1135 -350.124014)
				)
				(arc
					(start 271.970246 -350.124014)
					(mid 271.5895 -350.505141)
					(end 271.9705 -350.886014)
				)
			)
		)
		(polygon
			(pts
				(arc
					(start 280.636726 -351.053908)
					(mid 281.185366 -350.505268)
					(end 280.636726 -349.956628)
				)
				(arc
					(start 279.236678 -349.956628)
					(mid 278.688038 -350.505268)
					(end 279.236678 -351.053908)
				)
			)
		)
		(polygon
			(pts
				(arc
					(start 287.83661 -351.056448)
					(mid 288.38779 -350.505268)
					(end 287.83661 -349.954088)
				)
				(arc
					(start 286.436562 -349.954088)
					(mid 285.885382 -350.505268)
					(end 286.436562 -351.056448)
				)
			)
		)
		(polygon
			(pts
				(arc
					(start 279.636728 -349.25381)
					(mid 280.185368 -348.70517)
					(end 279.636728 -348.15653)
				)
				(arc
					(start 278.23668 -348.15653)
					(mid 277.68804 -348.70517)
					(end 278.23668 -349.25381)
				)
			)
		)
		(polygon
			(pts
				(arc
					(start 286.836612 -349.25635)
					(mid 287.387792 -348.70517)
					(end 286.836612 -348.15399)
				)
				(arc
					(start 285.436564 -348.15399)
					(mid 284.885384 -348.70517)
					(end 285.436564 -349.25635)
				)
			)
		)
		(polygon
			(pts
				(arc
					(start 287.83661 -347.453712)
					(mid 288.38525 -346.905072)
					(end 287.83661 -346.356432)
				)
				(arc
					(start 286.436562 -346.356432)
					(mid 285.887922 -346.905072)
					(end 286.436562 -347.453712)
				)
			)
		)
		(polygon
			(pts
				(arc
					(start 280.636726 -347.453712)
					(mid 281.185366 -346.905072)
					(end 280.636726 -346.356432)
				)
				(arc
					(start 279.236678 -346.356432)
					(mid 278.688038 -346.905072)
					(end 279.236678 -347.453712)
				)
			)
		)
		(polygon
			(pts
				(arc
					(start 286.836612 -345.653868)
					(mid 287.385252 -345.105228)
					(end 286.836612 -344.556588)
				)
				(arc
					(start 285.436564 -344.556588)
					(mid 284.887924 -345.105228)
					(end 285.436564 -345.653868)
				)
			)
		)
		(polygon
			(pts
				(arc
					(start 279.636728 -345.653868)
					(mid 280.185368 -345.105228)
					(end 279.636728 -344.556588)
				)
				(arc
					(start 278.23668 -344.556588)
					(mid 277.68804 -345.105228)
					(end 278.23668 -345.653868)
				)
			)
		)
		(polygon
			(pts
				(arc
					(start 287.83661 -343.85377)
					(mid 288.38525 -343.30513)
					(end 287.83661 -342.75649)
				)
				(arc
					(start 286.436562 -342.75649)
					(mid 285.887922 -343.30513)
					(end 286.436562 -343.85377)
				)
			)
		)
		(polygon
			(pts
				(arc
					(start 280.636726 -343.85377)
					(mid 281.185366 -343.30513)
					(end 280.636726 -342.75649)
				)
				(arc
					(start 279.236678 -342.75649)
					(mid 278.688038 -343.30513)
					(end 279.236678 -343.85377)
				)
			)
		)
		(polygon
			(pts
				(arc
					(start 286.836612 -342.053672)
					(mid 287.385252 -341.505032)
					(end 286.836612 -340.956392)
				)
				(arc
					(start 285.436564 -340.956392)
					(mid 284.887924 -341.505032)
					(end 285.436564 -342.053672)
				)
			)
		)
		(polygon
			(pts
				(arc
					(start 279.636728 -342.053672)
					(mid 280.185368 -341.505032)
					(end 279.636728 -340.956392)
				)
				(arc
					(start 278.23668 -340.956392)
					(mid 277.68804 -341.505032)
					(end 278.23668 -342.053672)
				)
			)
		)
		(polygon
			(pts
				(arc
					(start 287.83661 -340.253828)
					(mid 288.38525 -339.705188)
					(end 287.83661 -339.156548)
				)
				(arc
					(start 286.436562 -339.156548)
					(mid 285.887922 -339.705188)
					(end 286.436562 -340.253828)
				)
			)
		)
		(polygon
			(pts
				(arc
					(start 280.636726 -340.253828)
					(mid 281.185366 -339.705188)
					(end 280.636726 -339.156548)
				)
				(arc
					(start 279.236678 -339.156548)
					(mid 278.688038 -339.705188)
					(end 279.236678 -340.253828)
				)
			)
		)
		(polygon
			(pts
				(arc
					(start 273.1135 -338.28863)
					(mid 273.49704 -337.90509)
					(end 273.1135 -337.52155)
				)
				(arc
					(start 271.970246 -337.52155)
					(mid 271.58696 -337.905217)
					(end 271.9705 -338.28863)
				)
			)
		)
		(polygon
			(pts
				(arc
					(start 286.836612 -338.45373)
					(mid 287.385252 -337.90509)
					(end 286.836612 -337.35645)
				)
				(arc
					(start 285.436564 -337.35645)
					(mid 284.887924 -337.90509)
					(end 285.436564 -338.45373)
				)
			)
		)
		(polygon
			(pts
				(arc
					(start 279.636728 -338.45373)
					(mid 280.185368 -337.90509)
					(end 279.636728 -337.35645)
				)
				(arc
					(start 278.23668 -337.35645)
					(mid 277.68804 -337.90509)
					(end 278.23668 -338.45373)
				)
			)
		)
		(polygon
			(pts
				(arc
					(start 273.1135 -336.488532)
					(mid 273.49704 -336.104992)
					(end 273.1135 -335.721452)
				)
				(arc
					(start 271.970246 -335.721452)
					(mid 271.58696 -336.105119)
					(end 271.9705 -336.488532)
				)
			)
		)
		(polygon
			(pts
				(arc
					(start 280.636726 -336.653886)
					(mid 281.185366 -336.105246)
					(end 280.636726 -335.556606)
				)
				(arc
					(start 279.236678 -335.556606)
					(mid 278.688038 -336.105246)
					(end 279.236678 -336.653886)
				)
			)
		)
		(polygon
			(pts
				(arc
					(start 287.83661 -336.656426)
					(mid 288.38779 -336.105246)
					(end 287.83661 -335.554066)
				)
				(arc
					(start 286.436562 -335.554066)
					(mid 285.885382 -336.105246)
					(end 286.436562 -336.656426)
				)
			)
		)
		(polygon
			(pts
				(arc
					(start 273.1135 -334.688434)
					(mid 273.49704 -334.304894)
					(end 273.1135 -333.921354)
				)
				(arc
					(start 271.970246 -333.921354)
					(mid 271.58696 -334.305021)
					(end 271.9705 -334.688434)
				)
			)
		)
		(polygon
			(pts
				(arc
					(start 279.636728 -334.853788)
					(mid 280.185368 -334.305148)
					(end 279.636728 -333.756508)
				)
				(arc
					(start 278.23668 -333.756508)
					(mid 277.68804 -334.305148)
					(end 278.23668 -334.853788)
				)
			)
		)
		(polygon
			(pts
				(arc
					(start 286.836612 -334.856328)
					(mid 287.387792 -334.305148)
					(end 286.836612 -333.753968)
				)
				(arc
					(start 285.436564 -333.753968)
					(mid 284.885384 -334.305148)
					(end 285.436564 -334.856328)
				)
			)
		)
		(polygon
			(pts
				(arc
					(start 273.1135 -332.88859)
					(mid 273.49704 -332.50505)
					(end 273.1135 -332.12151)
				)
				(arc
					(start 271.970246 -332.12151)
					(mid 271.58696 -332.505177)
					(end 271.9705 -332.88859)
				)
			)
		)
		(polygon
			(pts
				(arc
					(start 280.636726 -333.05369)
					(mid 281.185366 -332.50505)
					(end 280.636726 -331.95641)
				)
				(arc
					(start 279.236678 -331.95641)
					(mid 278.688038 -332.50505)
					(end 279.236678 -333.05369)
				)
			)
		)
		(polygon
			(pts
				(arc
					(start 287.83661 -333.05623)
					(mid 288.38779 -332.50505)
					(end 287.83661 -331.95387)
				)
				(arc
					(start 286.436562 -331.95387)
					(mid 285.885382 -332.50505)
					(end 286.436562 -333.05623)
				)
			)
		)
		(polygon
			(pts
				(arc
					(start 273.1135 -331.088492)
					(mid 273.49704 -330.704952)
					(end 273.1135 -330.321412)
				)
				(arc
					(start 271.970246 -330.321412)
					(mid 271.58696 -330.705079)
					(end 271.9705 -331.088492)
				)
			)
		)
		(polygon
			(pts
				(arc
					(start 279.636728 -331.253846)
					(mid 280.185368 -330.705206)
					(end 279.636728 -330.156566)
				)
				(arc
					(start 278.23668 -330.156566)
					(mid 277.68804 -330.705206)
					(end 278.23668 -331.253846)
				)
			)
		)
		(polygon
			(pts
				(arc
					(start 286.836612 -331.256386)
					(mid 287.387792 -330.705206)
					(end 286.836612 -330.154026)
				)
				(arc
					(start 285.436564 -330.154026)
					(mid 284.885384 -330.705206)
					(end 285.436564 -331.256386)
				)
			)
		)
		(polygon
			(pts
				(arc
					(start 273.1135 -329.288648)
					(mid 273.49704 -328.905108)
					(end 273.1135 -328.521568)
				)
				(arc
					(start 271.970246 -328.521568)
					(mid 271.58696 -328.905235)
					(end 271.9705 -329.288648)
				)
			)
		)
		(polygon
			(pts
				(arc
					(start 280.636726 -329.453748)
					(mid 281.185366 -328.905108)
					(end 280.636726 -328.356468)
				)
				(arc
					(start 279.236678 -328.356468)
					(mid 278.688038 -328.905108)
					(end 279.236678 -329.453748)
				)
			)
		)
		(polygon
			(pts
				(arc
					(start 287.83661 -329.456288)
					(mid 288.38779 -328.905108)
					(end 287.83661 -328.353928)
				)
				(arc
					(start 286.436562 -328.353928)
					(mid 285.885382 -328.905108)
					(end 286.436562 -329.456288)
				)
			)
		)
		(polygon
			(pts
				(arc
					(start 279.636728 -327.653904)
					(mid 280.185368 -327.105264)
					(end 279.636728 -326.556624)
				)
				(arc
					(start 278.23668 -326.556624)
					(mid 277.68804 -327.105264)
					(end 278.23668 -327.653904)
				)
			)
		)
		(polygon
			(pts
				(arc
					(start 286.836612 -327.656444)
					(mid 287.387792 -327.105264)
					(end 286.836612 -326.554084)
				)
				(arc
					(start 285.436564 -326.554084)
					(mid 284.885384 -327.105264)
					(end 285.436564 -327.656444)
				)
			)
		)
		(polygon
			(pts
				(arc
					(start 287.83661 -325.853806)
					(mid 288.38525 -325.305166)
					(end 287.83661 -324.756526)
				)
				(arc
					(start 286.436562 -324.756526)
					(mid 285.887922 -325.305166)
					(end 286.436562 -325.853806)
				)
			)
		)
		(polygon
			(pts
				(arc
					(start 280.636726 -325.853806)
					(mid 281.185366 -325.305166)
					(end 280.636726 -324.756526)
				)
				(arc
					(start 279.236678 -324.756526)
					(mid 278.688038 -325.305166)
					(end 279.236678 -325.853806)
				)
			)
		)
		(polygon
			(pts
				(arc
					(start 286.836612 -324.053708)
					(mid 287.385252 -323.505068)
					(end 286.836612 -322.956428)
				)
				(arc
					(start 285.436564 -322.956428)
					(mid 284.887924 -323.505068)
					(end 285.436564 -324.053708)
				)
			)
		)
		(polygon
			(pts
				(arc
					(start 279.636728 -324.053708)
					(mid 280.185368 -323.505068)
					(end 279.636728 -322.956428)
				)
				(arc
					(start 278.23668 -322.956428)
					(mid 277.68804 -323.505068)
					(end 278.23668 -324.053708)
				)
			)
		)
		(polygon
			(pts
				(arc
					(start 287.83661 -322.253864)
					(mid 288.38525 -321.705224)
					(end 287.83661 -321.156584)
				)
				(arc
					(start 286.436562 -321.156584)
					(mid 285.887922 -321.705224)
					(end 286.436562 -322.253864)
				)
			)
		)
		(polygon
			(pts
				(arc
					(start 280.636726 -322.253864)
					(mid 281.185366 -321.705224)
					(end 280.636726 -321.156584)
				)
				(arc
					(start 279.236678 -321.156584)
					(mid 278.688038 -321.705224)
					(end 279.236678 -322.253864)
				)
			)
		)
		(polygon
			(pts
				(arc
					(start 286.836612 -320.453766)
					(mid 287.385252 -319.905126)
					(end 286.836612 -319.356486)
				)
				(arc
					(start 285.436564 -319.356486)
					(mid 284.887924 -319.905126)
					(end 285.436564 -320.453766)
				)
			)
		)
		(polygon
			(pts
				(arc
					(start 279.636728 -320.453766)
					(mid 280.185368 -319.905126)
					(end 279.636728 -319.356486)
				)
				(arc
					(start 278.23668 -319.356486)
					(mid 277.68804 -319.905126)
					(end 278.23668 -320.453766)
				)
			)
		)
		(polygon
			(pts
				(arc
					(start 287.83661 -318.653668)
					(mid 288.38525 -318.105028)
					(end 287.83661 -317.556388)
				)
				(arc
					(start 286.436562 -317.556388)
					(mid 285.887922 -318.105028)
					(end 286.436562 -318.653668)
				)
			)
		)
		(polygon
			(pts
				(arc
					(start 280.636726 -318.653668)
					(mid 281.185366 -318.105028)
					(end 280.636726 -317.556388)
				)
				(arc
					(start 279.236678 -317.556388)
					(mid 278.688038 -318.105028)
					(end 279.236678 -318.653668)
				)
			)
		)
		(polygon
			(pts
				(arc
					(start 273.1135 -316.68847)
					(mid 273.49704 -316.30493)
					(end 273.1135 -315.92139)
				)
				(arc
					(start 271.970246 -315.92139)
					(mid 271.58696 -316.305057)
					(end 271.9705 -316.68847)
				)
			)
		)
		(polygon
			(pts
				(arc
					(start 286.836612 -316.853824)
					(mid 287.385252 -316.305184)
					(end 286.836612 -315.756544)
				)
				(arc
					(start 285.436564 -315.756544)
					(mid 284.887924 -316.305184)
					(end 285.436564 -316.853824)
				)
			)
		)
		(polygon
			(pts
				(arc
					(start 279.636728 -316.853824)
					(mid 280.185368 -316.305184)
					(end 279.636728 -315.756544)
				)
				(arc
					(start 278.23668 -315.756544)
					(mid 277.68804 -316.305184)
					(end 278.23668 -316.853824)
				)
			)
		)
		(polygon
			(pts
				(arc
					(start 273.1135 -314.888626)
					(mid 273.49704 -314.505086)
					(end 273.1135 -314.121546)
				)
				(arc
					(start 271.970246 -314.121546)
					(mid 271.58696 -314.505213)
					(end 271.9705 -314.888626)
				)
			)
		)
		(polygon
			(pts
				(arc
					(start 280.636726 -315.053726)
					(mid 281.185366 -314.505086)
					(end 280.636726 -313.956446)
				)
				(arc
					(start 279.236678 -313.956446)
					(mid 278.688038 -314.505086)
					(end 279.236678 -315.053726)
				)
			)
		)
		(polygon
			(pts
				(arc
					(start 287.83661 -315.056266)
					(mid 288.38779 -314.505086)
					(end 287.83661 -313.953906)
				)
				(arc
					(start 286.436562 -313.953906)
					(mid 285.885382 -314.505086)
					(end 286.436562 -315.056266)
				)
			)
		)
		(polygon
			(pts
				(arc
					(start 273.1135 -313.088528)
					(mid 273.49704 -312.704988)
					(end 273.1135 -312.321448)
				)
				(arc
					(start 271.970246 -312.321448)
					(mid 271.58696 -312.705115)
					(end 271.9705 -313.088528)
				)
			)
		)
		(polygon
			(pts
				(arc
					(start 279.636728 -313.253882)
					(mid 280.185368 -312.705242)
					(end 279.636728 -312.156602)
				)
				(arc
					(start 278.23668 -312.156602)
					(mid 277.68804 -312.705242)
					(end 278.23668 -313.253882)
				)
			)
		)
		(polygon
			(pts
				(arc
					(start 286.836612 -313.256422)
					(mid 287.387792 -312.705242)
					(end 286.836612 -312.154062)
				)
				(arc
					(start 285.436564 -312.154062)
					(mid 284.885384 -312.705242)
					(end 285.436564 -313.256422)
				)
			)
		)
		(polygon
			(pts
				(arc
					(start 273.1135 -311.28843)
					(mid 273.49704 -310.90489)
					(end 273.1135 -310.52135)
				)
				(arc
					(start 271.970246 -310.52135)
					(mid 271.58696 -310.905017)
					(end 271.9705 -311.28843)
				)
			)
		)
		(polygon
			(pts
				(arc
					(start 280.636726 -311.453784)
					(mid 281.185366 -310.905144)
					(end 280.636726 -310.356504)
				)
				(arc
					(start 279.236678 -310.356504)
					(mid 278.688038 -310.905144)
					(end 279.236678 -311.453784)
				)
			)
		)
		(polygon
			(pts
				(arc
					(start 287.83661 -311.456324)
					(mid 288.38779 -310.905144)
					(end 287.83661 -310.353964)
				)
				(arc
					(start 286.436562 -310.353964)
					(mid 285.885382 -310.905144)
					(end 286.436562 -311.456324)
				)
			)
		)
		(polygon
			(pts
				(arc
					(start 273.1135 -309.488586)
					(mid 273.49704 -309.105046)
					(end 273.1135 -308.721506)
				)
				(arc
					(start 271.970246 -308.721506)
					(mid 271.58696 -309.105173)
					(end 271.9705 -309.488586)
				)
			)
		)
		(polygon
			(pts
				(arc
					(start 279.636728 -309.653686)
					(mid 280.185368 -309.105046)
					(end 279.636728 -308.556406)
				)
				(arc
					(start 278.23668 -308.556406)
					(mid 277.68804 -309.105046)
					(end 278.23668 -309.653686)
				)
			)
		)
		(polygon
			(pts
				(arc
					(start 286.836612 -309.656226)
					(mid 287.387792 -309.105046)
					(end 286.836612 -308.553866)
				)
				(arc
					(start 285.436564 -308.553866)
					(mid 284.885384 -309.105046)
					(end 285.436564 -309.656226)
				)
			)
		)
		(polygon
			(pts
				(arc
					(start 273.1135 -307.688488)
					(mid 273.49704 -307.304948)
					(end 273.1135 -306.921408)
				)
				(arc
					(start 271.970246 -306.921408)
					(mid 271.58696 -307.305075)
					(end 271.9705 -307.688488)
				)
			)
		)
		(polygon
			(pts
				(arc
					(start 280.636726 -307.853842)
					(mid 281.185366 -307.305202)
					(end 280.636726 -306.756562)
				)
				(arc
					(start 279.236678 -306.756562)
					(mid 278.688038 -307.305202)
					(end 279.236678 -307.853842)
				)
			)
		)
		(polygon
			(pts
				(arc
					(start 287.83661 -307.856382)
					(mid 288.38779 -307.305202)
					(end 287.83661 -306.754022)
				)
				(arc
					(start 286.436562 -306.754022)
					(mid 285.885382 -307.305202)
					(end 286.436562 -307.856382)
				)
			)
		)
		(polygon
			(pts
				(arc
					(start 279.636728 -306.053744)
					(mid 280.185368 -305.505104)
					(end 279.636728 -304.956464)
				)
				(arc
					(start 278.23668 -304.956464)
					(mid 277.68804 -305.505104)
					(end 278.23668 -306.053744)
				)
			)
		)
		(polygon
			(pts
				(arc
					(start 286.836612 -306.056284)
					(mid 287.387792 -305.505104)
					(end 286.836612 -304.953924)
				)
				(arc
					(start 285.436564 -304.953924)
					(mid 284.885384 -305.505104)
					(end 285.436564 -306.056284)
				)
			)
		)
		(polygon
			(pts
				(arc
					(start 287.83661 -304.2539)
					(mid 288.38525 -303.70526)
					(end 287.83661 -303.15662)
				)
				(arc
					(start 286.436562 -303.15662)
					(mid 285.887922 -303.70526)
					(end 286.436562 -304.2539)
				)
			)
		)
		(polygon
			(pts
				(arc
					(start 280.636726 -304.2539)
					(mid 281.185366 -303.70526)
					(end 280.636726 -303.15662)
				)
				(arc
					(start 279.236678 -303.15662)
					(mid 278.688038 -303.70526)
					(end 279.236678 -304.2539)
				)
			)
		)
		(polygon
			(pts
				(arc
					(start 286.836612 -302.453802)
					(mid 287.385252 -301.905162)
					(end 286.836612 -301.356522)
				)
				(arc
					(start 285.436564 -301.356522)
					(mid 284.887924 -301.905162)
					(end 285.436564 -302.453802)
				)
			)
		)
		(polygon
			(pts
				(arc
					(start 279.636728 -302.453802)
					(mid 280.185368 -301.905162)
					(end 279.636728 -301.356522)
				)
				(arc
					(start 278.23668 -301.356522)
					(mid 277.68804 -301.905162)
					(end 278.23668 -302.453802)
				)
			)
		)
		(polygon
			(pts
				(arc
					(start 287.83661 -300.653704)
					(mid 288.38525 -300.105064)
					(end 287.83661 -299.556424)
				)
				(arc
					(start 286.436562 -299.556424)
					(mid 285.887922 -300.105064)
					(end 286.436562 -300.653704)
				)
			)
		)
		(polygon
			(pts
				(arc
					(start 280.636726 -300.653704)
					(mid 281.185366 -300.105064)
					(end 280.636726 -299.556424)
				)
				(arc
					(start 279.236678 -299.556424)
					(mid 278.688038 -300.105064)
					(end 279.236678 -300.653704)
				)
			)
		)
		(polygon
			(pts
				(arc
					(start 286.836612 -298.85386)
					(mid 287.385252 -298.30522)
					(end 286.836612 -297.75658)
				)
				(arc
					(start 285.436564 -297.75658)
					(mid 284.887924 -298.30522)
					(end 285.436564 -298.85386)
				)
			)
		)
		(polygon
			(pts
				(arc
					(start 279.636728 -298.85386)
					(mid 280.185368 -298.30522)
					(end 279.636728 -297.75658)
				)
				(arc
					(start 278.23668 -297.75658)
					(mid 277.68804 -298.30522)
					(end 278.23668 -298.85386)
				)
			)
		)
		(polygon
			(pts
				(arc
					(start 280.636726 -297.053762)
					(mid 281.185366 -296.505122)
					(end 280.636726 -295.956482)
				)
				(arc
					(start 279.236678 -295.956482)
					(mid 278.688038 -296.505122)
					(end 279.236678 -297.053762)
				)
			)
		)
		(polygon
			(pts
				(arc
					(start 287.83661 -297.056302)
					(mid 288.38779 -296.505122)
					(end 287.83661 -295.953942)
				)
				(arc
					(start 286.436562 -295.953942)
					(mid 285.885382 -296.505122)
					(end 286.436562 -297.056302)
				)
			)
		)
		(polygon
			(pts
				(arc
					(start 279.636728 -295.253918)
					(mid 280.185368 -294.705278)
					(end 279.636728 -294.156638)
				)
				(arc
					(start 278.23668 -294.156638)
					(mid 277.68804 -294.705278)
					(end 278.23668 -295.253918)
				)
			)
		)
		(polygon
			(pts
				(arc
					(start 286.836612 -295.256458)
					(mid 287.387792 -294.705278)
					(end 286.836612 -294.154098)
				)
				(arc
					(start 285.436564 -294.154098)
					(mid 284.885384 -294.705278)
					(end 285.436564 -295.256458)
				)
			)
		)
	)
	(zone
		(net "P5V_A_4")
		(layer "In6.Cu")
		(hatch none 0.5)
		(connect_pads
			(clearance 0.5)
		)
		(min_thickness 0.25)
		(fill yes
			(thermal_gap 0.5)
			(thermal_bridge_width 0.5)
			(island_removal_mode 0)
		)
		(polygon
			(pts
				(xy 406.220676 -40.555418) (xy 396.445994 -50.3301) (xy 338.940394 -50.3301) (xy 338.1375 -51.132994)
				(xy 338.1375 -62.532006) (xy 343.068148 -67.462654) (xy 343.068148 -71.021956) (xy 343.51595 -71.469758)
				(xy 403.717252 -71.469758) (xy 408.570176 -76.322682) (xy 408.570176 -129.608326) (xy 409.055824 -130.093974)
				(xy 431.00752 -130.093974) (xy 432.541426 -131.62788) (xy 432.541426 -188.711332) (xy 434.545994 -190.7159)
				(xy 448.693794 -190.7159) (xy 463.5119 -205.534006) (xy 463.5119 -213.865206) (xy 465.412074 -215.76538)
				(xy 485.094026 -215.76538) (xy 485.627426 -215.23198) (xy 485.627426 -116.96192) (xy 478.7011 -110.035594)
				(xy 478.7011 -50.751994) (xy 475.9833 -48.034194) (xy 475.9833 -43.487594) (xy 473.051124 -40.555418)
			)
		)
		(polygon
			(pts
				(arc
					(start 482.870002 -162.178238)
					(mid 482.488875 -161.797492)
					(end 482.108002 -162.178492)
				)
				(arc
					(start 482.108002 -163.321492)
					(mid 482.489002 -163.702492)
					(end 482.870002 -163.321492)
				)
			)
		)
		(polygon
			(pts
				(arc
					(start 438.6199 -162.178238)
					(mid 438.238773 -161.797492)
					(end 437.8579 -162.178492)
				)
				(arc
					(start 437.8579 -163.321492)
					(mid 438.2389 -163.702492)
					(end 438.6199 -163.321492)
				)
			)
		)
		(polygon
			(pts
				(arc
					(start 478.120202 -158.368492)
					(mid 477.739202 -157.987492)
					(end 477.358202 -158.368492)
				)
				(arc
					(start 477.358202 -159.511746)
					(mid 477.739329 -159.892492)
					(end 478.120202 -159.511492)
				)
			)
		)
		(polygon
			(pts
				(arc
					(start 440.2201 -158.368492)
					(mid 439.8391 -157.987492)
					(end 439.4581 -158.368492)
				)
				(arc
					(start 439.4581 -159.511746)
					(mid 439.839227 -159.892492)
					(end 440.2201 -159.511492)
				)
			)
		)
		(polygon
			(pts
				(arc
					(start 451.3199 -47.178214)
					(mid 450.938773 -46.797468)
					(end 450.5579 -47.178468)
				)
				(arc
					(start 450.5579 -48.321468)
					(mid 450.9389 -48.702468)
					(end 451.3199 -48.321468)
				)
			)
		)
		(polygon
			(pts
				(arc
					(start 419.770052 -47.178214)
					(mid 419.388925 -46.797468)
					(end 419.008052 -47.178468)
				)
				(arc
					(start 419.008052 -48.321468)
					(mid 419.389052 -48.702468)
					(end 419.770052 -48.321468)
				)
			)
		)
		(polygon
			(pts
				(arc
					(start 446.5701 -43.368468)
					(mid 446.1891 -42.987468)
					(end 445.8081 -43.368468)
				)
				(arc
					(start 445.8081 -44.511722)
					(mid 446.189227 -44.892468)
					(end 446.5701 -44.511468)
				)
			)
		)
		(polygon
			(pts
				(arc
					(start 415.020252 -43.368468)
					(mid 414.639252 -42.987468)
					(end 414.258252 -43.368468)
				)
				(arc
					(start 414.258252 -44.511722)
					(mid 414.639379 -44.892468)
					(end 415.020252 -44.511468)
				)
			)
		)
	)
	(zone
		(net "GND")
		(layer "In6.Cu")
		(hatch none 0.5)
		(connect_pads
			(clearance 0.5)
		)
		(min_thickness 0.25)
		(fill yes
			(thermal_gap 0.5)
			(thermal_bridge_width 0.5)
			(island_removal_mode 0)
		)
		(polygon
			(pts
				(xy 284.942026 -101.68128) (xy 283.893768 -102.729538) (xy 280.099516 -102.729538) (xy 279.103074 -101.733096)
				(xy 278.252936 -101.733096) (xy 277.438358 -102.547674) (xy 277.438358 -186.839606) (xy 278.012652 -187.4139)
				(xy 282.775406 -187.4139) (xy 287.47974 -182.709566) (xy 287.47974 -103.005636) (xy 286.155384 -101.68128)
			)
		)
		(polygon
			(pts
				(arc
					(start 283.563314 -178.872642)
					(mid 282.622752 -179.186332)
					(end 282.936442 -180.126894)
				)
				(arc
					(start 284.928056 -181.122574)
					(mid 285.874832 -180.817389)
					(end 285.56331 -179.87264)
				)
			)
		)
		(polygon
			(pts
				(arc
					(start 281.074876 -178.149504)
					(mid 281.399742 -177.174906)
					(end 280.425144 -176.85004)
				)
				(xy 280.423874 -176.847754) (xy 278.424132 -177.847752) (xy 278.424132 -177.848006)
				(arc
					(start 278.425148 -177.850038)
					(mid 278.100282 -178.824636)
					(end 279.07488 -179.149502)
				)
				(xy 279.07615 -179.151788) (xy 281.076146 -178.15179)
			)
		)
		(polygon
			(pts
				(arc
					(start 283.563314 -174.87265)
					(mid 282.622752 -175.18634)
					(end 282.936442 -176.126902)
				)
				(arc
					(start 284.928056 -177.122582)
					(mid 285.874832 -176.817397)
					(end 285.56331 -175.872648)
				)
			)
		)
		(polygon
			(pts
				(arc
					(start 281.074876 -174.149512)
					(mid 281.399742 -173.174914)
					(end 280.425144 -172.850048)
				)
				(xy 280.423874 -172.847762) (xy 278.424132 -173.84776) (xy 278.424132 -173.848014)
				(arc
					(start 278.425148 -173.850046)
					(mid 278.100282 -174.824644)
					(end 279.07488 -175.14951)
				)
				(xy 279.07615 -175.151796) (xy 281.076146 -174.151798)
			)
		)
		(polygon
			(pts
				(arc
					(start 283.563314 -170.872658)
					(mid 282.622752 -171.186348)
					(end 282.936442 -172.12691)
				)
				(arc
					(start 284.928056 -173.12259)
					(mid 285.874832 -172.817405)
					(end 285.56331 -171.872656)
				)
			)
		)
		(polygon
			(pts
				(arc
					(start 281.074876 -170.14952)
					(mid 281.399742 -169.174922)
					(end 280.425144 -168.850056)
				)
				(xy 280.423874 -168.84777) (xy 278.424132 -169.847768) (xy 278.424132 -169.848022)
				(arc
					(start 278.425148 -169.850054)
					(mid 278.100282 -170.824652)
					(end 279.07488 -171.149518)
				)
				(xy 279.07615 -171.151804) (xy 281.076146 -170.151806)
			)
		)
		(polygon
			(pts
				(arc
					(start 283.563314 -166.872666)
					(mid 282.622752 -167.186356)
					(end 282.936442 -168.126918)
				)
				(arc
					(start 284.928056 -169.122598)
					(mid 285.874832 -168.817413)
					(end 285.56331 -167.872664)
				)
			)
		)
		(polygon
			(pts
				(arc
					(start 281.074876 -166.149528)
					(mid 281.399742 -165.17493)
					(end 280.425144 -164.850064)
				)
				(xy 280.423874 -164.847778) (xy 278.424132 -165.847776) (xy 278.424132 -165.84803)
				(arc
					(start 278.425148 -165.850062)
					(mid 278.100282 -166.82466)
					(end 279.07488 -167.149526)
				)
				(xy 279.07615 -167.151812) (xy 281.076146 -166.151814)
			)
		)
		(polygon
			(pts
				(arc
					(start 283.563314 -162.872674)
					(mid 282.622752 -163.186364)
					(end 282.936442 -164.126926)
				)
				(arc
					(start 284.928056 -165.122606)
					(mid 285.874832 -164.817421)
					(end 285.56331 -163.872672)
				)
			)
		)
		(polygon
			(pts
				(arc
					(start 281.07386 -162.14725)
					(mid 281.397456 -161.175954)
					(end 280.42616 -160.852358)
				)
				(xy 278.426418 -161.852102)
				(arc
					(start 278.426418 -161.852356)
					(mid 278.102619 -162.8235)
					(end 279.073864 -163.147248)
				)
			)
		)
		(polygon
			(pts
				(arc
					(start 283.571696 -158.877)
					(mid 282.62492 -159.182185)
					(end 282.936442 -160.126934)
				)
				(arc
					(start 284.936438 -161.126932)
					(mid 285.877 -160.813242)
					(end 285.56331 -159.87268)
				)
			)
		)
		(polygon
			(pts
				(arc
					(start 281.07386 -158.147258)
					(mid 281.397456 -157.175962)
					(end 280.42616 -156.852366)
				)
				(xy 278.426418 -157.85211)
				(arc
					(start 278.426418 -157.852364)
					(mid 278.102619 -158.823508)
					(end 279.073864 -159.147256)
				)
			)
		)
		(polygon
			(pts
				(arc
					(start 283.563314 -154.87269)
					(mid 282.622752 -155.18638)
					(end 282.936442 -156.126942)
				)
				(arc
					(start 284.928056 -157.122622)
					(mid 285.874832 -156.817437)
					(end 285.56331 -155.872688)
				)
			)
		)
		(polygon
			(pts
				(arc
					(start 281.07386 -154.147266)
					(mid 281.397456 -153.17597)
					(end 280.42616 -152.852374)
				)
				(xy 278.426418 -153.852118)
				(arc
					(start 278.426418 -153.852372)
					(mid 278.102619 -154.823516)
					(end 279.073864 -155.147264)
				)
			)
		)
		(polygon
			(pts
				(arc
					(start 283.563314 -150.872698)
					(mid 282.622752 -151.186388)
					(end 282.936442 -152.12695)
				)
				(arc
					(start 284.928056 -153.12263)
					(mid 285.874832 -152.817445)
					(end 285.56331 -151.872696)
				)
			)
		)
		(polygon
			(pts
				(arc
					(start 281.07386 -150.147274)
					(mid 281.397456 -149.175978)
					(end 280.42616 -148.852382)
				)
				(xy 278.426418 -149.852126)
				(arc
					(start 278.426418 -149.85238)
					(mid 278.102619 -150.823524)
					(end 279.073864 -151.147272)
				)
			)
		)
		(polygon
			(pts
				(arc
					(start 281.074876 -138.149584)
					(mid 281.399742 -137.174986)
					(end 280.425144 -136.85012)
				)
				(xy 280.423874 -136.847834) (xy 278.424132 -137.847832) (xy 278.424132 -137.848086)
				(arc
					(start 278.425148 -137.850118)
					(mid 278.100282 -138.824716)
					(end 279.07488 -139.149582)
				)
				(xy 279.07615 -139.151868) (xy 281.076146 -138.15187)
			)
		)
		(polygon
			(pts
				(arc
					(start 283.574744 -134.850124)
					(mid 282.600146 -135.17499)
					(end 282.925012 -136.149588)
				)
				(xy 282.923742 -136.151874) (xy 284.923738 -137.151872) (xy 284.923992 -137.151618)
				(arc
					(start 284.925008 -137.149586)
					(mid 285.899606 -136.82472)
					(end 285.57474 -135.850122)
				)
				(xy 285.57601 -135.847836) (xy 283.576014 -134.847838)
			)
		)
		(polygon
			(pts
				(arc
					(start 281.07386 -130.147314)
					(mid 281.397456 -129.176018)
					(end 280.42616 -128.852422)
				)
				(xy 278.426418 -129.852166)
				(arc
					(start 278.426418 -129.85242)
					(mid 278.102619 -130.823564)
					(end 279.073864 -131.147312)
				)
			)
		)
		(polygon
			(pts
				(arc
					(start 283.563314 -126.872746)
					(mid 282.622752 -127.186436)
					(end 282.936442 -128.126998)
				)
				(arc
					(start 284.928056 -129.122678)
					(mid 285.874832 -128.817493)
					(end 285.56331 -127.872744)
				)
			)
		)
		(polygon
			(pts
				(arc
					(start 281.07386 -126.147322)
					(mid 281.397456 -125.176026)
					(end 280.42616 -124.85243)
				)
				(xy 278.426418 -125.852174)
				(arc
					(start 278.426418 -125.852428)
					(mid 278.102619 -126.823572)
					(end 279.073864 -127.14732)
				)
			)
		)
		(polygon
			(pts
				(arc
					(start 283.563314 -122.872754)
					(mid 282.622752 -123.186444)
					(end 282.936442 -124.127006)
				)
				(arc
					(start 284.928056 -125.122686)
					(mid 285.874832 -124.817501)
					(end 285.56331 -123.872752)
				)
			)
		)
		(polygon
			(pts
				(arc
					(start 281.07386 -122.14733)
					(mid 281.397456 -121.176034)
					(end 280.42616 -120.852438)
				)
				(xy 278.426418 -121.852182)
				(arc
					(start 278.426418 -121.852436)
					(mid 278.102619 -122.82358)
					(end 279.073864 -123.147328)
				)
			)
		)
		(polygon
			(pts
				(arc
					(start 283.563314 -118.872762)
					(mid 282.622752 -119.186452)
					(end 282.936442 -120.127014)
				)
				(arc
					(start 284.928056 -121.122694)
					(mid 285.874832 -120.817509)
					(end 285.56331 -119.87276)
				)
			)
		)
		(polygon
			(pts
				(arc
					(start 281.07386 -118.147338)
					(mid 281.397456 -117.176042)
					(end 280.42616 -116.852446)
				)
				(xy 278.426418 -117.85219)
				(arc
					(start 278.426418 -117.852444)
					(mid 278.102619 -118.823588)
					(end 279.073864 -119.147336)
				)
			)
		)
		(polygon
			(pts
				(arc
					(start 283.563314 -114.87277)
					(mid 282.622752 -115.18646)
					(end 282.936442 -116.127022)
				)
				(arc
					(start 284.928056 -117.122702)
					(mid 285.874832 -116.817517)
					(end 285.56331 -115.872768)
				)
			)
		)
		(polygon
			(pts
				(arc
					(start 281.063446 -114.127026)
					(mid 281.377136 -113.186464)
					(end 280.436574 -112.872774)
				)
				(arc
					(start 278.44496 -113.868708)
					(mid 278.120865 -114.809139)
					(end 279.06345 -115.127024)
				)
			)
		)
		(polygon
			(pts
				(arc
					(start 283.576014 -106.847894)
					(mid 282.59786 -107.173776)
					(end 282.923742 -108.15193)
				)
				(arc
					(start 284.923738 -109.151928)
					(mid 285.901892 -108.826046)
					(end 285.57601 -107.847892)
				)
			)
		)
	)
	(zone
		(net "GND")
		(layer "In6.Cu")
		(hatch none 0.5)
		(connect_pads
			(clearance 0.5)
		)
		(min_thickness 0.25)
		(fill yes
			(thermal_gap 0.5)
			(thermal_bridge_width 0.5)
			(island_removal_mode 0)
		)
		(polygon
			(pts
				(xy 221.270068 37.530024)
				(arc
					(start 221.270068 2.999994)
					(mid 220.605201 1.394863)
					(end 219.00007 0.729996)
				)
				(arc
					(start 201.254106 0.729996)
					(mid 200.506839 -0.697991)
					(end 199.00011 -1.27)
				)
				(xy 151.269954 -1.27)
				(arc
					(start 151.269954 -13.999972)
					(mid 150.605087 -15.605103)
					(end 148.999956 -16.26997)
				)
				(arc
					(start 103.000048 -16.26997)
					(mid 101.394917 -15.605103)
					(end 100.73005 -13.999972)
				)
				(xy 100.73005 -1.27) (xy 1.27 -1.27) (xy 1.27 -347.929962)
				(arc
					(start 189.6999 -347.929962)
					(mid 191.305031 -348.594829)
					(end 191.969898 -350.19996)
				)
				(xy 191.969898 -371.730016)
				(arc
					(start 199.00011 -371.730016)
					(mid 200.605241 -372.394883)
					(end 201.270108 -374.000014)
				)
				(xy 201.270108 -419.930072) (xy 229.619048 -419.930072) (xy 230.107236 -419.441884) (xy 230.107236 -405.46401)
				(xy 224.0915 -399.448274) (xy 224.0915 -393.651994) (xy 210.1215 -379.681994) (xy 210.1215 -327.738994)
				(xy 208.709006 -326.3265) (xy 174.673006 -326.3265) (xy 164.132006 -315.7855) (xy 148.003006 -315.7855)
				(xy 142.948406 -310.7309) (xy 6.728206 -310.7309) (xy 5.2705 -309.273194) (xy 5.2705 -298.879006)
				(xy 14.170406 -289.9791) (xy 15.045436 -289.9791) (xy 15.5575 -289.467036) (xy 15.5575 -165.224206)
				(xy 17.352264 -163.429442) (xy 27.944064 -163.429442) (xy 31.036006 -160.3375) (xy 34.368994 -160.3375)
				(xy 39.245794 -165.2143) (xy 49.063148 -165.2143) (xy 51.737006 -162.540442) (xy 60.710064 -162.540442)
				(xy 62.913006 -160.3375) (xy 64.975994 -160.3375) (xy 69.497194 -164.8587) (xy 81.422748 -164.8587)
				(xy 83.233006 -163.048442) (xy 87.708994 -163.048442) (xy 88.9635 -164.302948) (xy 88.9635 -240.469166)
				(xy 91.221052 -242.726718) (xy 154.223212 -242.726718) (xy 164.162994 -252.6665) (xy 172.798994 -252.6665)
				(xy 183.0705 -262.938006) (xy 183.0705 -289.578796) (xy 183.470804 -289.9791) (xy 207.642206 -289.9791)
				(xy 210.5025 -287.118806) (xy 210.5025 -224.457006) (xy 252.9205 -182.039006) (xy 252.9205 21.496782)
				(xy 255.007872 23.584154) (xy 260.592316 23.584154) (xy 261.071106 24.062944) (xy 261.071106 37.530024)
			)
		)
		(polygon
			(pts
				(arc
					(start 223.148652 -416.799776)
					(mid 222.599885 -416.25139)
					(end 222.051372 -416.80003)
				)
				(arc
					(start 222.051372 -418.200078)
					(mid 222.600012 -418.748718)
					(end 223.148652 -418.200078)
				)
			)
		)
		(polygon
			(pts
				(arc
					(start 219.54871 -416.799776)
					(mid 218.999943 -416.25139)
					(end 218.45143 -416.80003)
				)
				(arc
					(start 218.45143 -418.200078)
					(mid 219.00007 -418.748718)
					(end 219.54871 -418.200078)
				)
			)
		)
		(polygon
			(pts
				(arc
					(start 215.948768 -416.799776)
					(mid 215.400001 -416.25139)
					(end 214.851488 -416.80003)
				)
				(arc
					(start 214.851488 -418.200078)
					(mid 215.400128 -418.748718)
					(end 215.948768 -418.200078)
				)
			)
		)
		(polygon
			(pts
				(arc
					(start 212.348826 -416.799776)
					(mid 211.800059 -416.25139)
					(end 211.251546 -416.80003)
				)
				(arc
					(start 211.251546 -418.200078)
					(mid 211.800186 -418.748718)
					(end 212.348826 -418.200078)
				)
			)
		)
		(polygon
			(pts
				(arc
					(start 221.348808 -414.199832)
					(mid 220.800041 -413.651446)
					(end 220.251528 -414.200086)
				)
				(arc
					(start 220.251528 -415.600134)
					(mid 220.800168 -416.148774)
					(end 221.348808 -415.600134)
				)
			)
		)
		(polygon
			(pts
				(arc
					(start 217.748612 -414.199832)
					(mid 217.199845 -413.651446)
					(end 216.651332 -414.200086)
				)
				(arc
					(start 216.651332 -415.600134)
					(mid 217.199972 -416.148774)
					(end 217.748612 -415.600134)
				)
			)
		)
		(polygon
			(pts
				(arc
					(start 214.14867 -414.199832)
					(mid 213.599903 -413.651446)
					(end 213.05139 -414.200086)
				)
				(arc
					(start 213.05139 -415.600134)
					(mid 213.60003 -416.148774)
					(end 214.14867 -415.600134)
				)
			)
		)
		(polygon
			(pts
				(arc
					(start 210.548728 -414.199832)
					(mid 209.999961 -413.651446)
					(end 209.451448 -414.200086)
				)
				(arc
					(start 209.451448 -415.600134)
					(mid 210.000088 -416.148774)
					(end 210.548728 -415.600134)
				)
			)
		)
		(polygon
			(pts
				(arc
					(start 210.548728 -410.59989)
					(mid 209.999961 -410.051504)
					(end 209.451448 -410.600144)
				)
				(arc
					(start 209.451448 -412.000192)
					(mid 210.000088 -412.548832)
					(end 210.548728 -412.000192)
				)
			)
		)
		(polygon
			(pts
				(arc
					(start 221.348808 -406.999948)
					(mid 220.800041 -406.451562)
					(end 220.251528 -407.000202)
				)
				(arc
					(start 220.251528 -408.399996)
					(mid 220.800168 -408.948636)
					(end 221.348808 -408.399996)
				)
			)
		)
		(polygon
			(pts
				(arc
					(start 217.748612 -406.999948)
					(mid 217.199845 -406.451562)
					(end 216.651332 -407.000202)
				)
				(arc
					(start 216.651332 -408.399996)
					(mid 217.199972 -408.948636)
					(end 217.748612 -408.399996)
				)
			)
		)
		(polygon
			(pts
				(arc
					(start 214.14867 -406.999948)
					(mid 213.599903 -406.451562)
					(end 213.05139 -407.000202)
				)
				(arc
					(start 213.05139 -408.399996)
					(mid 213.60003 -408.948636)
					(end 214.14867 -408.399996)
				)
			)
		)
		(polygon
			(pts
				(arc
					(start 210.548728 -406.999948)
					(mid 209.999961 -406.451562)
					(end 209.451448 -407.000202)
				)
				(arc
					(start 209.451448 -408.399996)
					(mid 210.000088 -408.948636)
					(end 210.548728 -408.399996)
				)
			)
		)
		(polygon
			(pts
				(arc
					(start 223.148652 -405.999696)
					(mid 222.599885 -405.45131)
					(end 222.051372 -405.99995)
				)
				(arc
					(start 222.051372 -407.399998)
					(mid 222.600012 -407.948638)
					(end 223.148652 -407.399998)
				)
			)
		)
		(polygon
			(pts
				(arc
					(start 219.54871 -405.999696)
					(mid 218.999943 -405.45131)
					(end 218.45143 -405.99995)
				)
				(arc
					(start 218.45143 -407.399998)
					(mid 219.00007 -407.948638)
					(end 219.54871 -407.399998)
				)
			)
		)
		(polygon
			(pts
				(arc
					(start 215.948768 -405.999696)
					(mid 215.400001 -405.45131)
					(end 214.851488 -405.99995)
				)
				(arc
					(start 214.851488 -407.399998)
					(mid 215.400128 -407.948638)
					(end 215.948768 -407.399998)
				)
			)
		)
		(polygon
			(pts
				(arc
					(start 212.348826 -405.999696)
					(mid 211.800059 -405.45131)
					(end 211.251546 -405.99995)
				)
				(arc
					(start 211.251546 -407.399998)
					(mid 211.800186 -407.948638)
					(end 212.348826 -407.399998)
				)
			)
		)
		(polygon
			(pts
				(arc
					(start 190.639954 -277.178262)
					(mid 190.258827 -276.797516)
					(end 189.877954 -277.178516)
				)
				(arc
					(start 189.877954 -278.321516)
					(mid 190.258954 -278.702516)
					(end 190.639954 -278.321516)
				)
			)
		)
		(polygon
			(pts
				(arc
					(start 240.871756 -178.87696)
					(mid 239.92498 -179.182145)
					(end 240.236502 -180.126894)
				)
				(arc
					(start 242.236498 -181.126892)
					(mid 243.17706 -180.813202)
					(end 242.86337 -179.87264)
				)
			)
		)
		(polygon
			(pts
				(arc
					(start 238.374936 -178.149504)
					(mid 238.699802 -177.174906)
					(end 237.725204 -176.85004)
				)
				(xy 237.723934 -176.847754) (xy 235.724192 -177.847752) (xy 235.724192 -177.848006)
				(arc
					(start 235.725208 -177.850038)
					(mid 235.400342 -178.824636)
					(end 236.37494 -179.149502)
				)
				(xy 236.37621 -179.151788) (xy 238.376206 -178.15179)
			)
		)
		(polygon
			(pts
				(arc
					(start 240.871756 -174.876968)
					(mid 239.92498 -175.182153)
					(end 240.236502 -176.126902)
				)
				(arc
					(start 242.236498 -177.1269)
					(mid 243.17706 -176.81321)
					(end 242.86337 -175.872648)
				)
			)
		)
		(polygon
			(pts
				(arc
					(start 238.374936 -174.149512)
					(mid 238.699802 -173.174914)
					(end 237.725204 -172.850048)
				)
				(xy 237.723934 -172.847762) (xy 235.724192 -173.84776) (xy 235.724192 -173.848014)
				(arc
					(start 235.725208 -173.850046)
					(mid 235.400342 -174.824644)
					(end 236.37494 -175.14951)
				)
				(xy 236.37621 -175.151796) (xy 238.376206 -174.151798)
			)
		)
		(polygon
			(pts
				(arc
					(start 240.871756 -170.876976)
					(mid 239.92498 -171.182161)
					(end 240.236502 -172.12691)
				)
				(arc
					(start 242.236498 -173.126908)
					(mid 243.17706 -172.813218)
					(end 242.86337 -171.872656)
				)
			)
		)
		(polygon
			(pts
				(arc
					(start 238.374936 -170.14952)
					(mid 238.699802 -169.174922)
					(end 237.725204 -168.850056)
				)
				(xy 237.723934 -168.84777) (xy 235.724192 -169.847768) (xy 235.724192 -169.848022)
				(arc
					(start 235.725208 -169.850054)
					(mid 235.400342 -170.824652)
					(end 236.37494 -171.149518)
				)
				(xy 236.37621 -171.151804) (xy 238.376206 -170.151806)
			)
		)
		(polygon
			(pts
				(arc
					(start 240.871756 -166.876984)
					(mid 239.92498 -167.182169)
					(end 240.236502 -168.126918)
				)
				(arc
					(start 242.236498 -169.126916)
					(mid 243.17706 -168.813226)
					(end 242.86337 -167.872664)
				)
			)
		)
		(polygon
			(pts
				(arc
					(start 238.374936 -166.149528)
					(mid 238.699802 -165.17493)
					(end 237.725204 -164.850064)
				)
				(xy 237.723934 -164.847778) (xy 235.724192 -165.847776) (xy 235.724192 -165.84803)
				(arc
					(start 235.725208 -165.850062)
					(mid 235.400342 -166.82466)
					(end 236.37494 -167.149526)
				)
				(xy 236.37621 -167.151812) (xy 238.376206 -166.151814)
			)
		)
		(polygon
			(pts
				(arc
					(start 240.877344 -162.845496)
					(mid 239.895939 -163.172546)
					(end 240.222786 -164.154104)
				)
				(arc
					(start 242.222782 -165.154102)
					(mid 243.204238 -164.82695)
					(end 242.877086 -163.845494)
				)
			)
		)
		(polygon
			(pts
				(arc
					(start 190.639954 -162.178238)
					(mid 190.258827 -161.797492)
					(end 189.877954 -162.178492)
				)
				(arc
					(start 189.877954 -163.321492)
					(mid 190.258954 -163.702492)
					(end 190.639954 -163.321492)
				)
			)
		)
		(polygon
			(pts
				(arc
					(start 159.089852 -162.178238)
					(mid 158.708725 -161.797492)
					(end 158.327852 -162.178492)
				)
				(arc
					(start 158.327852 -163.321492)
					(mid 158.708852 -163.702492)
					(end 159.089852 -163.321492)
				)
			)
		)
		(polygon
			(pts
				(arc
					(start 127.53975 -162.178238)
					(mid 127.158623 -161.797492)
					(end 126.77775 -162.178492)
				)
				(arc
					(start 126.77775 -163.321492)
					(mid 127.15875 -163.702492)
					(end 127.53975 -163.321492)
				)
			)
		)
		(polygon
			(pts
				(arc
					(start 95.989902 -162.178238)
					(mid 95.608775 -161.797492)
					(end 95.227902 -162.178492)
				)
				(arc
					(start 95.227902 -163.321492)
					(mid 95.608902 -163.702492)
					(end 95.989902 -163.321492)
				)
			)
		)
		(polygon
			(pts
				(arc
					(start 238.377222 -162.154108)
					(mid 238.704374 -161.172652)
					(end 237.722918 -160.8455)
				)
				(arc
					(start 235.733844 -161.840164)
					(mid 235.393447 -162.821194)
					(end 236.377226 -163.154106)
				)
			)
		)
		(polygon
			(pts
				(arc
					(start 240.87709 -158.845504)
					(mid 239.895634 -159.172656)
					(end 240.222786 -160.154112)
				)
				(arc
					(start 242.222528 -161.15411)
					(mid 243.204289 -160.82711)
					(end 242.877086 -159.845502)
				)
			)
		)
		(polygon
			(pts
				(arc
					(start 238.377222 -158.154116)
					(mid 238.704374 -157.17266)
					(end 237.722918 -156.845508)
				)
				(arc
					(start 235.733844 -157.840172)
					(mid 235.393447 -158.821202)
					(end 236.377226 -159.154114)
				)
			)
		)
		(polygon
			(pts
				(arc
					(start 240.87709 -154.845512)
					(mid 239.895634 -155.172664)
					(end 240.222786 -156.15412)
				)
				(arc
					(start 242.222528 -157.154118)
					(mid 243.204289 -156.827118)
					(end 242.877086 -155.84551)
				)
			)
		)
		(polygon
			(pts
				(arc
					(start 238.377222 -154.154124)
					(mid 238.704374 -153.172668)
					(end 237.722918 -152.845516)
				)
				(arc
					(start 235.733844 -153.84018)
					(mid 235.393447 -154.82121)
					(end 236.377226 -155.154122)
				)
			)
		)
		(polygon
			(pts
				(arc
					(start 240.877344 -150.84552)
					(mid 239.895939 -151.17257)
					(end 240.222786 -152.154128)
				)
				(arc
					(start 242.222782 -153.154126)
					(mid 243.204238 -152.826974)
					(end 242.877086 -151.845518)
				)
			)
		)
		(polygon
			(pts
				(arc
					(start 238.377222 -150.154132)
					(mid 238.704374 -149.172676)
					(end 237.722918 -148.845524)
				)
				(arc
					(start 235.733844 -149.840188)
					(mid 235.393447 -150.821218)
					(end 236.377226 -151.15413)
				)
			)
		)
		(polygon
			(pts
				(arc
					(start 238.374936 -138.149584)
					(mid 238.699802 -137.174986)
					(end 237.725204 -136.85012)
				)
				(xy 237.723934 -136.847834) (xy 235.724192 -137.847832) (xy 235.724192 -137.848086)
				(arc
					(start 235.725208 -137.850118)
					(mid 235.400342 -138.824716)
					(end 236.37494 -139.149582)
				)
				(xy 236.37621 -139.151868) (xy 238.376206 -138.15187)
			)
		)
		(polygon
			(pts
				(arc
					(start 240.874804 -134.850124)
					(mid 239.900206 -135.17499)
					(end 240.225072 -136.149588)
				)
				(xy 240.223802 -136.151874) (xy 242.223798 -137.151872) (xy 242.224052 -137.151618)
				(arc
					(start 242.225068 -137.149586)
					(mid 243.199666 -136.82472)
					(end 242.8748 -135.850122)
				)
				(xy 242.87607 -135.847836) (xy 240.876074 -134.847838)
			)
		)
		(polygon
			(pts
				(arc
					(start 238.377222 -130.154172)
					(mid 238.704374 -129.172716)
					(end 237.722918 -128.845564)
				)
				(arc
					(start 235.733844 -129.840228)
					(mid 235.393447 -130.821258)
					(end 236.377226 -131.15417)
				)
			)
		)
		(polygon
			(pts
				(arc
					(start 240.891822 -126.844552)
					(mid 239.891674 -127.163691)
					(end 240.219484 -128.161034)
				)
				(arc
					(start 242.21948 -129.161032)
					(mid 243.211096 -128.830324)
					(end 242.880388 -127.838708)
				)
			)
		)
		(polygon
			(pts
				(arc
					(start 238.377222 -126.15418)
					(mid 238.704374 -125.172724)
					(end 237.722918 -124.845572)
				)
				(arc
					(start 235.733844 -125.840236)
					(mid 235.393447 -126.821266)
					(end 236.377226 -127.154178)
				)
			)
		)
		(polygon
			(pts
				(arc
					(start 240.880392 -122.838718)
					(mid 239.888776 -123.169426)
					(end 240.219484 -124.161042)
				)
				(arc
					(start 242.20805 -125.155198)
					(mid 243.208198 -124.836059)
					(end 242.880388 -123.838716)
				)
			)
		)
		(polygon
			(pts
				(arc
					(start 238.3663 -122.159522)
					(mid 238.706697 -121.178492)
					(end 237.722918 -120.84558)
				)
				(arc
					(start 235.722922 -121.845578)
					(mid 235.39577 -122.827034)
					(end 236.377226 -123.154186)
				)
			)
		)
		(polygon
			(pts
				(arc
					(start 240.87709 -118.845584)
					(mid 239.895634 -119.172736)
					(end 240.222786 -120.154192)
				)
				(arc
					(start 242.222528 -121.15419)
					(mid 243.204289 -120.82719)
					(end 242.877086 -119.845582)
				)
			)
		)
		(polygon
			(pts
				(arc
					(start 238.377222 -118.154196)
					(mid 238.704374 -117.17274)
					(end 237.722918 -116.845588)
				)
				(arc
					(start 235.733844 -117.840252)
					(mid 235.393447 -118.821282)
					(end 236.377226 -119.154194)
				)
			)
		)
		(polygon
			(pts
				(arc
					(start 240.877344 -114.845592)
					(mid 239.895939 -115.172642)
					(end 240.222786 -116.1542)
				)
				(arc
					(start 242.222782 -117.154198)
					(mid 243.204238 -116.827046)
					(end 242.877086 -115.84559)
				)
			)
		)
		(polygon
			(pts
				(arc
					(start 238.377222 -114.154204)
					(mid 238.704374 -113.172748)
					(end 237.722918 -112.845596)
				)
				(arc
					(start 235.733844 -113.84026)
					(mid 235.393447 -114.82129)
					(end 236.377226 -115.154202)
				)
			)
		)
		(polygon
			(pts
				(arc
					(start 240.874804 -106.85018)
					(mid 239.900206 -107.175046)
					(end 240.225072 -108.149644)
				)
				(xy 240.223802 -108.15193) (xy 242.223798 -109.151928) (xy 242.224052 -109.151674)
				(arc
					(start 242.225068 -109.149642)
					(mid 243.199666 -108.824776)
					(end 242.8748 -107.850178)
				)
				(xy 242.87607 -107.847892) (xy 240.876074 -106.847894)
			)
		)
		(polygon
			(pts
				(arc
					(start 240.871756 -82.577178)
					(mid 239.92498 -82.882363)
					(end 240.236502 -83.827112)
				)
				(arc
					(start 242.236498 -84.82711)
					(mid 243.17706 -84.51342)
					(end 242.86337 -83.572858)
				)
			)
		)
		(polygon
			(pts
				(arc
					(start 238.374936 -81.849722)
					(mid 238.699802 -80.875124)
					(end 237.725204 -80.550258)
				)
				(xy 237.723934 -80.547972) (xy 235.724192 -81.54797) (xy 235.724192 -81.548224)
				(arc
					(start 235.725208 -81.550256)
					(mid 235.400342 -82.524854)
					(end 236.37494 -82.84972)
				)
				(xy 236.37621 -82.852006) (xy 238.376206 -81.852008)
			)
		)
		(polygon
			(pts
				(arc
					(start 240.863374 -78.572868)
					(mid 239.922812 -78.886558)
					(end 240.236502 -79.82712)
				)
				(arc
					(start 242.228116 -80.8228)
					(mid 243.174892 -80.517615)
					(end 242.86337 -79.572866)
				)
			)
		)
		(polygon
			(pts
				(arc
					(start 238.374936 -77.84973)
					(mid 238.699802 -76.875132)
					(end 237.725204 -76.550266)
				)
				(xy 237.723934 -76.54798) (xy 235.724192 -77.547978) (xy 235.724192 -77.548232)
				(arc
					(start 235.725208 -77.550264)
					(mid 235.400342 -78.524862)
					(end 236.37494 -78.849728)
				)
				(xy 236.37621 -78.852014) (xy 238.376206 -77.852016)
			)
		)
		(polygon
			(pts
				(arc
					(start 240.863374 -74.572876)
					(mid 239.922812 -74.886566)
					(end 240.236502 -75.827128)
				)
				(arc
					(start 242.228116 -76.822808)
					(mid 243.174892 -76.517623)
					(end 242.86337 -75.572874)
				)
			)
		)
		(polygon
			(pts
				(arc
					(start 238.374936 -73.849738)
					(mid 238.699802 -72.87514)
					(end 237.725204 -72.550274)
				)
				(xy 237.723934 -72.547988) (xy 235.724192 -73.547986) (xy 235.724192 -73.54824)
				(arc
					(start 235.725208 -73.550272)
					(mid 235.400342 -74.52487)
					(end 236.37494 -74.849736)
				)
				(xy 236.37621 -74.852022) (xy 238.376206 -73.852024)
			)
		)
		(polygon
			(pts
				(arc
					(start 240.863374 -70.572884)
					(mid 239.922812 -70.886574)
					(end 240.236502 -71.827136)
				)
				(arc
					(start 242.228116 -72.822816)
					(mid 243.174892 -72.517631)
					(end 242.86337 -71.572882)
				)
			)
		)
		(polygon
			(pts
				(arc
					(start 238.374936 -69.849746)
					(mid 238.699802 -68.875148)
					(end 237.725204 -68.550282)
				)
				(xy 237.723934 -68.547996) (xy 235.724192 -69.547994) (xy 235.724192 -69.548248)
				(arc
					(start 235.725208 -69.55028)
					(mid 235.400342 -70.524878)
					(end 236.37494 -70.849744)
				)
				(xy 236.37621 -70.85203) (xy 238.376206 -69.852032)
			)
		)
		(polygon
			(pts
				(arc
					(start 240.871756 -66.57721)
					(mid 239.92498 -66.882395)
					(end 240.236502 -67.827144)
				)
				(arc
					(start 242.236498 -68.827142)
					(mid 243.17706 -68.513452)
					(end 242.86337 -67.57289)
				)
			)
		)
		(polygon
			(pts
				(arc
					(start 238.374936 -65.849754)
					(mid 238.699802 -64.875156)
					(end 237.725204 -64.55029)
				)
				(xy 237.723934 -64.548004) (xy 235.723938 -65.548002)
				(arc
					(start 235.725208 -65.550288)
					(mid 235.400342 -66.524886)
					(end 236.37494 -66.849752)
				)
				(xy 236.37621 -66.852038) (xy 238.375952 -65.85204) (xy 238.375952 -65.851786)
			)
		)
		(polygon
			(pts
				(arc
					(start 240.871756 -62.577218)
					(mid 239.92498 -62.882403)
					(end 240.236502 -63.827152)
				)
				(arc
					(start 242.236498 -64.82715)
					(mid 243.17706 -64.51346)
					(end 242.86337 -63.572898)
				)
			)
		)
		(polygon
			(pts
				(arc
					(start 238.374936 -61.849762)
					(mid 238.699802 -60.875164)
					(end 237.725204 -60.550298)
				)
				(xy 237.723934 -60.548012) (xy 235.724192 -61.54801) (xy 235.724192 -61.548264)
				(arc
					(start 235.725208 -61.550296)
					(mid 235.400342 -62.524894)
					(end 236.37494 -62.84976)
				)
				(xy 236.37621 -62.852046) (xy 238.376206 -61.852048)
			)
		)
		(polygon
			(pts
				(arc
					(start 240.871756 -58.577226)
					(mid 239.92498 -58.882411)
					(end 240.236502 -59.82716)
				)
				(arc
					(start 242.236498 -60.827158)
					(mid 243.17706 -60.513468)
					(end 242.86337 -59.572906)
				)
			)
		)
		(polygon
			(pts
				(arc
					(start 238.374936 -57.84977)
					(mid 238.699802 -56.875172)
					(end 237.725204 -56.550306)
				)
				(xy 237.723934 -56.54802) (xy 235.724192 -57.548018) (xy 235.724192 -57.548272)
				(arc
					(start 235.725208 -57.550304)
					(mid 235.400342 -58.524902)
					(end 236.37494 -58.849768)
				)
				(xy 236.37621 -58.852054) (xy 238.376206 -57.852056)
			)
		)
		(polygon
			(pts
				(arc
					(start 240.871756 -54.577234)
					(mid 239.92498 -54.882419)
					(end 240.236502 -55.827168)
				)
				(arc
					(start 242.236498 -56.827166)
					(mid 243.17706 -56.513476)
					(end 242.86337 -55.572914)
				)
			)
		)
		(polygon
			(pts
				(arc
					(start 238.374936 -53.849778)
					(mid 238.699802 -52.87518)
					(end 237.725204 -52.550314)
				)
				(xy 237.723934 -52.548028) (xy 235.724192 -53.548026) (xy 235.724192 -53.54828)
				(arc
					(start 235.725208 -53.550312)
					(mid 235.400342 -54.52491)
					(end 236.37494 -54.849776)
				)
				(xy 236.37621 -54.852062) (xy 238.376206 -53.852064)
			)
		)
		(polygon
			(pts
				(arc
					(start 240.863374 -50.572924)
					(mid 239.922812 -50.886614)
					(end 240.236502 -51.827176)
				)
				(arc
					(start 242.228116 -52.822856)
					(mid 243.174892 -52.517671)
					(end 242.86337 -51.572922)
				)
			)
		)
		(polygon
			(pts
				(arc
					(start 238.374936 -49.849786)
					(mid 238.699802 -48.875188)
					(end 237.725204 -48.550322)
				)
				(xy 237.723934 -48.548036) (xy 235.724192 -49.548034) (xy 235.724192 -49.548288)
				(arc
					(start 235.725208 -49.55032)
					(mid 235.400342 -50.524918)
					(end 236.37494 -50.849784)
				)
				(xy 236.37621 -50.85207) (xy 238.376206 -49.852072)
			)
		)
		(polygon
			(pts
				(arc
					(start 190.639954 -47.178214)
					(mid 190.258827 -46.797468)
					(end 189.877954 -47.178468)
				)
				(arc
					(start 189.877954 -48.321468)
					(mid 190.258954 -48.702468)
					(end 190.639954 -48.321468)
				)
			)
		)
		(polygon
			(pts
				(arc
					(start 240.871756 -46.57725)
					(mid 239.92498 -46.882435)
					(end 240.236502 -47.827184)
				)
				(arc
					(start 242.236498 -48.827182)
					(mid 243.17706 -48.513492)
					(end 242.86337 -47.57293)
				)
			)
		)
		(polygon
			(pts
				(arc
					(start 238.374936 -45.849794)
					(mid 238.699802 -44.875196)
					(end 237.725204 -44.55033)
				)
				(xy 237.723934 -44.548044) (xy 235.724192 -45.548042) (xy 235.724192 -45.548296)
				(arc
					(start 235.725208 -45.550328)
					(mid 235.400342 -46.524926)
					(end 236.37494 -46.849792)
				)
				(xy 236.37621 -46.852078) (xy 238.376206 -45.85208)
			)
		)
		(polygon
			(pts
				(arc
					(start 240.871756 -42.577258)
					(mid 239.92498 -42.882443)
					(end 240.236502 -43.827192)
				)
				(arc
					(start 242.236498 -44.82719)
					(mid 243.17706 -44.5135)
					(end 242.86337 -43.572938)
				)
			)
		)
		(polygon
			(pts
				(arc
					(start 238.374936 -41.849802)
					(mid 238.699802 -40.875204)
					(end 237.725204 -40.550338)
				)
				(xy 237.723934 -40.548052) (xy 235.724192 -41.54805) (xy 235.724192 -41.548304)
				(arc
					(start 235.725208 -41.550336)
					(mid 235.400342 -42.524934)
					(end 236.37494 -42.8498)
				)
				(xy 236.37621 -42.852086) (xy 238.376206 -41.852088)
			)
		)
		(polygon
			(pts
				(arc
					(start 240.871756 -38.577266)
					(mid 239.92498 -38.882451)
					(end 240.236502 -39.8272)
				)
				(arc
					(start 242.236498 -40.827198)
					(mid 243.17706 -40.513508)
					(end 242.86337 -39.572946)
				)
			)
		)
		(polygon
			(pts
				(arc
					(start 238.374936 -37.84981)
					(mid 238.699802 -36.875212)
					(end 237.725204 -36.550346)
				)
				(xy 237.723934 -36.54806) (xy 235.724192 -37.548058) (xy 235.724192 -37.548312)
				(arc
					(start 235.725208 -37.550344)
					(mid 235.400342 -38.524942)
					(end 236.37494 -38.849808)
				)
				(xy 236.37621 -38.852094) (xy 238.376206 -37.852096)
			)
		)
		(polygon
			(pts
				(arc
					(start 240.876074 -34.548064)
					(mid 239.89792 -34.873946)
					(end 240.223802 -35.8521)
				)
				(arc
					(start 242.223798 -36.852098)
					(mid 243.201952 -36.526216)
					(end 242.87607 -35.548062)
				)
			)
		)
		(polygon
			(pts
				(arc
					(start 143.89862 -29.149802)
					(mid 143.349853 -28.601416)
					(end 142.80134 -29.150056)
				)
				(arc
					(start 142.80134 -30.550104)
					(mid 143.34998 -31.098744)
					(end 143.89862 -30.550104)
				)
			)
		)
		(polygon
			(pts
				(arc
					(start 136.698736 -29.149802)
					(mid 136.149969 -28.601416)
					(end 135.601456 -29.150056)
				)
				(arc
					(start 135.601456 -30.550104)
					(mid 136.150096 -31.098744)
					(end 136.698736 -30.550104)
				)
			)
		)
		(polygon
			(pts
				(arc
					(start 122.301254 -29.150056)
					(mid 121.750074 -28.598876)
					(end 121.198894 -29.150056)
				)
				(arc
					(start 121.198894 -30.550358)
					(mid 121.750201 -31.101284)
					(end 122.301254 -30.550104)
				)
			)
		)
		(polygon
			(pts
				(arc
					(start 116.898674 -28.149804)
					(mid 116.349907 -27.601418)
					(end 115.801394 -28.150058)
				)
				(arc
					(start 115.801394 -29.550106)
					(mid 116.350034 -30.098746)
					(end 116.898674 -29.550106)
				)
			)
		)
		(polygon
			(pts
				(arc
					(start 143.89862 -21.949918)
					(mid 143.349853 -21.401532)
					(end 142.80134 -21.950172)
				)
				(arc
					(start 142.80134 -23.35022)
					(mid 143.34998 -23.89886)
					(end 143.89862 -23.35022)
				)
			)
		)
		(polygon
			(pts
				(arc
					(start 140.298678 -21.949918)
					(mid 139.749911 -21.401532)
					(end 139.201398 -21.950172)
				)
				(arc
					(start 139.201398 -23.35022)
					(mid 139.750038 -23.89886)
					(end 140.298678 -23.35022)
				)
			)
		)
		(polygon
			(pts
				(arc
					(start 136.698736 -21.949918)
					(mid 136.149969 -21.401532)
					(end 135.601456 -21.950172)
				)
				(arc
					(start 135.601456 -23.35022)
					(mid 136.150096 -23.89886)
					(end 136.698736 -23.35022)
				)
			)
		)
		(polygon
			(pts
				(arc
					(start 133.09854 -21.949918)
					(mid 132.549773 -21.401532)
					(end 132.00126 -21.950172)
				)
				(arc
					(start 132.00126 -23.35022)
					(mid 132.5499 -23.89886)
					(end 133.09854 -23.35022)
				)
			)
		)
		(polygon
			(pts
				(arc
					(start 122.298714 -21.949918)
					(mid 121.749947 -21.401532)
					(end 121.201434 -21.950172)
				)
				(arc
					(start 121.201434 -23.35022)
					(mid 121.750074 -23.89886)
					(end 122.298714 -23.35022)
				)
			)
		)
		(polygon
			(pts
				(arc
					(start 118.698518 -21.949918)
					(mid 118.149751 -21.401532)
					(end 117.601238 -21.950172)
				)
				(arc
					(start 117.601238 -23.35022)
					(mid 118.149878 -23.89886)
					(end 118.698518 -23.35022)
				)
			)
		)
		(polygon
			(pts
				(arc
					(start 115.098576 -21.949918)
					(mid 114.549809 -21.401532)
					(end 114.001296 -21.950172)
				)
				(arc
					(start 114.001296 -23.35022)
					(mid 114.549936 -23.89886)
					(end 115.098576 -23.35022)
				)
			)
		)
		(polygon
			(pts
				(arc
					(start 111.498634 -21.949918)
					(mid 110.949867 -21.401532)
					(end 110.401354 -21.950172)
				)
				(arc
					(start 110.401354 -23.35022)
					(mid 110.949994 -23.89886)
					(end 111.498634 -23.35022)
				)
			)
		)
		(polygon
			(pts
				(arc
					(start 142.098522 -20.94992)
					(mid 141.549755 -20.401534)
					(end 141.001242 -20.950174)
				)
				(arc
					(start 141.001242 -22.350222)
					(mid 141.549882 -22.898862)
					(end 142.098522 -22.350222)
				)
			)
		)
		(polygon
			(pts
				(arc
					(start 138.49858 -20.94992)
					(mid 137.949813 -20.401534)
					(end 137.4013 -20.950174)
				)
				(arc
					(start 137.4013 -22.350222)
					(mid 137.94994 -22.898862)
					(end 138.49858 -22.350222)
				)
			)
		)
		(polygon
			(pts
				(arc
					(start 134.898638 -20.94992)
					(mid 134.349871 -20.401534)
					(end 133.801358 -20.950174)
				)
				(arc
					(start 133.801358 -22.350222)
					(mid 134.349998 -22.898862)
					(end 134.898638 -22.350222)
				)
			)
		)
		(polygon
			(pts
				(arc
					(start 131.298696 -20.94992)
					(mid 130.749929 -20.401534)
					(end 130.201416 -20.950174)
				)
				(arc
					(start 130.201416 -22.350222)
					(mid 130.750056 -22.898862)
					(end 131.298696 -22.350222)
				)
			)
		)
		(polygon
			(pts
				(arc
					(start 120.498616 -20.94992)
					(mid 119.949849 -20.401534)
					(end 119.401336 -20.950174)
				)
				(arc
					(start 119.401336 -22.350222)
					(mid 119.949976 -22.898862)
					(end 120.498616 -22.350222)
				)
			)
		)
		(polygon
			(pts
				(arc
					(start 116.898674 -20.94992)
					(mid 116.349907 -20.401534)
					(end 115.801394 -20.950174)
				)
				(arc
					(start 115.801394 -22.350222)
					(mid 116.350034 -22.898862)
					(end 116.898674 -22.350222)
				)
			)
		)
		(polygon
			(pts
				(arc
					(start 113.298732 -20.94992)
					(mid 112.749965 -20.401534)
					(end 112.201452 -20.950174)
				)
				(arc
					(start 112.201452 -22.350222)
					(mid 112.750092 -22.898862)
					(end 113.298732 -22.350222)
				)
			)
		)
		(polygon
			(pts
				(arc
					(start 109.698536 -20.94992)
					(mid 109.149769 -20.401534)
					(end 108.601256 -20.950174)
				)
				(arc
					(start 108.601256 -22.350222)
					(mid 109.149896 -22.898862)
					(end 109.698536 -22.350222)
				)
			)
		)
		(polygon
			(pts
				(arc
					(start 133.09854 -18.35023)
					(mid 132.5499 -17.80159)
					(end 132.00126 -18.35023)
				)
				(arc
					(start 132.00126 -19.750278)
					(mid 132.550027 -20.298664)
					(end 133.09854 -19.750024)
				)
			)
		)
		(polygon
			(pts
				(arc
					(start 143.89862 -18.349976)
					(mid 143.349853 -17.80159)
					(end 142.80134 -18.35023)
				)
				(arc
					(start 142.80134 -19.750024)
					(mid 143.34998 -20.298664)
					(end 143.89862 -19.750024)
				)
			)
		)
		(polygon
			(pts
				(arc
					(start 140.298678 -18.349976)
					(mid 139.749911 -17.80159)
					(end 139.201398 -18.35023)
				)
				(arc
					(start 139.201398 -19.750024)
					(mid 139.750038 -20.298664)
					(end 140.298678 -19.750024)
				)
			)
		)
		(polygon
			(pts
				(arc
					(start 136.698736 -18.349976)
					(mid 136.149969 -17.80159)
					(end 135.601456 -18.35023)
				)
				(arc
					(start 135.601456 -19.750024)
					(mid 136.150096 -20.298664)
					(end 136.698736 -19.750024)
				)
			)
		)
		(polygon
			(pts
				(arc
					(start 122.298714 -18.349976)
					(mid 121.749947 -17.80159)
					(end 121.201434 -18.35023)
				)
				(arc
					(start 121.201434 -19.750024)
					(mid 121.750074 -20.298664)
					(end 122.298714 -19.750024)
				)
			)
		)
		(polygon
			(pts
				(arc
					(start 118.698518 -18.349976)
					(mid 118.149751 -17.80159)
					(end 117.601238 -18.35023)
				)
				(arc
					(start 117.601238 -19.750024)
					(mid 118.149878 -20.298664)
					(end 118.698518 -19.750024)
				)
			)
		)
		(polygon
			(pts
				(arc
					(start 115.098576 -18.349976)
					(mid 114.549809 -17.80159)
					(end 114.001296 -18.35023)
				)
				(arc
					(start 114.001296 -19.750024)
					(mid 114.549936 -20.298664)
					(end 115.098576 -19.750024)
				)
			)
		)
		(polygon
			(pts
				(arc
					(start 111.498634 -18.349976)
					(mid 110.949867 -17.80159)
					(end 110.401354 -18.35023)
				)
				(arc
					(start 110.401354 -19.750024)
					(mid 110.949994 -20.298664)
					(end 111.498634 -19.750024)
				)
			)
		)
		(polygon
			(pts
				(arc
					(start 142.098522 -17.349724)
					(mid 141.549755 -16.801338)
					(end 141.001242 -17.349978)
				)
				(arc
					(start 141.001242 -18.750026)
					(mid 141.549882 -19.298666)
					(end 142.098522 -18.750026)
				)
			)
		)
		(polygon
			(pts
				(arc
					(start 138.49858 -17.349724)
					(mid 137.949813 -16.801338)
					(end 137.4013 -17.349978)
				)
				(arc
					(start 137.4013 -18.750026)
					(mid 137.94994 -19.298666)
					(end 138.49858 -18.750026)
				)
			)
		)
		(polygon
			(pts
				(arc
					(start 134.898638 -17.349724)
					(mid 134.349871 -16.801338)
					(end 133.801358 -17.349978)
				)
				(arc
					(start 133.801358 -18.750026)
					(mid 134.349998 -19.298666)
					(end 134.898638 -18.750026)
				)
			)
		)
		(polygon
			(pts
				(arc
					(start 131.298696 -17.349724)
					(mid 130.749929 -16.801338)
					(end 130.201416 -17.349978)
				)
				(arc
					(start 130.201416 -18.750026)
					(mid 130.750056 -19.298666)
					(end 131.298696 -18.750026)
				)
			)
		)
		(polygon
			(pts
				(arc
					(start 120.498616 -17.349724)
					(mid 119.949849 -16.801338)
					(end 119.401336 -17.349978)
				)
				(arc
					(start 119.401336 -18.750026)
					(mid 119.949976 -19.298666)
					(end 120.498616 -18.750026)
				)
			)
		)
		(polygon
			(pts
				(arc
					(start 116.898674 -17.349724)
					(mid 116.349907 -16.801338)
					(end 115.801394 -17.349978)
				)
				(arc
					(start 115.801394 -18.750026)
					(mid 116.350034 -19.298666)
					(end 116.898674 -18.750026)
				)
			)
		)
		(polygon
			(pts
				(arc
					(start 113.298732 -17.349724)
					(mid 112.749965 -16.801338)
					(end 112.201452 -17.349978)
				)
				(arc
					(start 112.201452 -18.750026)
					(mid 112.750092 -19.298666)
					(end 113.298732 -18.750026)
				)
			)
		)
		(polygon
			(pts
				(arc
					(start 109.698536 -17.349724)
					(mid 109.149769 -16.801338)
					(end 108.601256 -17.349978)
				)
				(arc
					(start 108.601256 -18.750026)
					(mid 109.149896 -19.298666)
					(end 109.698536 -18.750026)
				)
			)
		)
		(polygon
			(pts
				(arc
					(start 238.374936 -17.84985)
					(mid 238.699802 -16.875252)
					(end 237.725204 -16.550386)
				)
				(xy 237.723934 -16.5481) (xy 235.724192 -17.548098) (xy 235.724192 -17.548352)
				(arc
					(start 235.725208 -17.550384)
					(mid 235.400342 -18.524982)
					(end 236.37494 -18.849848)
				)
				(xy 236.37621 -18.852134) (xy 238.376206 -17.852136)
			)
		)
		(polygon
			(pts
				(arc
					(start 238.377222 -11.854434)
					(mid 238.704374 -10.872978)
					(end 237.722918 -10.545826)
				)
				(arc
					(start 235.733844 -11.54049)
					(mid 235.393447 -12.52152)
					(end 236.377226 -12.854432)
				)
			)
		)
		(polygon
			(pts
				(xy 218.216988 -8.401558) (xy 197.796912 -8.401558) (xy 189.9285 -16.26997) (xy 185.899806 -20.298664)
				(xy 173.312328 -32.886142) (xy 173.312328 -49.430178) (xy 172.590206 -50.1523) (xy 164.594794 -50.1523)
				(xy 159.844994 -45.4025) (xy 157.909006 -45.4025) (xy 155.445206 -47.8663) (xy 142.135606 -47.8663)
				(xy 139.875006 -50.1269) (xy 132.438394 -50.1269) (xy 127.713994 -45.4025) (xy 125.651006 -45.4025)
				(xy 122.831606 -48.2219) (xy 114.170206 -48.2219) (xy 112.519206 -49.8729) (xy 100.942394 -49.8729)
				(xy 96.344994 -45.2755) (xy 94.917006 -45.2755) (xy 91.716606 -48.4759) (xy 82.598006 -48.4759)
				(xy 80.870806 -50.2031) (xy 72.570594 -50.2031) (xy 67.769994 -45.4025) (xy 62.786006 -45.4025)
				(xy 60.068206 -48.1203) (xy 51.508406 -48.1203) (xy 49.832006 -49.7967) (xy 42.827194 -49.7967)
				(xy 38.305994 -45.2755) (xy 30.655006 -45.2755) (xy 28.242006 -47.6885) (xy 20.342606 -47.6885)
				(xy 17.2847 -50.746406) (xy 17.2847 -110.543594) (xy 54.526434 -147.785328) (xy 68.826126 -147.785328)
				(xy 70.472554 -146.1389) (xy 104.111806 -146.1389) (xy 111.4933 -153.520394) (xy 111.4933 -167.845994)
				(xy 112.290606 -168.6433) (xy 124.234194 -168.6433) (xy 126.1745 -166.702994) (xy 126.1745 -160.860994)
				(xy 126.570994 -160.4645) (xy 127.683006 -160.4645) (xy 135.861806 -168.6433) (xy 154.841194 -168.6433)
				(xy 157.4165 -166.067994) (xy 157.4165 -161.749994) (xy 158.447994 -160.7185) (xy 159.941006 -160.7185)
				(xy 167.865806 -168.6433) (xy 181.790594 -168.6433) (xy 183.2229 -167.210994) (xy 183.2229 -46.698916)
				(xy 218.745308 -11.176508) (xy 218.745308 -8.929878)
			)
		)
	)
	(zone
		(net "GND")
		(layer "In6.Cu")
		(hatch none 0.5)
		(connect_pads
			(clearance 0.5)
		)
		(min_thickness 0.25)
		(fill yes
			(thermal_gap 0.5)
			(thermal_bridge_width 0.5)
			(island_removal_mode 0)
		)
		(polygon
			(pts
				(xy 273.028918 -235.173012) (xy 270.216884 -237.985046) (xy 270.216884 -263.67232) (xy 272.193512 -265.648948)
				(xy 304.897282 -265.648948) (xy 307.207158 -263.339072) (xy 307.207158 -237.928658) (xy 304.451512 -235.173012)
			)
		)
		(polygon
			(pts
				(arc
					(start 284.236668 -264.250932)
					(mid 284.785308 -263.702292)
					(end 284.236668 -263.153652)
				)
				(arc
					(start 282.83662 -263.153652)
					(mid 282.28798 -263.702292)
					(end 282.83662 -264.250932)
				)
			)
		)
		(polygon
			(pts
				(arc
					(start 287.83661 -264.253472)
					(mid 288.38779 -263.702292)
					(end 287.83661 -263.151112)
				)
				(arc
					(start 286.436562 -263.151112)
					(mid 285.885382 -263.702292)
					(end 286.436562 -264.253472)
				)
			)
		)
		(polygon
			(pts
				(arc
					(start 280.636726 -264.253472)
					(mid 281.187906 -263.702292)
					(end 280.636726 -263.151112)
				)
				(arc
					(start 279.236678 -263.151112)
					(mid 278.685498 -263.702292)
					(end 279.236678 -264.253472)
				)
			)
		)
		(polygon
			(pts
				(arc
					(start 286.836612 -262.453374)
					(mid 287.387792 -261.902194)
					(end 286.836612 -261.351014)
				)
				(arc
					(start 285.436564 -261.351014)
					(mid 284.885384 -261.902194)
					(end 285.436564 -262.453374)
				)
			)
		)
		(polygon
			(pts
				(arc
					(start 279.636728 -262.453374)
					(mid 280.187908 -261.902194)
					(end 279.636728 -261.351014)
				)
				(arc
					(start 278.23668 -261.351014)
					(mid 277.6855 -261.902194)
					(end 278.23668 -262.453374)
				)
			)
		)
		(polygon
			(pts
				(arc
					(start 287.83661 -260.65353)
					(mid 288.38779 -260.10235)
					(end 287.83661 -259.55117)
				)
				(arc
					(start 286.436562 -259.55117)
					(mid 285.885382 -260.10235)
					(end 286.436562 -260.65353)
				)
			)
		)
		(polygon
			(pts
				(arc
					(start 280.636726 -260.65353)
					(mid 281.187906 -260.10235)
					(end 280.636726 -259.55117)
				)
				(arc
					(start 279.236678 -259.55117)
					(mid 278.685498 -260.10235)
					(end 279.236678 -260.65353)
				)
			)
		)
		(polygon
			(pts
				(arc
					(start 286.836612 -258.853432)
					(mid 287.387792 -258.302252)
					(end 286.836612 -257.751072)
				)
				(arc
					(start 285.436564 -257.751072)
					(mid 284.885384 -258.302252)
					(end 285.436564 -258.853432)
				)
			)
		)
		(polygon
			(pts
				(arc
					(start 279.636728 -258.853432)
					(mid 280.187908 -258.302252)
					(end 279.636728 -257.751072)
				)
				(arc
					(start 278.23668 -257.751072)
					(mid 277.6855 -258.302252)
					(end 278.23668 -258.853432)
				)
			)
		)
		(polygon
			(pts
				(arc
					(start 287.83661 -257.053588)
					(mid 288.38779 -256.502408)
					(end 287.83661 -255.951228)
				)
				(arc
					(start 286.436562 -255.951228)
					(mid 285.885382 -256.502408)
					(end 286.436562 -257.053588)
				)
			)
		)
		(polygon
			(pts
				(arc
					(start 280.636726 -257.053588)
					(mid 281.187906 -256.502408)
					(end 280.636726 -255.951228)
				)
				(arc
					(start 279.236678 -255.951228)
					(mid 278.685498 -256.502408)
					(end 279.236678 -257.053588)
				)
			)
		)
		(polygon
			(pts
				(arc
					(start 286.836612 -255.25349)
					(mid 287.387792 -254.70231)
					(end 286.836612 -254.15113)
				)
				(arc
					(start 285.436564 -254.15113)
					(mid 284.885384 -254.70231)
					(end 285.436564 -255.25349)
				)
			)
		)
		(polygon
			(pts
				(arc
					(start 279.636728 -255.25349)
					(mid 280.187908 -254.70231)
					(end 279.636728 -254.15113)
				)
				(arc
					(start 278.23668 -254.15113)
					(mid 277.6855 -254.70231)
					(end 278.23668 -255.25349)
				)
			)
		)
		(polygon
			(pts
				(arc
					(start 287.83661 -253.453392)
					(mid 288.38779 -252.902212)
					(end 287.83661 -252.351032)
				)
				(arc
					(start 286.436562 -252.351032)
					(mid 285.885382 -252.902212)
					(end 286.436562 -253.453392)
				)
			)
		)
		(polygon
			(pts
				(arc
					(start 280.636726 -253.453392)
					(mid 281.187906 -252.902212)
					(end 280.636726 -252.351032)
				)
				(arc
					(start 279.236678 -252.351032)
					(mid 278.685498 -252.902212)
					(end 279.236678 -253.453392)
				)
			)
		)
		(polygon
			(pts
				(arc
					(start 286.836612 -251.653548)
					(mid 287.387792 -251.102368)
					(end 286.836612 -250.551188)
				)
				(arc
					(start 285.436564 -250.551188)
					(mid 284.885384 -251.102368)
					(end 285.436564 -251.653548)
				)
			)
		)
		(polygon
			(pts
				(arc
					(start 279.636728 -251.653548)
					(mid 280.187908 -251.102368)
					(end 279.636728 -250.551188)
				)
				(arc
					(start 278.23668 -250.551188)
					(mid 277.6855 -251.102368)
					(end 278.23668 -251.653548)
				)
			)
		)
	)
	(zone
		(net "P5V_A_2")
		(layer "In6.Cu")
		(hatch none 0.5)
		(connect_pads
			(clearance 0.5)
		)
		(min_thickness 0.25)
		(fill yes
			(thermal_gap 0.5)
			(thermal_bridge_width 0.5)
			(island_removal_mode 0)
		)
		(polygon
			(pts
				(xy 197.9549 -8.782558) (xy 173.693328 -33.04413) (xy 173.693328 -49.588166) (xy 172.748194 -50.5333)
				(xy 164.436806 -50.5333) (xy 159.687006 -45.7835) (xy 158.066994 -45.7835) (xy 155.603194 -48.2473)
				(xy 142.293594 -48.2473) (xy 140.032994 -50.5079) (xy 132.280406 -50.5079) (xy 127.556006 -45.7835)
				(xy 125.808994 -45.7835) (xy 122.989594 -48.6029) (xy 114.328194 -48.6029) (xy 112.677194 -50.2539)
				(xy 100.784406 -50.2539) (xy 96.187006 -45.6565) (xy 95.074994 -45.6565) (xy 91.874594 -48.8569)
				(xy 82.755994 -48.8569) (xy 81.028794 -50.5841) (xy 72.412606 -50.5841) (xy 67.612006 -45.7835)
				(xy 62.943994 -45.7835) (xy 60.226194 -48.5013) (xy 51.666394 -48.5013) (xy 49.989994 -50.1777)
				(xy 42.669206 -50.1777) (xy 38.148006 -45.6565) (xy 30.812994 -45.6565) (xy 28.399994 -48.0695)
				(xy 20.500594 -48.0695) (xy 17.6657 -50.904394) (xy 17.6657 -110.385606) (xy 54.684422 -147.404328)
				(xy 68.668138 -147.404328) (xy 70.314566 -145.7579) (xy 104.269794 -145.7579) (xy 111.8743 -153.362406)
				(xy 111.8743 -167.688006) (xy 112.448594 -168.2623) (xy 124.076206 -168.2623) (xy 125.7935 -166.545006)
				(xy 125.7935 -160.703006) (xy 126.413006 -160.0835) (xy 127.840994 -160.0835) (xy 136.019794 -168.2623)
				(xy 154.683206 -168.2623) (xy 157.0355 -165.910006) (xy 157.0355 -161.592006) (xy 158.290006 -160.3375)
				(xy 160.098994 -160.3375) (xy 168.023794 -168.2623) (xy 181.632606 -168.2623) (xy 182.8419 -167.053006)
				(xy 182.8419 -46.540928) (xy 218.364308 -11.01852) (xy 218.364308 -9.087866) (xy 218.059 -8.782558)
			)
		)
		(polygon
			(pts
				(arc
					(start 159.089852 -47.178214)
					(mid 158.708725 -46.797468)
					(end 158.327852 -47.178468)
				)
				(arc
					(start 158.327852 -48.321468)
					(mid 158.708852 -48.702468)
					(end 159.089852 -48.321468)
				)
			)
		)
		(polygon
			(pts
				(arc
					(start 127.53975 -47.178214)
					(mid 127.158623 -46.797468)
					(end 126.77775 -47.178468)
				)
				(arc
					(start 126.77775 -48.321468)
					(mid 127.15875 -48.702468)
					(end 127.53975 -48.321468)
				)
			)
		)
		(polygon
			(pts
				(arc
					(start 95.989902 -47.178214)
					(mid 95.608775 -46.797468)
					(end 95.227902 -47.178468)
				)
				(arc
					(start 95.227902 -48.321468)
					(mid 95.608902 -48.702468)
					(end 95.989902 -48.321468)
				)
			)
		)
		(polygon
			(pts
				(arc
					(start 64.4398 -47.178214)
					(mid 64.058673 -46.797468)
					(end 63.6778 -47.178468)
				)
				(arc
					(start 63.6778 -48.321468)
					(mid 64.0588 -48.702468)
					(end 64.4398 -48.321468)
				)
			)
		)
		(polygon
			(pts
				(arc
					(start 32.889952 -47.178214)
					(mid 32.508825 -46.797468)
					(end 32.127952 -47.178468)
				)
				(arc
					(start 32.127952 -48.321468)
					(mid 32.508952 -48.702468)
					(end 32.889952 -48.321468)
				)
			)
		)
	)
	(zone
		(net "P5V_B")
		(layer "In6.Cu")
		(hatch none 0.5)
		(connect_pads
			(clearance 0.5)
		)
		(min_thickness 0.25)
		(fill yes
			(thermal_gap 0.5)
			(thermal_bridge_width 0.5)
			(island_removal_mode 0)
		)
		(polygon
			(pts
				(xy 401.639278 -283.320998) (xy 398.278858 -286.681418) (xy 305.408076 -286.681418) (xy 290.0045 -302.084994)
				(xy 290.0045 -358.751886) (xy 287.382458 -361.373928) (xy 287.382458 -366.328452) (xy 287.766506 -366.7125)
				(xy 294.429942 -366.7125)
				(arc
					(start 294.429942 -350.19996)
					(mid 295.094809 -348.594829)
					(end 296.69994 -347.929962)
				)
				(xy 297.700446 -347.929962) (xy 297.7007 -347.929708) (xy 297.7007 -321.408806) (xy 318.183006 -300.9265)
				(xy 469.186006 -300.9265) (xy 470.4715 -299.641006) (xy 470.4715 -287.158938) (xy 469.995504 -286.682942)
				(xy 469.860884 -286.682942) (xy 469.85936 -286.681418) (xy 417.02482 -286.681418) (xy 413.6644 -283.320998)
			)
		)
	)
	(zone
		(net "GND")
		(layer "In6.Cu")
		(hatch none 0.5)
		(connect_pads
			(clearance 0.5)
		)
		(min_thickness 0.25)
		(fill yes
			(thermal_gap 0.5)
			(thermal_bridge_width 0.5)
			(island_removal_mode 0)
		)
		(polygon
			(pts
				(xy 397.26997 -1.27)
				(arc
					(start 397.26997 -13.999972)
					(mid 396.605103 -15.605103)
					(end 394.999972 -16.26997)
				)
				(xy 349.738442 -16.26997) (xy 349.396304 -16.612362) (xy 349.396304 -33.270444) (xy 349.879158 -33.753298)
				(xy 368.059208 -33.753298) (xy 369.28171 -32.530796) (xy 369.28171 -25.807924) (xy 371.912134 -23.1775)
				(xy 378.001276 -23.1775)
				(arc
					(start 378.001276 -21.950172)
					(mid 378.549789 -21.401532)
					(end 379.098556 -21.949918)
				)
				(arc
					(start 379.098556 -23.35022)
					(mid 379.009483 -23.649968)
					(end 378.77115 -23.852378)
				)
				(xy 380.5555 -25.636474) (xy 380.5555 -49.452276) (xy 381.052324 -49.9491) (xy 396.288006 -49.9491)
				(xy 406.062688 -40.174418) (xy 473.209112 -40.174418) (xy 476.3643 -43.329606) (xy 476.3643 -47.876206)
				(xy 479.0821 -50.594006) (xy 479.0821 -109.877606) (xy 486.008426 -116.803932) (xy 486.008426 -116.882926)
				(xy 486.008426 -215.389968) (xy 485.252014 -216.14638) (xy 465.254086 -216.14638) (xy 463.1309 -214.023194)
				(xy 463.1309 -205.691994) (xy 448.535806 -191.0969) (xy 434.388006 -191.0969) (xy 432.160426 -188.86932)
				(xy 432.160426 -131.785868) (xy 430.849532 -130.474974) (xy 408.897836 -130.474974) (xy 408.189176 -129.766314)
				(xy 408.189176 -76.48067) (xy 403.559264 -71.850758) (xy 343.508584 -71.850758) (xy 343.068148 -72.291194)
				(xy 343.068148 -142.674848) (xy 345.205812 -144.812512) (xy 353.282758 -144.812512) (xy 354.026724 -145.556478)
				(xy 354.026724 -154.644852) (xy 352.946462 -155.725114) (xy 342.132666 -155.725114) (xy 338.307426 -159.550354)
				(xy 338.307426 -163.34994) (xy 338.702904 -163.745418) (xy 350.171512 -163.745418) (xy 352.199194 -165.7731)
				(xy 369.15725 -165.7731) (xy 371.184932 -163.745418) (xy 402.20392 -163.745418) (xy 403.458426 -164.999924)
				(xy 403.458426 -235.792772) (xy 410.714952 -243.049298) (xy 474.531182 -243.049298) (xy 476.009716 -244.527832)
				(xy 476.009716 -259.453634) (xy 480.420426 -263.864344) (xy 480.420426 -281.870912) (xy 475.60992 -286.681418)
				(xy 471.288364 -286.681418) (xy 470.8525 -287.117282) (xy 470.8525 -299.798994) (xy 469.343994 -301.3075)
				(xy 318.340994 -301.3075) (xy 298.0817 -321.566794) (xy 298.0817 -347.929962) (xy 490.180122 -347.929962)
				(xy 490.180122 -1.27)
			)
		)
		(polygon
			(pts
				(arc
					(start 482.870002 -277.178262)
					(mid 482.488875 -276.797516)
					(end 482.108002 -277.178516)
				)
				(arc
					(start 482.108002 -278.321516)
					(mid 482.489002 -278.702516)
					(end 482.870002 -278.321516)
				)
			)
		)
		(polygon
			(pts
				(arc
					(start 419.770052 -162.178238)
					(mid 419.388925 -161.797492)
					(end 419.008052 -162.178492)
				)
				(arc
					(start 419.008052 -163.321492)
					(mid 419.389052 -163.702492)
					(end 419.770052 -163.321492)
				)
			)
		)
		(polygon
			(pts
				(arc
					(start 388.21995 -162.178238)
					(mid 387.838823 -161.797492)
					(end 387.45795 -162.178492)
				)
				(arc
					(start 387.45795 -163.321492)
					(mid 387.83895 -163.702492)
					(end 388.21995 -163.321492)
				)
			)
		)
		(polygon
			(pts
				(arc
					(start 356.670102 -162.178238)
					(mid 356.288975 -161.797492)
					(end 355.908102 -162.178492)
				)
				(arc
					(start 355.908102 -163.321492)
					(mid 356.289102 -163.702492)
					(end 356.670102 -163.321492)
				)
			)
		)
		(polygon
			(pts
				(arc
					(start 415.020252 -158.368492)
					(mid 414.639252 -157.987492)
					(end 414.258252 -158.368492)
				)
				(arc
					(start 414.258252 -159.511746)
					(mid 414.639379 -159.892492)
					(end 415.020252 -159.511492)
				)
			)
		)
		(polygon
			(pts
				(arc
					(start 383.47015 -158.368492)
					(mid 383.08915 -157.987492)
					(end 382.70815 -158.368492)
				)
				(arc
					(start 382.70815 -159.511746)
					(mid 383.089277 -159.892492)
					(end 383.47015 -159.511492)
				)
			)
		)
		(polygon
			(pts
				(arc
					(start 351.920302 -158.368492)
					(mid 351.539302 -157.987492)
					(end 351.158302 -158.368492)
				)
				(arc
					(start 351.158302 -159.511746)
					(mid 351.539429 -159.892492)
					(end 351.920302 -159.511492)
				)
			)
		)
		(polygon
			(pts
				(arc
					(start 482.870002 -47.178214)
					(mid 482.488875 -46.797468)
					(end 482.108002 -47.178468)
				)
				(arc
					(start 482.108002 -48.321468)
					(mid 482.489002 -48.702468)
					(end 482.870002 -48.321468)
				)
			)
		)
		(polygon
			(pts
				(arc
					(start 388.21995 -47.178214)
					(mid 387.838823 -46.797468)
					(end 387.45795 -47.178468)
				)
				(arc
					(start 387.45795 -48.321468)
					(mid 387.83895 -48.702468)
					(end 388.21995 -48.321468)
				)
			)
		)
		(polygon
			(pts
				(arc
					(start 383.908554 -46.5328)
					(mid 384.2893 -46.151673)
					(end 383.9083 -45.7708)
				)
				(arc
					(start 382.7653 -45.7708)
					(mid 382.3843 -46.1518)
					(end 382.7653 -46.5328)
				)
			)
		)
		(polygon
			(pts
				(arc
					(start 478.120202 -43.368468)
					(mid 477.739202 -42.987468)
					(end 477.358202 -43.368468)
				)
				(arc
					(start 477.358202 -44.511722)
					(mid 477.739329 -44.892468)
					(end 478.120202 -44.511468)
				)
			)
		)
		(polygon
			(pts
				(arc
					(start 389.898636 -29.149802)
					(mid 389.349869 -28.601416)
					(end 388.801356 -29.150056)
				)
				(arc
					(start 388.801356 -30.550104)
					(mid 389.349996 -31.098744)
					(end 389.898636 -30.550104)
				)
			)
		)
		(polygon
			(pts
				(arc
					(start 368.30127 -29.150056)
					(mid 367.75009 -28.598876)
					(end 367.19891 -29.150056)
				)
				(arc
					(start 367.19891 -30.550358)
					(mid 367.750217 -31.101284)
					(end 368.30127 -30.550104)
				)
			)
		)
		(polygon
			(pts
				(arc
					(start 382.701292 -29.149802)
					(mid 382.149985 -28.598876)
					(end 381.598932 -29.150056)
				)
				(arc
					(start 381.598932 -30.550104)
					(mid 382.150112 -31.101284)
					(end 382.701292 -30.550104)
				)
			)
		)
		(polygon
			(pts
				(arc
					(start 362.89869 -28.149804)
					(mid 362.349923 -27.601418)
					(end 361.80141 -28.150058)
				)
				(arc
					(start 361.80141 -29.550106)
					(mid 362.35005 -30.098746)
					(end 362.89869 -29.550106)
				)
			)
		)
		(polygon
			(pts
				(arc
					(start 389.898636 -21.949918)
					(mid 389.349869 -21.401532)
					(end 388.801356 -21.950172)
				)
				(arc
					(start 388.801356 -23.35022)
					(mid 389.349996 -23.89886)
					(end 389.898636 -23.35022)
				)
			)
		)
		(polygon
			(pts
				(arc
					(start 386.298694 -21.949918)
					(mid 385.749927 -21.401532)
					(end 385.201414 -21.950172)
				)
				(arc
					(start 385.201414 -23.35022)
					(mid 385.750054 -23.89886)
					(end 386.298694 -23.35022)
				)
			)
		)
		(polygon
			(pts
				(arc
					(start 382.698752 -21.949918)
					(mid 382.149985 -21.401532)
					(end 381.601472 -21.950172)
				)
				(arc
					(start 381.601472 -23.35022)
					(mid 382.150112 -23.89886)
					(end 382.698752 -23.35022)
				)
			)
		)
		(polygon
			(pts
				(arc
					(start 368.29873 -21.949918)
					(mid 367.749963 -21.401532)
					(end 367.20145 -21.950172)
				)
				(arc
					(start 367.20145 -23.35022)
					(mid 367.75009 -23.89886)
					(end 368.29873 -23.35022)
				)
			)
		)
		(polygon
			(pts
				(arc
					(start 364.698534 -21.949918)
					(mid 364.149767 -21.401532)
					(end 363.601254 -21.950172)
				)
				(arc
					(start 363.601254 -23.35022)
					(mid 364.149894 -23.89886)
					(end 364.698534 -23.35022)
				)
			)
		)
		(polygon
			(pts
				(arc
					(start 361.098592 -21.949918)
					(mid 360.549825 -21.401532)
					(end 360.001312 -21.950172)
				)
				(arc
					(start 360.001312 -23.35022)
					(mid 360.549952 -23.89886)
					(end 361.098592 -23.35022)
				)
			)
		)
		(polygon
			(pts
				(arc
					(start 357.49865 -21.949918)
					(mid 356.949883 -21.401532)
					(end 356.40137 -21.950172)
				)
				(arc
					(start 356.40137 -23.35022)
					(mid 356.95001 -23.89886)
					(end 357.49865 -23.35022)
				)
			)
		)
		(polygon
			(pts
				(arc
					(start 388.098538 -20.94992)
					(mid 387.549771 -20.401534)
					(end 387.001258 -20.950174)
				)
				(arc
					(start 387.001258 -22.350222)
					(mid 387.549898 -22.898862)
					(end 388.098538 -22.350222)
				)
			)
		)
		(polygon
			(pts
				(arc
					(start 384.498596 -20.94992)
					(mid 383.949829 -20.401534)
					(end 383.401316 -20.950174)
				)
				(arc
					(start 383.401316 -22.350222)
					(mid 383.949956 -22.898862)
					(end 384.498596 -22.350222)
				)
			)
		)
		(polygon
			(pts
				(arc
					(start 380.898654 -20.94992)
					(mid 380.349887 -20.401534)
					(end 379.801374 -20.950174)
				)
				(arc
					(start 379.801374 -22.350222)
					(mid 380.350014 -22.898862)
					(end 380.898654 -22.350222)
				)
			)
		)
		(polygon
			(pts
				(arc
					(start 377.298712 -20.94992)
					(mid 376.749945 -20.401534)
					(end 376.201432 -20.950174)
				)
				(arc
					(start 376.201432 -22.350222)
					(mid 376.750072 -22.898862)
					(end 377.298712 -22.350222)
				)
			)
		)
		(polygon
			(pts
				(arc
					(start 366.498632 -20.94992)
					(mid 365.949865 -20.401534)
					(end 365.401352 -20.950174)
				)
				(arc
					(start 365.401352 -22.350222)
					(mid 365.949992 -22.898862)
					(end 366.498632 -22.350222)
				)
			)
		)
		(polygon
			(pts
				(arc
					(start 362.89869 -20.94992)
					(mid 362.349923 -20.401534)
					(end 361.80141 -20.950174)
				)
				(arc
					(start 361.80141 -22.350222)
					(mid 362.35005 -22.898862)
					(end 362.89869 -22.350222)
				)
			)
		)
		(polygon
			(pts
				(arc
					(start 359.298748 -20.94992)
					(mid 358.749981 -20.401534)
					(end 358.201468 -20.950174)
				)
				(arc
					(start 358.201468 -22.350222)
					(mid 358.750108 -22.898862)
					(end 359.298748 -22.350222)
				)
			)
		)
		(polygon
			(pts
				(arc
					(start 355.698552 -20.94992)
					(mid 355.149785 -20.401534)
					(end 354.601272 -20.950174)
				)
				(arc
					(start 354.601272 -22.350222)
					(mid 355.149912 -22.898862)
					(end 355.698552 -22.350222)
				)
			)
		)
		(polygon
			(pts
				(arc
					(start 389.898636 -18.349976)
					(mid 389.349869 -17.80159)
					(end 388.801356 -18.35023)
				)
				(arc
					(start 388.801356 -19.750024)
					(mid 389.349996 -20.298664)
					(end 389.898636 -19.750024)
				)
			)
		)
		(polygon
			(pts
				(arc
					(start 386.298694 -18.349976)
					(mid 385.749927 -17.80159)
					(end 385.201414 -18.35023)
				)
				(arc
					(start 385.201414 -19.750024)
					(mid 385.750054 -20.298664)
					(end 386.298694 -19.750024)
				)
			)
		)
		(polygon
			(pts
				(arc
					(start 382.698752 -18.349976)
					(mid 382.149985 -17.80159)
					(end 381.601472 -18.35023)
				)
				(arc
					(start 381.601472 -19.750024)
					(mid 382.150112 -20.298664)
					(end 382.698752 -19.750024)
				)
			)
		)
		(polygon
			(pts
				(arc
					(start 379.098556 -18.349976)
					(mid 378.549789 -17.80159)
					(end 378.001276 -18.35023)
				)
				(arc
					(start 378.001276 -19.750024)
					(mid 378.549916 -20.298664)
					(end 379.098556 -19.750024)
				)
			)
		)
		(polygon
			(pts
				(arc
					(start 368.29873 -18.349976)
					(mid 367.749963 -17.80159)
					(end 367.20145 -18.35023)
				)
				(arc
					(start 367.20145 -19.750024)
					(mid 367.75009 -20.298664)
					(end 368.29873 -19.750024)
				)
			)
		)
		(polygon
			(pts
				(arc
					(start 364.698534 -18.349976)
					(mid 364.149767 -17.80159)
					(end 363.601254 -18.35023)
				)
				(arc
					(start 363.601254 -19.750024)
					(mid 364.149894 -20.298664)
					(end 364.698534 -19.750024)
				)
			)
		)
		(polygon
			(pts
				(arc
					(start 361.098592 -18.349976)
					(mid 360.549825 -17.80159)
					(end 360.001312 -18.35023)
				)
				(arc
					(start 360.001312 -19.750024)
					(mid 360.549952 -20.298664)
					(end 361.098592 -19.750024)
				)
			)
		)
		(polygon
			(pts
				(arc
					(start 357.49865 -18.349976)
					(mid 356.949883 -17.80159)
					(end 356.40137 -18.35023)
				)
				(arc
					(start 356.40137 -19.750024)
					(mid 356.95001 -20.298664)
					(end 357.49865 -19.750024)
				)
			)
		)
		(polygon
			(pts
				(arc
					(start 388.098538 -17.349724)
					(mid 387.549771 -16.801338)
					(end 387.001258 -17.349978)
				)
				(arc
					(start 387.001258 -18.750026)
					(mid 387.549898 -19.298666)
					(end 388.098538 -18.750026)
				)
			)
		)
		(polygon
			(pts
				(arc
					(start 384.498596 -17.349724)
					(mid 383.949829 -16.801338)
					(end 383.401316 -17.349978)
				)
				(arc
					(start 383.401316 -18.750026)
					(mid 383.949956 -19.298666)
					(end 384.498596 -18.750026)
				)
			)
		)
		(polygon
			(pts
				(arc
					(start 380.898654 -17.349724)
					(mid 380.349887 -16.801338)
					(end 379.801374 -17.349978)
				)
				(arc
					(start 379.801374 -18.750026)
					(mid 380.350014 -19.298666)
					(end 380.898654 -18.750026)
				)
			)
		)
		(polygon
			(pts
				(arc
					(start 377.298712 -17.349724)
					(mid 376.749945 -16.801338)
					(end 376.201432 -17.349978)
				)
				(arc
					(start 376.201432 -18.750026)
					(mid 376.750072 -19.298666)
					(end 377.298712 -18.750026)
				)
			)
		)
		(polygon
			(pts
				(arc
					(start 366.498632 -17.349724)
					(mid 365.949865 -16.801338)
					(end 365.401352 -17.349978)
				)
				(arc
					(start 365.401352 -18.750026)
					(mid 365.949992 -19.298666)
					(end 366.498632 -18.750026)
				)
			)
		)
		(polygon
			(pts
				(arc
					(start 362.89869 -17.349724)
					(mid 362.349923 -16.801338)
					(end 361.80141 -17.349978)
				)
				(arc
					(start 361.80141 -18.750026)
					(mid 362.35005 -19.298666)
					(end 362.89869 -18.750026)
				)
			)
		)
		(polygon
			(pts
				(arc
					(start 359.298748 -17.349724)
					(mid 358.749981 -16.801338)
					(end 358.201468 -17.349978)
				)
				(arc
					(start 358.201468 -18.750026)
					(mid 358.750108 -19.298666)
					(end 359.298748 -18.750026)
				)
			)
		)
		(polygon
			(pts
				(arc
					(start 355.698552 -17.349724)
					(mid 355.149785 -16.801338)
					(end 354.601272 -17.349978)
				)
				(arc
					(start 354.601272 -18.750026)
					(mid 355.149912 -19.298666)
					(end 355.698552 -18.750026)
				)
			)
		)
	)
	(zone
		(net "GND")
		(layer "In6.Cu")
		(hatch none 0.5)
		(connect_pads
			(clearance 0.5)
		)
		(min_thickness 0.25)
		(fill yes
			(thermal_gap 0.5)
			(thermal_bridge_width 0.5)
			(island_removal_mode 0)
		)
		(polygon
			(pts
				(xy 284.914594 -5.3975) (xy 283.898594 -6.4135) (xy 280.083006 -6.4135) (xy 279.092406 -5.4229)
				(xy 278.259794 -5.4229) (xy 277.4315 -6.251194) (xy 277.4315 -84.579206) (xy 277.853394 -85.0011)
				(xy 279.244806 -85.0011) (xy 279.981406 -84.2645) (xy 281.180794 -84.2645) (xy 284.050994 -87.1347)
				(xy 286.641286 -87.1347) (xy 287.47974 -86.296246) (xy 287.47974 -6.698234) (xy 286.179006 -5.3975)
			)
		)
		(polygon
			(pts
				(arc
					(start 283.563314 -82.57286)
					(mid 282.622752 -82.88655)
					(end 282.936442 -83.827112)
				)
				(arc
					(start 284.928056 -84.822792)
					(mid 285.874832 -84.517607)
					(end 285.56331 -83.572858)
				)
			)
		)
		(polygon
			(pts
				(arc
					(start 281.074876 -81.849722)
					(mid 281.399742 -80.875124)
					(end 280.425144 -80.550258)
				)
				(xy 280.423874 -80.547972) (xy 278.424132 -81.54797) (xy 278.424132 -81.548224)
				(arc
					(start 278.425148 -81.550256)
					(mid 278.100282 -82.524854)
					(end 279.07488 -82.84972)
				)
				(xy 279.07615 -82.852006) (xy 281.076146 -81.852008)
			)
		)
		(polygon
			(pts
				(arc
					(start 283.563314 -78.572868)
					(mid 282.622752 -78.886558)
					(end 282.936442 -79.82712)
				)
				(arc
					(start 284.928056 -80.8228)
					(mid 285.874832 -80.517615)
					(end 285.56331 -79.572866)
				)
			)
		)
		(polygon
			(pts
				(arc
					(start 281.074876 -77.84973)
					(mid 281.399742 -76.875132)
					(end 280.425144 -76.550266)
				)
				(xy 280.423874 -76.54798) (xy 278.424132 -77.547978) (xy 278.424132 -77.548232)
				(arc
					(start 278.425148 -77.550264)
					(mid 278.100282 -78.524862)
					(end 279.07488 -78.849728)
				)
				(xy 279.07615 -78.852014) (xy 281.076146 -77.852016)
			)
		)
		(polygon
			(pts
				(arc
					(start 283.563314 -74.572876)
					(mid 282.622752 -74.886566)
					(end 282.936442 -75.827128)
				)
				(arc
					(start 284.928056 -76.822808)
					(mid 285.874832 -76.517623)
					(end 285.56331 -75.572874)
				)
			)
		)
		(polygon
			(pts
				(arc
					(start 281.074876 -73.849738)
					(mid 281.399742 -72.87514)
					(end 280.425144 -72.550274)
				)
				(xy 280.423874 -72.547988) (xy 278.424132 -73.547986) (xy 278.424132 -73.54824)
				(arc
					(start 278.425148 -73.550272)
					(mid 278.100282 -74.52487)
					(end 279.07488 -74.849736)
				)
				(xy 279.07615 -74.852022) (xy 281.076146 -73.852024)
			)
		)
		(polygon
			(pts
				(arc
					(start 283.563314 -70.572884)
					(mid 282.622752 -70.886574)
					(end 282.936442 -71.827136)
				)
				(arc
					(start 284.928056 -72.822816)
					(mid 285.874832 -72.517631)
					(end 285.56331 -71.572882)
				)
			)
		)
		(polygon
			(pts
				(arc
					(start 281.074876 -69.849746)
					(mid 281.399742 -68.875148)
					(end 280.425144 -68.550282)
				)
				(xy 280.423874 -68.547996) (xy 278.424132 -69.547994) (xy 278.424132 -69.548248)
				(arc
					(start 278.425148 -69.55028)
					(mid 278.100282 -70.524878)
					(end 279.07488 -70.849744)
				)
				(xy 279.07615 -70.85203) (xy 281.076146 -69.852032)
			)
		)
		(polygon
			(pts
				(arc
					(start 283.563314 -66.572892)
					(mid 282.622752 -66.886582)
					(end 282.936442 -67.827144)
				)
				(arc
					(start 284.928056 -68.822824)
					(mid 285.874832 -68.517639)
					(end 285.56331 -67.57289)
				)
			)
		)
		(polygon
			(pts
				(arc
					(start 281.074876 -65.849754)
					(mid 281.399742 -64.875156)
					(end 280.425144 -64.55029)
				)
				(xy 280.423874 -64.548004) (xy 278.424132 -65.548002) (xy 278.424132 -65.548256)
				(arc
					(start 278.425148 -65.550288)
					(mid 278.100282 -66.524886)
					(end 279.07488 -66.849752)
				)
				(xy 279.07615 -66.852038) (xy 281.076146 -65.85204)
			)
		)
		(polygon
			(pts
				(arc
					(start 283.563314 -62.5729)
					(mid 282.622752 -62.88659)
					(end 282.936442 -63.827152)
				)
				(arc
					(start 284.928056 -64.822832)
					(mid 285.874832 -64.517647)
					(end 285.56331 -63.572898)
				)
			)
		)
		(polygon
			(pts
				(arc
					(start 281.074876 -61.849762)
					(mid 281.399742 -60.875164)
					(end 280.425144 -60.550298)
				)
				(xy 280.423874 -60.548012) (xy 278.424132 -61.54801) (xy 278.424132 -61.548264)
				(arc
					(start 278.425148 -61.550296)
					(mid 278.100282 -62.524894)
					(end 279.07488 -62.84976)
				)
				(xy 279.07615 -62.852046) (xy 281.076146 -61.852048)
			)
		)
		(polygon
			(pts
				(arc
					(start 283.563314 -58.572908)
					(mid 282.622752 -58.886598)
					(end 282.936442 -59.82716)
				)
				(arc
					(start 284.928056 -60.82284)
					(mid 285.874832 -60.517655)
					(end 285.56331 -59.572906)
				)
			)
		)
		(polygon
			(pts
				(arc
					(start 281.074876 -57.84977)
					(mid 281.399742 -56.875172)
					(end 280.425144 -56.550306)
				)
				(xy 280.423874 -56.54802) (xy 278.424132 -57.548018) (xy 278.424132 -57.548272)
				(arc
					(start 278.425148 -57.550304)
					(mid 278.100282 -58.524902)
					(end 279.07488 -58.849768)
				)
				(xy 279.07615 -58.852054) (xy 281.076146 -57.852056)
			)
		)
		(polygon
			(pts
				(arc
					(start 283.563314 -54.572916)
					(mid 282.622752 -54.886606)
					(end 282.936442 -55.827168)
				)
				(arc
					(start 284.928056 -56.822848)
					(mid 285.874832 -56.517663)
					(end 285.56331 -55.572914)
				)
			)
		)
		(polygon
			(pts
				(arc
					(start 281.074876 -53.849778)
					(mid 281.399742 -52.87518)
					(end 280.425144 -52.550314)
				)
				(xy 280.423874 -52.548028) (xy 278.424132 -53.548026) (xy 278.424132 -53.54828)
				(arc
					(start 278.425148 -53.550312)
					(mid 278.100282 -54.52491)
					(end 279.07488 -54.849776)
				)
				(xy 279.07615 -54.852062) (xy 281.076146 -53.852064)
			)
		)
		(polygon
			(pts
				(arc
					(start 283.563314 -50.572924)
					(mid 282.622752 -50.886614)
					(end 282.936442 -51.827176)
				)
				(arc
					(start 284.928056 -52.822856)
					(mid 285.874832 -52.517671)
					(end 285.56331 -51.572922)
				)
			)
		)
		(polygon
			(pts
				(arc
					(start 281.074876 -49.849786)
					(mid 281.399742 -48.875188)
					(end 280.425144 -48.550322)
				)
				(xy 280.423874 -48.548036) (xy 278.424132 -49.548034) (xy 278.424132 -49.548288)
				(arc
					(start 278.425148 -49.55032)
					(mid 278.100282 -50.524918)
					(end 279.07488 -50.849784)
				)
				(xy 279.07615 -50.85207) (xy 281.076146 -49.852072)
			)
		)
		(polygon
			(pts
				(arc
					(start 283.563314 -46.572932)
					(mid 282.622752 -46.886622)
					(end 282.936442 -47.827184)
				)
				(arc
					(start 284.928056 -48.822864)
					(mid 285.874832 -48.517679)
					(end 285.56331 -47.57293)
				)
			)
		)
		(polygon
			(pts
				(arc
					(start 281.074876 -45.849794)
					(mid 281.399742 -44.875196)
					(end 280.425144 -44.55033)
				)
				(xy 280.423874 -44.548044) (xy 278.424132 -45.548042) (xy 278.424132 -45.548296)
				(arc
					(start 278.425148 -45.550328)
					(mid 278.100282 -46.524926)
					(end 279.07488 -46.849792)
				)
				(xy 279.07615 -46.852078) (xy 281.076146 -45.85208)
			)
		)
		(polygon
			(pts
				(arc
					(start 283.563314 -42.57294)
					(mid 282.622752 -42.88663)
					(end 282.936442 -43.827192)
				)
				(arc
					(start 284.928056 -44.822872)
					(mid 285.874832 -44.517687)
					(end 285.56331 -43.572938)
				)
			)
		)
		(polygon
			(pts
				(arc
					(start 281.074876 -41.849802)
					(mid 281.399742 -40.875204)
					(end 280.425144 -40.550338)
				)
				(xy 280.423874 -40.548052) (xy 278.424132 -41.54805) (xy 278.424132 -41.548304)
				(arc
					(start 278.425148 -41.550336)
					(mid 278.100282 -42.524934)
					(end 279.07488 -42.8498)
				)
				(xy 279.07615 -42.852086) (xy 281.076146 -41.852088)
			)
		)
		(polygon
			(pts
				(arc
					(start 283.563314 -38.572948)
					(mid 282.622752 -38.886638)
					(end 282.936442 -39.8272)
				)
				(arc
					(start 284.928056 -40.82288)
					(mid 285.874832 -40.517695)
					(end 285.56331 -39.572946)
				)
			)
		)
		(polygon
			(pts
				(arc
					(start 281.074876 -37.84981)
					(mid 281.399742 -36.875212)
					(end 280.425144 -36.550346)
				)
				(xy 280.423874 -36.54806) (xy 278.424132 -37.548058) (xy 278.424132 -37.548312)
				(arc
					(start 278.425148 -37.550344)
					(mid 278.100282 -38.524942)
					(end 279.07488 -38.849808)
				)
				(xy 279.07615 -38.852094) (xy 281.076146 -37.852096)
			)
		)
		(polygon
			(pts
				(arc
					(start 283.57703 -34.545778)
					(mid 282.595574 -34.87293)
					(end 282.922726 -35.854386)
				)
				(arc
					(start 284.922468 -36.854384)
					(mid 285.904229 -36.527384)
					(end 285.577026 -35.545776)
				)
			)
		)
		(polygon
			(pts
				(arc
					(start 281.074876 -17.84985)
					(mid 281.399742 -16.875252)
					(end 280.425144 -16.550386)
				)
				(xy 280.423874 -16.5481) (xy 278.424132 -17.548098) (xy 278.424132 -17.548352)
				(arc
					(start 278.425148 -17.550384)
					(mid 278.100282 -18.524982)
					(end 279.07488 -18.849848)
				)
				(xy 279.07615 -18.852134) (xy 281.076146 -17.852136)
			)
		)
		(polygon
			(pts
				(arc
					(start 281.077162 -11.854434)
					(mid 281.404314 -10.872978)
					(end 280.422858 -10.545826)
				)
				(arc
					(start 278.433784 -11.54049)
					(mid 278.093387 -12.52152)
					(end 279.077166 -12.854432)
				)
			)
		)
	)
	(zone
		(net "P5V_B")
		(layer "In6.Cu")
		(hatch none 0.5)
		(connect_pads
			(clearance 0.5)
		)
		(min_thickness 0.25)
		(fill yes
			(thermal_gap 0.5)
			(thermal_bridge_width 0.5)
			(island_removal_mode 0)
		)
		(polygon
			(pts
				(xy 255.16586 23.203154) (xy 253.3015 21.338794) (xy 253.3015 -182.196994) (xy 210.8835 -224.614994)
				(xy 210.8835 -287.276794) (xy 207.800194 -290.3601) (xy 172.869606 -290.3601) (xy 166.9415 -284.431994)
				(xy 166.9415 -282.780994) (xy 159.687006 -275.5265) (xy 158.320994 -275.5265) (xy 157.6705 -276.176994)
				(xy 157.6705 -279.829006) (xy 164.5285 -286.687006) (xy 164.5285 -289.130994) (xy 163.299394 -290.3601)
				(xy 92.986606 -290.3601) (xy 85.138006 -282.5115) (xy 79.423006 -282.5115) (xy 72.438006 -275.5265)
				(xy 63.705994 -275.5265) (xy 62.9285 -276.303994) (xy 62.9285 -280.113994) (xy 57.863994 -285.1785)
				(xy 43.101006 -285.1785) (xy 33.322006 -275.3995) (xy 32.209994 -275.3995) (xy 31.5595 -276.049994)
				(xy 31.5595 -288.368994) (xy 29.568394 -290.3601) (xy 14.328394 -290.3601) (xy 5.6515 -299.036994)
				(xy 5.6515 -309.115206) (xy 6.886194 -310.3499) (xy 143.106394 -310.3499) (xy 148.160994 -315.4045)
				(xy 164.289994 -315.4045) (xy 174.830994 -325.9455) (xy 208.866994 -325.9455) (xy 210.5025 -327.581006)
				(xy 210.5025 -379.524006) (xy 224.4725 -393.494006) (xy 224.4725 -399.290286) (xy 230.355394 -405.17318)
				(xy 232.52938 -405.17318) (xy 233.917236 -403.785324) (xy 233.917236 -388.23773) (xy 220.2815 -374.601994)
				(xy 220.2815 -363.903006) (xy 225.35642 -358.828086) (xy 227.301298 -358.828086) (xy 229.26675 -356.862634)
				(xy 229.26675 -354.917756) (xy 231.2035 -352.981006) (xy 231.2035 -220.647006) (xy 263.2075 -188.643006)
				(xy 263.2075 -1.445006) (xy 272.9865 8.333994) (xy 272.9865 17.574006) (xy 267.357352 23.203154)
				(xy 260.750304 23.203154) (xy 260.75005 23.2029) (xy 260.592062 23.2029) (xy 260.591808 23.203154)
			)
		)
		(polygon
			(pts
				(arc
					(start 159.089852 -277.178262)
					(mid 158.708725 -276.797516)
					(end 158.327852 -277.178516)
				)
				(arc
					(start 158.327852 -278.321516)
					(mid 158.708852 -278.702516)
					(end 159.089852 -278.321516)
				)
			)
		)
		(polygon
			(pts
				(arc
					(start 64.4398 -277.178262)
					(mid 64.058673 -276.797516)
					(end 63.6778 -277.178516)
				)
				(arc
					(start 63.6778 -278.321516)
					(mid 64.0588 -278.702516)
					(end 64.4398 -278.321516)
				)
			)
		)
		(polygon
			(pts
				(arc
					(start 32.889952 -277.178262)
					(mid 32.508825 -276.797516)
					(end 32.127952 -277.178516)
				)
				(arc
					(start 32.127952 -278.321516)
					(mid 32.508952 -278.702516)
					(end 32.889952 -278.321516)
				)
			)
		)
	)
	(zone
		(net "P5V_A_1")
		(layer "In6.Cu")
		(hatch none 0.5)
		(connect_pads
			(clearance 0.5)
		)
		(min_thickness 0.25)
		(fill yes
			(thermal_gap 0.5)
			(thermal_bridge_width 0.5)
			(island_removal_mode 0)
		)
		(polygon
			(pts
				(xy 31.193994 -160.7185) (xy 28.102052 -163.810442) (xy 17.510252 -163.810442) (xy 15.9385 -165.382194)
				(xy 15.9385 -289.467036) (xy 16.450564 -289.9791) (xy 29.410406 -289.9791) (xy 31.1785 -288.211006)
				(xy 31.1785 -275.892006) (xy 32.052006 -275.0185) (xy 33.479994 -275.0185) (xy 43.258994 -284.7975)
				(xy 57.706006 -284.7975) (xy 62.5475 -279.956006) (xy 62.5475 -276.146006) (xy 63.548006 -275.1455)
				(xy 72.595994 -275.1455) (xy 79.580994 -282.1305) (xy 85.295994 -282.1305) (xy 93.144594 -289.9791)
				(xy 163.141406 -289.9791) (xy 164.1475 -288.973006) (xy 164.1475 -286.844994) (xy 157.2895 -279.986994)
				(xy 157.2895 -276.019006) (xy 158.163006 -275.1455) (xy 159.844994 -275.1455) (xy 167.3225 -282.623006)
				(xy 167.3225 -284.274006) (xy 173.027594 -289.9791) (xy 182.290974 -289.9791) (xy 182.6895 -289.580574)
				(xy 182.6895 -263.095994) (xy 172.641006 -253.0475) (xy 164.005006 -253.0475) (xy 154.065224 -243.107718)
				(xy 91.063064 -243.107718) (xy 88.5825 -240.627154) (xy 88.5825 -164.460936) (xy 87.551006 -163.429442)
				(xy 83.390994 -163.429442) (xy 81.580736 -165.2397) (xy 69.339206 -165.2397) (xy 64.818006 -160.7185)
				(xy 63.070994 -160.7185) (xy 60.868052 -162.921442) (xy 51.894994 -162.921442) (xy 49.221136 -165.5953)
				(xy 39.087806 -165.5953) (xy 34.211006 -160.7185)
			)
		)
		(polygon
			(pts
				(arc
					(start 127.53975 -277.178262)
					(mid 127.158623 -276.797516)
					(end 126.77775 -277.178516)
				)
				(arc
					(start 126.77775 -278.321516)
					(mid 127.15875 -278.702516)
					(end 127.53975 -278.321516)
				)
			)
		)
		(polygon
			(pts
				(arc
					(start 95.989902 -277.178262)
					(mid 95.608775 -276.797516)
					(end 95.227902 -277.178516)
				)
				(arc
					(start 95.227902 -278.321516)
					(mid 95.608902 -278.702516)
					(end 95.989902 -278.321516)
				)
			)
		)
		(polygon
			(pts
				(arc
					(start 64.4398 -162.178238)
					(mid 64.058673 -161.797492)
					(end 63.6778 -162.178492)
				)
				(arc
					(start 63.6778 -163.321492)
					(mid 64.0588 -163.702492)
					(end 64.4398 -163.321492)
				)
			)
		)
		(polygon
			(pts
				(arc
					(start 32.889952 -162.178238)
					(mid 32.508825 -161.797492)
					(end 32.127952 -162.178492)
				)
				(arc
					(start 32.127952 -163.321492)
					(mid 32.508952 -163.702492)
					(end 32.889952 -163.321492)
				)
			)
		)
	)
	(zone
		(net "P12V_B")
		(layer "In6.Cu")
		(hatch none 0.5)
		(connect_pads
			(clearance 0.5)
		)
		(min_thickness 0.25)
		(fill yes
			(thermal_gap 0.5)
			(thermal_bridge_width 0.5)
			(island_removal_mode 0)
		)
		(polygon
			(pts
				(xy 372.070122 -23.5585) (xy 369.66271 -25.965912) (xy 369.66271 -32.688784) (xy 368.217196 -34.134298)
				(xy 314.750196 -34.134298) (xy 310.704484 -38.18001) (xy 310.704484 -80.161892) (xy 287.86074 -103.005636)
				(xy 287.86074 -182.867554) (xy 282.933394 -187.7949) (xy 280.977594 -187.7949) (xy 280.5811 -188.191394)
				(xy 280.5811 -190.147194) (xy 251.81179 -218.916504) (xy 251.81179 -378.895356) (xy 244.81409 -385.893056)
				(xy 244.81409 -419.499796) (xy 245.244366 -419.930072) (xy 276.927056 -419.930072) (xy 277.218648 -419.63848)
				(xy 277.218648 -404.35022) (xy 287.001458 -394.56741) (xy 287.001458 -361.373928) (xy 286.610806 -360.983276)
				(xy 271.10309 -360.983276) (xy 269.835884 -359.71607) (xy 269.835884 -286.928052) (xy 270.463518 -286.300418)
				(xy 337.439762 -286.300418) (xy 337.926426 -285.813754) (xy 337.926426 -274.67052) (xy 335.7245 -272.468594)
				(xy 335.7245 -266.976606) (xy 337.926426 -264.77468) (xy 337.926426 -159.392366) (xy 341.974678 -155.344114)
				(xy 352.788474 -155.344114) (xy 353.645724 -154.486864) (xy 353.645724 -145.714466) (xy 353.12477 -145.193512)
				(xy 345.047824 -145.193512) (xy 342.687148 -142.832836) (xy 342.687148 -67.620642) (xy 337.7565 -62.689994)
				(xy 337.7565 -50.975006) (xy 338.782406 -49.9491) (xy 379.727206 -49.9491) (xy 380.1745 -49.501552)
				(xy 380.1745 -25.794462) (xy 377.938538 -23.5585)
			)
		)
		(polygon
			(pts
				(arc
					(start 325.12 -277.178262)
					(mid 324.738873 -276.797516)
					(end 324.358 -277.178516)
				)
				(arc
					(start 324.358 -278.321516)
					(mid 324.739 -278.702516)
					(end 325.12 -278.321516)
				)
			)
		)
		(polygon
			(pts
				(arc
					(start 320.41084 -273.368262)
					(mid 319.989073 -272.946876)
					(end 319.56756 -273.368516)
				)
				(arc
					(start 319.56756 -274.511516)
					(mid 319.9892 -274.933156)
					(end 320.41084 -274.511516)
				)
			)
		)
		(polygon
			(pts
				(xy 304.6095 -234.792012) (xy 272.87093 -234.792012) (xy 269.835884 -237.827058) (xy 269.835884 -263.830308)
				(xy 272.035524 -266.029948) (xy 305.05527 -266.029948) (xy 307.588158 -263.49706) (xy 307.588158 -237.77067)
			)
		)
		(polygon
			(pts
				(arc
					(start 325.12 -162.178238)
					(mid 324.738873 -161.797492)
					(end 324.358 -162.178492)
				)
				(arc
					(start 324.358 -163.321492)
					(mid 324.739 -163.702492)
					(end 325.12 -163.321492)
				)
			)
		)
		(polygon
			(pts
				(arc
					(start 320.3702 -158.368492)
					(mid 319.9892 -157.987492)
					(end 319.6082 -158.368492)
				)
				(arc
					(start 319.6082 -159.511746)
					(mid 319.989327 -159.892492)
					(end 320.3702 -159.511492)
				)
			)
		)
		(polygon
			(pts
				(arc
					(start 356.675182 -47.178214)
					(mid 356.288975 -46.792388)
					(end 355.903022 -47.178468)
				)
				(arc
					(start 355.903022 -48.321468)
					(mid 356.289102 -48.707548)
					(end 356.675182 -48.321468)
				)
			)
		)
		(polygon
			(pts
				(arc
					(start 323.824854 -46.818042)
					(mid 324.2056 -46.436915)
					(end 323.8246 -46.056042)
				)
				(arc
					(start 322.6816 -46.056042)
					(mid 322.3006 -46.437042)
					(end 322.6816 -46.818042)
				)
			)
		)
		(polygon
			(pts
				(arc
					(start 320.3575 -43.008042)
					(mid 320.7385 -42.627042)
					(end 320.3575 -42.246042)
				)
				(arc
					(start 319.214246 -42.246042)
					(mid 318.8335 -42.627169)
					(end 319.2145 -43.008042)
				)
			)
		)
		(polygon
			(pts
				(arc
					(start 351.907602 -43.013122)
					(mid 352.293682 -42.627042)
					(end 351.907602 -42.240962)
				)
				(arc
					(start 350.764348 -42.240962)
					(mid 350.378522 -42.627169)
					(end 350.764602 -43.013122)
				)
			)
		)
	)
	(zone
		(net "GND")
		(layer "In6.Cu")
		(hatch none 0.5)
		(connect_pads
			(clearance 0.5)
		)
		(min_thickness 0.25)
		(fill yes
			(thermal_gap 0.5)
			(thermal_bridge_width 0.5)
			(island_removal_mode 0)
		)
		(polygon
			(pts
				(xy 287.774126 -367.0935) (xy 287.382458 -367.485168) (xy 287.382458 -394.725398) (xy 277.599648 -404.508208)
				(xy 277.599648 -419.63086) (xy 277.89886 -419.930072) (xy 308.729888 -419.930072) (xy 308.729888 -375.270014)
				(arc
					(start 296.69994 -375.270014)
					(mid 295.094809 -374.605147)
					(end 294.429942 -373.000016)
				)
				(xy 294.429942 -367.0935)
			)
		)
	)
	(zone
		(layer "In7.Cu")
		(hatch none 0.5)
		(connect_pads
			(clearance 0)
		)
		(min_thickness 0.25)
		(keepout
			(tracks not_allowed)
			(vias allowed)
			(pads allowed)
			(copperpour not_allowed)
			(footprints allowed)
		)
		(placement
			(enabled no)
			(sheetname "")
		)
		(fill
			(thermal_gap 0.5)
			(thermal_bridge_width 0.5)
			(island_removal_mode 0)
		)
		(polygon
			(pts
				(arc
					(start 240.87709 -158.845504)
					(mid 239.895634 -159.172656)
					(end 240.222786 -160.154112)
				)
				(arc
					(start 241.042698 -160.564068)
					(mid 241.073936 -160.454533)
					(end 241.12982 -160.35528)
				)
				(xy 241.249708 -160.116774) (xy 241.249708 -160.103058) (xy 241.263678 -160.089088) (xy 241.27206 -160.072324)
				(arc
					(start 241.299746 -160.01746)
					(mid 241.302594 -159.978615)
					(end 241.27714 -159.949134)
				)
				(arc
					(start 240.999264 -159.810196)
					(mid 240.061663 -159.255222)
					(end 241.06759 -159.673798)
				)
				(xy 241.345212 -159.81299) (xy 241.373406 -159.82696)
				(arc
					(start 241.37493 -159.831024)
					(mid 241.447181 -159.930546)
					(end 241.448844 -160.053528)
				)
				(xy 241.450114 -160.057338) (xy 241.402362 -160.152588) (xy 241.402362 -160.16605) (xy 241.388646 -160.179766)
				(xy 241.38001 -160.197038) (xy 241.248692 -160.457896)
				(arc
					(start 241.242596 -160.459928)
					(mid 241.203252 -160.544777)
					(end 241.189002 -160.63722)
				)
				(arc
					(start 241.326416 -160.706054)
					(mid 241.320164 -160.600579)
					(end 241.367056 -160.505902)
				)
				(xy 241.50701 -160.227772) (xy 241.506756 -160.227264) (xy 241.52098 -160.199324) (xy 241.534696 -160.171638)
				(xy 241.535204 -160.171384) (xy 241.544348 -160.15335) (xy 241.545872 -160.150556) (xy 241.558826 -160.124902)
				(arc
					(start 241.562128 -160.123886)
					(mid 241.66951 -160.044712)
					(end 241.80292 -160.043622)
				)
				(xy 241.806476 -160.042352)
				(arc
					(start 242.100608 -160.189672)
					(mid 243.037692 -160.745281)
					(end 242.032282 -160.325816)
				)
				(arc
					(start 241.766598 -160.19272)
					(mid 241.71832 -160.188987)
					(end 241.681254 -160.220152)
				)
				(xy 241.658394 -160.265618) (xy 241.658394 -160.265872) (xy 241.64417 -160.293812) (xy 241.630454 -160.321752)
				(xy 241.6302 -160.322006) (xy 241.48415 -160.612328)
				(arc
					(start 241.475514 -160.615122)
					(mid 241.469014 -160.648697)
					(end 241.48415 -160.679384)
				)
				(xy 241.695224 -160.890458)
				(arc
					(start 242.222528 -161.15411)
					(mid 243.204289 -160.82711)
					(end 242.877086 -159.845502)
				)
			)
		)
	)
	(zone
		(net "MB3_P12V_IN_R")
		(layer "In7.Cu")
		(hatch none 0.5)
		(connect_pads
			(clearance 0.5)
		)
		(min_thickness 0.25)
		(fill yes
			(thermal_gap 0.5)
			(thermal_bridge_width 0.5)
			(island_removal_mode 0)
		)
		(polygon
			(pts
				(xy 253.12116 -390.15416) (xy 273.92884 -390.15416) (xy 274.465542 -389.617458) (xy 274.465542 -386.81025)
				(xy 274.465542 -381.720598) (xy 274.465542 -379.113542) (xy 274.465542 -378.074682) (xy 274.21586 -377.825)
				(xy 253.36754 -377.825) (xy 252.975872 -377.825) (xy 252.552708 -378.248164) (xy 252.552708 -389.780018)
				(xy 252.92685 -390.15416)
			)
		)
	)
	(zone
		(layer "In7.Cu")
		(hatch none 0.5)
		(connect_pads
			(clearance 0)
		)
		(min_thickness 0.25)
		(keepout
			(tracks not_allowed)
			(vias allowed)
			(pads allowed)
			(copperpour not_allowed)
			(footprints allowed)
		)
		(placement
			(enabled no)
			(sheetname "")
		)
		(fill
			(thermal_gap 0.5)
			(thermal_bridge_width 0.5)
			(island_removal_mode 0)
		)
		(polygon
			(pts
				(arc
					(start 127.53975 -162.178746)
					(mid 127.158877 -161.797492)
					(end 126.77775 -162.178492)
				)
				(arc
					(start 126.77775 -163.321492)
					(mid 127.15875 -163.702492)
					(end 127.53975 -163.321492)
				)
				(xy 127.53975 -162.978592)
				(arc
					(start 127.26035 -162.978592)
					(mid 127.233409 -162.989751)
					(end 127.22225 -163.016692)
				)
				(arc
					(start 127.22225 -163.062412)
					(mid 127.15875 -163.58824)
					(end 127.09525 -163.062412)
				)
				(xy 127.09525 -162.990276)
				(arc
					(start 127.09779 -162.987736)
					(mid 127.143593 -162.899935)
					(end 127.231394 -162.854132)
				)
				(xy 127.233934 -162.851592) (xy 127.53975 -162.851592) (xy 127.53975 -162.648392) (xy 127.233934 -162.648392)
				(arc
					(start 127.231394 -162.645852)
					(mid 127.143593 -162.600049)
					(end 127.09779 -162.512248)
				)
				(xy 127.09525 -162.509708)
				(arc
					(start 127.09525 -162.437572)
					(mid 127.15875 -161.911744)
					(end 127.22225 -162.437572)
				)
				(arc
					(start 127.22225 -162.483292)
					(mid 127.233409 -162.510233)
					(end 127.26035 -162.521392)
				)
				(xy 127.53975 -162.521392)
			)
		)
	)
	(zone
		(layer "In7.Cu")
		(hatch none 0.5)
		(connect_pads
			(clearance 0)
		)
		(min_thickness 0.25)
		(keepout
			(tracks not_allowed)
			(vias allowed)
			(pads allowed)
			(copperpour not_allowed)
			(footprints allowed)
		)
		(placement
			(enabled no)
			(sheetname "")
		)
		(fill
			(thermal_gap 0.5)
			(thermal_bridge_width 0.5)
			(island_removal_mode 0)
		)
		(polygon
			(pts
				(arc
					(start 64.4398 -162.178746)
					(mid 64.058927 -161.797492)
					(end 63.6778 -162.178492)
				)
				(arc
					(start 63.6778 -163.321492)
					(mid 64.0588 -163.702492)
					(end 64.4398 -163.321492)
				)
				(xy 64.4398 -162.978592)
				(arc
					(start 64.1604 -162.978592)
					(mid 64.133459 -162.989751)
					(end 64.1223 -163.016692)
				)
				(arc
					(start 64.1223 -163.062412)
					(mid 64.0588 -163.58824)
					(end 63.9953 -163.062412)
				)
				(xy 63.9953 -162.990276)
				(arc
					(start 63.99784 -162.987736)
					(mid 64.043643 -162.899935)
					(end 64.131444 -162.854132)
				)
				(xy 64.133984 -162.851592) (xy 64.4398 -162.851592) (xy 64.4398 -162.648392) (xy 64.133984 -162.648392)
				(arc
					(start 64.131444 -162.645852)
					(mid 64.043643 -162.600049)
					(end 63.99784 -162.512248)
				)
				(xy 63.9953 -162.509708)
				(arc
					(start 63.9953 -162.437572)
					(mid 64.0588 -161.911744)
					(end 64.1223 -162.437572)
				)
				(arc
					(start 64.1223 -162.483292)
					(mid 64.133459 -162.510233)
					(end 64.1604 -162.521392)
				)
				(xy 64.4398 -162.521392)
			)
		)
	)
	(zone
		(layer "In7.Cu")
		(hatch none 0.5)
		(connect_pads
			(clearance 0)
		)
		(min_thickness 0.25)
		(keepout
			(tracks not_allowed)
			(vias allowed)
			(pads allowed)
			(copperpour not_allowed)
			(footprints allowed)
		)
		(placement
			(enabled no)
			(sheetname "")
		)
		(fill
			(thermal_gap 0.5)
			(thermal_bridge_width 0.5)
			(island_removal_mode 0)
		)
		(polygon
			(pts
				(arc
					(start 238.377222 -126.15418)
					(mid 238.704374 -125.172724)
					(end 237.722918 -124.845572)
				)
				(arc
					(start 236.720126 -125.346968)
					(mid 236.795394 -125.390464)
					(end 236.86389 -125.443996)
				)
				(xy 236.864906 -125.443996)
				(arc
					(start 237.201964 -125.781054)
					(mid 237.243617 -125.802304)
					(end 237.289848 -125.795278)
				)
				(arc
					(start 237.532418 -125.673866)
					(mid 238.537816 -125.254407)
					(end 237.600744 -125.81001)
				)
				(xy 237.358174 -125.931422) (xy 237.32998 -125.945646)
				(arc
					(start 237.326678 -125.944376)
					(mid 237.219406 -125.952717)
					(end 237.120176 -125.911102)
				)
				(xy 237.11662 -125.911102)
				(arc
					(start 236.779562 -125.574044)
					(mid 236.663684 -125.489168)
					(end 236.527594 -125.443234)
				)
				(xy 236.287564 -125.563376) (xy 236.478318 -125.563376)
				(arc
					(start 236.480096 -125.5649)
					(mid 236.578254 -125.589502)
					(end 236.665008 -125.641608)
				)
				(xy 236.667294 -125.641608) (xy 236.913166 -125.88748)
				(arc
					(start 236.913166 -125.891544)
					(mid 236.947699 -126.040972)
					(end 236.867954 -126.17196)
				)
				(xy 236.866684 -126.175516) (xy 236.856524 -126.18085) (xy 236.85627 -126.181358) (xy 236.828584 -126.195328)
				(xy 236.800644 -126.209552) (xy 236.80039 -126.209298)
				(arc
					(start 236.567726 -126.325884)
					(mid 235.561798 -126.744461)
					(end 236.4994 -126.189486)
				)
				(xy 236.759496 -126.059184) (xy 236.769148 -126.054358)
				(arc
					(start 236.770926 -126.053342)
					(mid 236.797167 -126.016171)
					(end 236.783118 -125.972824)
				)
				(arc
					(start 236.58195 -125.771656)
					(mid 236.519953 -125.730231)
					(end 236.446822 -125.715776)
				)
				(xy 235.982764 -125.715776)
				(arc
					(start 235.733844 -125.840236)
					(mid 235.393447 -126.821266)
					(end 236.377226 -127.154178)
				)
			)
		)
	)
	(zone
		(layer "In7.Cu")
		(hatch none 0.5)
		(connect_pads
			(clearance 0)
		)
		(min_thickness 0.25)
		(keepout
			(tracks not_allowed)
			(vias allowed)
			(pads allowed)
			(copperpour not_allowed)
			(footprints allowed)
		)
		(placement
			(enabled no)
			(sheetname "")
		)
		(fill
			(thermal_gap 0.5)
			(thermal_bridge_width 0.5)
			(island_removal_mode 0)
		)
		(polygon
			(pts
				(arc
					(start 286.436562 -335.554066)
					(mid 285.885382 -336.105246)
					(end 286.436562 -336.656426)
				)
				(arc
					(start 287.83661 -336.656426)
					(mid 288.38779 -336.105246)
					(end 287.83661 -335.554066)
				)
				(xy 287.367472 -335.554066)
				(arc
					(start 287.367472 -335.978246)
					(mid 287.386071 -336.023147)
					(end 287.430972 -336.041746)
				)
				(arc
					(start 287.44799 -336.041746)
					(mid 288.230384 -336.105246)
					(end 287.44799 -336.168746)
				)
				(xy 287.404556 -336.168746)
				(arc
					(start 287.402524 -336.166714)
					(mid 287.296195 -336.113023)
					(end 287.242504 -336.006694)
				)
				(xy 287.240472 -336.004662) (xy 287.240472 -335.554066) (xy 287.037272 -335.554066) (xy 287.037272 -336.004662)
				(arc
					(start 287.03524 -336.006694)
					(mid 286.981549 -336.113023)
					(end 286.87522 -336.166714)
				)
				(xy 286.873188 -336.168746)
				(arc
					(start 286.825182 -336.168746)
					(mid 286.042788 -336.105246)
					(end 286.825182 -336.041746)
				)
				(arc
					(start 286.846772 -336.041746)
					(mid 286.891673 -336.023147)
					(end 286.910272 -335.978246)
				)
				(xy 286.910272 -335.554066) (xy 286.436816 -335.554066)
			)
		)
	)
	(zone
		(layer "In7.Cu")
		(hatch none 0.5)
		(connect_pads
			(clearance 0)
		)
		(min_thickness 0.25)
		(keepout
			(tracks not_allowed)
			(vias allowed)
			(pads allowed)
			(copperpour not_allowed)
			(footprints allowed)
		)
		(placement
			(enabled no)
			(sheetname "")
		)
		(fill
			(thermal_gap 0.5)
			(thermal_bridge_width 0.5)
			(island_removal_mode 0)
		)
		(polygon
			(pts
				(arc
					(start 240.877344 -162.845496)
					(mid 239.895939 -163.172546)
					(end 240.222786 -164.154104)
				)
				(arc
					(start 241.043714 -164.564568)
					(mid 241.074189 -164.455056)
					(end 241.129566 -164.35578)
				)
				(xy 241.249708 -164.116766) (xy 241.249708 -164.10305) (xy 241.263678 -164.08908) (xy 241.27206 -164.072316)
				(arc
					(start 241.299746 -164.017452)
					(mid 241.302594 -163.978607)
					(end 241.27714 -163.949126)
				)
				(arc
					(start 240.999264 -163.810188)
					(mid 240.061663 -163.255214)
					(end 241.06759 -163.67379)
				)
				(xy 241.345212 -163.812982) (xy 241.373406 -163.826952)
				(arc
					(start 241.37493 -163.831016)
					(mid 241.447181 -163.930538)
					(end 241.448844 -164.05352)
				)
				(xy 241.450114 -164.05733) (xy 241.402362 -164.15258) (xy 241.402362 -164.166042) (xy 241.388646 -164.179758)
				(xy 241.38001 -164.19703) (xy 241.248692 -164.458142)
				(arc
					(start 241.24285 -164.45992)
					(mid 241.20378 -164.545157)
					(end 241.190526 -164.637974)
				)
				(arc
					(start 241.330734 -164.708078)
					(mid 241.321028 -164.601996)
					(end 241.367056 -164.505894)
				)
				(xy 241.50701 -164.227764) (xy 241.506756 -164.227256) (xy 241.52098 -164.199316) (xy 241.534696 -164.17163)
				(xy 241.535204 -164.171376) (xy 241.544348 -164.153342) (xy 241.545872 -164.150548) (xy 241.558826 -164.124894)
				(arc
					(start 241.562128 -164.123878)
					(mid 241.66951 -164.044704)
					(end 241.80292 -164.043614)
				)
				(xy 241.806476 -164.042344)
				(arc
					(start 242.100608 -164.189664)
					(mid 243.037692 -164.745273)
					(end 242.032282 -164.325808)
				)
				(arc
					(start 241.766598 -164.192712)
					(mid 241.71832 -164.188979)
					(end 241.681254 -164.220144)
				)
				(xy 241.658394 -164.26561) (xy 241.658394 -164.265864) (xy 241.64417 -164.293804) (xy 241.630454 -164.321744)
				(xy 241.6302 -164.321998) (xy 241.48415 -164.61232)
				(arc
					(start 241.475768 -164.615114)
					(mid 241.470738 -164.644549)
					(end 241.48415 -164.671248)
				)
				(xy 241.71148 -164.898324)
				(arc
					(start 242.222782 -165.154102)
					(mid 243.204238 -164.82695)
					(end 242.877086 -163.845494)
				)
			)
		)
	)
	(zone
		(layer "In7.Cu")
		(hatch none 0.5)
		(connect_pads
			(clearance 0)
		)
		(min_thickness 0.25)
		(keepout
			(tracks not_allowed)
			(vias allowed)
			(pads allowed)
			(copperpour not_allowed)
			(footprints allowed)
		)
		(placement
			(enabled no)
			(sheetname "")
		)
		(fill
			(thermal_gap 0.5)
			(thermal_bridge_width 0.5)
			(island_removal_mode 0)
		)
		(polygon
			(pts
				(arc
					(start 190.639954 -277.17877)
					(mid 190.259081 -276.797516)
					(end 189.877954 -277.178516)
				)
				(arc
					(start 189.877954 -278.321516)
					(mid 190.258954 -278.702516)
					(end 190.639954 -278.321516)
				)
				(xy 190.639954 -277.978616)
				(arc
					(start 190.360554 -277.978616)
					(mid 190.333613 -277.989775)
					(end 190.322454 -278.016716)
				)
				(arc
					(start 190.322454 -278.062436)
					(mid 190.258954 -278.588264)
					(end 190.195454 -278.062436)
				)
				(xy 190.195454 -277.9903)
				(arc
					(start 190.197994 -277.98776)
					(mid 190.243797 -277.899959)
					(end 190.331598 -277.854156)
				)
				(xy 190.334138 -277.851616) (xy 190.639954 -277.851616) (xy 190.639954 -277.648416) (xy 190.334138 -277.648416)
				(arc
					(start 190.331598 -277.645876)
					(mid 190.243797 -277.600073)
					(end 190.197994 -277.512272)
				)
				(xy 190.195454 -277.509732)
				(arc
					(start 190.195454 -277.437596)
					(mid 190.258954 -276.911768)
					(end 190.322454 -277.437596)
				)
				(arc
					(start 190.322454 -277.483316)
					(mid 190.333613 -277.510257)
					(end 190.360554 -277.521416)
				)
				(xy 190.639954 -277.521416)
			)
		)
	)
	(zone
		(layer "In7.Cu")
		(hatch none 0.5)
		(connect_pads
			(clearance 0)
		)
		(min_thickness 0.25)
		(keepout
			(tracks not_allowed)
			(vias allowed)
			(pads allowed)
			(copperpour not_allowed)
			(footprints allowed)
		)
		(placement
			(enabled no)
			(sheetname "")
		)
		(fill
			(thermal_gap 0.5)
			(thermal_bridge_width 0.5)
			(island_removal_mode 0)
		)
		(polygon
			(pts
				(arc
					(start 285.436564 -312.154062)
					(mid 284.885384 -312.705242)
					(end 285.436564 -313.256422)
				)
				(arc
					(start 286.836612 -313.256422)
					(mid 287.387792 -312.705242)
					(end 286.836612 -312.154062)
				)
				(xy 286.367474 -312.154062)
				(arc
					(start 286.367474 -312.578242)
					(mid 286.386073 -312.623143)
					(end 286.430974 -312.641742)
				)
				(arc
					(start 286.447992 -312.641742)
					(mid 287.230386 -312.705242)
					(end 286.447992 -312.768742)
				)
				(xy 286.404558 -312.768742)
				(arc
					(start 286.402526 -312.76671)
					(mid 286.296197 -312.713019)
					(end 286.242506 -312.60669)
				)
				(xy 286.240474 -312.604658) (xy 286.240474 -312.154062) (xy 286.037274 -312.154062) (xy 286.037274 -312.604658)
				(arc
					(start 286.035242 -312.60669)
					(mid 285.981551 -312.713019)
					(end 285.875222 -312.76671)
				)
				(xy 285.87319 -312.768742)
				(arc
					(start 285.825184 -312.768742)
					(mid 285.04279 -312.705242)
					(end 285.825184 -312.641742)
				)
				(arc
					(start 285.846774 -312.641742)
					(mid 285.891675 -312.623143)
					(end 285.910274 -312.578242)
				)
				(xy 285.910274 -312.154062) (xy 285.436818 -312.154062)
			)
		)
	)
	(zone
		(layer "In7.Cu")
		(hatch none 0.5)
		(connect_pads
			(clearance 0)
		)
		(min_thickness 0.25)
		(keepout
			(tracks not_allowed)
			(vias allowed)
			(pads allowed)
			(copperpour not_allowed)
			(footprints allowed)
		)
		(placement
			(enabled no)
			(sheetname "")
		)
		(fill
			(thermal_gap 0.5)
			(thermal_bridge_width 0.5)
			(island_removal_mode 0)
		)
		(polygon
			(pts
				(arc
					(start 285.436564 -333.753968)
					(mid 284.885384 -334.305148)
					(end 285.436564 -334.856328)
				)
				(arc
					(start 286.836612 -334.856328)
					(mid 287.387792 -334.305148)
					(end 286.836612 -333.753968)
				)
				(xy 286.367474 -333.753968)
				(arc
					(start 286.367474 -334.178148)
					(mid 286.386073 -334.223049)
					(end 286.430974 -334.241648)
				)
				(arc
					(start 286.447992 -334.241648)
					(mid 287.230386 -334.305148)
					(end 286.447992 -334.368648)
				)
				(xy 286.404558 -334.368648)
				(arc
					(start 286.402526 -334.366616)
					(mid 286.296197 -334.312925)
					(end 286.242506 -334.206596)
				)
				(xy 286.240474 -334.204564) (xy 286.240474 -333.753968) (xy 286.037274 -333.753968) (xy 286.037274 -334.204564)
				(arc
					(start 286.035242 -334.206596)
					(mid 285.981551 -334.312925)
					(end 285.875222 -334.366616)
				)
				(xy 285.87319 -334.368648)
				(arc
					(start 285.825184 -334.368648)
					(mid 285.04279 -334.305148)
					(end 285.825184 -334.241648)
				)
				(arc
					(start 285.846774 -334.241648)
					(mid 285.891675 -334.223049)
					(end 285.910274 -334.178148)
				)
				(xy 285.910274 -333.753968) (xy 285.436818 -333.753968)
			)
		)
	)
	(zone
		(layer "In7.Cu")
		(hatch none 0.5)
		(connect_pads
			(clearance 0)
		)
		(min_thickness 0.25)
		(keepout
			(tracks not_allowed)
			(vias allowed)
			(pads allowed)
			(copperpour not_allowed)
			(footprints allowed)
		)
		(placement
			(enabled no)
			(sheetname "")
		)
		(fill
			(thermal_gap 0.5)
			(thermal_bridge_width 0.5)
			(island_removal_mode 0)
		)
		(polygon
			(pts
				(arc
					(start 286.436562 -310.353964)
					(mid 285.885382 -310.905144)
					(end 286.436562 -311.456324)
				)
				(arc
					(start 287.83661 -311.456324)
					(mid 288.38779 -310.905144)
					(end 287.83661 -310.353964)
				)
				(xy 287.367472 -310.353964)
				(arc
					(start 287.367472 -310.778144)
					(mid 287.386071 -310.823045)
					(end 287.430972 -310.841644)
				)
				(arc
					(start 287.44799 -310.841644)
					(mid 288.230384 -310.905144)
					(end 287.44799 -310.968644)
				)
				(xy 287.404556 -310.968644)
				(arc
					(start 287.402524 -310.966612)
					(mid 287.296195 -310.912921)
					(end 287.242504 -310.806592)
				)
				(xy 287.240472 -310.80456) (xy 287.240472 -310.353964) (xy 287.037272 -310.353964) (xy 287.037272 -310.80456)
				(arc
					(start 287.03524 -310.806592)
					(mid 286.981549 -310.912921)
					(end 286.87522 -310.966612)
				)
				(xy 286.873188 -310.968644)
				(arc
					(start 286.825182 -310.968644)
					(mid 286.042788 -310.905144)
					(end 286.825182 -310.841644)
				)
				(arc
					(start 286.846772 -310.841644)
					(mid 286.891673 -310.823045)
					(end 286.910272 -310.778144)
				)
				(xy 286.910272 -310.353964) (xy 286.436816 -310.353964)
			)
		)
	)
	(zone
		(layer "In7.Cu")
		(hatch none 0.5)
		(connect_pads
			(clearance 0)
		)
		(min_thickness 0.25)
		(keepout
			(tracks not_allowed)
			(vias allowed)
			(pads allowed)
			(copperpour not_allowed)
			(footprints allowed)
		)
		(placement
			(enabled no)
			(sheetname "")
		)
		(fill
			(thermal_gap 0.5)
			(thermal_bridge_width 0.5)
			(island_removal_mode 0)
		)
		(polygon
			(pts
				(arc
					(start 32.889952 -162.178746)
					(mid 32.509079 -161.797492)
					(end 32.127952 -162.178492)
				)
				(arc
					(start 32.127952 -163.321492)
					(mid 32.508952 -163.702492)
					(end 32.889952 -163.321492)
				)
				(xy 32.889952 -162.978592)
				(arc
					(start 32.610552 -162.978592)
					(mid 32.583611 -162.989751)
					(end 32.572452 -163.016692)
				)
				(arc
					(start 32.572452 -163.062412)
					(mid 32.508952 -163.58824)
					(end 32.445452 -163.062412)
				)
				(xy 32.445452 -162.990276)
				(arc
					(start 32.447992 -162.987736)
					(mid 32.493795 -162.899935)
					(end 32.581596 -162.854132)
				)
				(xy 32.584136 -162.851592) (xy 32.889952 -162.851592) (xy 32.889952 -162.648392) (xy 32.584136 -162.648392)
				(arc
					(start 32.581596 -162.645852)
					(mid 32.493795 -162.600049)
					(end 32.447992 -162.512248)
				)
				(xy 32.445452 -162.509708)
				(arc
					(start 32.445452 -162.437572)
					(mid 32.508952 -161.911744)
					(end 32.572452 -162.437572)
				)
				(arc
					(start 32.572452 -162.483292)
					(mid 32.583611 -162.510233)
					(end 32.610552 -162.521392)
				)
				(xy 32.889952 -162.521392)
			)
		)
	)
	(zone
		(layer "In7.Cu")
		(hatch none 0.5)
		(connect_pads
			(clearance 0)
		)
		(min_thickness 0.25)
		(keepout
			(tracks not_allowed)
			(vias allowed)
			(pads allowed)
			(copperpour not_allowed)
			(footprints allowed)
		)
		(placement
			(enabled no)
			(sheetname "")
		)
		(fill
			(thermal_gap 0.5)
			(thermal_bridge_width 0.5)
			(island_removal_mode 0)
		)
		(polygon
			(pts
				(arc
					(start 278.23668 -254.15113)
					(mid 277.6855 -254.70231)
					(end 278.23668 -255.25349)
				)
				(xy 278.720804 -255.25349)
				(arc
					(start 278.720804 -254.82931)
					(mid 278.705925 -254.793389)
					(end 278.670004 -254.77851)
				)
				(arc
					(start 278.623014 -254.77851)
					(mid 277.842903 -254.70231)
					(end 278.623014 -254.62611)
				)
				(xy 278.7015 -254.62611)
				(arc
					(start 278.704548 -254.629158)
					(mid 278.813625 -254.685689)
					(end 278.870156 -254.794766)
				)
				(xy 278.873204 -254.797814) (xy 278.873204 -255.25349) (xy 279.000204 -255.25349) (xy 279.000204 -254.797814)
				(arc
					(start 279.003252 -254.794766)
					(mid 279.059783 -254.685689)
					(end 279.16886 -254.629158)
				)
				(xy 279.171908 -254.62611)
				(arc
					(start 279.250394 -254.62611)
					(mid 280.030505 -254.70231)
					(end 279.250394 -254.77851)
				)
				(arc
					(start 279.203404 -254.77851)
					(mid 279.167483 -254.793389)
					(end 279.152604 -254.82931)
				)
				(xy 279.152604 -255.25349)
				(arc
					(start 279.636728 -255.25349)
					(mid 280.187908 -254.70231)
					(end 279.636728 -254.15113)
				)
				(xy 278.236934 -254.15113)
			)
		)
	)
	(zone
		(layer "In7.Cu")
		(hatch none 0.5)
		(connect_pads
			(clearance 0)
		)
		(min_thickness 0.25)
		(keepout
			(tracks not_allowed)
			(vias allowed)
			(pads allowed)
			(copperpour not_allowed)
			(footprints allowed)
		)
		(placement
			(enabled no)
			(sheetname "")
		)
		(fill
			(thermal_gap 0.5)
			(thermal_bridge_width 0.5)
			(island_removal_mode 0)
		)
		(polygon
			(pts
				(arc
					(start 286.436562 -263.151112)
					(mid 285.885382 -263.702292)
					(end 286.436562 -264.253472)
				)
				(xy 286.920686 -264.253472)
				(arc
					(start 286.920686 -263.829292)
					(mid 286.905807 -263.793371)
					(end 286.869886 -263.778492)
				)
				(arc
					(start 286.822896 -263.778492)
					(mid 286.042785 -263.702292)
					(end 286.822896 -263.626092)
				)
				(xy 286.901382 -263.626092)
				(arc
					(start 286.90443 -263.62914)
					(mid 287.013507 -263.685671)
					(end 287.070038 -263.794748)
				)
				(xy 287.073086 -263.797796) (xy 287.073086 -264.253472) (xy 287.200086 -264.253472) (xy 287.200086 -263.797796)
				(arc
					(start 287.203134 -263.794748)
					(mid 287.259665 -263.685671)
					(end 287.368742 -263.62914)
				)
				(xy 287.37179 -263.626092)
				(arc
					(start 287.450276 -263.626092)
					(mid 288.230387 -263.702292)
					(end 287.450276 -263.778492)
				)
				(arc
					(start 287.403286 -263.778492)
					(mid 287.367365 -263.793371)
					(end 287.352486 -263.829292)
				)
				(xy 287.352486 -264.253472)
				(arc
					(start 287.83661 -264.253472)
					(mid 288.38779 -263.702292)
					(end 287.83661 -263.151112)
				)
				(xy 286.436816 -263.151112)
			)
		)
	)
	(zone
		(layer "In7.Cu")
		(hatch none 0.5)
		(connect_pads
			(clearance 0)
		)
		(min_thickness 0.25)
		(keepout
			(tracks not_allowed)
			(vias allowed)
			(pads allowed)
			(copperpour not_allowed)
			(footprints allowed)
		)
		(placement
			(enabled no)
			(sheetname "")
		)
		(fill
			(thermal_gap 0.5)
			(thermal_bridge_width 0.5)
			(island_removal_mode 0)
		)
		(polygon
			(pts
				(arc
					(start 286.436562 -331.95387)
					(mid 285.885382 -332.50505)
					(end 286.436562 -333.05623)
				)
				(arc
					(start 287.83661 -333.05623)
					(mid 288.38779 -332.50505)
					(end 287.83661 -331.95387)
				)
				(xy 287.367472 -331.95387)
				(arc
					(start 287.367472 -332.37805)
					(mid 287.386071 -332.422951)
					(end 287.430972 -332.44155)
				)
				(arc
					(start 287.44799 -332.44155)
					(mid 288.230384 -332.50505)
					(end 287.44799 -332.56855)
				)
				(xy 287.404556 -332.56855)
				(arc
					(start 287.402524 -332.566518)
					(mid 287.296195 -332.512827)
					(end 287.242504 -332.406498)
				)
				(xy 287.240472 -332.404466) (xy 287.240472 -331.95387) (xy 287.037272 -331.95387) (xy 287.037272 -332.404466)
				(arc
					(start 287.03524 -332.406498)
					(mid 286.981549 -332.512827)
					(end 286.87522 -332.566518)
				)
				(xy 286.873188 -332.56855)
				(arc
					(start 286.825182 -332.56855)
					(mid 286.042788 -332.50505)
					(end 286.825182 -332.44155)
				)
				(arc
					(start 286.846772 -332.44155)
					(mid 286.891673 -332.422951)
					(end 286.910272 -332.37805)
				)
				(xy 286.910272 -331.95387) (xy 286.436816 -331.95387)
			)
		)
	)
	(zone
		(layer "In7.Cu")
		(hatch none 0.5)
		(connect_pads
			(clearance 0)
		)
		(min_thickness 0.25)
		(keepout
			(tracks not_allowed)
			(vias allowed)
			(pads allowed)
			(copperpour not_allowed)
			(footprints allowed)
		)
		(placement
			(enabled no)
			(sheetname "")
		)
		(fill
			(thermal_gap 0.5)
			(thermal_bridge_width 0.5)
			(island_removal_mode 0)
		)
		(polygon
			(pts
				(arc
					(start 279.236678 -255.951228)
					(mid 278.685498 -256.502408)
					(end 279.236678 -257.053588)
				)
				(xy 279.720802 -257.053588)
				(arc
					(start 279.720802 -256.629408)
					(mid 279.705923 -256.593487)
					(end 279.670002 -256.578608)
				)
				(arc
					(start 279.623012 -256.578608)
					(mid 278.842901 -256.502408)
					(end 279.623012 -256.426208)
				)
				(xy 279.701498 -256.426208)
				(arc
					(start 279.704546 -256.429256)
					(mid 279.813623 -256.485787)
					(end 279.870154 -256.594864)
				)
				(xy 279.873202 -256.597912) (xy 279.873202 -257.053588) (xy 280.000202 -257.053588) (xy 280.000202 -256.597912)
				(arc
					(start 280.00325 -256.594864)
					(mid 280.059781 -256.485787)
					(end 280.168858 -256.429256)
				)
				(xy 280.171906 -256.426208)
				(arc
					(start 280.250392 -256.426208)
					(mid 281.030503 -256.502408)
					(end 280.250392 -256.578608)
				)
				(arc
					(start 280.203402 -256.578608)
					(mid 280.167481 -256.593487)
					(end 280.152602 -256.629408)
				)
				(xy 280.152602 -257.053588)
				(arc
					(start 280.636726 -257.053588)
					(mid 281.187906 -256.502408)
					(end 280.636726 -255.951228)
				)
				(xy 279.236932 -255.951228)
			)
		)
	)
	(zone
		(net "P12V_A_COMP")
		(layer "In7.Cu")
		(hatch none 0.5)
		(connect_pads
			(clearance 0.5)
		)
		(min_thickness 0.25)
		(fill yes
			(thermal_gap 0.5)
			(thermal_bridge_width 0.5)
			(island_removal_mode 0)
		)
		(polygon
			(pts
				(xy 231.9528 -83.0072) (xy 243.332 -83.0072) (xy 244.6782 -84.3534) (xy 244.6782 -97.9932) (xy 244.6782 -103.5812)
				(xy 244.6782 -104.6226) (xy 243.7638 -105.537) (xy 234.2896 -105.537) (xy 219.7862 -105.537) (xy 218.8464 -104.5972)
				(xy 218.8464 -94.6912) (xy 220.98 -92.5576) (xy 230.5304 -83.0072)
			)
		)
	)
	(zone
		(layer "In7.Cu")
		(hatch none 0.5)
		(connect_pads
			(clearance 0)
		)
		(min_thickness 0.25)
		(keepout
			(tracks not_allowed)
			(vias allowed)
			(pads allowed)
			(copperpour not_allowed)
			(footprints allowed)
		)
		(placement
			(enabled no)
			(sheetname "")
		)
		(fill
			(thermal_gap 0.5)
			(thermal_bridge_width 0.5)
			(island_removal_mode 0)
		)
		(polygon
			(pts
				(arc
					(start 127.53975 -277.17877)
					(mid 127.158877 -276.797516)
					(end 126.77775 -277.178516)
				)
				(arc
					(start 126.77775 -278.321516)
					(mid 127.15875 -278.702516)
					(end 127.53975 -278.321516)
				)
				(xy 127.53975 -277.978616)
				(arc
					(start 127.26035 -277.978616)
					(mid 127.233409 -277.989775)
					(end 127.22225 -278.016716)
				)
				(arc
					(start 127.22225 -278.062436)
					(mid 127.15875 -278.588264)
					(end 127.09525 -278.062436)
				)
				(xy 127.09525 -277.9903)
				(arc
					(start 127.09779 -277.98776)
					(mid 127.143593 -277.899959)
					(end 127.231394 -277.854156)
				)
				(xy 127.233934 -277.851616) (xy 127.53975 -277.851616) (xy 127.53975 -277.648416) (xy 127.233934 -277.648416)
				(arc
					(start 127.231394 -277.645876)
					(mid 127.143593 -277.600073)
					(end 127.09779 -277.512272)
				)
				(xy 127.09525 -277.509732)
				(arc
					(start 127.09525 -277.437596)
					(mid 127.15875 -276.911768)
					(end 127.22225 -277.437596)
				)
				(arc
					(start 127.22225 -277.483316)
					(mid 127.233409 -277.510257)
					(end 127.26035 -277.521416)
				)
				(xy 127.53975 -277.521416)
			)
		)
	)
	(zone
		(layer "In7.Cu")
		(hatch none 0.5)
		(connect_pads
			(clearance 0)
		)
		(min_thickness 0.25)
		(keepout
			(tracks not_allowed)
			(vias allowed)
			(pads allowed)
			(copperpour not_allowed)
			(footprints allowed)
		)
		(placement
			(enabled no)
			(sheetname "")
		)
		(fill
			(thermal_gap 0.5)
			(thermal_bridge_width 0.5)
			(island_removal_mode 0)
		)
		(polygon
			(pts
				(arc
					(start 285.436564 -294.154098)
					(mid 284.885384 -294.705278)
					(end 285.436564 -295.256458)
				)
				(arc
					(start 286.836612 -295.256458)
					(mid 287.387792 -294.705278)
					(end 286.836612 -294.154098)
				)
				(xy 286.367474 -294.154098)
				(arc
					(start 286.367474 -294.578278)
					(mid 286.386073 -294.623179)
					(end 286.430974 -294.641778)
				)
				(arc
					(start 286.447992 -294.641778)
					(mid 287.230386 -294.705278)
					(end 286.447992 -294.768778)
				)
				(xy 286.404558 -294.768778)
				(arc
					(start 286.402526 -294.766746)
					(mid 286.296197 -294.713055)
					(end 286.242506 -294.606726)
				)
				(xy 286.240474 -294.604694) (xy 286.240474 -294.154098) (xy 286.037274 -294.154098) (xy 286.037274 -294.604694)
				(arc
					(start 286.035242 -294.606726)
					(mid 285.981551 -294.713055)
					(end 285.875222 -294.766746)
				)
				(xy 285.87319 -294.768778)
				(arc
					(start 285.825184 -294.768778)
					(mid 285.04279 -294.705278)
					(end 285.825184 -294.641778)
				)
				(arc
					(start 285.846774 -294.641778)
					(mid 285.891675 -294.623179)
					(end 285.910274 -294.578278)
				)
				(xy 285.910274 -294.154098) (xy 285.436818 -294.154098)
			)
		)
	)
	(zone
		(layer "In7.Cu")
		(hatch none 0.5)
		(connect_pads
			(clearance 0)
		)
		(min_thickness 0.25)
		(keepout
			(tracks not_allowed)
			(vias allowed)
			(pads allowed)
			(copperpour not_allowed)
			(footprints allowed)
		)
		(placement
			(enabled no)
			(sheetname "")
		)
		(fill
			(thermal_gap 0.5)
			(thermal_bridge_width 0.5)
			(island_removal_mode 0)
		)
		(polygon
			(pts
				(arc
					(start 190.639954 -47.178722)
					(mid 190.259081 -46.797468)
					(end 189.877954 -47.178468)
				)
				(arc
					(start 189.877954 -48.321468)
					(mid 190.258954 -48.702468)
					(end 190.639954 -48.321468)
				)
				(xy 190.639954 -47.978568)
				(arc
					(start 190.360554 -47.978568)
					(mid 190.333613 -47.989727)
					(end 190.322454 -48.016668)
				)
				(arc
					(start 190.322454 -48.062388)
					(mid 190.258954 -48.588216)
					(end 190.195454 -48.062388)
				)
				(xy 190.195454 -47.990252)
				(arc
					(start 190.197994 -47.987712)
					(mid 190.243797 -47.899911)
					(end 190.331598 -47.854108)
				)
				(xy 190.334138 -47.851568) (xy 190.639954 -47.851568) (xy 190.639954 -47.648368) (xy 190.334138 -47.648368)
				(arc
					(start 190.331598 -47.645828)
					(mid 190.243797 -47.600025)
					(end 190.197994 -47.512224)
				)
				(xy 190.195454 -47.509684)
				(arc
					(start 190.195454 -47.437548)
					(mid 190.258954 -46.91172)
					(end 190.322454 -47.437548)
				)
				(arc
					(start 190.322454 -47.483268)
					(mid 190.333613 -47.510209)
					(end 190.360554 -47.521368)
				)
				(xy 190.639954 -47.521368)
			)
		)
	)
	(zone
		(layer "In7.Cu")
		(hatch none 0.5)
		(connect_pads
			(clearance 0)
		)
		(min_thickness 0.25)
		(keepout
			(tracks not_allowed)
			(vias allowed)
			(pads allowed)
			(copperpour not_allowed)
			(footprints allowed)
		)
		(placement
			(enabled no)
			(sheetname "")
		)
		(fill
			(thermal_gap 0.5)
			(thermal_bridge_width 0.5)
			(island_removal_mode 0)
		)
		(polygon
			(pts
				(arc
					(start 286.436562 -349.954088)
					(mid 285.885382 -350.505268)
					(end 286.436562 -351.056448)
				)
				(arc
					(start 287.83661 -351.056448)
					(mid 288.38779 -350.505268)
					(end 287.83661 -349.954088)
				)
				(xy 287.367472 -349.954088)
				(arc
					(start 287.367472 -350.378268)
					(mid 287.386071 -350.423169)
					(end 287.430972 -350.441768)
				)
				(arc
					(start 287.44799 -350.441768)
					(mid 288.230384 -350.505268)
					(end 287.44799 -350.568768)
				)
				(xy 287.404556 -350.568768)
				(arc
					(start 287.402524 -350.566736)
					(mid 287.296195 -350.513045)
					(end 287.242504 -350.406716)
				)
				(xy 287.240472 -350.404684) (xy 287.240472 -349.954088) (xy 287.037272 -349.954088) (xy 287.037272 -350.404684)
				(arc
					(start 287.03524 -350.406716)
					(mid 286.981549 -350.513045)
					(end 286.87522 -350.566736)
				)
				(xy 286.873188 -350.568768)
				(arc
					(start 286.825182 -350.568768)
					(mid 286.042788 -350.505268)
					(end 286.825182 -350.441768)
				)
				(arc
					(start 286.846772 -350.441768)
					(mid 286.891673 -350.423169)
					(end 286.910272 -350.378268)
				)
				(xy 286.910272 -349.954088) (xy 286.436816 -349.954088)
			)
		)
	)
	(zone
		(layer "In7.Cu")
		(hatch none 0.5)
		(connect_pads
			(clearance 0)
		)
		(min_thickness 0.25)
		(keepout
			(tracks not_allowed)
			(vias allowed)
			(pads allowed)
			(copperpour not_allowed)
			(footprints allowed)
		)
		(placement
			(enabled no)
			(sheetname "")
		)
		(fill
			(thermal_gap 0.5)
			(thermal_bridge_width 0.5)
			(island_removal_mode 0)
		)
		(polygon
			(pts
				(arc
					(start 278.23668 -261.351014)
					(mid 277.6855 -261.902194)
					(end 278.23668 -262.453374)
				)
				(xy 278.720804 -262.453374)
				(arc
					(start 278.720804 -262.029194)
					(mid 278.705925 -261.993273)
					(end 278.670004 -261.978394)
				)
				(arc
					(start 278.623014 -261.978394)
					(mid 277.842903 -261.902194)
					(end 278.623014 -261.825994)
				)
				(xy 278.7015 -261.825994)
				(arc
					(start 278.704548 -261.829042)
					(mid 278.813625 -261.885573)
					(end 278.870156 -261.99465)
				)
				(xy 278.873204 -261.997698) (xy 278.873204 -262.453374) (xy 279.000204 -262.453374) (xy 279.000204 -261.997698)
				(arc
					(start 279.003252 -261.99465)
					(mid 279.059783 -261.885573)
					(end 279.16886 -261.829042)
				)
				(xy 279.171908 -261.825994)
				(arc
					(start 279.250394 -261.825994)
					(mid 280.030505 -261.902194)
					(end 279.250394 -261.978394)
				)
				(arc
					(start 279.203404 -261.978394)
					(mid 279.167483 -261.993273)
					(end 279.152604 -262.029194)
				)
				(xy 279.152604 -262.453374)
				(arc
					(start 279.636728 -262.453374)
					(mid 280.187908 -261.902194)
					(end 279.636728 -261.351014)
				)
				(xy 278.236934 -261.351014)
			)
		)
	)
	(zone
		(layer "In7.Cu")
		(hatch none 0.5)
		(connect_pads
			(clearance 0)
		)
		(min_thickness 0.25)
		(keepout
			(tracks not_allowed)
			(vias allowed)
			(pads allowed)
			(copperpour not_allowed)
			(footprints allowed)
		)
		(placement
			(enabled no)
			(sheetname "")
		)
		(fill
			(thermal_gap 0.5)
			(thermal_bridge_width 0.5)
			(island_removal_mode 0)
		)
		(polygon
			(pts
				(arc
					(start 240.891822 -126.844552)
					(mid 239.891674 -127.163691)
					(end 240.219484 -128.161034)
				)
				(arc
					(start 241.048794 -128.575562)
					(mid 241.061459 -128.511934)
					(end 241.082576 -128.450594)
				)
				(xy 241.082068 -128.44907) (xy 241.096292 -128.420876) (xy 241.291618 -128.033526) (xy 241.291618 -128.01981)
				(arc
					(start 241.303048 -128.008126)
					(mid 241.300768 -127.973849)
					(end 241.27714 -127.948944)
				)
				(arc
					(start 240.999518 -127.810006)
					(mid 240.061555 -127.255934)
					(end 241.06759 -127.673862)
				)
				(xy 241.373406 -127.82677)
				(arc
					(start 241.37493 -127.830834)
					(mid 241.44723 -127.930506)
					(end 241.44859 -128.053592)
				)
				(xy 241.450114 -128.057656) (xy 241.444018 -128.069594) (xy 241.444018 -128.083056) (xy 241.430302 -128.096772)
				(arc
					(start 241.232436 -128.489456)
					(mid 241.204619 -128.567488)
					(end 241.19713 -128.649984)
				)
				(arc
					(start 241.342418 -128.722628)
					(mid 241.324653 -128.651736)
					(end 241.33302 -128.579118)
				)
				(xy 241.33175 -128.575054) (xy 241.345974 -128.54686) (xy 241.535458 -128.17094) (xy 241.541554 -128.158748)
				(xy 241.541554 -128.145286) (xy 241.542062 -128.144778) (xy 241.542062 -128.144016) (xy 241.555778 -128.130046)
				(xy 241.56416 -128.113536)
				(arc
					(start 241.56797 -128.112266)
					(mid 241.667511 -128.039687)
					(end 241.790728 -128.037844)
				)
				(xy 241.794538 -128.036574) (xy 241.822732 -128.050544) (xy 241.822732 -128.050798)
				(arc
					(start 242.100354 -128.189736)
					(mid 243.038317 -128.743808)
					(end 242.032282 -128.32588)
				)
				(arc
					(start 241.754406 -128.186942)
					(mid 241.722639 -128.182465)
					(end 241.694462 -128.197864)
				)
				(xy 241.694462 -128.207262) (xy 241.693954 -128.20777) (xy 241.693954 -128.208532) (xy 241.680238 -128.222248)
				(arc
					(start 241.482118 -128.61544)
					(mid 241.477343 -128.646396)
					(end 241.491516 -128.674368)
				)
				(xy 241.737134 -128.919732)
				(arc
					(start 242.21948 -129.161032)
					(mid 243.211096 -128.830324)
					(end 242.880388 -127.838708)
				)
			)
		)
	)
	(zone
		(layer "In7.Cu")
		(hatch none 0.5)
		(connect_pads
			(clearance 0)
		)
		(min_thickness 0.25)
		(keepout
			(tracks not_allowed)
			(vias allowed)
			(pads allowed)
			(copperpour not_allowed)
			(footprints allowed)
		)
		(placement
			(enabled no)
			(sheetname "")
		)
		(fill
			(thermal_gap 0.5)
			(thermal_bridge_width 0.5)
			(island_removal_mode 0)
		)
		(polygon
			(pts
				(arc
					(start 322.6816 -46.056042)
					(mid 322.3006 -46.437042)
					(end 322.6816 -46.818042)
				)
				(xy 323.0245 -46.818042)
				(arc
					(start 323.0245 -46.538642)
					(mid 323.013341 -46.511701)
					(end 322.9864 -46.500542)
				)
				(arc
					(start 322.94068 -46.500542)
					(mid 322.414852 -46.437042)
					(end 322.94068 -46.373542)
				)
				(xy 323.012816 -46.373542)
				(arc
					(start 323.015356 -46.376082)
					(mid 323.103157 -46.421885)
					(end 323.14896 -46.509686)
				)
				(xy 323.1515 -46.512226) (xy 323.1515 -46.818042) (xy 323.3547 -46.818042) (xy 323.3547 -46.512226)
				(arc
					(start 323.35724 -46.509686)
					(mid 323.402219 -46.422716)
					(end 323.488558 -46.37659)
				)
				(xy 323.491352 -46.373542)
				(arc
					(start 323.56552 -46.373542)
					(mid 324.091348 -46.437042)
					(end 323.56552 -46.500542)
				)
				(arc
					(start 323.5198 -46.500542)
					(mid 323.492859 -46.511701)
					(end 323.4817 -46.538642)
				)
				(xy 323.4817 -46.818042)
				(arc
					(start 323.824346 -46.818042)
					(mid 324.2056 -46.437169)
					(end 323.8246 -46.056042)
				)
			)
		)
	)
	(zone
		(net "P12V_A")
		(layer "In7.Cu")
		(hatch none 0.5)
		(connect_pads
			(clearance 0.5)
		)
		(min_thickness 0.25)
		(fill yes
			(thermal_gap 0.5)
			(thermal_bridge_width 0.5)
			(island_removal_mode 0)
		)
		(polygon
			(pts
				(xy 274.828 -381.742188) (xy 274.828 -408.836622) (xy 276.026626 -410.035248) (xy 289.047428 -410.035248)
				(xy 291.079682 -408.002994) (xy 291.079682 -370.775738) (xy 289.744404 -369.44046) (xy 288.830004 -368.52606)
				(xy 254.934974 -368.52606) (xy 254.020574 -369.44046) (xy 252.598682 -370.862352) (xy 252.598682 -376.695462)
				(xy 253.26848 -377.36526) (xy 274.42668 -377.36526) (xy 274.828 -377.76658) (xy 274.828 -378.968)
			)
		)
	)
	(zone
		(layer "In7.Cu")
		(hatch none 0.5)
		(connect_pads
			(clearance 0)
		)
		(min_thickness 0.25)
		(keepout
			(tracks not_allowed)
			(vias allowed)
			(pads allowed)
			(copperpour not_allowed)
			(footprints allowed)
		)
		(placement
			(enabled no)
			(sheetname "")
		)
		(fill
			(thermal_gap 0.5)
			(thermal_bridge_width 0.5)
			(island_removal_mode 0)
		)
		(polygon
			(pts
				(arc
					(start 285.436564 -351.753932)
					(mid 284.885384 -352.305112)
					(end 285.436564 -352.856292)
				)
				(arc
					(start 286.836612 -352.856292)
					(mid 287.387792 -352.305112)
					(end 286.836612 -351.753932)
				)
				(xy 286.367474 -351.753932)
				(arc
					(start 286.367474 -352.178112)
					(mid 286.386073 -352.223013)
					(end 286.430974 -352.241612)
				)
				(arc
					(start 286.447992 -352.241612)
					(mid 287.230386 -352.305112)
					(end 286.447992 -352.368612)
				)
				(xy 286.404558 -352.368612)
				(arc
					(start 286.402526 -352.36658)
					(mid 286.296197 -352.312889)
					(end 286.242506 -352.20656)
				)
				(xy 286.240474 -352.204528) (xy 286.240474 -351.753932) (xy 286.037274 -351.753932) (xy 286.037274 -352.204528)
				(arc
					(start 286.035242 -352.20656)
					(mid 285.981551 -352.312889)
					(end 285.875222 -352.36658)
				)
				(xy 285.87319 -352.368612)
				(arc
					(start 285.825184 -352.368612)
					(mid 285.04279 -352.305112)
					(end 285.825184 -352.241612)
				)
				(arc
					(start 285.846774 -352.241612)
					(mid 285.891675 -352.223013)
					(end 285.910274 -352.178112)
				)
				(xy 285.910274 -351.753932) (xy 285.436818 -351.753932)
			)
		)
	)
	(zone
		(layer "In7.Cu")
		(hatch none 0.5)
		(connect_pads
			(clearance 0)
		)
		(min_thickness 0.25)
		(keepout
			(tracks not_allowed)
			(vias allowed)
			(pads allowed)
			(copperpour not_allowed)
			(footprints allowed)
		)
		(placement
			(enabled no)
			(sheetname "")
		)
		(fill
			(thermal_gap 0.5)
			(thermal_bridge_width 0.5)
			(island_removal_mode 0)
		)
		(polygon
			(pts
				(arc
					(start 64.4398 -47.178722)
					(mid 64.058927 -46.797468)
					(end 63.6778 -47.178468)
				)
				(arc
					(start 63.6778 -48.321468)
					(mid 64.0588 -48.702468)
					(end 64.4398 -48.321468)
				)
				(xy 64.4398 -47.978568)
				(arc
					(start 64.1604 -47.978568)
					(mid 64.133459 -47.989727)
					(end 64.1223 -48.016668)
				)
				(arc
					(start 64.1223 -48.062388)
					(mid 64.0588 -48.588216)
					(end 63.9953 -48.062388)
				)
				(xy 63.9953 -47.990252)
				(arc
					(start 63.99784 -47.987712)
					(mid 64.043643 -47.899911)
					(end 64.131444 -47.854108)
				)
				(xy 64.133984 -47.851568) (xy 64.4398 -47.851568) (xy 64.4398 -47.648368) (xy 64.133984 -47.648368)
				(arc
					(start 64.131444 -47.645828)
					(mid 64.043643 -47.600025)
					(end 63.99784 -47.512224)
				)
				(xy 63.9953 -47.509684)
				(arc
					(start 63.9953 -47.437548)
					(mid 64.0588 -46.91172)
					(end 64.1223 -47.437548)
				)
				(arc
					(start 64.1223 -47.483268)
					(mid 64.133459 -47.510209)
					(end 64.1604 -47.521368)
				)
				(xy 64.4398 -47.521368)
			)
		)
	)
	(zone
		(layer "In7.Cu")
		(hatch none 0.5)
		(connect_pads
			(clearance 0)
		)
		(min_thickness 0.25)
		(keepout
			(tracks not_allowed)
			(vias allowed)
			(pads allowed)
			(copperpour not_allowed)
			(footprints allowed)
		)
		(placement
			(enabled no)
			(sheetname "")
		)
		(fill
			(thermal_gap 0.5)
			(thermal_bridge_width 0.5)
			(island_removal_mode 0)
		)
		(polygon
			(pts
				(arc
					(start 236.775498 -149.569932)
					(mid 236.661965 -149.487082)
					(end 236.52861 -149.442678)
				)
				(xy 236.287564 -149.563328) (xy 236.48416 -149.563328)
				(arc
					(start 236.485938 -149.565106)
					(mid 236.578763 -149.58844)
					(end 236.660944 -149.637496)
				)
				(xy 236.66323 -149.637496)
				(arc
					(start 236.685582 -149.659848)
					(mid 236.694332 -149.670329)
					(end 236.701076 -149.6822)
				)
				(xy 236.707934 -149.6822) (xy 236.913166 -149.887432)
				(arc
					(start 236.913166 -149.891496)
					(mid 236.947699 -150.040924)
					(end 236.867954 -150.171912)
				)
				(xy 236.866684 -150.175468) (xy 236.856524 -150.180802) (xy 236.85627 -150.18131) (xy 236.828584 -150.19528)
				(xy 236.800644 -150.209504) (xy 236.80039 -150.20925)
				(arc
					(start 236.567726 -150.325836)
					(mid 235.561798 -150.744413)
					(end 236.4994 -150.189438)
				)
				(xy 236.759496 -150.059136) (xy 236.769148 -150.05431)
				(arc
					(start 236.770926 -150.053294)
					(mid 236.797167 -150.016123)
					(end 236.783118 -149.972776)
				)
				(arc
					(start 236.577886 -149.767544)
					(mid 236.520434 -149.729156)
					(end 236.452664 -149.715728)
				)
				(xy 235.982764 -149.715728)
				(arc
					(start 235.733844 -149.840188)
					(mid 235.393447 -150.821218)
					(end 236.377226 -151.15413)
				)
				(arc
					(start 238.377222 -150.154132)
					(mid 238.704374 -149.172676)
					(end 237.722918 -148.845524)
				)
				(arc
					(start 236.721396 -149.346412)
					(mid 236.793712 -149.388379)
					(end 236.859572 -149.439884)
				)
				(xy 236.860842 -149.439884)
				(arc
					(start 237.201964 -149.781006)
					(mid 237.243617 -149.802256)
					(end 237.289848 -149.79523)
				)
				(arc
					(start 237.532418 -149.673818)
					(mid 238.537816 -149.254359)
					(end 237.600744 -149.809962)
				)
				(xy 237.358174 -149.931374) (xy 237.32998 -149.945598)
				(arc
					(start 237.326678 -149.944328)
					(mid 237.219406 -149.952669)
					(end 237.120176 -149.911054)
				)
				(xy 237.11662 -149.911054)
			)
		)
	)
	(zone
		(layer "In7.Cu")
		(hatch none 0.5)
		(connect_pads
			(clearance 0)
		)
		(min_thickness 0.25)
		(keepout
			(tracks not_allowed)
			(vias allowed)
			(pads allowed)
			(copperpour not_allowed)
			(footprints allowed)
		)
		(placement
			(enabled no)
			(sheetname "")
		)
		(fill
			(thermal_gap 0.5)
			(thermal_bridge_width 0.5)
			(island_removal_mode 0)
		)
		(polygon
			(pts
				(arc
					(start 285.436564 -355.353874)
					(mid 284.885384 -355.905054)
					(end 285.436564 -356.456234)
				)
				(arc
					(start 286.836612 -356.456234)
					(mid 287.387792 -355.905054)
					(end 286.836612 -355.353874)
				)
				(xy 286.367474 -355.353874)
				(arc
					(start 286.367474 -355.778054)
					(mid 286.386073 -355.822955)
					(end 286.430974 -355.841554)
				)
				(arc
					(start 286.447992 -355.841554)
					(mid 287.230386 -355.905054)
					(end 286.447992 -355.968554)
				)
				(xy 286.404558 -355.968554)
				(arc
					(start 286.402526 -355.966522)
					(mid 286.296197 -355.912831)
					(end 286.242506 -355.806502)
				)
				(xy 286.240474 -355.80447) (xy 286.240474 -355.353874) (xy 286.037274 -355.353874) (xy 286.037274 -355.80447)
				(arc
					(start 286.035242 -355.806502)
					(mid 285.981551 -355.912831)
					(end 285.875222 -355.966522)
				)
				(xy 285.87319 -355.968554)
				(arc
					(start 285.825184 -355.968554)
					(mid 285.04279 -355.905054)
					(end 285.825184 -355.841554)
				)
				(arc
					(start 285.846774 -355.841554)
					(mid 285.891675 -355.822955)
					(end 285.910274 -355.778054)
				)
				(xy 285.910274 -355.353874) (xy 285.436818 -355.353874)
			)
		)
	)
	(zone
		(layer "In7.Cu")
		(hatch none 0.5)
		(connect_pads
			(clearance 0)
		)
		(min_thickness 0.25)
		(keepout
			(tracks not_allowed)
			(vias allowed)
			(pads allowed)
			(copperpour not_allowed)
			(footprints allowed)
		)
		(placement
			(enabled no)
			(sheetname "")
		)
		(fill
			(thermal_gap 0.5)
			(thermal_bridge_width 0.5)
			(island_removal_mode 0)
		)
		(polygon
			(pts
				(arc
					(start 368.30127 -29.150056)
					(mid 367.75009 -28.598876)
					(end 367.19891 -29.150056)
				)
				(xy 367.19891 -29.602938)
				(arc
					(start 367.62309 -29.602938)
					(mid 367.659011 -29.588059)
					(end 367.67389 -29.552138)
				)
				(arc
					(start 367.67389 -29.53639)
					(mid 367.75009 -28.756279)
					(end 367.82629 -29.53639)
				)
				(xy 367.82629 -29.583634)
				(arc
					(start 367.823242 -29.586682)
					(mid 367.766711 -29.695759)
					(end 367.657634 -29.75229)
				)
				(xy 367.654586 -29.755338) (xy 367.19891 -29.755338) (xy 367.19891 -29.882338) (xy 367.654586 -29.882338)
				(arc
					(start 367.657634 -29.885386)
					(mid 367.766711 -29.941917)
					(end 367.823242 -30.050994)
				)
				(xy 367.82629 -30.054042)
				(arc
					(start 367.82629 -30.16377)
					(mid 367.75009 -30.943881)
					(end 367.67389 -30.16377)
				)
				(arc
					(start 367.67389 -30.085538)
					(mid 367.659011 -30.049617)
					(end 367.62309 -30.034738)
				)
				(xy 367.19891 -30.034738)
				(arc
					(start 367.19891 -30.54985)
					(mid 367.749963 -31.101284)
					(end 368.30127 -30.550104)
				)
			)
		)
	)
	(zone
		(layer "In7.Cu")
		(hatch none 0.5)
		(connect_pads
			(clearance 0)
		)
		(min_thickness 0.25)
		(keepout
			(tracks not_allowed)
			(vias allowed)
			(pads allowed)
			(copperpour not_allowed)
			(footprints allowed)
		)
		(placement
			(enabled no)
			(sheetname "")
		)
		(fill
			(thermal_gap 0.5)
			(thermal_bridge_width 0.5)
			(island_removal_mode 0)
		)
		(polygon
			(pts
				(arc
					(start 238.377222 -130.154172)
					(mid 238.704374 -129.172716)
					(end 237.722918 -128.845564)
				)
				(arc
					(start 236.726222 -129.343912)
					(mid 236.787476 -129.380134)
					(end 236.84357 -129.423922)
				)
				(xy 236.84484 -129.423922)
				(arc
					(start 237.201964 -129.781046)
					(mid 237.243617 -129.802296)
					(end 237.289848 -129.79527)
				)
				(arc
					(start 237.532418 -129.673858)
					(mid 238.537816 -129.254399)
					(end 237.600744 -129.810002)
				)
				(xy 237.358174 -129.931414) (xy 237.32998 -129.945638)
				(arc
					(start 237.326678 -129.944368)
					(mid 237.219406 -129.952709)
					(end 237.120176 -129.911094)
				)
				(xy 237.11662 -129.911094)
				(arc
					(start 236.759496 -129.55397)
					(mid 236.655512 -129.478917)
					(end 236.533182 -129.440432)
				)
				(xy 236.287564 -129.563368) (xy 236.506766 -129.563368)
				(arc
					(start 236.508798 -129.5654)
					(mid 236.580425 -129.584258)
					(end 236.644434 -129.621534)
				)
				(xy 236.647228 -129.621534) (xy 236.913166 -129.887472)
				(arc
					(start 236.913166 -129.891536)
					(mid 236.947699 -130.040964)
					(end 236.867954 -130.171952)
				)
				(xy 236.866684 -130.175508) (xy 236.856524 -130.180842) (xy 236.85627 -130.18135) (xy 236.828584 -130.19532)
				(xy 236.800644 -130.209544) (xy 236.80039 -130.20929)
				(arc
					(start 236.567726 -130.325876)
					(mid 235.561798 -130.744453)
					(end 236.4994 -130.189478)
				)
				(xy 236.759496 -130.059176) (xy 236.769148 -130.05435)
				(arc
					(start 236.770926 -130.053334)
					(mid 236.797167 -130.016163)
					(end 236.783118 -129.972816)
				)
				(arc
					(start 236.561884 -129.751582)
					(mid 236.522145 -129.725029)
					(end 236.47527 -129.715768)
				)
				(xy 235.982764 -129.715768)
				(arc
					(start 235.733844 -129.840228)
					(mid 235.393447 -130.821258)
					(end 236.377226 -131.15417)
				)
			)
		)
	)
	(zone
		(layer "In7.Cu")
		(hatch none 0.5)
		(connect_pads
			(clearance 0)
		)
		(min_thickness 0.25)
		(keepout
			(tracks not_allowed)
			(vias allowed)
			(pads allowed)
			(copperpour not_allowed)
			(footprints allowed)
		)
		(placement
			(enabled no)
			(sheetname "")
		)
		(fill
			(thermal_gap 0.5)
			(thermal_bridge_width 0.5)
			(island_removal_mode 0)
		)
		(polygon
			(pts
				(arc
					(start 159.089852 -47.178722)
					(mid 158.708979 -46.797468)
					(end 158.327852 -47.178468)
				)
				(arc
					(start 158.327852 -48.321468)
					(mid 158.708852 -48.702468)
					(end 159.089852 -48.321468)
				)
				(xy 159.089852 -47.978568)
				(arc
					(start 158.810452 -47.978568)
					(mid 158.783511 -47.989727)
					(end 158.772352 -48.016668)
				)
				(arc
					(start 158.772352 -48.062388)
					(mid 158.708852 -48.588216)
					(end 158.645352 -48.062388)
				)
				(xy 158.645352 -47.990252)
				(arc
					(start 158.647892 -47.987712)
					(mid 158.693695 -47.899911)
					(end 158.781496 -47.854108)
				)
				(xy 158.784036 -47.851568) (xy 159.089852 -47.851568) (xy 159.089852 -47.648368) (xy 158.784036 -47.648368)
				(arc
					(start 158.781496 -47.645828)
					(mid 158.693695 -47.600025)
					(end 158.647892 -47.512224)
				)
				(xy 158.645352 -47.509684)
				(arc
					(start 158.645352 -47.437548)
					(mid 158.708852 -46.91172)
					(end 158.772352 -47.437548)
				)
				(arc
					(start 158.772352 -47.483268)
					(mid 158.783511 -47.510209)
					(end 158.810452 -47.521368)
				)
				(xy 159.089852 -47.521368)
			)
		)
	)
	(zone
		(layer "In7.Cu")
		(hatch none 0.5)
		(connect_pads
			(clearance 0)
		)
		(min_thickness 0.25)
		(keepout
			(tracks not_allowed)
			(vias allowed)
			(pads allowed)
			(copperpour not_allowed)
			(footprints allowed)
		)
		(placement
			(enabled no)
			(sheetname "")
		)
		(fill
			(thermal_gap 0.5)
			(thermal_bridge_width 0.5)
			(island_removal_mode 0)
		)
		(polygon
			(pts
				(arc
					(start 283.57703 -34.545778)
					(mid 282.595574 -34.87293)
					(end 282.922726 -35.854386)
				)
				(arc
					(start 284.922468 -36.854384)
					(mid 285.904229 -36.527384)
					(end 285.577026 -35.545776)
				)
				(xy 285.351474 -35.433)
				(arc
					(start 284.736286 -35.433)
					(mid 284.642118 -35.459671)
					(end 284.576012 -35.531806)
				)
				(xy 284.550104 -35.583114) (xy 284.550104 -35.59683) (xy 284.536134 -35.6108) (xy 284.527752 -35.627564)
				(arc
					(start 284.500066 -35.682428)
					(mid 284.497218 -35.721273)
					(end 284.522672 -35.750754)
				)
				(arc
					(start 284.800548 -35.889692)
					(mid 285.738149 -36.444666)
					(end 284.732222 -36.02609)
				)
				(xy 284.4546 -35.886898) (xy 284.426406 -35.872928)
				(arc
					(start 284.424882 -35.868864)
					(mid 284.352631 -35.769342)
					(end 284.350968 -35.64636)
				)
				(xy 284.349698 -35.64255) (xy 284.39745 -35.5473) (xy 284.39745 -35.533838) (xy 284.411166 -35.520122)
				(xy 284.419802 -35.50285) (xy 284.439868 -35.463226) (xy 284.454092 -35.435032)
				(arc
					(start 284.456378 -35.43427)
					(mid 284.562249 -35.329995)
					(end 284.703012 -35.282378)
				)
				(xy 284.70479 -35.2806) (xy 285.046674 -35.2806) (xy 284.792674 -35.1536)
				(arc
					(start 284.721046 -35.1536)
					(mid 284.492783 -35.21844)
					(end 284.332426 -35.393376)
				)
				(xy 284.255464 -35.546284) (xy 284.254702 -35.547808) (xy 284.24124 -35.574732)
				(arc
					(start 284.237938 -35.575748)
					(mid 284.130489 -35.655175)
					(end 283.996892 -35.656266)
				)
				(xy 283.993336 -35.657536)
				(arc
					(start 283.699204 -35.510216)
					(mid 282.76212 -34.954607)
					(end 283.76753 -35.374072)
				)
				(arc
					(start 284.033214 -35.507168)
					(mid 284.08187 -35.510778)
					(end 284.118812 -35.478974)
				)
				(xy 284.210506 -35.296602)
				(arc
					(start 284.211522 -35.296348)
					(mid 284.35226 -35.131447)
					(end 284.543246 -35.028886)
				)
			)
		)
	)
	(zone
		(net "P3V3_STBY_A")
		(layer "In7.Cu")
		(hatch none 0.5)
		(connect_pads
			(clearance 0.5)
		)
		(min_thickness 0.25)
		(fill yes
			(thermal_gap 0.5)
			(thermal_bridge_width 0.5)
			(island_removal_mode 0)
		)
		(polygon
			(pts
				(xy 223.236282 -120.662192) (xy 223.236282 -113.302796) (xy 222.359728 -112.426242) (xy 214.851488 -112.426242)
				(xy 214.256112 -113.021618) (xy 214.256112 -120.877076) (xy 214.256112 -121.248932) (xy 214.714074 -121.706894)
				(xy 222.668084 -121.706894) (xy 223.236282 -121.138696)
			)
		)
	)
	(zone
		(layer "In7.Cu")
		(hatch none 0.5)
		(connect_pads
			(clearance 0)
		)
		(min_thickness 0.25)
		(keepout
			(tracks not_allowed)
			(vias allowed)
			(pads allowed)
			(copperpour not_allowed)
			(footprints allowed)
		)
		(placement
			(enabled no)
			(sheetname "")
		)
		(fill
			(thermal_gap 0.5)
			(thermal_bridge_width 0.5)
			(island_removal_mode 0)
		)
		(polygon
			(pts
				(arc
					(start 281.077162 -11.854434)
					(mid 281.404314 -10.872978)
					(end 280.422858 -10.545826)
				)
				(arc
					(start 278.433784 -11.54049)
					(mid 278.093387 -12.52152)
					(end 279.077166 -12.854432)
				)
				(arc
					(start 280.105104 -12.34059)
					(mid 279.974585 -12.269548)
					(end 279.857708 -12.177776)
				)
				(xy 279.856946 -12.177776)
				(arc
					(start 279.59812 -11.91895)
					(mid 279.556467 -11.8977)
					(end 279.510236 -11.904726)
				)
				(xy 279.509982 -11.904726)
				(arc
					(start 279.267666 -12.026138)
					(mid 278.262268 -12.445597)
					(end 279.19934 -11.889994)
				)
				(xy 279.44191 -11.768582) (xy 279.470104 -11.754358)
				(arc
					(start 279.473406 -11.755628)
					(mid 279.580678 -11.747287)
					(end 279.679908 -11.788902)
				)
				(xy 279.683464 -11.788902)
				(arc
					(start 279.94229 -12.047728)
					(mid 280.105781 -12.171015)
					(end 280.296874 -12.244578)
				)
				(xy 280.512774 -12.136628) (xy 280.432256 -12.136628)
				(arc
					(start 280.43124 -12.135866)
					(mid 280.230184 -12.090193)
					(end 280.055828 -11.980164)
				)
				(xy 280.054558 -11.980164) (xy 280.032206 -11.957812) (xy 279.886918 -11.812524)
				(arc
					(start 279.886918 -11.80846)
					(mid 279.852385 -11.659032)
					(end 279.93213 -11.528044)
				)
				(xy 279.9334 -11.524488) (xy 279.94356 -11.519154) (xy 279.943814 -11.518646) (xy 279.9715 -11.504676)
				(xy 279.99944 -11.490452) (xy 279.999694 -11.490706)
				(arc
					(start 280.232358 -11.37412)
					(mid 281.238286 -10.955543)
					(end 280.300684 -11.510518)
				)
				(xy 280.040588 -11.64082) (xy 280.030936 -11.645646)
				(arc
					(start 280.029158 -11.646662)
					(mid 280.002917 -11.683833)
					(end 280.016966 -11.72718)
				)
				(arc
					(start 280.139902 -11.850116)
					(mid 280.288486 -11.949396)
					(end 280.463752 -11.984228)
				)
				(xy 280.817574 -11.984228)
			)
		)
	)
	(zone
		(layer "In7.Cu")
		(hatch none 0.5)
		(connect_pads
			(clearance 0)
		)
		(min_thickness 0.25)
		(keepout
			(tracks not_allowed)
			(vias allowed)
			(pads allowed)
			(copperpour not_allowed)
			(footprints allowed)
		)
		(placement
			(enabled no)
			(sheetname "")
		)
		(fill
			(thermal_gap 0.5)
			(thermal_bridge_width 0.5)
			(island_removal_mode 0)
		)
		(polygon
			(pts
				(arc
					(start 242.100608 -124.189744)
					(mid 243.037692 -124.745353)
					(end 242.032282 -124.325888)
				)
				(arc
					(start 241.766598 -124.192792)
					(mid 241.71832 -124.189059)
					(end 241.681254 -124.220224)
				)
				(xy 241.658394 -124.26569) (xy 241.658394 -124.265944) (xy 241.64417 -124.293884) (xy 241.630454 -124.321824)
				(xy 241.6302 -124.322078) (xy 241.48415 -124.6124)
				(arc
					(start 241.475514 -124.615194)
					(mid 241.469014 -124.648769)
					(end 241.48415 -124.679456)
				)
				(xy 241.711988 -124.907294)
				(arc
					(start 242.20805 -125.155198)
					(mid 243.208198 -124.836059)
					(end 242.880388 -123.838716)
				)
				(arc
					(start 240.880392 -122.838718)
					(mid 239.888776 -123.169426)
					(end 240.219484 -124.161042)
				)
				(arc
					(start 241.041428 -124.572014)
					(mid 241.072371 -124.458276)
					(end 241.12982 -124.355352)
				)
				(xy 241.249708 -124.116846) (xy 241.249708 -124.10313) (xy 241.263678 -124.08916) (xy 241.27206 -124.072396)
				(arc
					(start 241.299746 -124.017532)
					(mid 241.302594 -123.978687)
					(end 241.27714 -123.949206)
				)
				(arc
					(start 240.999264 -123.810268)
					(mid 240.061663 -123.255294)
					(end 241.06759 -123.67387)
				)
				(xy 241.345212 -123.813062) (xy 241.373406 -123.827032)
				(arc
					(start 241.37493 -123.831096)
					(mid 241.447181 -123.930618)
					(end 241.448844 -124.0536)
				)
				(xy 241.450114 -124.05741) (xy 241.402362 -124.15266) (xy 241.402362 -124.166122) (xy 241.388646 -124.179838)
				(xy 241.38001 -124.19711) (xy 241.248692 -124.457968)
				(arc
					(start 241.242596 -124.46)
					(mid 241.202066 -124.548868)
					(end 241.189002 -124.645674)
				)
				(arc
					(start 241.330226 -124.716286)
					(mid 241.319302 -124.60601)
					(end 241.367056 -124.505974)
				)
				(xy 241.50701 -124.227844) (xy 241.506756 -124.227336) (xy 241.52098 -124.199396) (xy 241.534696 -124.17171)
				(xy 241.535204 -124.171456) (xy 241.544348 -124.153422) (xy 241.545872 -124.150628) (xy 241.558826 -124.124974)
				(arc
					(start 241.562128 -124.123958)
					(mid 241.66951 -124.044784)
					(end 241.80292 -124.043694)
				)
				(xy 241.806476 -124.042424)
			)
		)
	)
	(zone
		(layer "In7.Cu")
		(hatch none 0.5)
		(connect_pads
			(clearance 0)
		)
		(min_thickness 0.25)
		(keepout
			(tracks not_allowed)
			(vias allowed)
			(pads allowed)
			(copperpour not_allowed)
			(footprints allowed)
		)
		(placement
			(enabled no)
			(sheetname "")
		)
		(fill
			(thermal_gap 0.5)
			(thermal_bridge_width 0.5)
			(island_removal_mode 0)
		)
		(polygon
			(pts
				(arc
					(start 285.436564 -348.15399)
					(mid 284.885384 -348.70517)
					(end 285.436564 -349.25635)
				)
				(arc
					(start 286.836612 -349.25635)
					(mid 287.387792 -348.70517)
					(end 286.836612 -348.15399)
				)
				(xy 286.367474 -348.15399)
				(arc
					(start 286.367474 -348.57817)
					(mid 286.386073 -348.623071)
					(end 286.430974 -348.64167)
				)
				(arc
					(start 286.447992 -348.64167)
					(mid 287.230386 -348.70517)
					(end 286.447992 -348.76867)
				)
				(xy 286.404558 -348.76867)
				(arc
					(start 286.402526 -348.766638)
					(mid 286.296197 -348.712947)
					(end 286.242506 -348.606618)
				)
				(xy 286.240474 -348.604586) (xy 286.240474 -348.15399) (xy 286.037274 -348.15399) (xy 286.037274 -348.604586)
				(arc
					(start 286.035242 -348.606618)
					(mid 285.981551 -348.712947)
					(end 285.875222 -348.766638)
				)
				(xy 285.87319 -348.76867)
				(arc
					(start 285.825184 -348.76867)
					(mid 285.04279 -348.70517)
					(end 285.825184 -348.64167)
				)
				(arc
					(start 285.846774 -348.64167)
					(mid 285.891675 -348.623071)
					(end 285.910274 -348.57817)
				)
				(xy 285.910274 -348.15399) (xy 285.436818 -348.15399)
			)
		)
	)
	(zone
		(layer "In7.Cu")
		(hatch none 0.5)
		(connect_pads
			(clearance 0)
		)
		(min_thickness 0.25)
		(keepout
			(tracks not_allowed)
			(vias allowed)
			(pads allowed)
			(copperpour not_allowed)
			(footprints allowed)
		)
		(placement
			(enabled no)
			(sheetname "")
		)
		(fill
			(thermal_gap 0.5)
			(thermal_bridge_width 0.5)
			(island_removal_mode 0)
		)
		(polygon
			(pts
				(arc
					(start 236.788452 -121.582942)
					(mid 236.667155 -121.493674)
					(end 236.5248 -121.444512)
				)
				(xy 236.28731 -121.563384) (xy 236.465872 -121.563384)
				(arc
					(start 236.467396 -121.564908)
					(mid 236.577325 -121.591878)
					(end 236.674152 -121.650506)
				)
				(xy 236.676184 -121.650506) (xy 236.698536 -121.672858) (xy 236.913166 -121.887488)
				(arc
					(start 236.913166 -121.891552)
					(mid 236.947699 -122.04098)
					(end 236.867954 -122.171968)
				)
				(xy 236.866684 -122.175524) (xy 236.856524 -122.180858) (xy 236.85627 -122.181366) (xy 236.828584 -122.195336)
				(xy 236.800644 -122.20956) (xy 236.80039 -122.209306)
				(arc
					(start 236.567726 -122.325892)
					(mid 235.561798 -122.744469)
					(end 236.4994 -122.189494)
				)
				(xy 236.759496 -122.059192) (xy 236.769148 -122.054366)
				(arc
					(start 236.770926 -122.05335)
					(mid 236.797167 -122.016179)
					(end 236.783118 -121.972832)
				)
				(arc
					(start 236.59084 -121.780554)
					(mid 236.519054 -121.732588)
					(end 236.434376 -121.715784)
				)
				(xy 235.98251 -121.715784)
				(arc
					(start 235.722922 -121.845578)
					(mid 235.39577 -122.827034)
					(end 236.377226 -123.154186)
				)
				(arc
					(start 238.3663 -122.159522)
					(mid 238.706697 -121.178492)
					(end 237.722918 -120.84558)
				)
				(arc
					(start 236.717332 -121.3485)
					(mid 236.798811 -121.395105)
					(end 236.87278 -121.452894)
				)
				(xy 236.873796 -121.452894)
				(arc
					(start 237.201964 -121.781062)
					(mid 237.243617 -121.802312)
					(end 237.289848 -121.795286)
				)
				(arc
					(start 237.532418 -121.673874)
					(mid 238.537816 -121.254415)
					(end 237.600744 -121.810018)
				)
				(xy 237.358174 -121.93143) (xy 237.32998 -121.945654)
				(arc
					(start 237.326678 -121.944384)
					(mid 237.219406 -121.952725)
					(end 237.120176 -121.91111)
				)
				(xy 237.11662 -121.91111)
			)
		)
	)
	(zone
		(layer "In7.Cu")
		(hatch none 0.5)
		(connect_pads
			(clearance 0)
		)
		(min_thickness 0.25)
		(keepout
			(tracks not_allowed)
			(vias allowed)
			(pads allowed)
			(copperpour not_allowed)
			(footprints allowed)
		)
		(placement
			(enabled no)
			(sheetname "")
		)
		(fill
			(thermal_gap 0.5)
			(thermal_bridge_width 0.5)
			(island_removal_mode 0)
		)
		(polygon
			(pts
				(arc
					(start 236.717586 -161.348166)
					(mid 236.798126 -161.394206)
					(end 236.871256 -161.45129)
				)
				(xy 236.872272 -161.45129)
				(arc
					(start 237.201964 -161.780982)
					(mid 237.243617 -161.802232)
					(end 237.289848 -161.795206)
				)
				(arc
					(start 237.532418 -161.673794)
					(mid 238.537816 -161.254335)
					(end 237.600744 -161.809938)
				)
				(xy 237.358174 -161.93135) (xy 237.32998 -161.945574)
				(arc
					(start 237.326678 -161.944304)
					(mid 237.219406 -161.952645)
					(end 237.120176 -161.91103)
				)
				(xy 237.11662 -161.91103)
				(arc
					(start 236.786928 -161.581338)
					(mid 236.666448 -161.49297)
					(end 236.525054 -161.444686)
				)
				(xy 236.286548 -161.563812) (xy 236.469174 -161.563812)
				(arc
					(start 236.470698 -161.565336)
					(mid 236.578014 -161.591759)
					(end 236.672628 -161.648902)
				)
				(xy 236.67466 -161.648902) (xy 236.913166 -161.887408)
				(arc
					(start 236.913166 -161.891472)
					(mid 236.947699 -162.0409)
					(end 236.867954 -162.171888)
				)
				(xy 236.866684 -162.175444) (xy 236.856524 -162.180778) (xy 236.85627 -162.181286) (xy 236.828584 -162.195256)
				(xy 236.800644 -162.20948) (xy 236.80039 -162.209226)
				(arc
					(start 236.567726 -162.325812)
					(mid 235.561798 -162.744389)
					(end 236.4994 -162.189414)
				)
				(xy 236.759496 -162.059112) (xy 236.769148 -162.054286)
				(arc
					(start 236.770926 -162.05327)
					(mid 236.797167 -162.016099)
					(end 236.783118 -161.972752)
				)
				(arc
					(start 236.589316 -161.77895)
					(mid 236.519744 -161.732463)
					(end 236.437678 -161.716212)
				)
				(xy 235.981748 -161.716212)
				(arc
					(start 235.733844 -161.840164)
					(mid 235.393447 -162.821194)
					(end 236.377226 -163.154106)
				)
				(arc
					(start 238.377222 -162.154108)
					(mid 238.704374 -161.172652)
					(end 237.722918 -160.8455)
				)
			)
		)
	)
	(zone
		(layer "In7.Cu")
		(hatch none 0.5)
		(connect_pads
			(clearance 0)
		)
		(min_thickness 0.25)
		(keepout
			(tracks not_allowed)
			(vias allowed)
			(pads allowed)
			(copperpour not_allowed)
			(footprints allowed)
		)
		(placement
			(enabled no)
			(sheetname "")
		)
		(fill
			(thermal_gap 0.5)
			(thermal_bridge_width 0.5)
			(island_removal_mode 0)
		)
		(polygon
			(pts
				(arc
					(start 286.436562 -313.953906)
					(mid 285.885382 -314.505086)
					(end 286.436562 -315.056266)
				)
				(arc
					(start 287.83661 -315.056266)
					(mid 288.38779 -314.505086)
					(end 287.83661 -313.953906)
				)
				(xy 287.367472 -313.953906)
				(arc
					(start 287.367472 -314.378086)
					(mid 287.386071 -314.422987)
					(end 287.430972 -314.441586)
				)
				(arc
					(start 287.44799 -314.441586)
					(mid 288.230384 -314.505086)
					(end 287.44799 -314.568586)
				)
				(xy 287.404556 -314.568586)
				(arc
					(start 287.402524 -314.566554)
					(mid 287.296195 -314.512863)
					(end 287.242504 -314.406534)
				)
				(xy 287.240472 -314.404502) (xy 287.240472 -313.953906) (xy 287.037272 -313.953906) (xy 287.037272 -314.404502)
				(arc
					(start 287.03524 -314.406534)
					(mid 286.981549 -314.512863)
					(end 286.87522 -314.566554)
				)
				(xy 286.873188 -314.568586)
				(arc
					(start 286.825182 -314.568586)
					(mid 286.042788 -314.505086)
					(end 286.825182 -314.441586)
				)
				(arc
					(start 286.846772 -314.441586)
					(mid 286.891673 -314.422987)
					(end 286.910272 -314.378086)
				)
				(xy 286.910272 -313.953906) (xy 286.436816 -313.953906)
			)
		)
	)
	(zone
		(layer "In7.Cu")
		(hatch none 0.5)
		(connect_pads
			(clearance 0)
		)
		(min_thickness 0.25)
		(keepout
			(tracks not_allowed)
			(vias allowed)
			(pads allowed)
			(copperpour not_allowed)
			(footprints allowed)
		)
		(placement
			(enabled no)
			(sheetname "")
		)
		(fill
			(thermal_gap 0.5)
			(thermal_bridge_width 0.5)
			(island_removal_mode 0)
		)
		(polygon
			(pts
				(arc
					(start 159.089852 -162.178746)
					(mid 158.708979 -161.797492)
					(end 158.327852 -162.178492)
				)
				(arc
					(start 158.327852 -163.321492)
					(mid 158.708852 -163.702492)
					(end 159.089852 -163.321492)
				)
				(xy 159.089852 -162.978592)
				(arc
					(start 158.810452 -162.978592)
					(mid 158.783511 -162.989751)
					(end 158.772352 -163.016692)
				)
				(arc
					(start 158.772352 -163.062412)
					(mid 158.708852 -163.58824)
					(end 158.645352 -163.062412)
				)
				(xy 158.645352 -162.990276)
				(arc
					(start 158.647892 -162.987736)
					(mid 158.693695 -162.899935)
					(end 158.781496 -162.854132)
				)
				(xy 158.784036 -162.851592) (xy 159.089852 -162.851592) (xy 159.089852 -162.648392) (xy 158.784036 -162.648392)
				(xy 158.781242 -162.645598)
				(arc
					(start 158.77921 -162.64509)
					(mid 158.692974 -162.599039)
					(end 158.647892 -162.512248)
				)
				(xy 158.645352 -162.509708)
				(arc
					(start 158.645352 -162.437572)
					(mid 158.708852 -161.911744)
					(end 158.772352 -162.437572)
				)
				(arc
					(start 158.772352 -162.483292)
					(mid 158.781025 -162.507402)
					(end 158.803086 -162.520376)
				)
				(xy 158.804102 -162.52063) (xy 158.81096 -162.521392) (xy 159.089852 -162.521392)
			)
		)
	)
	(zone
		(layer "In7.Cu")
		(hatch none 0.5)
		(connect_pads
			(clearance 0)
		)
		(min_thickness 0.25)
		(keepout
			(tracks not_allowed)
			(vias allowed)
			(pads allowed)
			(copperpour not_allowed)
			(footprints allowed)
		)
		(placement
			(enabled no)
			(sheetname "")
		)
		(fill
			(thermal_gap 0.5)
			(thermal_bridge_width 0.5)
			(island_removal_mode 0)
		)
		(polygon
			(pts
				(arc
					(start 278.23668 -294.156638)
					(mid 277.68804 -294.705278)
					(end 278.23668 -295.253918)
				)
				(arc
					(start 279.636728 -295.253918)
					(mid 280.185368 -294.705278)
					(end 279.636728 -294.156638)
				)
				(xy 279.197308 -294.156638) (xy 279.165304 -294.188642)
				(arc
					(start 279.165304 -294.603678)
					(mid 279.176463 -294.630619)
					(end 279.203404 -294.641778)
				)
				(arc
					(start 279.248108 -294.641778)
					(mid 280.030502 -294.705278)
					(end 279.248108 -294.768778)
				)
				(xy 279.176988 -294.768778)
				(arc
					(start 279.174448 -294.766238)
					(mid 279.086647 -294.720435)
					(end 279.040844 -294.632634)
				)
				(xy 279.038304 -294.630094) (xy 279.038304 -294.188642) (xy 279.038304 -294.156638) (xy 278.835104 -294.156638)
				(xy 278.835104 -294.630094)
				(arc
					(start 278.832564 -294.632634)
					(mid 278.786761 -294.720435)
					(end 278.69896 -294.766238)
				)
				(xy 278.69642 -294.768778)
				(arc
					(start 278.6253 -294.768778)
					(mid 277.842906 -294.705278)
					(end 278.6253 -294.641778)
				)
				(arc
					(start 278.670004 -294.641778)
					(mid 278.696945 -294.630619)
					(end 278.708104 -294.603678)
				)
				(xy 278.708104 -294.156638) (xy 278.236934 -294.156638)
			)
		)
	)
	(zone
		(layer "In7.Cu")
		(hatch none 0.5)
		(connect_pads
			(clearance 0)
		)
		(min_thickness 0.25)
		(keepout
			(tracks not_allowed)
			(vias allowed)
			(pads allowed)
			(copperpour not_allowed)
			(footprints allowed)
		)
		(placement
			(enabled no)
			(sheetname "")
		)
		(fill
			(thermal_gap 0.5)
			(thermal_bridge_width 0.5)
			(island_removal_mode 0)
		)
		(polygon
			(pts
				(arc
					(start 236.76483 -11.259566)
					(mid 236.657 -11.181868)
					(end 236.530134 -11.142218)
				)
				(xy 236.284516 -11.265154) (xy 236.502956 -11.265154)
				(arc
					(start 236.504988 -11.267186)
					(mid 236.581525 -11.28713)
					(end 236.649768 -11.32713)
				)
				(xy 236.652562 -11.32713) (xy 236.67466 -11.349228) (xy 236.674914 -11.349482) (xy 236.913166 -11.587734)
				(arc
					(start 236.913166 -11.591798)
					(mid 236.947699 -11.741226)
					(end 236.867954 -11.872214)
				)
				(xy 236.866684 -11.87577) (xy 236.856524 -11.881104) (xy 236.85627 -11.881612) (xy 236.828584 -11.895582)
				(xy 236.800644 -11.909806) (xy 236.80039 -11.909552)
				(arc
					(start 236.567726 -12.026138)
					(mid 235.561798 -12.444715)
					(end 236.4994 -11.88974)
				)
				(xy 236.759496 -11.759438)
				(arc
					(start 236.770926 -11.753596)
					(mid 236.797167 -11.716425)
					(end 236.783118 -11.673078)
				)
				(arc
					(start 236.566964 -11.457178)
					(mid 236.523264 -11.427949)
					(end 236.471714 -11.417554)
				)
				(xy 235.979716 -11.417554)
				(arc
					(start 235.733844 -11.54049)
					(mid 235.393447 -12.52152)
					(end 236.377226 -12.854432)
				)
				(arc
					(start 238.377222 -11.854434)
					(mid 238.704374 -10.872978)
					(end 237.722918 -10.545826)
				)
				(arc
					(start 236.724444 -11.04519)
					(mid 236.789475 -11.083218)
					(end 236.848904 -11.129518)
				)
				(xy 236.850174 -11.129518) (xy 236.872526 -11.15187)
				(arc
					(start 237.201964 -11.481308)
					(mid 237.243617 -11.502558)
					(end 237.289848 -11.495532)
				)
				(arc
					(start 237.532418 -11.37412)
					(mid 238.537816 -10.954661)
					(end 237.600744 -11.510264)
				)
				(xy 237.358174 -11.631676) (xy 237.32998 -11.6459)
				(arc
					(start 237.326678 -11.64463)
					(mid 237.219406 -11.652971)
					(end 237.120176 -11.611356)
				)
				(xy 237.11662 -11.611356)
			)
		)
	)
	(zone
		(layer "In7.Cu")
		(hatch none 0.5)
		(connect_pads
			(clearance 0)
		)
		(min_thickness 0.25)
		(keepout
			(tracks not_allowed)
			(vias allowed)
			(pads allowed)
			(copperpour not_allowed)
			(footprints allowed)
		)
		(placement
			(enabled no)
			(sheetname "")
		)
		(fill
			(thermal_gap 0.5)
			(thermal_bridge_width 0.5)
			(island_removal_mode 0)
		)
		(polygon
			(pts
				(arc
					(start 285.436564 -250.551188)
					(mid 284.885384 -251.102368)
					(end 285.436564 -251.653548)
				)
				(xy 285.920688 -251.653548)
				(arc
					(start 285.920688 -251.229368)
					(mid 285.905809 -251.193447)
					(end 285.869888 -251.178568)
				)
				(arc
					(start 285.822898 -251.178568)
					(mid 285.042787 -251.102368)
					(end 285.822898 -251.026168)
				)
				(xy 285.901384 -251.026168)
				(arc
					(start 285.904432 -251.029216)
					(mid 286.013509 -251.085747)
					(end 286.07004 -251.194824)
				)
				(xy 286.073088 -251.197872) (xy 286.073088 -251.653548) (xy 286.200088 -251.653548) (xy 286.200088 -251.197872)
				(arc
					(start 286.203136 -251.194824)
					(mid 286.259667 -251.085747)
					(end 286.368744 -251.029216)
				)
				(xy 286.371792 -251.026168)
				(arc
					(start 286.450278 -251.026168)
					(mid 287.230389 -251.102368)
					(end 286.450278 -251.178568)
				)
				(arc
					(start 286.403288 -251.178568)
					(mid 286.367367 -251.193447)
					(end 286.352488 -251.229368)
				)
				(xy 286.352488 -251.653548)
				(arc
					(start 286.836612 -251.653548)
					(mid 287.387792 -251.102368)
					(end 286.836612 -250.551188)
				)
				(xy 285.436818 -250.551188)
			)
		)
	)
	(zone
		(layer "In7.Cu")
		(hatch none 0.5)
		(connect_pads
			(clearance 0)
		)
		(min_thickness 0.25)
		(keepout
			(tracks not_allowed)
			(vias allowed)
			(pads allowed)
			(copperpour not_allowed)
			(footprints allowed)
		)
		(placement
			(enabled no)
			(sheetname "")
		)
		(fill
			(thermal_gap 0.5)
			(thermal_bridge_width 0.5)
			(island_removal_mode 0)
		)
		(polygon
			(pts
				(arc
					(start 356.675182 -47.178722)
					(mid 356.289229 -46.792388)
					(end 355.903022 -47.178468)
				)
				(xy 355.903022 -47.521368)
				(arc
					(start 356.187502 -47.521368)
					(mid 356.214443 -47.510209)
					(end 356.225602 -47.483268)
				)
				(arc
					(start 356.225602 -47.437548)
					(mid 356.289102 -46.91172)
					(end 356.352602 -47.437548)
				)
				(xy 356.352602 -47.509684)
				(arc
					(start 356.350062 -47.512224)
					(mid 356.304259 -47.600025)
					(end 356.216458 -47.645828)
				)
				(xy 356.213918 -47.648368) (xy 355.903022 -47.648368) (xy 355.903022 -47.851568) (xy 356.213918 -47.851568)
				(arc
					(start 356.216458 -47.854108)
					(mid 356.304259 -47.899911)
					(end 356.350062 -47.987712)
				)
				(xy 356.352602 -47.990252)
				(arc
					(start 356.352602 -48.062388)
					(mid 356.289102 -48.588216)
					(end 356.225602 -48.062388)
				)
				(arc
					(start 356.225602 -48.016668)
					(mid 356.214443 -47.989727)
					(end 356.187502 -47.978568)
				)
				(xy 355.903022 -47.978568)
				(arc
					(start 355.903022 -48.321468)
					(mid 356.289102 -48.707548)
					(end 356.675182 -48.321468)
				)
			)
		)
	)
	(zone
		(layer "In7.Cu")
		(hatch none 0.5)
		(connect_pads
			(clearance 0)
		)
		(min_thickness 0.25)
		(keepout
			(tracks not_allowed)
			(vias allowed)
			(pads allowed)
			(copperpour not_allowed)
			(footprints allowed)
		)
		(placement
			(enabled no)
			(sheetname "")
		)
		(fill
			(thermal_gap 0.5)
			(thermal_bridge_width 0.5)
			(island_removal_mode 0)
		)
		(polygon
			(pts
				(arc
					(start 285.436564 -304.953924)
					(mid 284.885384 -305.505104)
					(end 285.436564 -306.056284)
				)
				(arc
					(start 286.836612 -306.056284)
					(mid 287.387792 -305.505104)
					(end 286.836612 -304.953924)
				)
				(xy 286.367474 -304.953924)
				(arc
					(start 286.367474 -305.378104)
					(mid 286.386073 -305.423005)
					(end 286.430974 -305.441604)
				)
				(arc
					(start 286.447992 -305.441604)
					(mid 287.230386 -305.505104)
					(end 286.447992 -305.568604)
				)
				(xy 286.404558 -305.568604)
				(arc
					(start 286.402526 -305.566572)
					(mid 286.296197 -305.512881)
					(end 286.242506 -305.406552)
				)
				(xy 286.240474 -305.40452) (xy 286.240474 -304.953924) (xy 286.037274 -304.953924) (xy 286.037274 -305.40452)
				(arc
					(start 286.035242 -305.406552)
					(mid 285.981551 -305.512881)
					(end 285.875222 -305.566572)
				)
				(xy 285.87319 -305.568604)
				(arc
					(start 285.825184 -305.568604)
					(mid 285.04279 -305.505104)
					(end 285.825184 -305.441604)
				)
				(arc
					(start 285.846774 -305.441604)
					(mid 285.891675 -305.423005)
					(end 285.910274 -305.378104)
				)
				(xy 285.910274 -304.953924) (xy 285.436818 -304.953924)
			)
		)
	)
	(zone
		(net "AGND_P5V_D")
		(layer "In7.Cu")
		(hatch none 0.5)
		(connect_pads
			(clearance 0.5)
		)
		(min_thickness 0.25)
		(fill yes
			(thermal_gap 0.5)
			(thermal_bridge_width 0.5)
			(island_removal_mode 0)
		)
		(polygon
			(pts
				(xy 479.149664 -237.444788) (xy 484.800656 -237.444788) (xy 485.483154 -236.76229) (xy 485.483154 -226.219512)
				(xy 485.027986 -225.764344) (xy 478.808288 -225.764344) (xy 478.39122 -226.181412) (xy 478.39122 -236.686344)
			)
		)
	)
	(zone
		(layer "In7.Cu")
		(hatch none 0.5)
		(connect_pads
			(clearance 0)
		)
		(min_thickness 0.25)
		(keepout
			(tracks not_allowed)
			(vias allowed)
			(pads allowed)
			(copperpour not_allowed)
			(footprints allowed)
		)
		(placement
			(enabled no)
			(sheetname "")
		)
		(fill
			(thermal_gap 0.5)
			(thermal_bridge_width 0.5)
			(island_removal_mode 0)
		)
		(polygon
			(pts
				(arc
					(start 279.236678 -295.956482)
					(mid 278.688038 -296.505122)
					(end 279.236678 -297.053762)
				)
				(arc
					(start 280.636726 -297.053762)
					(mid 281.185366 -296.505122)
					(end 280.636726 -295.956482)
				)
				(xy 280.167588 -295.956482)
				(arc
					(start 280.167588 -296.378122)
					(mid 280.186187 -296.423023)
					(end 280.231088 -296.441622)
				)
				(arc
					(start 280.248106 -296.441622)
					(mid 281.0305 -296.505122)
					(end 280.248106 -296.568622)
				)
				(xy 280.204672 -296.568622)
				(arc
					(start 280.20264 -296.56659)
					(mid 280.096311 -296.512899)
					(end 280.04262 -296.40657)
				)
				(xy 280.040588 -296.404538) (xy 280.040588 -295.956482) (xy 279.837388 -295.956482) (xy 279.837388 -296.404538)
				(arc
					(start 279.835356 -296.40657)
					(mid 279.781665 -296.512899)
					(end 279.675336 -296.56659)
				)
				(xy 279.673304 -296.568622)
				(arc
					(start 279.625298 -296.568622)
					(mid 278.842904 -296.505122)
					(end 279.625298 -296.441622)
				)
				(arc
					(start 279.646888 -296.441622)
					(mid 279.691789 -296.423023)
					(end 279.710388 -296.378122)
				)
				(xy 279.710388 -295.956482) (xy 279.236932 -295.956482)
			)
		)
	)
	(zone
		(layer "In7.Cu")
		(hatch none 0.5)
		(connect_pads
			(clearance 0)
		)
		(min_thickness 0.25)
		(keepout
			(tracks not_allowed)
			(vias allowed)
			(pads allowed)
			(copperpour not_allowed)
			(footprints allowed)
		)
		(placement
			(enabled no)
			(sheetname "")
		)
		(fill
			(thermal_gap 0.5)
			(thermal_bridge_width 0.5)
			(island_removal_mode 0)
		)
		(polygon
			(pts
				(arc
					(start 95.989902 -162.178746)
					(mid 95.609029 -161.797492)
					(end 95.227902 -162.178492)
				)
				(arc
					(start 95.227902 -163.321492)
					(mid 95.608902 -163.702492)
					(end 95.989902 -163.321492)
				)
				(xy 95.989902 -162.978592)
				(arc
					(start 95.710502 -162.978592)
					(mid 95.683561 -162.989751)
					(end 95.672402 -163.016692)
				)
				(arc
					(start 95.672402 -163.062412)
					(mid 95.608902 -163.58824)
					(end 95.545402 -163.062412)
				)
				(xy 95.545402 -162.990276)
				(arc
					(start 95.547942 -162.987736)
					(mid 95.593745 -162.899935)
					(end 95.681546 -162.854132)
				)
				(xy 95.684086 -162.851592) (xy 95.989902 -162.851592) (xy 95.989902 -162.648392) (xy 95.684086 -162.648392)
				(arc
					(start 95.681546 -162.645852)
					(mid 95.593745 -162.600049)
					(end 95.547942 -162.512248)
				)
				(xy 95.545402 -162.509708)
				(arc
					(start 95.545402 -162.437572)
					(mid 95.608902 -161.911744)
					(end 95.672402 -162.437572)
				)
				(arc
					(start 95.672402 -162.483292)
					(mid 95.683561 -162.510233)
					(end 95.710502 -162.521392)
				)
				(xy 95.989902 -162.521392)
			)
		)
	)
	(zone
		(layer "In7.Cu")
		(hatch none 0.5)
		(connect_pads
			(clearance 0)
		)
		(min_thickness 0.25)
		(keepout
			(tracks not_allowed)
			(vias allowed)
			(pads allowed)
			(copperpour not_allowed)
			(footprints allowed)
		)
		(placement
			(enabled no)
			(sheetname "")
		)
		(fill
			(thermal_gap 0.5)
			(thermal_bridge_width 0.5)
			(island_removal_mode 0)
		)
		(polygon
			(pts
				(arc
					(start 285.436564 -308.553866)
					(mid 284.885384 -309.105046)
					(end 285.436564 -309.656226)
				)
				(arc
					(start 286.836612 -309.656226)
					(mid 287.387792 -309.105046)
					(end 286.836612 -308.553866)
				)
				(xy 286.367474 -308.553866)
				(arc
					(start 286.367474 -308.978046)
					(mid 286.386073 -309.022947)
					(end 286.430974 -309.041546)
				)
				(arc
					(start 286.447992 -309.041546)
					(mid 287.230386 -309.105046)
					(end 286.447992 -309.168546)
				)
				(xy 286.404558 -309.168546)
				(arc
					(start 286.402526 -309.166514)
					(mid 286.296197 -309.112823)
					(end 286.242506 -309.006494)
				)
				(xy 286.240474 -309.004462) (xy 286.240474 -308.553866) (xy 286.037274 -308.553866) (xy 286.037274 -309.004462)
				(arc
					(start 286.035242 -309.006494)
					(mid 285.981551 -309.112823)
					(end 285.875222 -309.166514)
				)
				(xy 285.87319 -309.168546)
				(arc
					(start 285.825184 -309.168546)
					(mid 285.04279 -309.105046)
					(end 285.825184 -309.041546)
				)
				(arc
					(start 285.846774 -309.041546)
					(mid 285.891675 -309.022947)
					(end 285.910274 -308.978046)
				)
				(xy 285.910274 -308.553866) (xy 285.436818 -308.553866)
			)
		)
	)
	(zone
		(layer "In7.Cu")
		(hatch none 0.5)
		(connect_pads
			(clearance 0)
		)
		(min_thickness 0.25)
		(keepout
			(tracks not_allowed)
			(vias allowed)
			(pads allowed)
			(copperpour not_allowed)
			(footprints allowed)
		)
		(placement
			(enabled no)
			(sheetname "")
		)
		(fill
			(thermal_gap 0.5)
			(thermal_bridge_width 0.5)
			(island_removal_mode 0)
		)
		(polygon
			(pts
				(arc
					(start 95.989902 -277.17877)
					(mid 95.609029 -276.797516)
					(end 95.227902 -277.178516)
				)
				(arc
					(start 95.227902 -278.321516)
					(mid 95.608902 -278.702516)
					(end 95.989902 -278.321516)
				)
				(xy 95.989902 -277.978616)
				(arc
					(start 95.710502 -277.978616)
					(mid 95.683561 -277.989775)
					(end 95.672402 -278.016716)
				)
				(arc
					(start 95.672402 -278.062436)
					(mid 95.608902 -278.588264)
					(end 95.545402 -278.062436)
				)
				(xy 95.545402 -277.9903)
				(arc
					(start 95.547942 -277.98776)
					(mid 95.593745 -277.899959)
					(end 95.681546 -277.854156)
				)
				(xy 95.684086 -277.851616) (xy 95.989902 -277.851616) (xy 95.989902 -277.648416) (xy 95.684086 -277.648416)
				(arc
					(start 95.681546 -277.645876)
					(mid 95.593745 -277.600073)
					(end 95.547942 -277.512272)
				)
				(xy 95.545402 -277.509732)
				(arc
					(start 95.545402 -277.437596)
					(mid 95.608902 -276.911768)
					(end 95.672402 -277.437596)
				)
				(arc
					(start 95.672402 -277.483316)
					(mid 95.683561 -277.510257)
					(end 95.710502 -277.521416)
				)
				(xy 95.989902 -277.521416)
			)
		)
	)
	(zone
		(layer "In7.Cu")
		(hatch none 0.5)
		(connect_pads
			(clearance 0)
		)
		(min_thickness 0.25)
		(keepout
			(tracks not_allowed)
			(vias allowed)
			(pads allowed)
			(copperpour not_allowed)
			(footprints allowed)
		)
		(placement
			(enabled no)
			(sheetname "")
		)
		(fill
			(thermal_gap 0.5)
			(thermal_bridge_width 0.5)
			(island_removal_mode 0)
		)
		(polygon
			(pts
				(arc
					(start 286.436562 -259.55117)
					(mid 285.885382 -260.10235)
					(end 286.436562 -260.65353)
				)
				(xy 286.920686 -260.65353)
				(arc
					(start 286.920686 -260.22935)
					(mid 286.905807 -260.193429)
					(end 286.869886 -260.17855)
				)
				(arc
					(start 286.822896 -260.17855)
					(mid 286.042785 -260.10235)
					(end 286.822896 -260.02615)
				)
				(xy 286.901382 -260.02615)
				(arc
					(start 286.90443 -260.029198)
					(mid 287.013507 -260.085729)
					(end 287.070038 -260.194806)
				)
				(xy 287.073086 -260.197854) (xy 287.073086 -260.65353) (xy 287.200086 -260.65353) (xy 287.200086 -260.197854)
				(arc
					(start 287.203134 -260.194806)
					(mid 287.259665 -260.085729)
					(end 287.368742 -260.029198)
				)
				(xy 287.37179 -260.02615)
				(arc
					(start 287.450276 -260.02615)
					(mid 288.230387 -260.10235)
					(end 287.450276 -260.17855)
				)
				(arc
					(start 287.403286 -260.17855)
					(mid 287.367365 -260.193429)
					(end 287.352486 -260.22935)
				)
				(xy 287.352486 -260.65353)
				(arc
					(start 287.83661 -260.65353)
					(mid 288.38779 -260.10235)
					(end 287.83661 -259.55117)
				)
				(xy 286.436816 -259.55117)
			)
		)
	)
	(zone
		(layer "In7.Cu")
		(hatch none 0.5)
		(connect_pads
			(clearance 0)
		)
		(min_thickness 0.25)
		(keepout
			(tracks not_allowed)
			(vias allowed)
			(pads allowed)
			(copperpour not_allowed)
			(footprints allowed)
		)
		(placement
			(enabled no)
			(sheetname "")
		)
		(fill
			(thermal_gap 0.5)
			(thermal_bridge_width 0.5)
			(island_removal_mode 0)
		)
		(polygon
			(pts
				(arc
					(start 286.436562 -255.951228)
					(mid 285.885382 -256.502408)
					(end 286.436562 -257.053588)
				)
				(xy 286.920686 -257.053588)
				(arc
					(start 286.920686 -256.629408)
					(mid 286.905807 -256.593487)
					(end 286.869886 -256.578608)
				)
				(arc
					(start 286.822896 -256.578608)
					(mid 286.042785 -256.502408)
					(end 286.822896 -256.426208)
				)
				(xy 286.901382 -256.426208)
				(arc
					(start 286.90443 -256.429256)
					(mid 287.013507 -256.485787)
					(end 287.070038 -256.594864)
				)
				(xy 287.073086 -256.597912) (xy 287.073086 -257.053588) (xy 287.200086 -257.053588) (xy 287.200086 -256.597912)
				(arc
					(start 287.203134 -256.594864)
					(mid 287.259665 -256.485787)
					(end 287.368742 -256.429256)
				)
				(xy 287.37179 -256.426208)
				(arc
					(start 287.450276 -256.426208)
					(mid 288.230387 -256.502408)
					(end 287.450276 -256.578608)
				)
				(arc
					(start 287.403286 -256.578608)
					(mid 287.367365 -256.593487)
					(end 287.352486 -256.629408)
				)
				(xy 287.352486 -257.053588)
				(arc
					(start 287.83661 -257.053588)
					(mid 288.38779 -256.502408)
					(end 287.83661 -255.951228)
				)
				(xy 286.436816 -255.951228)
			)
		)
	)
	(zone
		(layer "In7.Cu")
		(hatch none 0.5)
		(connect_pads
			(clearance 0)
		)
		(min_thickness 0.25)
		(keepout
			(tracks not_allowed)
			(vias allowed)
			(pads allowed)
			(copperpour not_allowed)
			(footprints allowed)
		)
		(placement
			(enabled no)
			(sheetname "")
		)
		(fill
			(thermal_gap 0.5)
			(thermal_bridge_width 0.5)
			(island_removal_mode 0)
		)
		(polygon
			(pts
				(arc
					(start 286.436562 -357.153972)
					(mid 285.885382 -357.705152)
					(end 286.436562 -358.256332)
				)
				(arc
					(start 287.83661 -358.256332)
					(mid 288.38779 -357.705152)
					(end 287.83661 -357.153972)
				)
				(arc
					(start 287.359344 -357.153972)
					(mid 287.364274 -357.192724)
					(end 287.366964 -357.231696)
				)
				(xy 287.367472 -357.232204)
				(arc
					(start 287.367472 -357.578152)
					(mid 287.386071 -357.623053)
					(end 287.430972 -357.641652)
				)
				(arc
					(start 287.44799 -357.641652)
					(mid 288.230384 -357.705152)
					(end 287.44799 -357.768652)
				)
				(xy 287.404556 -357.768652)
				(arc
					(start 287.402524 -357.76662)
					(mid 287.296195 -357.712929)
					(end 287.242504 -357.6066)
				)
				(xy 287.240472 -357.604568)
				(arc
					(start 287.240472 -357.25862)
					(mid 287.238002 -357.206061)
					(end 287.230566 -357.153972)
				)
				(arc
					(start 287.02127 -357.153972)
					(mid 287.030919 -357.192161)
					(end 287.036256 -357.231188)
				)
				(xy 287.037272 -357.232204) (xy 287.037272 -357.604568)
				(arc
					(start 287.03524 -357.6066)
					(mid 286.981549 -357.712929)
					(end 286.87522 -357.76662)
				)
				(xy 286.873188 -357.768652)
				(arc
					(start 286.825182 -357.768652)
					(mid 286.042788 -357.705152)
					(end 286.825182 -357.641652)
				)
				(arc
					(start 286.846772 -357.641652)
					(mid 286.891673 -357.623053)
					(end 286.910272 -357.578152)
				)
				(arc
					(start 286.910272 -357.25862)
					(mid 286.903712 -357.20471)
					(end 286.884364 -357.153972)
				)
				(xy 286.436816 -357.153972)
			)
		)
	)
	(zone
		(layer "In7.Cu")
		(hatch none 0.5)
		(connect_pads
			(clearance 0)
		)
		(min_thickness 0.25)
		(keepout
			(tracks not_allowed)
			(vias allowed)
			(pads allowed)
			(copperpour not_allowed)
			(footprints allowed)
		)
		(placement
			(enabled no)
			(sheetname "")
		)
		(fill
			(thermal_gap 0.5)
			(thermal_bridge_width 0.5)
			(island_removal_mode 0)
		)
		(polygon
			(pts
				(arc
					(start 122.301254 -29.150056)
					(mid 121.750074 -28.598876)
					(end 121.198894 -29.150056)
				)
				(arc
					(start 121.198894 -30.54985)
					(mid 121.749947 -31.101284)
					(end 122.301254 -30.550104)
				)
				(xy 122.301254 -30.078934) (xy 121.90857 -30.078934) (xy 121.826274 -30.16123)
				(arc
					(start 121.826274 -30.16377)
					(mid 121.750074 -30.943881)
					(end 121.673874 -30.16377)
				)
				(xy 121.673874 -30.098238) (xy 121.845578 -29.926534) (xy 122.301254 -29.926534) (xy 122.301254 -29.799534)
				(xy 121.845832 -29.799534) (xy 121.673874 -29.627576)
				(arc
					(start 121.673874 -29.53639)
					(mid 121.750074 -28.756279)
					(end 121.826274 -29.53639)
				)
				(xy 121.826274 -29.564584) (xy 121.908824 -29.647134) (xy 122.301254 -29.647134)
			)
		)
	)
	(zone
		(layer "In7.Cu")
		(hatch none 0.5)
		(connect_pads
			(clearance 0)
		)
		(min_thickness 0.25)
		(keepout
			(tracks not_allowed)
			(vias allowed)
			(pads allowed)
			(copperpour not_allowed)
			(footprints allowed)
		)
		(placement
			(enabled no)
			(sheetname "")
		)
		(fill
			(thermal_gap 0.5)
			(thermal_bridge_width 0.5)
			(island_removal_mode 0)
		)
		(polygon
			(pts
				(arc
					(start 240.877344 -150.84552)
					(mid 239.895939 -151.17257)
					(end 240.222786 -152.154128)
				)
				(arc
					(start 241.042698 -152.564084)
					(mid 241.073936 -152.454549)
					(end 241.12982 -152.355296)
				)
				(xy 241.249708 -152.11679) (xy 241.249708 -152.103074) (xy 241.263678 -152.089104) (xy 241.27206 -152.07234)
				(arc
					(start 241.299746 -152.017476)
					(mid 241.302594 -151.978631)
					(end 241.27714 -151.94915)
				)
				(arc
					(start 240.999264 -151.810212)
					(mid 240.061663 -151.255238)
					(end 241.06759 -151.673814)
				)
				(xy 241.345212 -151.813006) (xy 241.373406 -151.826976)
				(arc
					(start 241.37493 -151.83104)
					(mid 241.447181 -151.930562)
					(end 241.448844 -152.053544)
				)
				(xy 241.450114 -152.057354) (xy 241.402362 -152.152604) (xy 241.402362 -152.166066) (xy 241.388646 -152.179782)
				(xy 241.38001 -152.197054) (xy 241.248692 -152.457912)
				(arc
					(start 241.242596 -152.459944)
					(mid 241.203252 -152.544793)
					(end 241.189002 -152.637236)
				)
				(arc
					(start 241.326416 -152.70607)
					(mid 241.320164 -152.600595)
					(end 241.367056 -152.505918)
				)
				(xy 241.50701 -152.227788) (xy 241.506756 -152.22728) (xy 241.52098 -152.19934) (xy 241.534696 -152.171654)
				(xy 241.535204 -152.1714) (xy 241.544348 -152.153366) (xy 241.545872 -152.150572) (xy 241.558826 -152.124918)
				(arc
					(start 241.562128 -152.123902)
					(mid 241.66951 -152.044728)
					(end 241.80292 -152.043638)
				)
				(xy 241.806476 -152.042368)
				(arc
					(start 242.100608 -152.189688)
					(mid 243.037692 -152.745297)
					(end 242.032282 -152.325832)
				)
				(arc
					(start 241.766598 -152.192736)
					(mid 241.71832 -152.189003)
					(end 241.681254 -152.220168)
				)
				(xy 241.658394 -152.265634) (xy 241.658394 -152.265888) (xy 241.64417 -152.293828) (xy 241.630454 -152.321768)
				(xy 241.6302 -152.322022) (xy 241.48415 -152.612344)
				(arc
					(start 241.475514 -152.615138)
					(mid 241.469014 -152.648713)
					(end 241.48415 -152.6794)
				)
				(xy 241.695224 -152.89022)
				(arc
					(start 242.222782 -153.154126)
					(mid 243.204238 -152.826974)
					(end 242.877086 -151.845518)
				)
			)
		)
	)
	(zone
		(layer "In7.Cu")
		(hatch none 0.5)
		(connect_pads
			(clearance 0)
		)
		(min_thickness 0.25)
		(keepout
			(tracks not_allowed)
			(vias allowed)
			(pads allowed)
			(copperpour not_allowed)
			(footprints allowed)
		)
		(placement
			(enabled no)
			(sheetname "")
		)
		(fill
			(thermal_gap 0.5)
			(thermal_bridge_width 0.5)
			(island_removal_mode 0)
		)
		(polygon
			(pts
				(arc
					(start 236.775498 -153.569924)
					(mid 236.661965 -153.487074)
					(end 236.52861 -153.44267)
				)
				(xy 236.287564 -153.56332) (xy 236.48416 -153.56332)
				(arc
					(start 236.485938 -153.565098)
					(mid 236.578763 -153.588432)
					(end 236.660944 -153.637488)
				)
				(xy 236.66323 -153.637488)
				(arc
					(start 236.685582 -153.65984)
					(mid 236.694332 -153.670321)
					(end 236.701076 -153.682192)
				)
				(xy 236.707934 -153.682192) (xy 236.913166 -153.887424)
				(arc
					(start 236.913166 -153.891488)
					(mid 236.947699 -154.040916)
					(end 236.867954 -154.171904)
				)
				(xy 236.866684 -154.17546) (xy 236.856524 -154.180794) (xy 236.85627 -154.181302) (xy 236.828584 -154.195272)
				(xy 236.800644 -154.209496) (xy 236.80039 -154.209242)
				(arc
					(start 236.567726 -154.325828)
					(mid 235.561798 -154.744405)
					(end 236.4994 -154.18943)
				)
				(xy 236.759496 -154.059128) (xy 236.769148 -154.054302)
				(arc
					(start 236.770926 -154.053286)
					(mid 236.797167 -154.016115)
					(end 236.783118 -153.972768)
				)
				(arc
					(start 236.577886 -153.767536)
					(mid 236.520434 -153.729148)
					(end 236.452664 -153.71572)
				)
				(xy 235.982764 -153.71572)
				(arc
					(start 235.733844 -153.84018)
					(mid 235.393447 -154.82121)
					(end 236.377226 -155.154122)
				)
				(arc
					(start 238.377222 -154.154124)
					(mid 238.704374 -153.172668)
					(end 237.722918 -152.845516)
				)
				(arc
					(start 236.721396 -153.346404)
					(mid 236.793712 -153.388371)
					(end 236.859572 -153.439876)
				)
				(xy 236.860842 -153.439876)
				(arc
					(start 237.201964 -153.780998)
					(mid 237.243617 -153.802248)
					(end 237.289848 -153.795222)
				)
				(arc
					(start 237.532418 -153.67381)
					(mid 238.537816 -153.254351)
					(end 237.600744 -153.809954)
				)
				(xy 237.358174 -153.931366) (xy 237.32998 -153.94559)
				(arc
					(start 237.326678 -153.94432)
					(mid 237.219406 -153.952661)
					(end 237.120176 -153.911046)
				)
				(xy 237.11662 -153.911046)
			)
		)
	)
	(zone
		(layer "In7.Cu")
		(hatch none 0.5)
		(connect_pads
			(clearance 0)
		)
		(min_thickness 0.25)
		(keepout
			(tracks not_allowed)
			(vias allowed)
			(pads allowed)
			(copperpour not_allowed)
			(footprints allowed)
		)
		(placement
			(enabled no)
			(sheetname "")
		)
		(fill
			(thermal_gap 0.5)
			(thermal_bridge_width 0.5)
			(island_removal_mode 0)
		)
		(polygon
			(pts
				(arc
					(start 307.708046 -243.200428)
					(mid 300.20006 -235.692442)
					(end 292.692074 -243.200428)
				)
				(arc
					(start 292.692074 -249.200416)
					(mid 292.692791 -249.30139)
					(end 292.694868 -249.402346)
				)
				(arc
					(start 293.557198 -252.696472)
					(mid 302.000811 -256.48644)
					(end 307.708046 -249.200416)
				)
			)
		)
	)
	(zone
		(layer "In7.Cu")
		(hatch none 0.5)
		(connect_pads
			(clearance 0)
		)
		(min_thickness 0.25)
		(keepout
			(tracks not_allowed)
			(vias allowed)
			(pads allowed)
			(copperpour not_allowed)
			(footprints allowed)
		)
		(placement
			(enabled no)
			(sheetname "")
		)
		(fill
			(thermal_gap 0.5)
			(thermal_bridge_width 0.5)
			(island_removal_mode 0)
		)
		(polygon
			(pts
				(arc
					(start 32.889952 -277.17877)
					(mid 32.509079 -276.797516)
					(end 32.127952 -277.178516)
				)
				(arc
					(start 32.127952 -278.321516)
					(mid 32.508952 -278.702516)
					(end 32.889952 -278.321516)
				)
				(xy 32.889952 -277.978616)
				(arc
					(start 32.610552 -277.978616)
					(mid 32.583611 -277.989775)
					(end 32.572452 -278.016716)
				)
				(arc
					(start 32.572452 -278.062436)
					(mid 32.508952 -278.588264)
					(end 32.445452 -278.062436)
				)
				(xy 32.445452 -277.9903)
				(arc
					(start 32.447992 -277.98776)
					(mid 32.493795 -277.899959)
					(end 32.581596 -277.854156)
				)
				(xy 32.584136 -277.851616) (xy 32.889952 -277.851616) (xy 32.889952 -277.648416) (xy 32.584136 -277.648416)
				(arc
					(start 32.581596 -277.645876)
					(mid 32.493795 -277.600073)
					(end 32.447992 -277.512272)
				)
				(xy 32.445452 -277.509732)
				(arc
					(start 32.445452 -277.437596)
					(mid 32.508952 -276.911768)
					(end 32.572452 -277.437596)
				)
				(arc
					(start 32.572452 -277.483316)
					(mid 32.583611 -277.510257)
					(end 32.610552 -277.521416)
				)
				(xy 32.889952 -277.521416)
			)
		)
	)
	(zone
		(layer "In7.Cu")
		(hatch none 0.5)
		(connect_pads
			(clearance 0)
		)
		(min_thickness 0.25)
		(keepout
			(tracks not_allowed)
			(vias allowed)
			(pads allowed)
			(copperpour not_allowed)
			(footprints allowed)
		)
		(placement
			(enabled no)
			(sheetname "")
		)
		(fill
			(thermal_gap 0.5)
			(thermal_bridge_width 0.5)
			(island_removal_mode 0)
		)
		(polygon
			(pts
				(arc
					(start 236.718856 -157.347666)
					(mid 236.797101 -157.392658)
					(end 236.868208 -157.44825)
				)
				(xy 236.869224 -157.44825)
				(arc
					(start 237.201964 -157.78099)
					(mid 237.243617 -157.80224)
					(end 237.289848 -157.795214)
				)
				(arc
					(start 237.532418 -157.673802)
					(mid 238.537816 -157.254343)
					(end 237.600744 -157.809946)
				)
				(xy 237.358174 -157.931358) (xy 237.32998 -157.945582)
				(arc
					(start 237.326678 -157.944312)
					(mid 237.219406 -157.952653)
					(end 237.120176 -157.911038)
				)
				(xy 237.11662 -157.911038)
				(arc
					(start 236.78388 -157.578298)
					(mid 236.665401 -157.49137)
					(end 236.526324 -157.443932)
				)
				(xy 236.287564 -157.563312) (xy 236.472222 -157.563312)
				(arc
					(start 236.473746 -157.564836)
					(mid 236.57781 -157.590504)
					(end 236.66958 -157.645862)
				)
				(xy 236.671612 -157.645862) (xy 236.913166 -157.887416)
				(arc
					(start 236.913166 -157.89148)
					(mid 236.947699 -158.040908)
					(end 236.867954 -158.171896)
				)
				(xy 236.866684 -158.175452) (xy 236.856524 -158.180786) (xy 236.85627 -158.181294) (xy 236.828584 -158.195264)
				(xy 236.800644 -158.209488) (xy 236.80039 -158.209234)
				(arc
					(start 236.567726 -158.32582)
					(mid 235.561798 -158.744397)
					(end 236.4994 -158.189422)
				)
				(xy 236.759496 -158.05912) (xy 236.769148 -158.054294)
				(arc
					(start 236.770926 -158.053278)
					(mid 236.797167 -158.016107)
					(end 236.783118 -157.97276)
				)
				(arc
					(start 236.586268 -157.77591)
					(mid 236.519493 -157.731292)
					(end 236.440726 -157.715712)
				)
				(xy 235.982764 -157.715712)
				(arc
					(start 235.733844 -157.840172)
					(mid 235.393447 -158.821202)
					(end 236.377226 -159.154114)
				)
				(arc
					(start 238.377222 -158.154116)
					(mid 238.704374 -157.17266)
					(end 237.722918 -156.845508)
				)
			)
		)
	)
	(zone
		(layer "In7.Cu")
		(hatch none 0.5)
		(connect_pads
			(clearance 0)
		)
		(min_thickness 0.25)
		(keepout
			(tracks not_allowed)
			(vias allowed)
			(pads allowed)
			(copperpour not_allowed)
			(footprints allowed)
		)
		(placement
			(enabled no)
			(sheetname "")
		)
		(fill
			(thermal_gap 0.5)
			(thermal_bridge_width 0.5)
			(island_removal_mode 0)
		)
		(polygon
			(pts
				(arc
					(start 286.436562 -295.953942)
					(mid 285.885382 -296.505122)
					(end 286.436562 -297.056302)
				)
				(xy 286.9057 -297.056302)
				(arc
					(start 286.9057 -296.632122)
					(mid 286.887101 -296.587221)
					(end 286.8422 -296.568622)
				)
				(arc
					(start 286.825182 -296.568622)
					(mid 286.042788 -296.505122)
					(end 286.825182 -296.441622)
				)
				(xy 286.868616 -296.441622)
				(arc
					(start 286.870648 -296.443654)
					(mid 286.976977 -296.497345)
					(end 287.030668 -296.603674)
				)
				(xy 287.0327 -296.605706) (xy 287.0327 -297.056302) (xy 287.2359 -297.056302) (xy 287.2359 -296.605706)
				(arc
					(start 287.237932 -296.603674)
					(mid 287.291623 -296.497345)
					(end 287.397952 -296.443654)
				)
				(xy 287.399984 -296.441622)
				(arc
					(start 287.44799 -296.441622)
					(mid 288.230384 -296.505122)
					(end 287.44799 -296.568622)
				)
				(arc
					(start 287.4264 -296.568622)
					(mid 287.381499 -296.587221)
					(end 287.3629 -296.632122)
				)
				(xy 287.3629 -297.056302)
				(arc
					(start 287.83661 -297.056302)
					(mid 288.38779 -296.505122)
					(end 287.83661 -295.953942)
				)
				(xy 286.436816 -295.953942)
			)
		)
	)
	(zone
		(layer "In7.Cu")
		(hatch none 0.5)
		(connect_pads
			(clearance 0)
		)
		(min_thickness 0.25)
		(keepout
			(tracks not_allowed)
			(vias allowed)
			(pads allowed)
			(copperpour not_allowed)
			(footprints allowed)
		)
		(placement
			(enabled no)
			(sheetname "")
		)
		(fill
			(thermal_gap 0.5)
			(thermal_bridge_width 0.5)
			(island_removal_mode 0)
		)
		(polygon
			(pts
				(xy 204.387196 -420.437056) (xy 204.387196 -419.514274) (xy 227.460302 -419.514274) (xy 227.96246 -420.016432)
				(xy 232.02392 -420.016432) (xy 232.526078 -419.514274) (xy 272.003266 -419.514274) (xy 272.003266 -420.437056)
			)
		)
	)
	(zone
		(layer "In7.Cu")
		(hatch none 0.5)
		(connect_pads
			(clearance 0)
		)
		(min_thickness 0.25)
		(keepout
			(tracks not_allowed)
			(vias allowed)
			(pads allowed)
			(copperpour not_allowed)
			(footprints allowed)
		)
		(placement
			(enabled no)
			(sheetname "")
		)
		(fill
			(thermal_gap 0.5)
			(thermal_bridge_width 0.5)
			(island_removal_mode 0)
		)
		(polygon
			(pts
				(arc
					(start 285.436564 -254.15113)
					(mid 284.885384 -254.70231)
					(end 285.436564 -255.25349)
				)
				(xy 285.920688 -255.25349)
				(arc
					(start 285.920688 -254.82931)
					(mid 285.905809 -254.793389)
					(end 285.869888 -254.77851)
				)
				(arc
					(start 285.822898 -254.77851)
					(mid 285.042787 -254.70231)
					(end 285.822898 -254.62611)
				)
				(xy 285.901384 -254.62611)
				(arc
					(start 285.904432 -254.629158)
					(mid 286.013509 -254.685689)
					(end 286.07004 -254.794766)
				)
				(xy 286.073088 -254.797814) (xy 286.073088 -255.25349) (xy 286.200088 -255.25349) (xy 286.200088 -254.797814)
				(arc
					(start 286.203136 -254.794766)
					(mid 286.259667 -254.685689)
					(end 286.368744 -254.629158)
				)
				(xy 286.371792 -254.62611)
				(arc
					(start 286.450278 -254.62611)
					(mid 287.230389 -254.70231)
					(end 286.450278 -254.77851)
				)
				(arc
					(start 286.403288 -254.77851)
					(mid 286.367367 -254.793389)
					(end 286.352488 -254.82931)
				)
				(xy 286.352488 -255.25349)
				(arc
					(start 286.836612 -255.25349)
					(mid 287.387792 -254.70231)
					(end 286.836612 -254.15113)
				)
				(xy 285.436818 -254.15113)
			)
		)
	)
	(zone
		(layer "In7.Cu")
		(hatch none 0.5)
		(connect_pads
			(clearance 0)
		)
		(min_thickness 0.25)
		(keepout
			(tracks not_allowed)
			(vias allowed)
			(pads allowed)
			(copperpour not_allowed)
			(footprints allowed)
		)
		(placement
			(enabled no)
			(sheetname "")
		)
		(fill
			(thermal_gap 0.5)
			(thermal_bridge_width 0.5)
			(island_removal_mode 0)
		)
		(polygon
			(pts
				(arc
					(start 240.87709 -154.845512)
					(mid 239.895634 -155.172664)
					(end 240.222786 -156.15412)
				)
				(arc
					(start 241.042698 -156.564076)
					(mid 241.073936 -156.454541)
					(end 241.12982 -156.355288)
				)
				(xy 241.249708 -156.116782) (xy 241.249708 -156.103066) (xy 241.263678 -156.089096) (xy 241.27206 -156.072332)
				(arc
					(start 241.299746 -156.017468)
					(mid 241.302594 -155.978623)
					(end 241.27714 -155.949142)
				)
				(arc
					(start 240.999264 -155.810204)
					(mid 240.061663 -155.25523)
					(end 241.06759 -155.673806)
				)
				(xy 241.345212 -155.812998) (xy 241.373406 -155.826968)
				(arc
					(start 241.37493 -155.831032)
					(mid 241.447181 -155.930554)
					(end 241.448844 -156.053536)
				)
				(xy 241.450114 -156.057346) (xy 241.402362 -156.152596) (xy 241.402362 -156.166058) (xy 241.388646 -156.179774)
				(xy 241.38001 -156.197046) (xy 241.248692 -156.457904)
				(arc
					(start 241.242596 -156.459936)
					(mid 241.203252 -156.544785)
					(end 241.189002 -156.637228)
				)
				(arc
					(start 241.326416 -156.706062)
					(mid 241.320164 -156.600587)
					(end 241.367056 -156.50591)
				)
				(xy 241.50701 -156.22778) (xy 241.506756 -156.227272) (xy 241.52098 -156.199332) (xy 241.534696 -156.171646)
				(xy 241.535204 -156.171392) (xy 241.544348 -156.153358) (xy 241.545872 -156.150564) (xy 241.558826 -156.12491)
				(arc
					(start 241.562128 -156.123894)
					(mid 241.66951 -156.04472)
					(end 241.80292 -156.04363)
				)
				(xy 241.806476 -156.04236)
				(arc
					(start 242.100608 -156.18968)
					(mid 243.037692 -156.745289)
					(end 242.032282 -156.325824)
				)
				(arc
					(start 241.766598 -156.192728)
					(mid 241.71832 -156.188995)
					(end 241.681254 -156.22016)
				)
				(xy 241.658394 -156.265626) (xy 241.658394 -156.26588) (xy 241.64417 -156.29382) (xy 241.630454 -156.32176)
				(xy 241.6302 -156.322014) (xy 241.48415 -156.612336)
				(arc
					(start 241.475514 -156.61513)
					(mid 241.469014 -156.648705)
					(end 241.48415 -156.679392)
				)
				(xy 241.695224 -156.890466)
				(arc
					(start 242.222528 -157.154118)
					(mid 243.204289 -156.827118)
					(end 242.877086 -155.84551)
				)
			)
		)
	)
	(zone
		(layer "In7.Cu")
		(hatch none 0.5)
		(connect_pads
			(clearance 0)
		)
		(min_thickness 0.25)
		(keepout
			(tracks not_allowed)
			(vias allowed)
			(pads allowed)
			(copperpour not_allowed)
			(footprints allowed)
		)
		(placement
			(enabled no)
			(sheetname "")
		)
		(fill
			(thermal_gap 0.5)
			(thermal_bridge_width 0.5)
			(island_removal_mode 0)
		)
		(polygon
			(pts
				(arc
					(start 240.877344 -114.845592)
					(mid 239.895939 -115.172642)
					(end 240.222786 -116.1542)
				)
				(arc
					(start 241.042698 -116.564156)
					(mid 241.073936 -116.454621)
					(end 241.12982 -116.355368)
				)
				(xy 241.249708 -116.116862) (xy 241.249708 -116.103146) (xy 241.263678 -116.089176) (xy 241.27206 -116.072412)
				(arc
					(start 241.299746 -116.017548)
					(mid 241.302594 -115.978703)
					(end 241.27714 -115.949222)
				)
				(arc
					(start 240.999264 -115.810284)
					(mid 240.061663 -115.25531)
					(end 241.06759 -115.673886)
				)
				(xy 241.345212 -115.813078) (xy 241.373406 -115.827048)
				(arc
					(start 241.37493 -115.831112)
					(mid 241.447181 -115.930634)
					(end 241.448844 -116.053616)
				)
				(xy 241.450114 -116.057426) (xy 241.402362 -116.152676) (xy 241.402362 -116.166138) (xy 241.388646 -116.179854)
				(xy 241.38001 -116.197126) (xy 241.248692 -116.457984)
				(arc
					(start 241.242596 -116.460016)
					(mid 241.203252 -116.544865)
					(end 241.189002 -116.637308)
				)
				(arc
					(start 241.326416 -116.706142)
					(mid 241.320164 -116.600667)
					(end 241.367056 -116.50599)
				)
				(xy 241.50701 -116.22786) (xy 241.506756 -116.227352) (xy 241.52098 -116.199412) (xy 241.534696 -116.171726)
				(xy 241.535204 -116.171472) (xy 241.544348 -116.153438) (xy 241.545872 -116.150644) (xy 241.558826 -116.12499)
				(arc
					(start 241.562128 -116.123974)
					(mid 241.66951 -116.0448)
					(end 241.80292 -116.04371)
				)
				(xy 241.806476 -116.04244)
				(arc
					(start 242.100608 -116.18976)
					(mid 243.037692 -116.745369)
					(end 242.032282 -116.325904)
				)
				(arc
					(start 241.766598 -116.192808)
					(mid 241.71832 -116.189075)
					(end 241.681254 -116.22024)
				)
				(xy 241.658394 -116.265706) (xy 241.658394 -116.26596) (xy 241.64417 -116.2939) (xy 241.630454 -116.32184)
				(xy 241.6302 -116.322094) (xy 241.48415 -116.612416)
				(arc
					(start 241.475514 -116.61521)
					(mid 241.469014 -116.648785)
					(end 241.48415 -116.679472)
				)
				(xy 241.695224 -116.890292)
				(arc
					(start 242.222782 -117.154198)
					(mid 243.204238 -116.827046)
					(end 242.877086 -115.84559)
				)
			)
		)
	)
	(zone
		(layer "In7.Cu")
		(hatch none 0.5)
		(connect_pads
			(clearance 0)
		)
		(min_thickness 0.25)
		(keepout
			(tracks not_allowed)
			(vias allowed)
			(pads allowed)
			(copperpour not_allowed)
			(footprints allowed)
		)
		(placement
			(enabled no)
			(sheetname "")
		)
		(fill
			(thermal_gap 0.5)
			(thermal_bridge_width 0.5)
			(island_removal_mode 0)
		)
		(polygon
			(pts
				(arc
					(start 285.436564 -330.154026)
					(mid 284.885384 -330.705206)
					(end 285.436564 -331.256386)
				)
				(arc
					(start 286.836612 -331.256386)
					(mid 287.387792 -330.705206)
					(end 286.836612 -330.154026)
				)
				(xy 286.367474 -330.154026)
				(arc
					(start 286.367474 -330.578206)
					(mid 286.386073 -330.623107)
					(end 286.430974 -330.641706)
				)
				(arc
					(start 286.447992 -330.641706)
					(mid 287.230386 -330.705206)
					(end 286.447992 -330.768706)
				)
				(xy 286.404558 -330.768706)
				(arc
					(start 286.402526 -330.766674)
					(mid 286.296197 -330.712983)
					(end 286.242506 -330.606654)
				)
				(xy 286.240474 -330.604622) (xy 286.240474 -330.154026) (xy 286.037274 -330.154026) (xy 286.037274 -330.604622)
				(arc
					(start 286.035242 -330.606654)
					(mid 285.981551 -330.712983)
					(end 285.875222 -330.766674)
				)
				(xy 285.87319 -330.768706)
				(arc
					(start 285.825184 -330.768706)
					(mid 285.04279 -330.705206)
					(end 285.825184 -330.641706)
				)
				(arc
					(start 285.846774 -330.641706)
					(mid 285.891675 -330.623107)
					(end 285.910274 -330.578206)
				)
				(xy 285.910274 -330.154026) (xy 285.436818 -330.154026)
			)
		)
	)
	(zone
		(layer "In7.Cu")
		(hatch none 0.5)
		(connect_pads
			(clearance 0)
		)
		(min_thickness 0.25)
		(keepout
			(tracks not_allowed)
			(vias allowed)
			(pads allowed)
			(copperpour not_allowed)
			(footprints allowed)
		)
		(placement
			(enabled no)
			(sheetname "")
		)
		(fill
			(thermal_gap 0.5)
			(thermal_bridge_width 0.5)
			(island_removal_mode 0)
		)
		(polygon
			(pts
				(arc
					(start 285.436564 -261.351014)
					(mid 284.885384 -261.902194)
					(end 285.436564 -262.453374)
				)
				(xy 285.920688 -262.453374)
				(arc
					(start 285.920688 -262.029194)
					(mid 285.905809 -261.993273)
					(end 285.869888 -261.978394)
				)
				(arc
					(start 285.822898 -261.978394)
					(mid 285.042787 -261.902194)
					(end 285.822898 -261.825994)
				)
				(xy 285.901384 -261.825994)
				(arc
					(start 285.904432 -261.829042)
					(mid 286.013509 -261.885573)
					(end 286.07004 -261.99465)
				)
				(xy 286.073088 -261.997698) (xy 286.073088 -262.453374) (xy 286.200088 -262.453374) (xy 286.200088 -261.997698)
				(arc
					(start 286.203136 -261.99465)
					(mid 286.259667 -261.885573)
					(end 286.368744 -261.829042)
				)
				(xy 286.371792 -261.825994)
				(arc
					(start 286.450278 -261.825994)
					(mid 287.230389 -261.902194)
					(end 286.450278 -261.978394)
				)
				(arc
					(start 286.403288 -261.978394)
					(mid 286.367367 -261.993273)
					(end 286.352488 -262.029194)
				)
				(xy 286.352488 -262.453374)
				(arc
					(start 286.836612 -262.453374)
					(mid 287.387792 -261.902194)
					(end 286.836612 -261.351014)
				)
				(xy 285.436818 -261.351014)
			)
		)
	)
	(zone
		(net "P12V_B_COMP")
		(layer "In7.Cu")
		(hatch none 0.5)
		(connect_pads
			(clearance 0.5)
		)
		(min_thickness 0.25)
		(fill yes
			(thermal_gap 0.5)
			(thermal_bridge_width 0.5)
			(island_removal_mode 0)
		)
		(polygon
			(pts
				(xy 288.0106 -103.6828) (xy 288.0106 -84.0486) (xy 287.1216 -83.1596) (xy 285.9532 -83.1596) (xy 276.4028 -83.1596)
				(xy 271.7292 -83.1596) (xy 270.002 -84.8868) (xy 270.002 -104.013) (xy 270.6624 -104.6734) (xy 287.02 -104.6734)
			)
		)
	)
	(zone
		(layer "In7.Cu")
		(hatch none 0.5)
		(connect_pads
			(clearance 0)
		)
		(min_thickness 0.25)
		(keepout
			(tracks not_allowed)
			(vias allowed)
			(pads allowed)
			(copperpour not_allowed)
			(footprints allowed)
		)
		(placement
			(enabled no)
			(sheetname "")
		)
		(fill
			(thermal_gap 0.5)
			(thermal_bridge_width 0.5)
			(island_removal_mode 0)
		)
		(polygon
			(pts
				(arc
					(start 95.989902 -47.178722)
					(mid 95.609029 -46.797468)
					(end 95.227902 -47.178468)
				)
				(arc
					(start 95.227902 -48.321468)
					(mid 95.608902 -48.702468)
					(end 95.989902 -48.321468)
				)
				(xy 95.989902 -47.978568)
				(arc
					(start 95.710502 -47.978568)
					(mid 95.683561 -47.989727)
					(end 95.672402 -48.016668)
				)
				(arc
					(start 95.672402 -48.062388)
					(mid 95.608902 -48.588216)
					(end 95.545402 -48.062388)
				)
				(xy 95.545402 -47.990252)
				(arc
					(start 95.547942 -47.987712)
					(mid 95.593745 -47.899911)
					(end 95.681546 -47.854108)
				)
				(xy 95.684086 -47.851568) (xy 95.989902 -47.851568) (xy 95.989902 -47.648368) (xy 95.684086 -47.648368)
				(arc
					(start 95.681546 -47.645828)
					(mid 95.593745 -47.600025)
					(end 95.547942 -47.512224)
				)
				(xy 95.545402 -47.509684)
				(arc
					(start 95.545402 -47.437548)
					(mid 95.608902 -46.91172)
					(end 95.672402 -47.437548)
				)
				(arc
					(start 95.672402 -47.483268)
					(mid 95.683561 -47.510209)
					(end 95.710502 -47.521368)
				)
				(xy 95.989902 -47.521368)
			)
		)
	)
	(zone
		(layer "In7.Cu")
		(hatch none 0.5)
		(connect_pads
			(clearance 0)
		)
		(min_thickness 0.25)
		(keepout
			(tracks not_allowed)
			(vias allowed)
			(pads allowed)
			(copperpour not_allowed)
			(footprints allowed)
		)
		(placement
			(enabled no)
			(sheetname "")
		)
		(fill
			(thermal_gap 0.5)
			(thermal_bridge_width 0.5)
			(island_removal_mode 0)
		)
		(polygon
			(pts
				(arc
					(start 278.23668 -257.751072)
					(mid 277.6855 -258.302252)
					(end 278.23668 -258.853432)
				)
				(xy 278.720804 -258.853432)
				(arc
					(start 278.720804 -258.429252)
					(mid 278.705925 -258.393331)
					(end 278.670004 -258.378452)
				)
				(arc
					(start 278.623014 -258.378452)
					(mid 277.842903 -258.302252)
					(end 278.623014 -258.226052)
				)
				(xy 278.7015 -258.226052)
				(arc
					(start 278.704548 -258.2291)
					(mid 278.813625 -258.285631)
					(end 278.870156 -258.394708)
				)
				(xy 278.873204 -258.397756) (xy 278.873204 -258.853432) (xy 279.000204 -258.853432) (xy 279.000204 -258.397756)
				(arc
					(start 279.003252 -258.394708)
					(mid 279.059783 -258.285631)
					(end 279.16886 -258.2291)
				)
				(xy 279.171908 -258.226052)
				(arc
					(start 279.250394 -258.226052)
					(mid 280.030505 -258.302252)
					(end 279.250394 -258.378452)
				)
				(arc
					(start 279.203404 -258.378452)
					(mid 279.167483 -258.393331)
					(end 279.152604 -258.429252)
				)
				(xy 279.152604 -258.853432)
				(arc
					(start 279.636728 -258.853432)
					(mid 280.187908 -258.302252)
					(end 279.636728 -257.751072)
				)
				(xy 278.236934 -257.751072)
			)
		)
	)
	(zone
		(layer "In7.Cu")
		(hatch none 0.5)
		(connect_pads
			(clearance 0)
		)
		(min_thickness 0.25)
		(keepout
			(tracks not_allowed)
			(vias allowed)
			(pads allowed)
			(copperpour not_allowed)
			(footprints allowed)
		)
		(placement
			(enabled no)
			(sheetname "")
		)
		(fill
			(thermal_gap 0.5)
			(thermal_bridge_width 0.5)
			(island_removal_mode 0)
		)
		(polygon
			(pts
				(arc
					(start 279.236678 -259.55117)
					(mid 278.685498 -260.10235)
					(end 279.236678 -260.65353)
				)
				(xy 279.720802 -260.65353)
				(arc
					(start 279.720802 -260.22935)
					(mid 279.705923 -260.193429)
					(end 279.670002 -260.17855)
				)
				(arc
					(start 279.623012 -260.17855)
					(mid 278.842901 -260.10235)
					(end 279.623012 -260.02615)
				)
				(xy 279.701498 -260.02615)
				(arc
					(start 279.704546 -260.029198)
					(mid 279.813623 -260.085729)
					(end 279.870154 -260.194806)
				)
				(xy 279.873202 -260.197854) (xy 279.873202 -260.65353) (xy 280.000202 -260.65353) (xy 280.000202 -260.197854)
				(arc
					(start 280.00325 -260.194806)
					(mid 280.059781 -260.085729)
					(end 280.168858 -260.029198)
				)
				(xy 280.171906 -260.02615)
				(arc
					(start 280.250392 -260.02615)
					(mid 281.030503 -260.10235)
					(end 280.250392 -260.17855)
				)
				(arc
					(start 280.203402 -260.17855)
					(mid 280.167481 -260.193429)
					(end 280.152602 -260.22935)
				)
				(xy 280.152602 -260.65353)
				(arc
					(start 280.636726 -260.65353)
					(mid 281.187906 -260.10235)
					(end 280.636726 -259.55117)
				)
				(xy 279.236932 -259.55117)
			)
		)
	)
	(zone
		(layer "In7.Cu")
		(hatch none 0.5)
		(connect_pads
			(clearance 0)
		)
		(min_thickness 0.25)
		(keepout
			(tracks not_allowed)
			(vias allowed)
			(pads allowed)
			(copperpour not_allowed)
			(footprints allowed)
		)
		(placement
			(enabled no)
			(sheetname "")
		)
		(fill
			(thermal_gap 0.5)
			(thermal_bridge_width 0.5)
			(island_removal_mode 0)
		)
		(polygon
			(pts
				(arc
					(start 286.436562 -328.353928)
					(mid 285.885382 -328.905108)
					(end 286.436562 -329.456288)
				)
				(arc
					(start 287.83661 -329.456288)
					(mid 288.38779 -328.905108)
					(end 287.83661 -328.353928)
				)
				(xy 287.367472 -328.353928)
				(arc
					(start 287.367472 -328.778108)
					(mid 287.386071 -328.823009)
					(end 287.430972 -328.841608)
				)
				(arc
					(start 287.44799 -328.841608)
					(mid 288.230384 -328.905108)
					(end 287.44799 -328.968608)
				)
				(xy 287.404556 -328.968608)
				(arc
					(start 287.402524 -328.966576)
					(mid 287.296195 -328.912885)
					(end 287.242504 -328.806556)
				)
				(xy 287.240472 -328.804524) (xy 287.240472 -328.353928) (xy 287.037272 -328.353928) (xy 287.037272 -328.804524)
				(arc
					(start 287.03524 -328.806556)
					(mid 286.981549 -328.912885)
					(end 286.87522 -328.966576)
				)
				(xy 286.873188 -328.968608)
				(arc
					(start 286.825182 -328.968608)
					(mid 286.042788 -328.905108)
					(end 286.825182 -328.841608)
				)
				(arc
					(start 286.846772 -328.841608)
					(mid 286.891673 -328.823009)
					(end 286.910272 -328.778108)
				)
				(xy 286.910272 -328.353928) (xy 286.436816 -328.353928)
			)
		)
	)
	(zone
		(layer "In7.Cu")
		(hatch none 0.5)
		(connect_pads
			(clearance 0)
		)
		(min_thickness 0.25)
		(keepout
			(tracks not_allowed)
			(vias allowed)
			(pads allowed)
			(copperpour not_allowed)
			(footprints allowed)
		)
		(placement
			(enabled no)
			(sheetname "")
		)
		(fill
			(thermal_gap 0.5)
			(thermal_bridge_width 0.5)
			(island_removal_mode 0)
		)
		(polygon
			(pts
				(arc
					(start 286.436562 -353.55403)
					(mid 285.885382 -354.10521)
					(end 286.436562 -354.65639)
				)
				(arc
					(start 287.83661 -354.65639)
					(mid 288.38779 -354.10521)
					(end 287.83661 -353.55403)
				)
				(xy 287.367472 -353.55403)
				(arc
					(start 287.367472 -353.97821)
					(mid 287.386071 -354.023111)
					(end 287.430972 -354.04171)
				)
				(arc
					(start 287.44799 -354.04171)
					(mid 288.230384 -354.10521)
					(end 287.44799 -354.16871)
				)
				(xy 287.404556 -354.16871)
				(arc
					(start 287.402524 -354.166678)
					(mid 287.296195 -354.112987)
					(end 287.242504 -354.006658)
				)
				(xy 287.240472 -354.004626) (xy 287.240472 -353.55403) (xy 287.037272 -353.55403) (xy 287.037272 -354.004626)
				(arc
					(start 287.03524 -354.006658)
					(mid 286.981549 -354.112987)
					(end 286.87522 -354.166678)
				)
				(xy 286.873188 -354.16871)
				(arc
					(start 286.825182 -354.16871)
					(mid 286.042788 -354.10521)
					(end 286.825182 -354.04171)
				)
				(arc
					(start 286.846772 -354.04171)
					(mid 286.891673 -354.023111)
					(end 286.910272 -353.97821)
				)
				(xy 286.910272 -353.55403) (xy 286.436816 -353.55403)
			)
		)
	)
	(zone
		(layer "In7.Cu")
		(hatch none 0.5)
		(connect_pads
			(clearance 0)
		)
		(min_thickness 0.25)
		(keepout
			(tracks not_allowed)
			(vias allowed)
			(pads allowed)
			(copperpour not_allowed)
			(footprints allowed)
		)
		(placement
			(enabled no)
			(sheetname "")
		)
		(fill
			(thermal_gap 0.5)
			(thermal_bridge_width 0.5)
			(island_removal_mode 0)
		)
		(polygon
			(pts
				(arc
					(start 127.53975 -47.178722)
					(mid 127.158877 -46.797468)
					(end 126.77775 -47.178468)
				)
				(arc
					(start 126.77775 -48.321468)
					(mid 127.15875 -48.702468)
					(end 127.53975 -48.321468)
				)
				(xy 127.53975 -47.978568)
				(arc
					(start 127.26035 -47.978568)
					(mid 127.233409 -47.989727)
					(end 127.22225 -48.016668)
				)
				(arc
					(start 127.22225 -48.062388)
					(mid 127.15875 -48.588216)
					(end 127.09525 -48.062388)
				)
				(xy 127.09525 -47.990252)
				(arc
					(start 127.09779 -47.987712)
					(mid 127.143593 -47.899911)
					(end 127.231394 -47.854108)
				)
				(xy 127.233934 -47.851568) (xy 127.53975 -47.851568) (xy 127.53975 -47.648368) (xy 127.233934 -47.648368)
				(arc
					(start 127.231394 -47.645828)
					(mid 127.143593 -47.600025)
					(end 127.09779 -47.512224)
				)
				(xy 127.09525 -47.509684)
				(arc
					(start 127.09525 -47.437548)
					(mid 127.15875 -46.91172)
					(end 127.22225 -47.437548)
				)
				(arc
					(start 127.22225 -47.483268)
					(mid 127.233409 -47.510209)
					(end 127.26035 -47.521368)
				)
				(xy 127.53975 -47.521368)
			)
		)
	)
	(zone
		(layer "In7.Cu")
		(hatch none 0.5)
		(connect_pads
			(clearance 0)
		)
		(min_thickness 0.25)
		(keepout
			(tracks not_allowed)
			(vias allowed)
			(pads allowed)
			(copperpour not_allowed)
			(footprints allowed)
		)
		(placement
			(enabled no)
			(sheetname "")
		)
		(fill
			(thermal_gap 0.5)
			(thermal_bridge_width 0.5)
			(island_removal_mode 0)
		)
		(polygon
			(pts
				(arc
					(start 350.764856 -42.240962)
					(mid 350.378522 -42.626915)
					(end 350.764602 -43.013122)
				)
				(xy 351.107502 -43.013122)
				(arc
					(start 351.107502 -42.728642)
					(mid 351.096343 -42.701701)
					(end 351.069402 -42.690542)
				)
				(arc
					(start 351.023682 -42.690542)
					(mid 350.497854 -42.627042)
					(end 351.023682 -42.563542)
				)
				(xy 351.095818 -42.563542)
				(arc
					(start 351.098358 -42.566082)
					(mid 351.186159 -42.611885)
					(end 351.231962 -42.699686)
				)
				(xy 351.234502 -42.702226) (xy 351.234502 -43.013122) (xy 351.437702 -43.013122) (xy 351.437702 -42.702226)
				(arc
					(start 351.440242 -42.699686)
					(mid 351.486045 -42.611885)
					(end 351.573846 -42.566082)
				)
				(xy 351.576386 -42.563542)
				(arc
					(start 351.648522 -42.563542)
					(mid 352.17435 -42.627042)
					(end 351.648522 -42.690542)
				)
				(arc
					(start 351.602802 -42.690542)
					(mid 351.575861 -42.701701)
					(end 351.564702 -42.728642)
				)
				(xy 351.564702 -43.013122)
				(arc
					(start 351.907602 -43.013122)
					(mid 352.293682 -42.627042)
					(end 351.907602 -42.240962)
				)
			)
		)
	)
	(zone
		(layer "In7.Cu")
		(hatch none 0.5)
		(connect_pads
			(clearance 0)
		)
		(min_thickness 0.25)
		(keepout
			(tracks not_allowed)
			(vias allowed)
			(pads allowed)
			(copperpour not_allowed)
			(footprints allowed)
		)
		(placement
			(enabled no)
			(sheetname "")
		)
		(fill
			(thermal_gap 0.5)
			(thermal_bridge_width 0.5)
			(island_removal_mode 0)
		)
		(polygon
			(pts
				(arc
					(start 382.701292 -29.15031)
					(mid 382.150239 -28.598876)
					(end 381.598932 -29.150056)
				)
				(xy 381.598932 -29.602938)
				(arc
					(start 382.023112 -29.602938)
					(mid 382.059033 -29.588059)
					(end 382.073912 -29.552138)
				)
				(arc
					(start 382.073912 -29.53639)
					(mid 382.150112 -28.756279)
					(end 382.226312 -29.53639)
				)
				(xy 382.226312 -29.583634)
				(arc
					(start 382.223264 -29.586682)
					(mid 382.166733 -29.695759)
					(end 382.057656 -29.75229)
				)
				(xy 382.054608 -29.755338) (xy 381.598932 -29.755338) (xy 381.598932 -29.882338) (xy 382.054608 -29.882338)
				(arc
					(start 382.057656 -29.885386)
					(mid 382.166733 -29.941917)
					(end 382.223264 -30.050994)
				)
				(xy 382.226312 -30.054042)
				(arc
					(start 382.226312 -30.16377)
					(mid 382.150112 -30.943881)
					(end 382.073912 -30.16377)
				)
				(arc
					(start 382.073912 -30.085538)
					(mid 382.059033 -30.049617)
					(end 382.023112 -30.034738)
				)
				(xy 381.598932 -30.034738)
				(arc
					(start 381.598932 -30.550104)
					(mid 382.150112 -31.101284)
					(end 382.701292 -30.550104)
				)
			)
		)
	)
	(zone
		(layer "In7.Cu")
		(hatch none 0.5)
		(connect_pads
			(clearance 0)
		)
		(min_thickness 0.25)
		(keepout
			(tracks not_allowed)
			(vias allowed)
			(pads allowed)
			(copperpour not_allowed)
			(footprints allowed)
		)
		(placement
			(enabled no)
			(sheetname "")
		)
		(fill
			(thermal_gap 0.5)
			(thermal_bridge_width 0.5)
			(island_removal_mode 0)
		)
		(polygon
			(pts
				(arc
					(start 159.089852 -277.17877)
					(mid 158.708979 -276.797516)
					(end 158.327852 -277.178516)
				)
				(arc
					(start 158.327852 -278.321516)
					(mid 158.708852 -278.702516)
					(end 159.089852 -278.321516)
				)
				(xy 159.089852 -277.978616)
				(arc
					(start 158.810452 -277.978616)
					(mid 158.783511 -277.989775)
					(end 158.772352 -278.016716)
				)
				(arc
					(start 158.772352 -278.062436)
					(mid 158.708852 -278.588264)
					(end 158.645352 -278.062436)
				)
				(xy 158.645352 -277.9903)
				(arc
					(start 158.647892 -277.98776)
					(mid 158.693695 -277.899959)
					(end 158.781496 -277.854156)
				)
				(xy 158.784036 -277.851616) (xy 159.089852 -277.851616) (xy 159.089852 -277.648416) (xy 158.784036 -277.648416)
				(arc
					(start 158.781496 -277.645876)
					(mid 158.693695 -277.600073)
					(end 158.647892 -277.512272)
				)
				(xy 158.645352 -277.509732)
				(arc
					(start 158.645352 -277.437596)
					(mid 158.708852 -276.911768)
					(end 158.772352 -277.437596)
				)
				(arc
					(start 158.772352 -277.483316)
					(mid 158.783511 -277.510257)
					(end 158.810452 -277.521416)
				)
				(xy 159.089852 -277.521416)
			)
		)
	)
	(zone
		(layer "In7.Cu")
		(hatch none 0.5)
		(connect_pads
			(clearance 0)
		)
		(min_thickness 0.25)
		(keepout
			(tracks not_allowed)
			(vias allowed)
			(pads allowed)
			(copperpour not_allowed)
			(footprints allowed)
		)
		(placement
			(enabled no)
			(sheetname "")
		)
		(fill
			(thermal_gap 0.5)
			(thermal_bridge_width 0.5)
			(island_removal_mode 0)
		)
		(polygon
			(pts
				(arc
					(start 190.639954 -162.178746)
					(mid 190.259081 -161.797492)
					(end 189.877954 -162.178492)
				)
				(arc
					(start 189.877954 -163.321492)
					(mid 190.258954 -163.702492)
					(end 190.639954 -163.321492)
				)
				(xy 190.639954 -162.978592)
				(arc
					(start 190.360554 -162.978592)
					(mid 190.333613 -162.989751)
					(end 190.322454 -163.016692)
				)
				(arc
					(start 190.322454 -163.062412)
					(mid 190.258954 -163.58824)
					(end 190.195454 -163.062412)
				)
				(xy 190.195454 -162.990276)
				(arc
					(start 190.197994 -162.987736)
					(mid 190.243797 -162.899935)
					(end 190.331598 -162.854132)
				)
				(xy 190.334138 -162.851592) (xy 190.639954 -162.851592) (xy 190.639954 -162.648392) (xy 190.334138 -162.648392)
				(arc
					(start 190.331598 -162.645852)
					(mid 190.243797 -162.600049)
					(end 190.197994 -162.512248)
				)
				(xy 190.195454 -162.509708)
				(arc
					(start 190.195454 -162.437572)
					(mid 190.258954 -161.911744)
					(end 190.322454 -162.437572)
				)
				(arc
					(start 190.322454 -162.483292)
					(mid 190.333613 -162.510233)
					(end 190.360554 -162.521392)
				)
				(xy 190.639954 -162.521392)
			)
		)
	)
	(zone
		(layer "In7.Cu")
		(hatch none 0.5)
		(connect_pads
			(clearance 0)
		)
		(min_thickness 0.25)
		(keepout
			(tracks not_allowed)
			(vias allowed)
			(pads allowed)
			(copperpour not_allowed)
			(footprints allowed)
		)
		(placement
			(enabled no)
			(sheetname "")
		)
		(fill
			(thermal_gap 0.5)
			(thermal_bridge_width 0.5)
			(island_removal_mode 0)
		)
		(polygon
			(pts
				(arc
					(start 32.889952 -47.178722)
					(mid 32.509079 -46.797468)
					(end 32.127952 -47.178468)
				)
				(arc
					(start 32.127952 -48.321468)
					(mid 32.508952 -48.702468)
					(end 32.889952 -48.321468)
				)
				(xy 32.889952 -47.978568)
				(arc
					(start 32.610552 -47.978568)
					(mid 32.583611 -47.989727)
					(end 32.572452 -48.016668)
				)
				(arc
					(start 32.572452 -48.062388)
					(mid 32.508952 -48.588216)
					(end 32.445452 -48.062388)
				)
				(xy 32.445452 -47.990252)
				(arc
					(start 32.447992 -47.987712)
					(mid 32.493795 -47.899911)
					(end 32.581596 -47.854108)
				)
				(xy 32.584136 -47.851568) (xy 32.889952 -47.851568) (xy 32.889952 -47.648368) (xy 32.584136 -47.648368)
				(arc
					(start 32.581596 -47.645828)
					(mid 32.493795 -47.600025)
					(end 32.447992 -47.512224)
				)
				(xy 32.445452 -47.509684)
				(arc
					(start 32.445452 -47.437548)
					(mid 32.508952 -46.91172)
					(end 32.572452 -47.437548)
				)
				(arc
					(start 32.572452 -47.483268)
					(mid 32.583611 -47.510209)
					(end 32.610552 -47.521368)
				)
				(xy 32.889952 -47.521368)
			)
		)
	)
	(zone
		(layer "In7.Cu")
		(hatch none 0.5)
		(connect_pads
			(clearance 0)
		)
		(min_thickness 0.25)
		(keepout
			(tracks not_allowed)
			(vias allowed)
			(pads allowed)
			(copperpour not_allowed)
			(footprints allowed)
		)
		(placement
			(enabled no)
			(sheetname "")
		)
		(fill
			(thermal_gap 0.5)
			(thermal_bridge_width 0.5)
			(island_removal_mode 0)
		)
		(polygon
			(pts
				(arc
					(start 242.100608 -120.189752)
					(mid 243.037692 -120.745361)
					(end 242.032282 -120.325896)
				)
				(arc
					(start 241.766598 -120.1928)
					(mid 241.71832 -120.189067)
					(end 241.681254 -120.220232)
				)
				(xy 241.658394 -120.265698) (xy 241.658394 -120.265952) (xy 241.64417 -120.293892) (xy 241.630454 -120.321832)
				(xy 241.6302 -120.322086) (xy 241.48415 -120.612408)
				(arc
					(start 241.475514 -120.615202)
					(mid 241.469014 -120.648777)
					(end 241.48415 -120.679464)
				)
				(xy 241.695224 -120.890538)
				(arc
					(start 242.222528 -121.15419)
					(mid 243.204289 -120.82719)
					(end 242.877086 -119.845582)
				)
				(arc
					(start 240.87709 -118.845584)
					(mid 239.895634 -119.172736)
					(end 240.222786 -120.154192)
				)
				(arc
					(start 241.042698 -120.564148)
					(mid 241.073936 -120.454613)
					(end 241.12982 -120.35536)
				)
				(xy 241.249708 -120.116854) (xy 241.249708 -120.103138) (xy 241.263678 -120.089168) (xy 241.27206 -120.072404)
				(arc
					(start 241.299746 -120.01754)
					(mid 241.302594 -119.978695)
					(end 241.27714 -119.949214)
				)
				(arc
					(start 240.999264 -119.810276)
					(mid 240.061663 -119.255302)
					(end 241.06759 -119.673878)
				)
				(xy 241.345212 -119.81307) (xy 241.373406 -119.82704)
				(arc
					(start 241.37493 -119.831104)
					(mid 241.447181 -119.930626)
					(end 241.448844 -120.053608)
				)
				(xy 241.450114 -120.057418) (xy 241.402362 -120.152668) (xy 241.402362 -120.16613) (xy 241.388646 -120.179846)
				(xy 241.38001 -120.197118) (xy 241.248692 -120.457976)
				(arc
					(start 241.242596 -120.460008)
					(mid 241.203252 -120.544857)
					(end 241.189002 -120.6373)
				)
				(arc
					(start 241.326416 -120.706134)
					(mid 241.320164 -120.600659)
					(end 241.367056 -120.505982)
				)
				(xy 241.50701 -120.227852) (xy 241.506756 -120.227344) (xy 241.52098 -120.199404) (xy 241.534696 -120.171718)
				(xy 241.535204 -120.171464) (xy 241.544348 -120.15343) (xy 241.545872 -120.150636) (xy 241.558826 -120.124982)
				(arc
					(start 241.562128 -120.123966)
					(mid 241.66951 -120.044792)
					(end 241.80292 -120.043702)
				)
				(xy 241.806476 -120.042432)
			)
		)
	)
	(zone
		(layer "In7.Cu")
		(hatch none 0.5)
		(connect_pads
			(clearance 0)
		)
		(min_thickness 0.25)
		(keepout
			(tracks not_allowed)
			(vias allowed)
			(pads allowed)
			(copperpour not_allowed)
			(footprints allowed)
		)
		(placement
			(enabled no)
			(sheetname "")
		)
		(fill
			(thermal_gap 0.5)
			(thermal_bridge_width 0.5)
			(island_removal_mode 0)
		)
		(polygon
			(pts
				(arc
					(start 285.436564 -257.751072)
					(mid 284.885384 -258.302252)
					(end 285.436564 -258.853432)
				)
				(xy 285.920688 -258.853432)
				(arc
					(start 285.920688 -258.429252)
					(mid 285.905809 -258.393331)
					(end 285.869888 -258.378452)
				)
				(arc
					(start 285.822898 -258.378452)
					(mid 285.042787 -258.302252)
					(end 285.822898 -258.226052)
				)
				(xy 285.901384 -258.226052)
				(arc
					(start 285.904432 -258.2291)
					(mid 286.013509 -258.285631)
					(end 286.07004 -258.394708)
				)
				(xy 286.073088 -258.397756) (xy 286.073088 -258.853432) (xy 286.200088 -258.853432) (xy 286.200088 -258.397756)
				(arc
					(start 286.203136 -258.394708)
					(mid 286.259667 -258.285631)
					(end 286.368744 -258.2291)
				)
				(xy 286.371792 -258.226052)
				(arc
					(start 286.450278 -258.226052)
					(mid 287.230389 -258.302252)
					(end 286.450278 -258.378452)
				)
				(arc
					(start 286.403288 -258.378452)
					(mid 286.367367 -258.393331)
					(end 286.352488 -258.429252)
				)
				(xy 286.352488 -258.853432)
				(arc
					(start 286.836612 -258.853432)
					(mid 287.387792 -258.302252)
					(end 286.836612 -257.751072)
				)
				(xy 285.436818 -257.751072)
			)
		)
	)
	(zone
		(layer "In7.Cu")
		(hatch none 0.5)
		(connect_pads
			(clearance 0)
		)
		(min_thickness 0.25)
		(keepout
			(tracks not_allowed)
			(vias allowed)
			(pads allowed)
			(copperpour not_allowed)
			(footprints allowed)
		)
		(placement
			(enabled no)
			(sheetname "")
		)
		(fill
			(thermal_gap 0.5)
			(thermal_bridge_width 0.5)
			(island_removal_mode 0)
		)
		(polygon
			(pts
				(arc
					(start 279.236678 -252.351032)
					(mid 278.685498 -252.902212)
					(end 279.236678 -253.453392)
				)
				(xy 279.720802 -253.453392)
				(arc
					(start 279.720802 -253.029212)
					(mid 279.705923 -252.993291)
					(end 279.670002 -252.978412)
				)
				(arc
					(start 279.623012 -252.978412)
					(mid 278.842901 -252.902212)
					(end 279.623012 -252.826012)
				)
				(xy 279.701498 -252.826012)
				(arc
					(start 279.704546 -252.82906)
					(mid 279.813623 -252.885591)
					(end 279.870154 -252.994668)
				)
				(xy 279.873202 -252.997716) (xy 279.873202 -253.453392) (xy 280.000202 -253.453392) (xy 280.000202 -252.997716)
				(arc
					(start 280.00325 -252.994668)
					(mid 280.059781 -252.885591)
					(end 280.168858 -252.82906)
				)
				(xy 280.171906 -252.826012)
				(arc
					(start 280.250392 -252.826012)
					(mid 281.030503 -252.902212)
					(end 280.250392 -252.978412)
				)
				(arc
					(start 280.203402 -252.978412)
					(mid 280.167481 -252.993291)
					(end 280.152602 -253.029212)
				)
				(xy 280.152602 -253.453392)
				(arc
					(start 280.636726 -253.453392)
					(mid 281.187906 -252.902212)
					(end 280.636726 -252.351032)
				)
				(xy 279.236932 -252.351032)
			)
		)
	)
	(zone
		(layer "In7.Cu")
		(hatch none 0.5)
		(connect_pads
			(clearance 0)
		)
		(min_thickness 0.25)
		(keepout
			(tracks not_allowed)
			(vias allowed)
			(pads allowed)
			(copperpour not_allowed)
			(footprints allowed)
		)
		(placement
			(enabled no)
			(sheetname "")
		)
		(fill
			(thermal_gap 0.5)
			(thermal_bridge_width 0.5)
			(island_removal_mode 0)
		)
		(polygon
			(pts
				(arc
					(start 279.236678 -263.151112)
					(mid 278.685498 -263.702292)
					(end 279.236678 -264.253472)
				)
				(xy 279.720802 -264.253472)
				(arc
					(start 279.720802 -263.829292)
					(mid 279.705923 -263.793371)
					(end 279.670002 -263.778492)
				)
				(arc
					(start 279.623012 -263.778492)
					(mid 278.842901 -263.702292)
					(end 279.623012 -263.626092)
				)
				(xy 279.701498 -263.626092)
				(arc
					(start 279.704546 -263.62914)
					(mid 279.813623 -263.685671)
					(end 279.870154 -263.794748)
				)
				(xy 279.873202 -263.797796) (xy 279.873202 -264.253472) (xy 280.000202 -264.253472) (xy 280.000202 -263.797796)
				(arc
					(start 280.00325 -263.794748)
					(mid 280.059781 -263.685671)
					(end 280.168858 -263.62914)
				)
				(xy 280.171906 -263.626092)
				(arc
					(start 280.250392 -263.626092)
					(mid 281.030503 -263.702292)
					(end 280.250392 -263.778492)
				)
				(arc
					(start 280.203402 -263.778492)
					(mid 280.167481 -263.793371)
					(end 280.152602 -263.829292)
				)
				(xy 280.152602 -264.253472)
				(arc
					(start 280.636726 -264.253472)
					(mid 281.187906 -263.702292)
					(end 280.636726 -263.151112)
				)
				(xy 279.236932 -263.151112)
			)
		)
	)
	(zone
		(layer "In7.Cu")
		(hatch none 0.5)
		(connect_pads
			(clearance 0)
		)
		(min_thickness 0.25)
		(keepout
			(tracks not_allowed)
			(vias allowed)
			(pads allowed)
			(copperpour not_allowed)
			(footprints allowed)
		)
		(placement
			(enabled no)
			(sheetname "")
		)
		(fill
			(thermal_gap 0.5)
			(thermal_bridge_width 0.5)
			(island_removal_mode 0)
		)
		(polygon
			(pts
				(arc
					(start 285.436564 -326.554084)
					(mid 284.885384 -327.105264)
					(end 285.436564 -327.656444)
				)
				(arc
					(start 286.836612 -327.656444)
					(mid 287.387792 -327.105264)
					(end 286.836612 -326.554084)
				)
				(xy 286.367474 -326.554084)
				(arc
					(start 286.367474 -326.978264)
					(mid 286.386073 -327.023165)
					(end 286.430974 -327.041764)
				)
				(arc
					(start 286.447992 -327.041764)
					(mid 287.230386 -327.105264)
					(end 286.447992 -327.168764)
				)
				(xy 286.404558 -327.168764)
				(arc
					(start 286.402526 -327.166732)
					(mid 286.296197 -327.113041)
					(end 286.242506 -327.006712)
				)
				(xy 286.240474 -327.00468) (xy 286.240474 -326.554084) (xy 286.037274 -326.554084) (xy 286.037274 -327.00468)
				(arc
					(start 286.035242 -327.006712)
					(mid 285.981551 -327.113041)
					(end 285.875222 -327.166732)
				)
				(xy 285.87319 -327.168764)
				(arc
					(start 285.825184 -327.168764)
					(mid 285.04279 -327.105264)
					(end 285.825184 -327.041764)
				)
				(arc
					(start 285.846774 -327.041764)
					(mid 285.891675 -327.023165)
					(end 285.910274 -326.978264)
				)
				(xy 285.910274 -326.554084) (xy 285.436818 -326.554084)
			)
		)
	)
	(zone
		(layer "In7.Cu")
		(hatch none 0.5)
		(connect_pads
			(clearance 0)
		)
		(min_thickness 0.25)
		(keepout
			(tracks not_allowed)
			(vias allowed)
			(pads allowed)
			(copperpour not_allowed)
			(footprints allowed)
		)
		(placement
			(enabled no)
			(sheetname "")
		)
		(fill
			(thermal_gap 0.5)
			(thermal_bridge_width 0.5)
			(island_removal_mode 0)
		)
		(polygon
			(pts
				(arc
					(start 286.436562 -252.351032)
					(mid 285.885382 -252.902212)
					(end 286.436562 -253.453392)
				)
				(xy 286.920686 -253.453392)
				(arc
					(start 286.920686 -253.029212)
					(mid 286.905807 -252.993291)
					(end 286.869886 -252.978412)
				)
				(arc
					(start 286.822896 -252.978412)
					(mid 286.042785 -252.902212)
					(end 286.822896 -252.826012)
				)
				(xy 286.901382 -252.826012)
				(arc
					(start 286.90443 -252.82906)
					(mid 287.013507 -252.885591)
					(end 287.070038 -252.994668)
				)
				(xy 287.073086 -252.997716) (xy 287.073086 -253.453392) (xy 287.200086 -253.453392) (xy 287.200086 -252.997716)
				(arc
					(start 287.203134 -252.994668)
					(mid 287.259665 -252.885591)
					(end 287.368742 -252.82906)
				)
				(xy 287.37179 -252.826012)
				(arc
					(start 287.450276 -252.826012)
					(mid 288.230387 -252.902212)
					(end 287.450276 -252.978412)
				)
				(arc
					(start 287.403286 -252.978412)
					(mid 287.367365 -252.993291)
					(end 287.352486 -253.029212)
				)
				(xy 287.352486 -253.453392)
				(arc
					(start 287.83661 -253.453392)
					(mid 288.38779 -252.902212)
					(end 287.83661 -252.351032)
				)
				(xy 286.436816 -252.351032)
			)
		)
	)
	(zone
		(layer "In7.Cu")
		(hatch none 0.5)
		(connect_pads
			(clearance 0)
		)
		(min_thickness 0.25)
		(keepout
			(tracks not_allowed)
			(vias allowed)
			(pads allowed)
			(copperpour not_allowed)
			(footprints allowed)
		)
		(placement
			(enabled no)
			(sheetname "")
		)
		(fill
			(thermal_gap 0.5)
			(thermal_bridge_width 0.5)
			(island_removal_mode 0)
		)
		(polygon
			(pts
				(arc
					(start 278.23668 -250.551188)
					(mid 277.6855 -251.102368)
					(end 278.23668 -251.653548)
				)
				(xy 278.720804 -251.653548)
				(arc
					(start 278.720804 -251.229368)
					(mid 278.705925 -251.193447)
					(end 278.670004 -251.178568)
				)
				(arc
					(start 278.623014 -251.178568)
					(mid 277.842903 -251.102368)
					(end 278.623014 -251.026168)
				)
				(xy 278.7015 -251.026168)
				(arc
					(start 278.704548 -251.029216)
					(mid 278.813625 -251.085747)
					(end 278.870156 -251.194824)
				)
				(xy 278.873204 -251.197872) (xy 278.873204 -251.653548) (xy 279.000204 -251.653548) (xy 279.000204 -251.197872)
				(arc
					(start 279.003252 -251.194824)
					(mid 279.059783 -251.085747)
					(end 279.16886 -251.029216)
				)
				(xy 279.171908 -251.026168)
				(arc
					(start 279.250394 -251.026168)
					(mid 280.030505 -251.102368)
					(end 279.250394 -251.178568)
				)
				(arc
					(start 279.203404 -251.178568)
					(mid 279.167483 -251.193447)
					(end 279.152604 -251.229368)
				)
				(xy 279.152604 -251.653548)
				(arc
					(start 279.636728 -251.653548)
					(mid 280.187908 -251.102368)
					(end 279.636728 -250.551188)
				)
				(xy 278.236934 -250.551188)
			)
		)
	)
	(zone
		(layer "In7.Cu")
		(hatch none 0.5)
		(connect_pads
			(clearance 0)
		)
		(min_thickness 0.25)
		(keepout
			(tracks not_allowed)
			(vias allowed)
			(pads allowed)
			(copperpour not_allowed)
			(footprints allowed)
		)
		(placement
			(enabled no)
			(sheetname "")
		)
		(fill
			(thermal_gap 0.5)
			(thermal_bridge_width 0.5)
			(island_removal_mode 0)
		)
		(polygon
			(pts
				(arc
					(start 64.4398 -277.17877)
					(mid 64.058927 -276.797516)
					(end 63.6778 -277.178516)
				)
				(arc
					(start 63.6778 -278.321516)
					(mid 64.0588 -278.702516)
					(end 64.4398 -278.321516)
				)
				(xy 64.4398 -277.978616)
				(arc
					(start 64.1604 -277.978616)
					(mid 64.133459 -277.989775)
					(end 64.1223 -278.016716)
				)
				(arc
					(start 64.1223 -278.062436)
					(mid 64.0588 -278.588264)
					(end 63.9953 -278.062436)
				)
				(xy 63.9953 -277.9903)
				(arc
					(start 63.99784 -277.98776)
					(mid 64.043643 -277.899959)
					(end 64.131444 -277.854156)
				)
				(xy 64.133984 -277.851616) (xy 64.4398 -277.851616) (xy 64.4398 -277.648416) (xy 64.133984 -277.648416)
				(arc
					(start 64.131444 -277.645876)
					(mid 64.043643 -277.600073)
					(end 63.99784 -277.512272)
				)
				(xy 63.9953 -277.509732)
				(arc
					(start 63.9953 -277.437596)
					(mid 64.0588 -276.911768)
					(end 64.1223 -277.437596)
				)
				(arc
					(start 64.1223 -277.483316)
					(mid 64.133459 -277.510257)
					(end 64.1604 -277.521416)
				)
				(xy 64.4398 -277.521416)
			)
		)
	)
	(zone
		(layer "In7.Cu")
		(hatch none 0.5)
		(connect_pads
			(clearance 0)
		)
		(min_thickness 0.25)
		(keepout
			(tracks not_allowed)
			(vias allowed)
			(pads allowed)
			(copperpour not_allowed)
			(footprints allowed)
		)
		(placement
			(enabled no)
			(sheetname "")
		)
		(fill
			(thermal_gap 0.5)
			(thermal_bridge_width 0.5)
			(island_removal_mode 0)
		)
		(polygon
			(pts
				(arc
					(start 286.436562 -306.754022)
					(mid 285.885382 -307.305202)
					(end 286.436562 -307.856382)
				)
				(arc
					(start 287.83661 -307.856382)
					(mid 288.38779 -307.305202)
					(end 287.83661 -306.754022)
				)
				(xy 287.367472 -306.754022)
				(arc
					(start 287.367472 -307.178202)
					(mid 287.386071 -307.223103)
					(end 287.430972 -307.241702)
				)
				(arc
					(start 287.44799 -307.241702)
					(mid 288.230384 -307.305202)
					(end 287.44799 -307.368702)
				)
				(xy 287.404556 -307.368702)
				(arc
					(start 287.402524 -307.36667)
					(mid 287.296195 -307.312979)
					(end 287.242504 -307.20665)
				)
				(xy 287.240472 -307.204618) (xy 287.240472 -306.754022) (xy 287.037272 -306.754022) (xy 287.037272 -307.204618)
				(arc
					(start 287.03524 -307.20665)
					(mid 286.981549 -307.312979)
					(end 286.87522 -307.36667)
				)
				(xy 286.873188 -307.368702)
				(arc
					(start 286.825182 -307.368702)
					(mid 286.042788 -307.305202)
					(end 286.825182 -307.241702)
				)
				(arc
					(start 286.846772 -307.241702)
					(mid 286.891673 -307.223103)
					(end 286.910272 -307.178202)
				)
				(xy 286.910272 -306.754022) (xy 286.436816 -306.754022)
			)
		)
	)
	(zone
		(layer "In7.Cu")
		(hatch none 0.5)
		(connect_pads
			(clearance 0)
		)
		(min_thickness 0.25)
		(keepout
			(tracks not_allowed)
			(vias allowed)
			(pads allowed)
			(copperpour not_allowed)
			(footprints allowed)
		)
		(placement
			(enabled no)
			(sheetname "")
		)
		(fill
			(thermal_gap 0.5)
			(thermal_bridge_width 0.5)
			(island_removal_mode 0)
		)
		(polygon
			(pts
				(arc
					(start 238.377222 -118.154196)
					(mid 238.704374 -117.17274)
					(end 237.722918 -116.845588)
				)
				(arc
					(start 236.72165 -117.346222)
					(mid 236.793151 -117.387758)
					(end 236.858302 -117.438678)
				)
				(xy 236.859572 -117.438678)
				(arc
					(start 237.201964 -117.78107)
					(mid 237.243617 -117.80232)
					(end 237.289848 -117.795294)
				)
				(arc
					(start 237.532418 -117.673882)
					(mid 238.537816 -117.254423)
					(end 237.600744 -117.810026)
				)
				(xy 237.358174 -117.931438) (xy 237.32998 -117.945662)
				(arc
					(start 237.326678 -117.944392)
					(mid 237.219406 -117.952733)
					(end 237.120176 -117.911118)
				)
				(xy 237.11662 -117.911118)
				(arc
					(start 236.774228 -117.568726)
					(mid 236.66153 -117.486466)
					(end 236.529118 -117.442488)
				)
				(xy 236.287564 -117.563392) (xy 236.485938 -117.563392)
				(arc
					(start 236.487716 -117.56517)
					(mid 236.578897 -117.588155)
					(end 236.659674 -117.63629)
				)
				(xy 236.66196 -117.63629) (xy 236.913166 -117.887496)
				(arc
					(start 236.913166 -117.89156)
					(mid 236.947699 -118.040988)
					(end 236.867954 -118.171976)
				)
				(xy 236.866684 -118.175532) (xy 236.856524 -118.180866) (xy 236.85627 -118.181374) (xy 236.828584 -118.195344)
				(xy 236.800644 -118.209568) (xy 236.80039 -118.209314)
				(arc
					(start 236.567726 -118.3259)
					(mid 235.561798 -118.744477)
					(end 236.4994 -118.189502)
				)
				(xy 236.759496 -118.0592) (xy 236.769148 -118.054374)
				(arc
					(start 236.770926 -118.053358)
					(mid 236.797167 -118.016187)
					(end 236.783118 -117.97284)
				)
				(arc
					(start 236.576616 -117.766338)
					(mid 236.520562 -117.728884)
					(end 236.454442 -117.715792)
				)
				(xy 235.982764 -117.715792)
				(arc
					(start 235.733844 -117.840252)
					(mid 235.393447 -118.821282)
					(end 236.377226 -119.154194)
				)
			)
		)
	)
	(zone
		(layer "In7.Cu")
		(hatch none 0.5)
		(connect_pads
			(clearance 0)
		)
		(min_thickness 0.25)
		(keepout
			(tracks not_allowed)
			(vias allowed)
			(pads allowed)
			(copperpour not_allowed)
			(footprints allowed)
		)
		(placement
			(enabled no)
			(sheetname "")
		)
		(fill
			(thermal_gap 0.5)
			(thermal_bridge_width 0.5)
			(island_removal_mode 0)
		)
		(polygon
			(pts
				(xy 319.8876 -42.702226)
				(arc
					(start 319.89014 -42.699686)
					(mid 319.935119 -42.612716)
					(end 320.021458 -42.56659)
				)
				(xy 320.024252 -42.563542)
				(arc
					(start 320.09842 -42.563542)
					(mid 320.624248 -42.627042)
					(end 320.09842 -42.690542)
				)
				(arc
					(start 320.0527 -42.690542)
					(mid 320.025759 -42.701701)
					(end 320.0146 -42.728642)
				)
				(xy 320.0146 -43.008042)
				(arc
					(start 320.3575 -43.008042)
					(mid 320.7385 -42.627042)
					(end 320.3575 -42.246042)
				)
				(arc
					(start 319.214754 -42.246042)
					(mid 318.8335 -42.626915)
					(end 319.2145 -43.008042)
				)
				(xy 319.5574 -43.008042)
				(arc
					(start 319.5574 -42.728642)
					(mid 319.546241 -42.701701)
					(end 319.5193 -42.690542)
				)
				(arc
					(start 319.47358 -42.690542)
					(mid 318.947752 -42.627042)
					(end 319.47358 -42.563542)
				)
				(xy 319.545716 -42.563542)
				(arc
					(start 319.548256 -42.566082)
					(mid 319.636057 -42.611885)
					(end 319.68186 -42.699686)
				)
				(xy 319.6844 -42.702226) (xy 319.6844 -43.008042) (xy 319.8876 -43.008042)
			)
		)
	)
	(zone
		(net "GND")
		(layers "In7.Cu" "In9.Cu")
		(hatch none 0.5)
		(connect_pads
			(clearance 0.5)
		)
		(min_thickness 0.25)
		(fill yes
			(thermal_gap 0.5)
			(thermal_bridge_width 0.5)
			(island_removal_mode 0)
		)
		(polygon
			(pts
				(arc
					(start 221.000066 38.037008)
					(mid 220.832494 37.967598)
					(end 220.763084 37.800026)
				)
				(xy 220.763084 4.156964) (xy 222.032068 4.156964) (xy 222.032068 36.768024) (xy 297.967908 36.768024)
				(arc
					(start 297.967908 0.999998)
					(mid 298.85596 -1.143948)
					(end 300.999906 -2.032)
				)
				(xy 345.968066 -2.032)
				(arc
					(start 345.968066 -13.999972)
					(mid 346.856118 -16.143918)
					(end 349.000064 -17.03197)
				)
				(xy 349.743776 -17.03197) (xy 349.743776 -15.762986)
				(arc
					(start 349.000064 -15.762986)
					(mid 347.753425 -15.246611)
					(end 347.23705 -13.999972)
				)
				(arc
					(start 347.23705 -0.999998)
					(mid 347.16764 -0.832426)
					(end 347.000068 -0.763016)
				)
				(arc
					(start 300.999906 -0.763016)
					(mid 299.753267 -0.246641)
					(end 299.236892 0.999998)
				)
				(arc
					(start 299.236892 37.800026)
					(mid 299.167482 37.967598)
					(end 298.99991 38.037008)
				)
			)
		)
	)
	(zone
		(layers "In7.Cu" "In9.Cu")
		(hatch none 0.5)
		(connect_pads
			(clearance 0)
		)
		(min_thickness 0.25)
		(keepout
			(tracks not_allowed)
			(vias allowed)
			(pads allowed)
			(copperpour not_allowed)
			(footprints allowed)
		)
		(placement
			(enabled no)
			(sheetname "")
		)
		(fill yes
			(thermal_gap 0.5)
			(thermal_bridge_width 0.5)
			(island_removal_mode 0)
		)
		(polygon
			(pts
				(arc
					(start 140.298678 -21.950172)
					(mid 139.750038 -21.401532)
					(end 139.201398 -21.950172)
				)
				(arc
					(start 139.201398 -23.35022)
					(mid 139.748768 -23.898859)
					(end 140.298678 -23.35276)
				)
				(arc
					(start 140.143738 -23.35276)
					(mid 139.750038 -23.743928)
					(end 139.356338 -23.35276)
				)
				(arc
					(start 139.356338 -23.35022)
					(mid 139.750038 -22.95652)
					(end 140.143738 -23.35022)
				)
				(xy 140.298678 -23.35022) (xy 140.298678 -21.952712)
				(arc
					(start 140.143738 -21.952712)
					(mid 139.750038 -22.34388)
					(end 139.356338 -21.952712)
				)
				(arc
					(start 139.356338 -21.950172)
					(mid 139.750038 -21.556472)
					(end 140.143738 -21.950172)
				)
			)
		)
	)
	(zone
		(layers "In7.Cu" "In9.Cu")
		(hatch none 0.5)
		(connect_pads
			(clearance 0)
		)
		(min_thickness 0.25)
		(keepout
			(tracks not_allowed)
			(vias allowed)
			(pads allowed)
			(copperpour not_allowed)
			(footprints allowed)
		)
		(placement
			(enabled no)
			(sheetname "")
		)
		(fill yes
			(thermal_gap 0.5)
			(thermal_bridge_width 0.5)
			(island_removal_mode 0)
		)
		(polygon
			(pts
				(arc
					(start 131.298696 -20.950174)
					(mid 130.750056 -20.401534)
					(end 130.201416 -20.950174)
				)
				(arc
					(start 130.201416 -22.350222)
					(mid 130.748786 -22.898861)
					(end 131.298696 -22.352762)
				)
				(arc
					(start 131.143756 -22.352762)
					(mid 130.750056 -22.74393)
					(end 130.356356 -22.352762)
				)
				(arc
					(start 130.356356 -22.350222)
					(mid 130.750056 -21.956522)
					(end 131.143756 -22.350222)
				)
				(xy 131.298696 -22.350222) (xy 131.298696 -20.952714)
				(arc
					(start 131.143756 -20.952714)
					(mid 130.750056 -21.343882)
					(end 130.356356 -20.952714)
				)
				(arc
					(start 130.356356 -20.950174)
					(mid 130.750056 -20.556474)
					(end 131.143756 -20.950174)
				)
			)
		)
	)
	(zone
		(layers "In7.Cu" "In9.Cu")
		(hatch none 0.5)
		(connect_pads
			(clearance 0)
		)
		(min_thickness 0.25)
		(keepout
			(tracks not_allowed)
			(vias allowed)
			(pads allowed)
			(copperpour not_allowed)
			(footprints allowed)
		)
		(placement
			(enabled no)
			(sheetname "")
		)
		(fill yes
			(thermal_gap 0.5)
			(thermal_bridge_width 0.5)
			(island_removal_mode 0)
		)
		(polygon
			(pts
				(arc
					(start 143.89862 -21.950172)
					(mid 143.34998 -21.401532)
					(end 142.80134 -21.950172)
				)
				(arc
					(start 142.80134 -23.35022)
					(mid 143.34871 -23.898859)
					(end 143.89862 -23.35276)
				)
				(arc
					(start 143.74368 -23.35276)
					(mid 143.34998 -23.743928)
					(end 142.95628 -23.35276)
				)
				(arc
					(start 142.95628 -23.35022)
					(mid 143.34998 -22.95652)
					(end 143.74368 -23.35022)
				)
				(xy 143.89862 -23.35022) (xy 143.89862 -21.952712)
				(arc
					(start 143.74368 -21.952712)
					(mid 143.34998 -22.34388)
					(end 142.95628 -21.952712)
				)
				(arc
					(start 142.95628 -21.950172)
					(mid 143.34998 -21.556472)
					(end 143.74368 -21.950172)
				)
			)
		)
	)
	(zone
		(layers "In7.Cu" "In9.Cu")
		(hatch none 0.5)
		(connect_pads
			(clearance 0)
		)
		(min_thickness 0.25)
		(keepout
			(tracks not_allowed)
			(vias allowed)
			(pads allowed)
			(copperpour not_allowed)
			(footprints allowed)
		)
		(placement
			(enabled no)
			(sheetname "")
		)
		(fill yes
			(thermal_gap 0.5)
			(thermal_bridge_width 0.5)
			(island_removal_mode 0)
		)
		(polygon
			(pts
				(arc
					(start 379.098556 -21.950172)
					(mid 378.549916 -21.401532)
					(end 378.001276 -21.950172)
				)
				(arc
					(start 378.001276 -23.35022)
					(mid 378.548646 -23.898859)
					(end 379.098556 -23.35276)
				)
				(arc
					(start 378.943616 -23.35276)
					(mid 378.549916 -23.743928)
					(end 378.156216 -23.35276)
				)
				(arc
					(start 378.156216 -23.35022)
					(mid 378.549916 -22.95652)
					(end 378.943616 -23.35022)
				)
				(xy 379.098556 -23.35022) (xy 379.098556 -21.952712)
				(arc
					(start 378.943616 -21.952712)
					(mid 378.549916 -22.34388)
					(end 378.156216 -21.952712)
				)
				(arc
					(start 378.156216 -21.950172)
					(mid 378.549916 -21.556472)
					(end 378.943616 -21.950172)
				)
			)
		)
	)
	(zone
		(layers "In7.Cu" "In9.Cu")
		(hatch none 0.5)
		(connect_pads
			(clearance 0)
		)
		(min_thickness 0.25)
		(keepout
			(tracks not_allowed)
			(vias allowed)
			(pads allowed)
			(copperpour not_allowed)
			(footprints allowed)
		)
		(placement
			(enabled no)
			(sheetname "")
		)
		(fill yes
			(thermal_gap 0.5)
			(thermal_bridge_width 0.5)
			(island_removal_mode 0)
		)
		(polygon
			(pts
				(arc
					(start 136.698736 -21.950172)
					(mid 136.150096 -21.401532)
					(end 135.601456 -21.950172)
				)
				(arc
					(start 135.601456 -23.35022)
					(mid 136.148826 -23.898859)
					(end 136.698736 -23.35276)
				)
				(arc
					(start 136.543796 -23.35276)
					(mid 136.150096 -23.743928)
					(end 135.756396 -23.35276)
				)
				(arc
					(start 135.756396 -23.35022)
					(mid 136.150096 -22.95652)
					(end 136.543796 -23.35022)
				)
				(xy 136.698736 -23.35022) (xy 136.698736 -21.952712)
				(arc
					(start 136.543796 -21.952712)
					(mid 136.150096 -22.34388)
					(end 135.756396 -21.952712)
				)
				(arc
					(start 135.756396 -21.950172)
					(mid 136.150096 -21.556472)
					(end 136.543796 -21.950172)
				)
			)
		)
	)
	(zone
		(layers "In7.Cu" "In9.Cu")
		(hatch none 0.5)
		(connect_pads
			(clearance 0)
		)
		(min_thickness 0.25)
		(keepout
			(tracks not_allowed)
			(vias allowed)
			(pads allowed)
			(copperpour not_allowed)
			(footprints allowed)
		)
		(placement
			(enabled no)
			(sheetname "")
		)
		(fill yes
			(thermal_gap 0.5)
			(thermal_bridge_width 0.5)
			(island_removal_mode 0)
		)
		(polygon
			(pts
				(arc
					(start 115.098576 -21.950172)
					(mid 114.549936 -21.401532)
					(end 114.001296 -21.950172)
				)
				(arc
					(start 114.001296 -23.35022)
					(mid 114.548666 -23.898859)
					(end 115.098576 -23.35276)
				)
				(arc
					(start 114.943636 -23.35276)
					(mid 114.549936 -23.743928)
					(end 114.156236 -23.35276)
				)
				(arc
					(start 114.156236 -23.35022)
					(mid 114.549936 -22.95652)
					(end 114.943636 -23.35022)
				)
				(xy 115.098576 -23.35022) (xy 115.098576 -21.952712)
				(arc
					(start 114.943636 -21.952712)
					(mid 114.549936 -22.34388)
					(end 114.156236 -21.952712)
				)
				(arc
					(start 114.156236 -21.950172)
					(mid 114.549936 -21.556472)
					(end 114.943636 -21.950172)
				)
			)
		)
	)
	(zone
		(layers "In7.Cu" "In9.Cu")
		(hatch none 0.5)
		(connect_pads
			(clearance 0)
		)
		(min_thickness 0.25)
		(keepout
			(tracks not_allowed)
			(vias allowed)
			(pads allowed)
			(copperpour not_allowed)
			(footprints allowed)
		)
		(placement
			(enabled no)
			(sheetname "")
		)
		(fill yes
			(thermal_gap 0.5)
			(thermal_bridge_width 0.5)
			(island_removal_mode 0)
		)
		(polygon
			(pts
				(arc
					(start 111.498634 -21.950172)
					(mid 110.949994 -21.401532)
					(end 110.401354 -21.950172)
				)
				(arc
					(start 110.401354 -23.35022)
					(mid 110.948724 -23.898859)
					(end 111.498634 -23.35276)
				)
				(arc
					(start 111.343694 -23.35276)
					(mid 110.949994 -23.743928)
					(end 110.556294 -23.35276)
				)
				(arc
					(start 110.556294 -23.35022)
					(mid 110.949994 -22.95652)
					(end 111.343694 -23.35022)
				)
				(xy 111.498634 -23.35022) (xy 111.498634 -21.952712)
				(arc
					(start 111.343694 -21.952712)
					(mid 110.949994 -22.34388)
					(end 110.556294 -21.952712)
				)
				(arc
					(start 110.556294 -21.950172)
					(mid 110.949994 -21.556472)
					(end 111.343694 -21.950172)
				)
			)
		)
	)
	(zone
		(layers "In7.Cu" "In9.Cu")
		(hatch none 0.5)
		(connect_pads
			(clearance 0)
		)
		(min_thickness 0.25)
		(keepout
			(tracks not_allowed)
			(vias allowed)
			(pads allowed)
			(copperpour not_allowed)
			(footprints allowed)
		)
		(placement
			(enabled no)
			(sheetname "")
		)
		(fill yes
			(thermal_gap 0.5)
			(thermal_bridge_width 0.5)
			(island_removal_mode 0)
		)
		(polygon
			(pts
				(arc
					(start 122.298714 -21.950172)
					(mid 121.750074 -21.401532)
					(end 121.201434 -21.950172)
				)
				(arc
					(start 121.201434 -23.35022)
					(mid 121.748804 -23.898859)
					(end 122.298714 -23.35276)
				)
				(arc
					(start 122.143774 -23.35276)
					(mid 121.750074 -23.743928)
					(end 121.356374 -23.35276)
				)
				(arc
					(start 121.356374 -23.35022)
					(mid 121.750074 -22.95652)
					(end 122.143774 -23.35022)
				)
				(xy 122.298714 -23.35022) (xy 122.298714 -21.952712)
				(arc
					(start 122.143774 -21.952712)
					(mid 121.750074 -22.34388)
					(end 121.356374 -21.952712)
				)
				(arc
					(start 121.356374 -21.950172)
					(mid 121.750074 -21.556472)
					(end 122.143774 -21.950172)
				)
			)
		)
	)
	(zone
		(layers "In7.Cu" "In9.Cu")
		(hatch none 0.5)
		(connect_pads
			(clearance 0)
		)
		(min_thickness 0.25)
		(keepout
			(tracks not_allowed)
			(vias allowed)
			(pads allowed)
			(copperpour not_allowed)
			(footprints allowed)
		)
		(placement
			(enabled no)
			(sheetname "")
		)
		(fill yes
			(thermal_gap 0.5)
			(thermal_bridge_width 0.5)
			(island_removal_mode 0)
		)
		(polygon
			(pts
				(arc
					(start 382.698752 -21.950172)
					(mid 382.150112 -21.401532)
					(end 381.601472 -21.950172)
				)
				(arc
					(start 381.601472 -23.35022)
					(mid 382.148842 -23.898859)
					(end 382.698752 -23.35276)
				)
				(arc
					(start 382.543812 -23.35276)
					(mid 382.150112 -23.743928)
					(end 381.756412 -23.35276)
				)
				(arc
					(start 381.756412 -23.35022)
					(mid 382.150112 -22.95652)
					(end 382.543812 -23.35022)
				)
				(xy 382.698752 -23.35022) (xy 382.698752 -21.952712)
				(arc
					(start 382.543812 -21.952712)
					(mid 382.150112 -22.34388)
					(end 381.756412 -21.952712)
				)
				(arc
					(start 381.756412 -21.950172)
					(mid 382.150112 -21.556472)
					(end 382.543812 -21.950172)
				)
			)
		)
	)
	(zone
		(layers "In7.Cu" "In9.Cu")
		(hatch none 0.5)
		(connect_pads
			(clearance 0)
		)
		(min_thickness 0.25)
		(keepout
			(tracks not_allowed)
			(vias allowed)
			(pads allowed)
			(copperpour not_allowed)
			(footprints allowed)
		)
		(placement
			(enabled no)
			(sheetname "")
		)
		(fill yes
			(thermal_gap 0.5)
			(thermal_bridge_width 0.5)
			(island_removal_mode 0)
		)
		(polygon
			(pts
				(arc
					(start 386.298694 -21.950172)
					(mid 385.750054 -21.401532)
					(end 385.201414 -21.950172)
				)
				(arc
					(start 385.201414 -23.35022)
					(mid 385.748784 -23.898859)
					(end 386.298694 -23.35276)
				)
				(arc
					(start 386.143754 -23.35276)
					(mid 385.750054 -23.743928)
					(end 385.356354 -23.35276)
				)
				(arc
					(start 385.356354 -23.35022)
					(mid 385.750054 -22.95652)
					(end 386.143754 -23.35022)
				)
				(xy 386.298694 -23.35022) (xy 386.298694 -21.952712)
				(arc
					(start 386.143754 -21.952712)
					(mid 385.750054 -22.34388)
					(end 385.356354 -21.952712)
				)
				(arc
					(start 385.356354 -21.950172)
					(mid 385.750054 -21.556472)
					(end 386.143754 -21.950172)
				)
			)
		)
	)
	(zone
		(layers "In7.Cu" "In9.Cu")
		(hatch none 0.5)
		(connect_pads
			(clearance 0)
		)
		(min_thickness 0.25)
		(keepout
			(tracks not_allowed)
			(vias allowed)
			(pads allowed)
			(copperpour not_allowed)
			(footprints allowed)
		)
		(placement
			(enabled no)
			(sheetname "")
		)
		(fill yes
			(thermal_gap 0.5)
			(thermal_bridge_width 0.5)
			(island_removal_mode 0)
		)
		(polygon
			(pts
				(arc
					(start 377.298712 -20.950174)
					(mid 376.750072 -20.401534)
					(end 376.201432 -20.950174)
				)
				(arc
					(start 376.201432 -22.350222)
					(mid 376.748802 -22.898861)
					(end 377.298712 -22.352762)
				)
				(arc
					(start 377.143772 -22.352762)
					(mid 376.750072 -22.74393)
					(end 376.356372 -22.352762)
				)
				(arc
					(start 376.356372 -22.350222)
					(mid 376.750072 -21.956522)
					(end 377.143772 -22.350222)
				)
				(xy 377.298712 -22.350222) (xy 377.298712 -20.952714)
				(arc
					(start 377.143772 -20.952714)
					(mid 376.750072 -21.343882)
					(end 376.356372 -20.952714)
				)
				(arc
					(start 376.356372 -20.950174)
					(mid 376.750072 -20.556474)
					(end 377.143772 -20.950174)
				)
			)
		)
	)
	(zone
		(layers "In7.Cu" "In9.Cu")
		(hatch none 0.5)
		(connect_pads
			(clearance 0)
		)
		(min_thickness 0.25)
		(keepout
			(tracks not_allowed)
			(vias allowed)
			(pads allowed)
			(copperpour not_allowed)
			(footprints allowed)
		)
		(placement
			(enabled no)
			(sheetname "")
		)
		(fill yes
			(thermal_gap 0.5)
			(thermal_bridge_width 0.5)
			(island_removal_mode 0)
		)
		(polygon
			(pts
				(arc
					(start 389.898636 -21.950172)
					(mid 389.349996 -21.401532)
					(end 388.801356 -21.950172)
				)
				(arc
					(start 388.801356 -23.35022)
					(mid 389.348726 -23.898859)
					(end 389.898636 -23.35276)
				)
				(arc
					(start 389.743696 -23.35276)
					(mid 389.349996 -23.743928)
					(end 388.956296 -23.35276)
				)
				(arc
					(start 388.956296 -23.35022)
					(mid 389.349996 -22.95652)
					(end 389.743696 -23.35022)
				)
				(xy 389.898636 -23.35022) (xy 389.898636 -21.952712)
				(arc
					(start 389.743696 -21.952712)
					(mid 389.349996 -22.34388)
					(end 388.956296 -21.952712)
				)
				(arc
					(start 388.956296 -21.950172)
					(mid 389.349996 -21.556472)
					(end 389.743696 -21.950172)
				)
			)
		)
	)
	(zone
		(layers "In7.Cu" "In9.Cu")
		(hatch none 0.5)
		(connect_pads
			(clearance 0)
		)
		(min_thickness 0.25)
		(keepout
			(tracks not_allowed)
			(vias allowed)
			(pads allowed)
			(copperpour not_allowed)
			(footprints allowed)
		)
		(placement
			(enabled no)
			(sheetname "")
		)
		(fill yes
			(thermal_gap 0.5)
			(thermal_bridge_width 0.5)
			(island_removal_mode 0)
		)
		(polygon
			(pts
				(arc
					(start 368.29873 -21.950172)
					(mid 367.75009 -21.401532)
					(end 367.20145 -21.950172)
				)
				(arc
					(start 367.20145 -23.35022)
					(mid 367.74882 -23.898859)
					(end 368.29873 -23.35276)
				)
				(arc
					(start 368.14379 -23.35276)
					(mid 367.75009 -23.743928)
					(end 367.35639 -23.35276)
				)
				(arc
					(start 367.35639 -23.35022)
					(mid 367.75009 -22.95652)
					(end 368.14379 -23.35022)
				)
				(xy 368.29873 -23.35022) (xy 368.29873 -21.952712)
				(arc
					(start 368.14379 -21.952712)
					(mid 367.75009 -22.34388)
					(end 367.35639 -21.952712)
				)
				(arc
					(start 367.35639 -21.950172)
					(mid 367.75009 -21.556472)
					(end 368.14379 -21.950172)
				)
			)
		)
	)
	(zone
		(layers "In7.Cu" "In9.Cu")
		(hatch none 0.5)
		(connect_pads
			(clearance 0)
		)
		(min_thickness 0.25)
		(keepout
			(tracks not_allowed)
			(vias allowed)
			(pads allowed)
			(copperpour not_allowed)
			(footprints allowed)
		)
		(placement
			(enabled no)
			(sheetname "")
		)
		(fill yes
			(thermal_gap 0.5)
			(thermal_bridge_width 0.5)
			(island_removal_mode 0)
		)
		(polygon
			(pts
				(arc
					(start 366.498632 -20.950174)
					(mid 365.949992 -20.401534)
					(end 365.401352 -20.950174)
				)
				(arc
					(start 365.401352 -22.350222)
					(mid 365.948722 -22.898861)
					(end 366.498632 -22.352762)
				)
				(arc
					(start 366.343692 -22.352762)
					(mid 365.949992 -22.74393)
					(end 365.556292 -22.352762)
				)
				(arc
					(start 365.556292 -22.350222)
					(mid 365.949992 -21.956522)
					(end 366.343692 -22.350222)
				)
				(xy 366.498632 -22.350222) (xy 366.498632 -20.952714)
				(arc
					(start 366.343692 -20.952714)
					(mid 365.949992 -21.343882)
					(end 365.556292 -20.952714)
				)
				(arc
					(start 365.556292 -20.950174)
					(mid 365.949992 -20.556474)
					(end 366.343692 -20.950174)
				)
			)
		)
	)
	(zone
		(layers "In7.Cu" "In9.Cu")
		(hatch none 0.5)
		(connect_pads
			(clearance 0)
		)
		(min_thickness 0.25)
		(keepout
			(tracks not_allowed)
			(vias allowed)
			(pads allowed)
			(copperpour not_allowed)
			(footprints allowed)
		)
		(placement
			(enabled no)
			(sheetname "")
		)
		(fill yes
			(thermal_gap 0.5)
			(thermal_bridge_width 0.5)
			(island_removal_mode 0)
		)
		(polygon
			(pts
				(arc
					(start 113.298732 -20.950174)
					(mid 112.750092 -20.401534)
					(end 112.201452 -20.950174)
				)
				(arc
					(start 112.201452 -22.350222)
					(mid 112.748822 -22.898861)
					(end 113.298732 -22.352762)
				)
				(arc
					(start 113.143792 -22.352762)
					(mid 112.750092 -22.74393)
					(end 112.356392 -22.352762)
				)
				(arc
					(start 112.356392 -22.350222)
					(mid 112.750092 -21.956522)
					(end 113.143792 -22.350222)
				)
				(xy 113.298732 -22.350222) (xy 113.298732 -20.952714)
				(arc
					(start 113.143792 -20.952714)
					(mid 112.750092 -21.343882)
					(end 112.356392 -20.952714)
				)
				(arc
					(start 112.356392 -20.950174)
					(mid 112.750092 -20.556474)
					(end 113.143792 -20.950174)
				)
			)
		)
	)
	(zone
		(layers "In7.Cu" "In9.Cu")
		(hatch none 0.5)
		(connect_pads
			(clearance 0)
		)
		(min_thickness 0.25)
		(keepout
			(tracks not_allowed)
			(vias allowed)
			(pads allowed)
			(copperpour not_allowed)
			(footprints allowed)
		)
		(placement
			(enabled no)
			(sheetname "")
		)
		(fill yes
			(thermal_gap 0.5)
			(thermal_bridge_width 0.5)
			(island_removal_mode 0)
		)
		(polygon
			(pts
				(arc
					(start 362.89869 -20.950174)
					(mid 362.35005 -20.401534)
					(end 361.80141 -20.950174)
				)
				(arc
					(start 361.80141 -22.350222)
					(mid 362.34878 -22.898861)
					(end 362.89869 -22.352762)
				)
				(arc
					(start 362.74375 -22.352762)
					(mid 362.35005 -22.74393)
					(end 361.95635 -22.352762)
				)
				(arc
					(start 361.95635 -22.350222)
					(mid 362.35005 -21.956522)
					(end 362.74375 -22.350222)
				)
				(xy 362.89869 -22.350222) (xy 362.89869 -20.952714)
				(arc
					(start 362.74375 -20.952714)
					(mid 362.35005 -21.343882)
					(end 361.95635 -20.952714)
				)
				(arc
					(start 361.95635 -20.950174)
					(mid 362.35005 -20.556474)
					(end 362.74375 -20.950174)
				)
			)
		)
	)
	(zone
		(layers "In7.Cu" "In9.Cu")
		(hatch none 0.5)
		(connect_pads
			(clearance 0)
		)
		(min_thickness 0.25)
		(keepout
			(tracks not_allowed)
			(vias allowed)
			(pads allowed)
			(copperpour not_allowed)
			(footprints allowed)
		)
		(placement
			(enabled no)
			(sheetname "")
		)
		(fill yes
			(thermal_gap 0.5)
			(thermal_bridge_width 0.5)
			(island_removal_mode 0)
		)
		(polygon
			(pts
				(arc
					(start 133.09854 -21.950172)
					(mid 132.5499 -21.401532)
					(end 132.00126 -21.950172)
				)
				(arc
					(start 132.00126 -23.35022)
					(mid 132.54863 -23.898859)
					(end 133.09854 -23.35276)
				)
				(arc
					(start 132.9436 -23.35276)
					(mid 132.5499 -23.743928)
					(end 132.1562 -23.35276)
				)
				(arc
					(start 132.1562 -23.35022)
					(mid 132.5499 -22.95652)
					(end 132.9436 -23.35022)
				)
				(xy 133.09854 -23.35022) (xy 133.09854 -21.952712)
				(arc
					(start 132.9436 -21.952712)
					(mid 132.5499 -22.34388)
					(end 132.1562 -21.952712)
				)
				(arc
					(start 132.1562 -21.950172)
					(mid 132.5499 -21.556472)
					(end 132.9436 -21.950172)
				)
			)
		)
	)
	(zone
		(layers "In7.Cu" "In9.Cu")
		(hatch none 0.5)
		(connect_pads
			(clearance 0)
		)
		(min_thickness 0.25)
		(keepout
			(tracks not_allowed)
			(vias allowed)
			(pads allowed)
			(copperpour not_allowed)
			(footprints allowed)
		)
		(placement
			(enabled no)
			(sheetname "")
		)
		(fill yes
			(thermal_gap 0.5)
			(thermal_bridge_width 0.5)
			(island_removal_mode 0)
		)
		(polygon
			(pts
				(arc
					(start 138.49858 -20.950174)
					(mid 137.94994 -20.401534)
					(end 137.4013 -20.950174)
				)
				(arc
					(start 137.4013 -22.350222)
					(mid 137.94867 -22.898861)
					(end 138.49858 -22.352762)
				)
				(arc
					(start 138.34364 -22.352762)
					(mid 137.94994 -22.74393)
					(end 137.55624 -22.352762)
				)
				(arc
					(start 137.55624 -22.350222)
					(mid 137.94994 -21.956522)
					(end 138.34364 -22.350222)
				)
				(xy 138.49858 -22.350222) (xy 138.49858 -20.952714)
				(arc
					(start 138.34364 -20.952714)
					(mid 137.94994 -21.343882)
					(end 137.55624 -20.952714)
				)
				(arc
					(start 137.55624 -20.950174)
					(mid 137.94994 -20.556474)
					(end 138.34364 -20.950174)
				)
			)
		)
	)
	(zone
		(layers "In7.Cu" "In9.Cu")
		(hatch none 0.5)
		(connect_pads
			(clearance 0)
		)
		(min_thickness 0.25)
		(keepout
			(tracks not_allowed)
			(vias allowed)
			(pads allowed)
			(copperpour not_allowed)
			(footprints allowed)
		)
		(placement
			(enabled no)
			(sheetname "")
		)
		(fill yes
			(thermal_gap 0.5)
			(thermal_bridge_width 0.5)
			(island_removal_mode 0)
		)
		(polygon
			(pts
				(arc
					(start 357.49865 -21.950172)
					(mid 356.95001 -21.401532)
					(end 356.40137 -21.950172)
				)
				(arc
					(start 356.40137 -23.35022)
					(mid 356.94874 -23.898859)
					(end 357.49865 -23.35276)
				)
				(arc
					(start 357.34371 -23.35276)
					(mid 356.95001 -23.743928)
					(end 356.55631 -23.35276)
				)
				(arc
					(start 356.55631 -23.35022)
					(mid 356.95001 -22.95652)
					(end 357.34371 -23.35022)
				)
				(xy 357.49865 -23.35022) (xy 357.49865 -21.952712)
				(arc
					(start 357.34371 -21.952712)
					(mid 356.95001 -22.34388)
					(end 356.55631 -21.952712)
				)
				(arc
					(start 356.55631 -21.950172)
					(mid 356.95001 -21.556472)
					(end 357.34371 -21.950172)
				)
			)
		)
	)
	(zone
		(layers "In7.Cu" "In9.Cu")
		(hatch none 0.5)
		(connect_pads
			(clearance 0)
		)
		(min_thickness 0.25)
		(keepout
			(tracks not_allowed)
			(vias allowed)
			(pads allowed)
			(copperpour not_allowed)
			(footprints allowed)
		)
		(placement
			(enabled no)
			(sheetname "")
		)
		(fill yes
			(thermal_gap 0.5)
			(thermal_bridge_width 0.5)
			(island_removal_mode 0)
		)
		(polygon
			(pts
				(arc
					(start 380.898654 -20.950174)
					(mid 380.350014 -20.401534)
					(end 379.801374 -20.950174)
				)
				(arc
					(start 379.801374 -22.350222)
					(mid 380.348744 -22.898861)
					(end 380.898654 -22.352762)
				)
				(arc
					(start 380.743714 -22.352762)
					(mid 380.350014 -22.74393)
					(end 379.956314 -22.352762)
				)
				(arc
					(start 379.956314 -22.350222)
					(mid 380.350014 -21.956522)
					(end 380.743714 -22.350222)
				)
				(xy 380.898654 -22.350222) (xy 380.898654 -20.952714)
				(arc
					(start 380.743714 -20.952714)
					(mid 380.350014 -21.343882)
					(end 379.956314 -20.952714)
				)
				(arc
					(start 379.956314 -20.950174)
					(mid 380.350014 -20.556474)
					(end 380.743714 -20.950174)
				)
			)
		)
	)
	(zone
		(layers "In7.Cu" "In9.Cu")
		(hatch none 0.5)
		(connect_pads
			(clearance 0)
		)
		(min_thickness 0.25)
		(keepout
			(tracks not_allowed)
			(vias allowed)
			(pads allowed)
			(copperpour not_allowed)
			(footprints allowed)
		)
		(placement
			(enabled no)
			(sheetname "")
		)
		(fill yes
			(thermal_gap 0.5)
			(thermal_bridge_width 0.5)
			(island_removal_mode 0)
		)
		(polygon
			(pts
				(arc
					(start 361.098592 -21.950172)
					(mid 360.549952 -21.401532)
					(end 360.001312 -21.950172)
				)
				(arc
					(start 360.001312 -23.35022)
					(mid 360.548682 -23.898859)
					(end 361.098592 -23.35276)
				)
				(arc
					(start 360.943652 -23.35276)
					(mid 360.549952 -23.743928)
					(end 360.156252 -23.35276)
				)
				(arc
					(start 360.156252 -23.35022)
					(mid 360.549952 -22.95652)
					(end 360.943652 -23.35022)
				)
				(xy 361.098592 -23.35022) (xy 361.098592 -21.952712)
				(arc
					(start 360.943652 -21.952712)
					(mid 360.549952 -22.34388)
					(end 360.156252 -21.952712)
				)
				(arc
					(start 360.156252 -21.950172)
					(mid 360.549952 -21.556472)
					(end 360.943652 -21.950172)
				)
			)
		)
	)
	(zone
		(layers "In7.Cu" "In9.Cu")
		(hatch none 0.5)
		(connect_pads
			(clearance 0)
		)
		(min_thickness 0.25)
		(keepout
			(tracks not_allowed)
			(vias allowed)
			(pads allowed)
			(copperpour not_allowed)
			(footprints allowed)
		)
		(placement
			(enabled no)
			(sheetname "")
		)
		(fill yes
			(thermal_gap 0.5)
			(thermal_bridge_width 0.5)
			(island_removal_mode 0)
		)
		(polygon
			(pts
				(arc
					(start 120.498616 -20.950174)
					(mid 119.949976 -20.401534)
					(end 119.401336 -20.950174)
				)
				(arc
					(start 119.401336 -22.350222)
					(mid 119.948706 -22.898861)
					(end 120.498616 -22.352762)
				)
				(arc
					(start 120.343676 -22.352762)
					(mid 119.949976 -22.74393)
					(end 119.556276 -22.352762)
				)
				(arc
					(start 119.556276 -22.350222)
					(mid 119.949976 -21.956522)
					(end 120.343676 -22.350222)
				)
				(xy 120.498616 -22.350222) (xy 120.498616 -20.952714)
				(arc
					(start 120.343676 -20.952714)
					(mid 119.949976 -21.343882)
					(end 119.556276 -20.952714)
				)
				(arc
					(start 119.556276 -20.950174)
					(mid 119.949976 -20.556474)
					(end 120.343676 -20.950174)
				)
			)
		)
	)
	(zone
		(layers "In7.Cu" "In9.Cu")
		(hatch none 0.5)
		(connect_pads
			(clearance 0)
		)
		(min_thickness 0.25)
		(keepout
			(tracks not_allowed)
			(vias allowed)
			(pads allowed)
			(copperpour not_allowed)
			(footprints allowed)
		)
		(placement
			(enabled no)
			(sheetname "")
		)
		(fill yes
			(thermal_gap 0.5)
			(thermal_bridge_width 0.5)
			(island_removal_mode 0)
		)
		(polygon
			(pts
				(arc
					(start 134.898638 -20.950174)
					(mid 134.349998 -20.401534)
					(end 133.801358 -20.950174)
				)
				(arc
					(start 133.801358 -22.350222)
					(mid 134.348728 -22.898861)
					(end 134.898638 -22.352762)
				)
				(arc
					(start 134.743698 -22.352762)
					(mid 134.349998 -22.74393)
					(end 133.956298 -22.352762)
				)
				(arc
					(start 133.956298 -22.350222)
					(mid 134.349998 -21.956522)
					(end 134.743698 -22.350222)
				)
				(xy 134.898638 -22.350222) (xy 134.898638 -20.952714)
				(arc
					(start 134.743698 -20.952714)
					(mid 134.349998 -21.343882)
					(end 133.956298 -20.952714)
				)
				(arc
					(start 133.956298 -20.950174)
					(mid 134.349998 -20.556474)
					(end 134.743698 -20.950174)
				)
			)
		)
	)
	(zone
		(layers "In7.Cu" "In9.Cu")
		(hatch none 0.5)
		(connect_pads
			(clearance 0)
		)
		(min_thickness 0.25)
		(keepout
			(tracks not_allowed)
			(vias allowed)
			(pads allowed)
			(copperpour not_allowed)
			(footprints allowed)
		)
		(placement
			(enabled no)
			(sheetname "")
		)
		(fill yes
			(thermal_gap 0.5)
			(thermal_bridge_width 0.5)
			(island_removal_mode 0)
		)
		(polygon
			(pts
				(arc
					(start 142.098522 -20.950174)
					(mid 141.549882 -20.401534)
					(end 141.001242 -20.950174)
				)
				(arc
					(start 141.001242 -22.350222)
					(mid 141.548612 -22.898861)
					(end 142.098522 -22.352762)
				)
				(arc
					(start 141.943582 -22.352762)
					(mid 141.549882 -22.74393)
					(end 141.156182 -22.352762)
				)
				(arc
					(start 141.156182 -22.350222)
					(mid 141.549882 -21.956522)
					(end 141.943582 -22.350222)
				)
				(xy 142.098522 -22.350222) (xy 142.098522 -20.952714)
				(arc
					(start 141.943582 -20.952714)
					(mid 141.549882 -21.343882)
					(end 141.156182 -20.952714)
				)
				(arc
					(start 141.156182 -20.950174)
					(mid 141.549882 -20.556474)
					(end 141.943582 -20.950174)
				)
			)
		)
	)
	(zone
		(layers "In7.Cu" "In9.Cu")
		(hatch none 0.5)
		(connect_pads
			(clearance 0)
		)
		(min_thickness 0.25)
		(keepout
			(tracks not_allowed)
			(vias allowed)
			(pads allowed)
			(copperpour not_allowed)
			(footprints allowed)
		)
		(placement
			(enabled no)
			(sheetname "")
		)
		(fill yes
			(thermal_gap 0.5)
			(thermal_bridge_width 0.5)
			(island_removal_mode 0)
		)
		(polygon
			(pts
				(arc
					(start 109.698536 -20.950174)
					(mid 109.149896 -20.401534)
					(end 108.601256 -20.950174)
				)
				(arc
					(start 108.601256 -22.350222)
					(mid 109.148626 -22.898861)
					(end 109.698536 -22.352762)
				)
				(arc
					(start 109.543596 -22.352762)
					(mid 109.149896 -22.74393)
					(end 108.756196 -22.352762)
				)
				(arc
					(start 108.756196 -22.350222)
					(mid 109.149896 -21.956522)
					(end 109.543596 -22.350222)
				)
				(xy 109.698536 -22.350222) (xy 109.698536 -20.952714)
				(arc
					(start 109.543596 -20.952714)
					(mid 109.149896 -21.343882)
					(end 108.756196 -20.952714)
				)
				(arc
					(start 108.756196 -20.950174)
					(mid 109.149896 -20.556474)
					(end 109.543596 -20.950174)
				)
			)
		)
	)
	(zone
		(layers "In7.Cu" "In9.Cu")
		(hatch none 0.5)
		(connect_pads
			(clearance 0)
		)
		(min_thickness 0.25)
		(keepout
			(tracks not_allowed)
			(vias allowed)
			(pads allowed)
			(copperpour not_allowed)
			(footprints allowed)
		)
		(placement
			(enabled no)
			(sheetname "")
		)
		(fill yes
			(thermal_gap 0.5)
			(thermal_bridge_width 0.5)
			(island_removal_mode 0)
		)
		(polygon
			(pts
				(arc
					(start 355.698552 -20.950174)
					(mid 355.149912 -20.401534)
					(end 354.601272 -20.950174)
				)
				(arc
					(start 354.601272 -22.350222)
					(mid 355.148642 -22.898861)
					(end 355.698552 -22.352762)
				)
				(arc
					(start 355.543612 -22.352762)
					(mid 355.149912 -22.74393)
					(end 354.756212 -22.352762)
				)
				(arc
					(start 354.756212 -22.350222)
					(mid 355.149912 -21.956522)
					(end 355.543612 -22.350222)
				)
				(xy 355.698552 -22.350222) (xy 355.698552 -20.952714)
				(arc
					(start 355.543612 -20.952714)
					(mid 355.149912 -21.343882)
					(end 354.756212 -20.952714)
				)
				(arc
					(start 354.756212 -20.950174)
					(mid 355.149912 -20.556474)
					(end 355.543612 -20.950174)
				)
			)
		)
	)
	(zone
		(layers "In7.Cu" "In9.Cu")
		(hatch none 0.5)
		(connect_pads
			(clearance 0)
		)
		(min_thickness 0.25)
		(keepout
			(tracks not_allowed)
			(vias allowed)
			(pads allowed)
			(copperpour not_allowed)
			(footprints allowed)
		)
		(placement
			(enabled no)
			(sheetname "")
		)
		(fill yes
			(thermal_gap 0.5)
			(thermal_bridge_width 0.5)
			(island_removal_mode 0)
		)
		(polygon
			(pts
				(arc
					(start 116.898674 -20.950174)
					(mid 116.350034 -20.401534)
					(end 115.801394 -20.950174)
				)
				(arc
					(start 115.801394 -22.350222)
					(mid 116.348764 -22.898861)
					(end 116.898674 -22.352762)
				)
				(arc
					(start 116.743734 -22.352762)
					(mid 116.350034 -22.74393)
					(end 115.956334 -22.352762)
				)
				(arc
					(start 115.956334 -22.350222)
					(mid 116.350034 -21.956522)
					(end 116.743734 -22.350222)
				)
				(xy 116.898674 -22.350222) (xy 116.898674 -20.952714)
				(arc
					(start 116.743734 -20.952714)
					(mid 116.350034 -21.343882)
					(end 115.956334 -20.952714)
				)
				(arc
					(start 115.956334 -20.950174)
					(mid 116.350034 -20.556474)
					(end 116.743734 -20.950174)
				)
			)
		)
	)
	(zone
		(layers "In7.Cu" "In9.Cu")
		(hatch none 0.5)
		(connect_pads
			(clearance 0)
		)
		(min_thickness 0.25)
		(keepout
			(tracks not_allowed)
			(vias allowed)
			(pads allowed)
			(copperpour not_allowed)
			(footprints allowed)
		)
		(placement
			(enabled no)
			(sheetname "")
		)
		(fill yes
			(thermal_gap 0.5)
			(thermal_bridge_width 0.5)
			(island_removal_mode 0)
		)
		(polygon
			(pts
				(arc
					(start 384.498596 -20.950174)
					(mid 383.949956 -20.401534)
					(end 383.401316 -20.950174)
				)
				(arc
					(start 383.401316 -22.350222)
					(mid 383.948686 -22.898861)
					(end 384.498596 -22.352762)
				)
				(arc
					(start 384.343656 -22.352762)
					(mid 383.949956 -22.74393)
					(end 383.556256 -22.352762)
				)
				(arc
					(start 383.556256 -22.350222)
					(mid 383.949956 -21.956522)
					(end 384.343656 -22.350222)
				)
				(xy 384.498596 -22.350222) (xy 384.498596 -20.952714)
				(arc
					(start 384.343656 -20.952714)
					(mid 383.949956 -21.343882)
					(end 383.556256 -20.952714)
				)
				(arc
					(start 383.556256 -20.950174)
					(mid 383.949956 -20.556474)
					(end 384.343656 -20.950174)
				)
			)
		)
	)
	(zone
		(layers "In7.Cu" "In9.Cu")
		(hatch none 0.5)
		(connect_pads
			(clearance 0)
		)
		(min_thickness 0.25)
		(keepout
			(tracks not_allowed)
			(vias allowed)
			(pads allowed)
			(copperpour not_allowed)
			(footprints allowed)
		)
		(placement
			(enabled no)
			(sheetname "")
		)
		(fill yes
			(thermal_gap 0.5)
			(thermal_bridge_width 0.5)
			(island_removal_mode 0)
		)
		(polygon
			(pts
				(arc
					(start 359.298748 -20.950174)
					(mid 358.750108 -20.401534)
					(end 358.201468 -20.950174)
				)
				(arc
					(start 358.201468 -22.350222)
					(mid 358.748838 -22.898861)
					(end 359.298748 -22.352762)
				)
				(arc
					(start 359.143808 -22.352762)
					(mid 358.750108 -22.74393)
					(end 358.356408 -22.352762)
				)
				(arc
					(start 358.356408 -22.350222)
					(mid 358.750108 -21.956522)
					(end 359.143808 -22.350222)
				)
				(xy 359.298748 -22.350222) (xy 359.298748 -20.952714)
				(arc
					(start 359.143808 -20.952714)
					(mid 358.750108 -21.343882)
					(end 358.356408 -20.952714)
				)
				(arc
					(start 358.356408 -20.950174)
					(mid 358.750108 -20.556474)
					(end 359.143808 -20.950174)
				)
			)
		)
	)
	(zone
		(layers "In7.Cu" "In9.Cu")
		(hatch none 0.5)
		(connect_pads
			(clearance 0)
		)
		(min_thickness 0.25)
		(keepout
			(tracks not_allowed)
			(vias allowed)
			(pads allowed)
			(copperpour not_allowed)
			(footprints allowed)
		)
		(placement
			(enabled no)
			(sheetname "")
		)
		(fill yes
			(thermal_gap 0.5)
			(thermal_bridge_width 0.5)
			(island_removal_mode 0)
		)
		(polygon
			(pts
				(arc
					(start 118.698518 -21.950172)
					(mid 118.149878 -21.401532)
					(end 117.601238 -21.950172)
				)
				(arc
					(start 117.601238 -23.35022)
					(mid 118.148608 -23.898859)
					(end 118.698518 -23.35276)
				)
				(arc
					(start 118.543578 -23.35276)
					(mid 118.149878 -23.743928)
					(end 117.756178 -23.35276)
				)
				(arc
					(start 117.756178 -23.35022)
					(mid 118.149878 -22.95652)
					(end 118.543578 -23.35022)
				)
				(xy 118.698518 -23.35022) (xy 118.698518 -21.952712)
				(arc
					(start 118.543578 -21.952712)
					(mid 118.149878 -22.34388)
					(end 117.756178 -21.952712)
				)
				(arc
					(start 117.756178 -21.950172)
					(mid 118.149878 -21.556472)
					(end 118.543578 -21.950172)
				)
			)
		)
	)
	(zone
		(layers "In7.Cu" "In9.Cu")
		(hatch none 0.5)
		(connect_pads
			(clearance 0)
		)
		(min_thickness 0.25)
		(keepout
			(tracks not_allowed)
			(vias allowed)
			(pads allowed)
			(copperpour not_allowed)
			(footprints allowed)
		)
		(placement
			(enabled no)
			(sheetname "")
		)
		(fill yes
			(thermal_gap 0.5)
			(thermal_bridge_width 0.5)
			(island_removal_mode 0)
		)
		(polygon
			(pts
				(arc
					(start 388.098538 -20.950174)
					(mid 387.549898 -20.401534)
					(end 387.001258 -20.950174)
				)
				(arc
					(start 387.001258 -22.350222)
					(mid 387.548628 -22.898861)
					(end 388.098538 -22.352762)
				)
				(arc
					(start 387.943598 -22.352762)
					(mid 387.549898 -22.74393)
					(end 387.156198 -22.352762)
				)
				(arc
					(start 387.156198 -22.350222)
					(mid 387.549898 -21.956522)
					(end 387.943598 -22.350222)
				)
				(xy 388.098538 -22.350222) (xy 388.098538 -20.952714)
				(arc
					(start 387.943598 -20.952714)
					(mid 387.549898 -21.343882)
					(end 387.156198 -20.952714)
				)
				(arc
					(start 387.156198 -20.950174)
					(mid 387.549898 -20.556474)
					(end 387.943598 -20.950174)
				)
			)
		)
	)
	(zone
		(layers "In7.Cu" "In9.Cu")
		(hatch none 0.5)
		(connect_pads
			(clearance 0)
		)
		(min_thickness 0.25)
		(keepout
			(tracks not_allowed)
			(vias allowed)
			(pads allowed)
			(copperpour not_allowed)
			(footprints allowed)
		)
		(placement
			(enabled no)
			(sheetname "")
		)
		(fill yes
			(thermal_gap 0.5)
			(thermal_bridge_width 0.5)
			(island_removal_mode 0)
		)
		(polygon
			(pts
				(arc
					(start 364.698534 -21.950172)
					(mid 364.149894 -21.401532)
					(end 363.601254 -21.950172)
				)
				(arc
					(start 363.601254 -23.35022)
					(mid 364.148624 -23.898859)
					(end 364.698534 -23.35276)
				)
				(arc
					(start 364.543594 -23.35276)
					(mid 364.149894 -23.743928)
					(end 363.756194 -23.35276)
				)
				(arc
					(start 363.756194 -23.35022)
					(mid 364.149894 -22.95652)
					(end 364.543594 -23.35022)
				)
				(xy 364.698534 -23.35022) (xy 364.698534 -21.952712)
				(arc
					(start 364.543594 -21.952712)
					(mid 364.149894 -22.34388)
					(end 363.756194 -21.952712)
				)
				(arc
					(start 363.756194 -21.950172)
					(mid 364.149894 -21.556472)
					(end 364.543594 -21.950172)
				)
			)
		)
	)
	(zone
		(layer "Cmts.User")
		(hatch none 0.5)
		(connect_pads
			(clearance 0)
		)
		(min_thickness 0.25)
		(keepout
			(tracks allowed)
			(vias allowed)
			(pads allowed)
			(copperpour allowed)
			(footprints allowed)
		)
		(placement
			(enabled no)
			(sheetname "")
		)
		(fill
			(thermal_gap 0.5)
			(thermal_bridge_width 0.5)
			(island_removal_mode 0)
		)
		(polygon
			(pts
				(xy 278.22398 -183.029606) (xy 278.22398 -98.98507) (xy 285.839154 -98.98507) (xy 285.839154 -183.029606)
			)
		)
	)
	(zone
		(layer "Cmts.User")
		(hatch none 0.5)
		(connect_pads
			(clearance 0)
		)
		(min_thickness 0.25)
		(keepout
			(tracks allowed)
			(vias allowed)
			(pads allowed)
			(copperpour allowed)
			(footprints allowed)
		)
		(placement
			(enabled no)
			(sheetname "")
		)
		(fill
			(thermal_gap 0.5)
			(thermal_bridge_width 0.5)
			(island_removal_mode 0)
		)
		(polygon
			(pts
				(xy 271.3228 -331.3938) (xy 271.3228 -330.0476) (xy 273.6342 -330.0476) (xy 273.6342 -331.3938)
			)
		)
	)
	(zone
		(layer "Cmts.User")
		(hatch none 0.5)
		(connect_pads
			(clearance 0)
		)
		(min_thickness 0.25)
		(keepout
			(tracks allowed)
			(vias allowed)
			(pads allowed)
			(copperpour allowed)
			(footprints allowed)
		)
		(placement
			(enabled no)
			(sheetname "")
		)
		(fill
			(thermal_gap 0.5)
			(thermal_bridge_width 0.5)
			(island_removal_mode 0)
		)
		(polygon
			(pts
				(xy 276.347682 -264.83056) (xy 276.347682 -250.443746) (xy 289.31235 -250.443746) (xy 289.31235 -264.83056)
			)
		)
	)
	(zone
		(layer "Cmts.User")
		(hatch none 0.5)
		(connect_pads
			(clearance 0)
		)
		(min_thickness 0.25)
		(keepout
			(tracks allowed)
			(vias allowed)
			(pads allowed)
			(copperpour allowed)
			(footprints allowed)
		)
		(placement
			(enabled no)
			(sheetname "")
		)
		(fill
			(thermal_gap 0.5)
			(thermal_bridge_width 0.5)
			(island_removal_mode 0)
		)
		(polygon
			(pts
				(xy 271.4244 -360.045) (xy 271.4244 -358.902) (xy 273.685 -358.902) (xy 273.685 -360.045)
			)
		)
	)
	(zone
		(layer "Cmts.User")
		(hatch none 0.5)
		(connect_pads
			(clearance 0)
		)
		(min_thickness 0.25)
		(keepout
			(tracks allowed)
			(vias allowed)
			(pads allowed)
			(copperpour allowed)
			(footprints allowed)
		)
		(placement
			(enabled no)
			(sheetname "")
		)
		(fill
			(thermal_gap 0.5)
			(thermal_bridge_width 0.5)
			(island_removal_mode 0)
		)
		(polygon
			(pts
				(xy 271.3228 -336.8548) (xy 271.3228 -335.5086) (xy 273.6342 -335.5086) (xy 273.6342 -336.8548)
			)
		)
	)
	(zone
		(layer "Cmts.User")
		(hatch none 0.5)
		(connect_pads
			(clearance 0)
		)
		(min_thickness 0.25)
		(keepout
			(tracks allowed)
			(vias allowed)
			(pads allowed)
			(copperpour allowed)
			(footprints allowed)
		)
		(placement
			(enabled no)
			(sheetname "")
		)
		(fill
			(thermal_gap 0.5)
			(thermal_bridge_width 0.5)
			(island_removal_mode 0)
		)
		(polygon
			(pts
				(xy 271.3228 -333.2226) (xy 271.3228 -331.8764) (xy 273.6342 -331.8764) (xy 273.6342 -333.2226)
			)
		)
	)
	(zone
		(layer "Cmts.User")
		(hatch none 0.5)
		(connect_pads
			(clearance 0)
		)
		(min_thickness 0.25)
		(keepout
			(tracks allowed)
			(vias allowed)
			(pads allowed)
			(copperpour allowed)
			(footprints allowed)
		)
		(placement
			(enabled no)
			(sheetname "")
		)
		(fill
			(thermal_gap 0.5)
			(thermal_bridge_width 0.5)
			(island_removal_mode 0)
		)
		(polygon
			(pts
				(xy 271.3482 -307.9496) (xy 271.3482 -306.6034) (xy 273.6596 -306.6034) (xy 273.6596 -307.9496)
			)
		)
	)
	(zone
		(layer "Cmts.User")
		(hatch none 0.5)
		(connect_pads
			(clearance 0)
		)
		(min_thickness 0.25)
		(keepout
			(tracks allowed)
			(vias allowed)
			(pads allowed)
			(copperpour allowed)
			(footprints allowed)
		)
		(placement
			(enabled no)
			(sheetname "")
		)
		(fill
			(thermal_gap 0.5)
			(thermal_bridge_width 0.5)
			(island_removal_mode 0)
		)
		(polygon
			(pts
				(xy 271.3228 -315.2394) (xy 271.3228 -313.8932) (xy 273.6342 -313.8932) (xy 273.6342 -315.2394)
			)
		)
	)
	(zone
		(layer "Cmts.User")
		(hatch none 0.5)
		(connect_pads
			(clearance 0)
		)
		(min_thickness 0.25)
		(keepout
			(tracks allowed)
			(vias allowed)
			(pads allowed)
			(copperpour allowed)
			(footprints allowed)
		)
		(placement
			(enabled no)
			(sheetname "")
		)
		(fill
			(thermal_gap 0.5)
			(thermal_bridge_width 0.5)
			(island_removal_mode 0)
		)
		(polygon
			(pts
				(xy 271.3228 -309.7784) (xy 271.3228 -308.4322) (xy 273.6342 -308.4322) (xy 273.6342 -309.7784)
			)
		)
	)
	(zone
		(layer "Cmts.User")
		(hatch none 0.5)
		(connect_pads
			(clearance 0)
		)
		(min_thickness 0.25)
		(keepout
			(tracks allowed)
			(vias allowed)
			(pads allowed)
			(copperpour allowed)
			(footprints allowed)
		)
		(placement
			(enabled no)
			(sheetname "")
		)
		(fill
			(thermal_gap 0.5)
			(thermal_bridge_width 0.5)
			(island_removal_mode 0)
		)
		(polygon
			(pts
				(xy 271.3482 -313.436) (xy 271.3482 -312.0898) (xy 273.6596 -312.0898) (xy 273.6596 -313.436)
			)
		)
	)
	(zone
		(layer "Cmts.User")
		(hatch none 0.5)
		(connect_pads
			(clearance 0)
		)
		(min_thickness 0.25)
		(keepout
			(tracks allowed)
			(vias allowed)
			(pads allowed)
			(copperpour allowed)
			(footprints allowed)
		)
		(placement
			(enabled no)
			(sheetname "")
		)
		(fill
			(thermal_gap 0.5)
			(thermal_bridge_width 0.5)
			(island_removal_mode 0)
		)
		(polygon
			(pts
				(xy 271.210024 -359.860342) (xy 271.210024 -350.167448) (xy 274.136358 -350.167448) (xy 274.136358 -359.860342)
			)
		)
	)
	(zone
		(layer "Cmts.User")
		(hatch none 0.5)
		(connect_pads
			(clearance 0)
		)
		(min_thickness 0.25)
		(keepout
			(tracks allowed)
			(vias allowed)
			(pads allowed)
			(copperpour allowed)
			(footprints allowed)
		)
		(placement
			(enabled no)
			(sheetname "")
		)
		(fill
			(thermal_gap 0.5)
			(thermal_bridge_width 0.5)
			(island_removal_mode 0)
		)
		(polygon
			(pts
				(xy 235.50372 -86.715854) (xy 235.50372 -2.671318) (xy 243.118894 -2.671318) (xy 243.118894 -86.715854)
			)
		)
	)
	(zone
		(layer "Cmts.User")
		(hatch none 0.5)
		(connect_pads
			(clearance 0)
		)
		(min_thickness 0.25)
		(keepout
			(tracks allowed)
			(vias allowed)
			(pads allowed)
			(copperpour allowed)
			(footprints allowed)
		)
		(placement
			(enabled no)
			(sheetname "")
		)
		(fill
			(thermal_gap 0.5)
			(thermal_bridge_width 0.5)
			(island_removal_mode 0)
		)
		(polygon
			(pts
				(xy 108.458 -32.7152) (xy 108.458 -15.621) (xy 144.7292 -15.621) (xy 144.7292 -32.7152)
			)
		)
	)
	(zone
		(layer "Cmts.User")
		(hatch none 0.5)
		(connect_pads
			(clearance 0)
		)
		(min_thickness 0.25)
		(keepout
			(tracks allowed)
			(vias allowed)
			(pads allowed)
			(copperpour allowed)
			(footprints allowed)
		)
		(placement
			(enabled no)
			(sheetname "")
		)
		(fill
			(thermal_gap 0.5)
			(thermal_bridge_width 0.5)
			(island_removal_mode 0)
		)
		(polygon
			(pts
				(xy 274.6248 -359.829354) (xy 274.6248 -359.0544) (xy 271.3736 -359.0544) (xy 271.3736 -358.3432)
				(xy 274.6248 -358.3432) (xy 274.6248 -357.124) (xy 271.3482 -357.124) (xy 271.3482 -356.5398) (xy 274.6248 -356.5398)
				(xy 274.6248 -355.4222) (xy 271.3736 -355.4222) (xy 271.3736 -354.7364) (xy 274.6248 -354.7364)
				(xy 274.6248 -353.5934) (xy 271.399 -353.5934) (xy 271.399 -352.8568) (xy 274.6248 -352.8568) (xy 274.6248 -351.8408)
				(xy 271.399 -351.8408) (xy 271.399 -351.0788) (xy 274.6248 -351.0788) (xy 274.6248 -337.4136) (xy 271.2466 -337.4136)
				(xy 271.2466 -336.7786) (xy 274.6248 -336.7786) (xy 274.6248 -335.5594) (xy 271.2466 -335.5594)
				(xy 271.2466 -335.0006) (xy 274.6248 -335.0006) (xy 274.6248 -333.7052) (xy 271.2974 -333.7052)
				(xy 271.2974 -333.1718) (xy 274.6248 -333.1718) (xy 274.6248 -331.9018) (xy 271.272 -331.9018) (xy 271.272 -331.343)
				(xy 274.6248 -331.343) (xy 274.6248 -330.0984) (xy 271.272 -330.0984) (xy 271.272 -329.5396) (xy 274.6248 -329.5396)
				(xy 274.6248 -315.7982) (xy 271.3482 -315.7982) (xy 271.3482 -315.214) (xy 274.6248 -315.214) (xy 274.6248 -313.944)
				(xy 271.2466 -313.944) (xy 271.2466 -313.4106) (xy 274.6248 -313.4106) (xy 274.6248 -312.1152) (xy 271.2974 -312.1152)
				(xy 271.2974 -311.5818) (xy 274.6248 -311.5818) (xy 274.6248 -310.3626) (xy 271.2974 -310.3626)
				(xy 271.2974 -309.7276) (xy 274.6248 -309.7276) (xy 274.6248 -308.5338) (xy 271.2974 -308.5338)
				(xy 271.2974 -307.8988) (xy 274.6248 -307.8988) (xy 274.6248 -292.1) (xy 290.576 -292.1) (xy 290.576 -359.829354)
			)
		)
	)
	(zone
		(layer "Cmts.User")
		(hatch none 0.5)
		(connect_pads
			(clearance 0)
		)
		(min_thickness 0.25)
		(keepout
			(tracks allowed)
			(vias allowed)
			(pads allowed)
			(copperpour allowed)
			(footprints allowed)
		)
		(placement
			(enabled no)
			(sheetname "")
		)
		(fill
			(thermal_gap 0.5)
			(thermal_bridge_width 0.5)
			(island_removal_mode 0)
		)
		(polygon
			(pts
				(xy 271.4244 -351.155) (xy 271.4244 -349.885) (xy 273.6596 -349.885) (xy 273.6596 -351.155)
			)
		)
	)
	(zone
		(layer "Cmts.User")
		(hatch none 0.5)
		(connect_pads
			(clearance 0)
		)
		(min_thickness 0.25)
		(keepout
			(tracks allowed)
			(vias allowed)
			(pads allowed)
			(copperpour allowed)
			(footprints allowed)
		)
		(placement
			(enabled no)
			(sheetname "")
		)
		(fill
			(thermal_gap 0.5)
			(thermal_bridge_width 0.5)
			(island_removal_mode 0)
		)
		(polygon
			(pts
				(xy 271.3736 -316.9666) (xy 271.3736 -315.6204) (xy 273.685 -315.6204) (xy 273.685 -316.9666)
			)
		)
	)
	(zone
		(layer "Cmts.User")
		(hatch none 0.5)
		(connect_pads
			(clearance 0)
		)
		(min_thickness 0.25)
		(keepout
			(tracks allowed)
			(vias allowed)
			(pads allowed)
			(copperpour allowed)
			(footprints allowed)
		)
		(placement
			(enabled no)
			(sheetname "")
		)
		(fill
			(thermal_gap 0.5)
			(thermal_bridge_width 0.5)
			(island_removal_mode 0)
		)
		(polygon
			(pts
				(xy 271.228312 -338.27974) (xy 271.228312 -328.659744) (xy 273.898614 -328.659744) (xy 273.898614 -338.27974)
			)
		)
	)
	(zone
		(layer "Cmts.User")
		(hatch none 0.5)
		(connect_pads
			(clearance 0)
		)
		(min_thickness 0.25)
		(keepout
			(tracks allowed)
			(vias allowed)
			(pads allowed)
			(copperpour allowed)
			(footprints allowed)
		)
		(placement
			(enabled no)
			(sheetname "")
		)
		(fill
			(thermal_gap 0.5)
			(thermal_bridge_width 0.5)
			(island_removal_mode 0)
		)
		(polygon
			(pts
				(xy 271.3228 -311.6072) (xy 271.3228 -310.261) (xy 273.6342 -310.261) (xy 273.6342 -311.6072)
			)
		)
	)
	(zone
		(layer "Cmts.User")
		(hatch none 0.5)
		(connect_pads
			(clearance 0)
		)
		(min_thickness 0.25)
		(keepout
			(tracks allowed)
			(vias allowed)
			(pads allowed)
			(copperpour allowed)
			(footprints allowed)
		)
		(placement
			(enabled no)
			(sheetname "")
		)
		(fill
			(thermal_gap 0.5)
			(thermal_bridge_width 0.5)
			(island_removal_mode 0)
		)
		(polygon
			(pts
				(xy 278.224234 -86.735158) (xy 278.224234 -10.348722) (xy 280.92527 -10.348722) (xy 281.23896 -10.035032)
				(xy 281.23896 -9.455404) (xy 281.23896 -2.690622) (xy 285.839408 -2.690622) (xy 285.839408 -86.735158)
			)
		)
	)
	(zone
		(layer "Cmts.User")
		(hatch none 0.5)
		(connect_pads
			(clearance 0)
		)
		(min_thickness 0.25)
		(keepout
			(tracks allowed)
			(vias allowed)
			(pads allowed)
			(copperpour allowed)
			(footprints allowed)
		)
		(placement
			(enabled no)
			(sheetname "")
		)
		(fill
			(thermal_gap 0.5)
			(thermal_bridge_width 0.5)
			(island_removal_mode 0)
		)
		(polygon
			(pts
				(xy 354.2792 -32.4104) (xy 354.2792 -15.748) (xy 390.2964 -15.748) (xy 390.2964 -32.4104)
			)
		)
	)
	(zone
		(layer "Cmts.User")
		(hatch none 0.5)
		(connect_pads
			(clearance 0)
		)
		(min_thickness 0.25)
		(keepout
			(tracks allowed)
			(vias allowed)
			(pads allowed)
			(copperpour allowed)
			(footprints allowed)
		)
		(placement
			(enabled no)
			(sheetname "")
		)
		(fill
			(thermal_gap 0.5)
			(thermal_bridge_width 0.5)
			(island_removal_mode 0)
		)
		(polygon
			(pts
				(xy 271.3482 -329.565) (xy 271.3482 -328.2188) (xy 273.6596 -328.2188) (xy 273.6596 -329.565)
			)
		)
	)
	(zone
		(layer "Cmts.User")
		(hatch none 0.5)
		(connect_pads
			(clearance 0)
		)
		(min_thickness 0.25)
		(keepout
			(tracks allowed)
			(vias allowed)
			(pads allowed)
			(copperpour allowed)
			(footprints allowed)
		)
		(placement
			(enabled no)
			(sheetname "")
		)
		(fill
			(thermal_gap 0.5)
			(thermal_bridge_width 0.5)
			(island_removal_mode 0)
		)
		(polygon
			(pts
				(xy 271.399 -358.3686) (xy 271.399 -357.0224) (xy 273.7104 -357.0224) (xy 273.7104 -358.3686)
			)
		)
	)
	(zone
		(layer "Cmts.User")
		(hatch none 0.5)
		(connect_pads
			(clearance 0)
		)
		(min_thickness 0.25)
		(keepout
			(tracks allowed)
			(vias allowed)
			(pads allowed)
			(copperpour allowed)
			(footprints allowed)
		)
		(placement
			(enabled no)
			(sheetname "")
		)
		(fill
			(thermal_gap 0.5)
			(thermal_bridge_width 0.5)
			(island_removal_mode 0)
		)
		(polygon
			(pts
				(xy 271.4498 -352.806) (xy 271.4498 -351.7138) (xy 273.6342 -351.7138) (xy 273.6342 -352.806)
			)
		)
	)
	(zone
		(layer "Cmts.User")
		(hatch none 0.5)
		(connect_pads
			(clearance 0)
		)
		(min_thickness 0.25)
		(keepout
			(tracks allowed)
			(vias allowed)
			(pads allowed)
			(copperpour allowed)
			(footprints allowed)
		)
		(placement
			(enabled no)
			(sheetname "")
		)
		(fill
			(thermal_gap 0.5)
			(thermal_bridge_width 0.5)
			(island_removal_mode 0)
		)
		(polygon
			(pts
				(xy 271.3736 -338.582) (xy 271.3736 -337.2358) (xy 273.685 -337.2358) (xy 273.685 -338.582)
			)
		)
	)
	(zone
		(layer "Cmts.User")
		(hatch none 0.5)
		(connect_pads
			(clearance 0)
		)
		(min_thickness 0.25)
		(keepout
			(tracks allowed)
			(vias allowed)
			(pads allowed)
			(copperpour allowed)
			(footprints allowed)
		)
		(placement
			(enabled no)
			(sheetname "")
		)
		(fill
			(thermal_gap 0.5)
			(thermal_bridge_width 0.5)
			(island_removal_mode 0)
		)
		(polygon
			(pts
				(xy 271.399 -356.5398) (xy 271.399 -355.346) (xy 273.685 -355.346) (xy 273.685 -356.5398)
			)
		)
	)
	(zone
		(layer "Cmts.User")
		(hatch none 0.5)
		(connect_pads
			(clearance 0)
		)
		(min_thickness 0.25)
		(keepout
			(tracks allowed)
			(vias allowed)
			(pads allowed)
			(copperpour allowed)
			(footprints allowed)
		)
		(placement
			(enabled no)
			(sheetname "")
		)
		(fill
			(thermal_gap 0.5)
			(thermal_bridge_width 0.5)
			(island_removal_mode 0)
		)
		(polygon
			(pts
				(xy 271.3482 -335.0514) (xy 271.3482 -333.7052) (xy 273.6596 -333.7052) (xy 273.6596 -335.0514)
			)
		)
	)
	(zone
		(layer "Cmts.User")
		(hatch none 0.5)
		(connect_pads
			(clearance 0)
		)
		(min_thickness 0.25)
		(keepout
			(tracks allowed)
			(vias allowed)
			(pads allowed)
			(copperpour allowed)
			(footprints allowed)
		)
		(placement
			(enabled no)
			(sheetname "")
		)
		(fill
			(thermal_gap 0.5)
			(thermal_bridge_width 0.5)
			(island_removal_mode 0)
		)
		(polygon
			(pts
				(xy 235.519468 -183.0324) (xy 235.519468 -98.987864) (xy 243.134642 -98.987864) (xy 243.134642 -183.0324)
			)
		)
	)
	(zone
		(layer "Cmts.User")
		(hatch none 0.5)
		(connect_pads
			(clearance 0)
		)
		(min_thickness 0.25)
		(keepout
			(tracks allowed)
			(vias allowed)
			(pads allowed)
			(copperpour allowed)
			(footprints allowed)
		)
		(placement
			(enabled no)
			(sheetname "")
		)
		(fill
			(thermal_gap 0.5)
			(thermal_bridge_width 0.5)
			(island_removal_mode 0)
		)
		(polygon
			(pts
				(xy 208.447894 -419.858698) (xy 208.447894 -402.764498) (xy 233.336592 -402.764498) (xy 233.336592 -419.858698)
			)
		)
	)
	(zone
		(layer "Cmts.User")
		(hatch none 0.5)
		(connect_pads
			(clearance 0)
		)
		(min_thickness 0.25)
		(keepout
			(tracks allowed)
			(vias allowed)
			(pads allowed)
			(copperpour allowed)
			(footprints allowed)
		)
		(placement
			(enabled no)
			(sheetname "")
		)
		(fill
			(thermal_gap 0.5)
			(thermal_bridge_width 0.5)
			(island_removal_mode 0)
		)
		(polygon
			(pts
				(xy 271.374616 -316.662562) (xy 271.374616 -306.896262) (xy 273.862038 -306.896262) (xy 273.862038 -316.662562)
			)
		)
	)
	(zone
		(layer "Cmts.User")
		(hatch none 0.5)
		(connect_pads
			(clearance 0)
		)
		(min_thickness 0.25)
		(keepout
			(tracks allowed)
			(vias allowed)
			(pads allowed)
			(copperpour allowed)
			(footprints allowed)
		)
		(placement
			(enabled no)
			(sheetname "")
		)
		(fill
			(thermal_gap 0.5)
			(thermal_bridge_width 0.5)
			(island_removal_mode 0)
		)
		(polygon
			(pts
				(xy 273.6342 -354.6094) (xy 273.6342 -353.5426) (xy 271.399 -353.5426) (xy 271.399 -354.6094)
			)
		)
	)
	(zone
		(layer "In9.Cu")
		(hatch none 0.5)
		(connect_pads
			(clearance 0)
		)
		(min_thickness 0.25)
		(keepout
			(tracks not_allowed)
			(vias allowed)
			(pads allowed)
			(copperpour not_allowed)
			(footprints allowed)
		)
		(placement
			(enabled no)
			(sheetname "")
		)
		(fill
			(thermal_gap 0.5)
			(thermal_bridge_width 0.5)
			(island_removal_mode 0)
		)
		(polygon
			(pts
				(arc
					(start 283.563314 -122.872754)
					(mid 282.622752 -123.186444)
					(end 282.936442 -124.127006)
				)
				(xy 283.224986 -124.271278)
				(arc
					(start 283.58592 -124.271278)
					(mid 283.769427 -124.236111)
					(end 283.926788 -124.135388)
				)
				(arc
					(start 283.982922 -124.022866)
					(mid 283.986109 -123.979251)
					(end 283.957522 -123.946158)
				)
				(arc
					(start 283.695648 -123.815094)
					(mid 282.761556 -123.255142)
					(end 283.769562 -123.66752)
				)
				(xy 284.031182 -123.79833) (xy 284.031436 -123.79833) (xy 284.061916 -123.813824)
				(arc
					(start 284.063186 -123.817888)
					(mid 284.142706 -123.926864)
					(end 284.144466 -124.061728)
				)
				(xy 284.14599 -124.066046) (xy 284.052772 -124.252228)
				(arc
					(start 284.038294 -124.257054)
					(mid 283.845435 -124.38318)
					(end 283.620972 -124.435362)
				)
				(xy 283.62021 -124.436378) (xy 283.555186 -124.436378)
				(arc
					(start 283.767022 -124.542296)
					(mid 283.985259 -124.454598)
					(end 284.167834 -124.30633)
				)
				(xy 284.259782 -124.122688)
				(arc
					(start 284.263846 -124.121418)
					(mid 284.372822 -124.041898)
					(end 284.507686 -124.040138)
				)
				(xy 284.512004 -124.038614)
				(arc
					(start 284.80385 -124.184664)
					(mid 285.738843 -124.743595)
					(end 284.73019 -124.332238)
				)
				(arc
					(start 284.468824 -124.201682)
					(mid 284.425209 -124.198495)
					(end 284.392116 -124.227082)
				)
				(xy 284.295088 -124.420884)
				(arc
					(start 284.28315 -124.424694)
					(mid 284.139736 -124.550777)
					(end 283.974032 -124.645674)
				)
				(arc
					(start 284.928056 -125.122686)
					(mid 285.874832 -124.817501)
					(end 285.56331 -123.872752)
				)
			)
		)
	)
	(zone
		(layer "In9.Cu")
		(hatch none 0.5)
		(connect_pads
			(clearance 0)
		)
		(min_thickness 0.25)
		(keepout
			(tracks not_allowed)
			(vias allowed)
			(pads allowed)
			(copperpour not_allowed)
			(footprints allowed)
		)
		(placement
			(enabled no)
			(sheetname "")
		)
		(fill
			(thermal_gap 0.5)
			(thermal_bridge_width 0.5)
			(island_removal_mode 0)
		)
		(polygon
			(pts
				(arc
					(start 440.2201 -158.368492)
					(mid 439.8391 -157.987492)
					(end 439.4581 -158.368492)
				)
				(xy 439.4581 -158.708344) (xy 439.715402 -158.708344)
				(arc
					(start 439.719466 -158.70809)
					(mid 439.739684 -158.704068)
					(end 439.756804 -158.692596)
				)
				(arc
					(start 439.756804 -158.692596)
					(mid 439.76825 -158.675465)
					(end 439.772298 -158.655258)
				)
				(xy 439.772552 -158.651194)
				(arc
					(start 439.772552 -158.62681)
					(mid 439.8391 -158.10174)
					(end 439.905648 -158.62681)
				)
				(xy 439.905648 -158.651194) (xy 439.905902 -158.655258) (xy 439.905648 -158.662116) (xy 439.905648 -158.682944)
				(arc
					(start 439.903362 -158.68523)
					(mid 439.885352 -158.740262)
					(end 439.851292 -158.787084)
				)
				(arc
					(start 439.851292 -158.787084)
					(mid 439.804456 -158.821117)
					(end 439.749438 -158.839154)
				)
				(xy 439.747152 -158.84144) (xy 439.726324 -158.84144) (xy 439.719466 -158.841694) (xy 439.715402 -158.84144)
				(xy 439.4581 -158.84144) (xy 439.4581 -159.038544) (xy 439.715402 -159.038544) (xy 439.719466 -159.03829)
				(xy 439.726324 -159.038544) (xy 439.747152 -159.038544)
				(arc
					(start 439.749438 -159.04083)
					(mid 439.80447 -159.05884)
					(end 439.851292 -159.0929)
				)
				(arc
					(start 439.851292 -159.0929)
					(mid 439.885325 -159.139736)
					(end 439.903362 -159.194754)
				)
				(xy 439.905648 -159.19704) (xy 439.905648 -159.217868) (xy 439.905902 -159.224726) (xy 439.905648 -159.22879)
				(arc
					(start 439.905648 -159.253174)
					(mid 439.8391 -159.778244)
					(end 439.772552 -159.253174)
				)
				(xy 439.772552 -159.22879)
				(arc
					(start 439.772298 -159.224726)
					(mid 439.768276 -159.204508)
					(end 439.756804 -159.187388)
				)
				(arc
					(start 439.756804 -159.187388)
					(mid 439.739673 -159.175942)
					(end 439.719466 -159.171894)
				)
				(xy 439.715402 -159.17164) (xy 439.4581 -159.17164)
				(arc
					(start 439.4581 -159.511238)
					(mid 439.838973 -159.892492)
					(end 440.2201 -159.511492)
				)
			)
		)
	)
	(zone
		(layer "In9.Cu")
		(hatch none 0.5)
		(connect_pads
			(clearance 0)
		)
		(min_thickness 0.25)
		(keepout
			(tracks not_allowed)
			(vias allowed)
			(pads allowed)
			(copperpour not_allowed)
			(footprints allowed)
		)
		(placement
			(enabled no)
			(sheetname "")
		)
		(fill
			(thermal_gap 0.5)
			(thermal_bridge_width 0.5)
			(island_removal_mode 0)
		)
		(polygon
			(pts
				(arc
					(start 400.802094 -92.80017)
					(mid 393.675108 -85.673184)
					(end 386.548122 -92.80017)
				)
				(arc
					(start 386.548122 -98.800412)
					(mid 393.675108 -105.927144)
					(end 400.802094 -98.800412)
				)
			)
		)
	)
	(zone
		(layer "In9.Cu")
		(hatch none 0.5)
		(connect_pads
			(clearance 0)
		)
		(min_thickness 0.25)
		(keepout
			(tracks not_allowed)
			(vias allowed)
			(pads allowed)
			(copperpour not_allowed)
			(footprints allowed)
		)
		(placement
			(enabled no)
			(sheetname "")
		)
		(fill
			(thermal_gap 0.5)
			(thermal_bridge_width 0.5)
			(island_removal_mode 0)
		)
		(polygon
			(pts
				(arc
					(start 240.871756 -62.577218)
					(mid 239.92498 -62.882403)
					(end 240.236502 -63.827152)
				)
				(xy 240.525046 -63.971424)
				(arc
					(start 240.88598 -63.971424)
					(mid 241.069487 -63.936257)
					(end 241.226848 -63.835534)
				)
				(arc
					(start 241.282982 -63.723012)
					(mid 241.286169 -63.679397)
					(end 241.257582 -63.646304)
				)
				(arc
					(start 240.995708 -63.51524)
					(mid 240.061616 -62.955288)
					(end 241.069622 -63.367666)
				)
				(xy 241.331242 -63.498476) (xy 241.331496 -63.498476) (xy 241.361976 -63.51397)
				(arc
					(start 241.363246 -63.518034)
					(mid 241.442766 -63.62701)
					(end 241.444526 -63.761874)
				)
				(xy 241.44605 -63.766192) (xy 241.352832 -63.952374)
				(arc
					(start 241.338354 -63.9572)
					(mid 241.145495 -64.083326)
					(end 240.921032 -64.135508)
				)
				(xy 240.92027 -64.136524) (xy 240.855246 -64.136524)
				(arc
					(start 241.067082 -64.242442)
					(mid 241.285319 -64.154744)
					(end 241.467894 -64.006476)
				)
				(xy 241.559842 -63.822834)
				(arc
					(start 241.563906 -63.821564)
					(mid 241.672882 -63.742044)
					(end 241.807746 -63.740284)
				)
				(xy 241.812064 -63.73876)
				(arc
					(start 242.10391 -63.88481)
					(mid 243.038903 -64.443741)
					(end 242.03025 -64.032384)
				)
				(arc
					(start 241.768884 -63.901828)
					(mid 241.725269 -63.898641)
					(end 241.692176 -63.927228)
				)
				(xy 241.595148 -64.12103)
				(arc
					(start 241.58321 -64.12484)
					(mid 241.43979 -64.251016)
					(end 241.274092 -64.346074)
				)
				(arc
					(start 242.236498 -64.82715)
					(mid 243.17706 -64.51346)
					(end 242.86337 -63.572898)
				)
			)
		)
	)
	(zone
		(net "MB0_CM_GATE_R")
		(layer "In9.Cu")
		(hatch none 0.5)
		(connect_pads
			(clearance 0.5)
		)
		(min_thickness 0.25)
		(fill yes
			(thermal_gap 0.5)
			(thermal_bridge_width 0.5)
			(island_removal_mode 0)
		)
		(polygon
			(pts
				(xy 158.52013 -135.321548) (xy 161.279332 -135.321548) (xy 165.48862 -139.530836) (xy 165.48862 -142.290038)
				(xy 165.48862 -145.14449) (xy 166.059358 -145.715228) (xy 167.678608 -145.715228) (xy 167.903144 -145.490692)
				(xy 167.903144 -142.399766) (xy 167.902636 -142.399004) (xy 167.902636 -138.968734) (xy 162.439858 -133.505956)
				(xy 159.009334 -133.505956) (xy 153.792682 -133.505956) (xy 152.370282 -132.083556) (xy 152.370282 -129.987294)
				(xy 152.10917 -129.726182) (xy 149.850602 -129.726182) (xy 149.673818 -129.902966) (xy 149.673818 -131.94919)
				(xy 149.673818 -132.849874) (xy 152.145492 -135.321548)
			)
		)
	)
	(zone
		(layer "In9.Cu")
		(hatch none 0.5)
		(connect_pads
			(clearance 0)
		)
		(min_thickness 0.25)
		(keepout
			(tracks not_allowed)
			(vias allowed)
			(pads allowed)
			(copperpour not_allowed)
			(footprints allowed)
		)
		(placement
			(enabled no)
			(sheetname "")
		)
		(fill
			(thermal_gap 0.5)
			(thermal_bridge_width 0.5)
			(island_removal_mode 0)
		)
		(polygon
			(pts
				(arc
					(start 283.563314 -78.572868)
					(mid 282.622752 -78.886558)
					(end 282.936442 -79.82712)
				)
				(arc
					(start 284.928056 -80.8228)
					(mid 285.874832 -80.517615)
					(end 285.56331 -79.572866)
				)
				(xy 285.274766 -79.428594)
				(arc
					(start 284.913832 -79.428594)
					(mid 284.730325 -79.463761)
					(end 284.572964 -79.564484)
				)
				(arc
					(start 284.51683 -79.677006)
					(mid 284.513643 -79.720621)
					(end 284.54223 -79.753714)
				)
				(arc
					(start 284.804104 -79.884778)
					(mid 285.738196 -80.44473)
					(end 284.73019 -80.032352)
				)
				(xy 284.46857 -79.901542) (xy 284.468316 -79.901542) (xy 284.437836 -79.886048)
				(arc
					(start 284.436566 -79.881984)
					(mid 284.357046 -79.773008)
					(end 284.355286 -79.638144)
				)
				(xy 284.353762 -79.633826) (xy 284.44698 -79.447644)
				(arc
					(start 284.461458 -79.442818)
					(mid 284.654317 -79.316692)
					(end 284.87878 -79.26451)
				)
				(xy 284.879542 -79.263494) (xy 284.944566 -79.263494)
				(arc
					(start 284.73273 -79.157576)
					(mid 284.514493 -79.245274)
					(end 284.331918 -79.393542)
				)
				(xy 284.23997 -79.577184)
				(arc
					(start 284.235906 -79.578454)
					(mid 284.12693 -79.657974)
					(end 283.992066 -79.659734)
				)
				(xy 283.987748 -79.661258)
				(arc
					(start 283.695902 -79.515208)
					(mid 282.760909 -78.956277)
					(end 283.769562 -79.367634)
				)
				(arc
					(start 284.030928 -79.49819)
					(mid 284.074543 -79.501377)
					(end 284.107636 -79.47279)
				)
				(xy 284.204664 -79.278988)
				(arc
					(start 284.216602 -79.275178)
					(mid 284.360022 -79.149002)
					(end 284.52572 -79.053944)
				)
			)
		)
	)
	(zone
		(layer "In9.Cu")
		(hatch none 0.5)
		(connect_pads
			(clearance 0)
		)
		(min_thickness 0.25)
		(keepout
			(tracks not_allowed)
			(vias allowed)
			(pads allowed)
			(copperpour not_allowed)
			(footprints allowed)
		)
		(placement
			(enabled no)
			(sheetname "")
		)
		(fill
			(thermal_gap 0.5)
			(thermal_bridge_width 0.5)
			(island_removal_mode 0)
		)
		(polygon
			(pts
				(arc
					(start 283.563314 -154.87269)
					(mid 282.622752 -155.18638)
					(end 282.936442 -156.126942)
				)
				(xy 283.224986 -156.271214)
				(arc
					(start 283.58592 -156.271214)
					(mid 283.769427 -156.236047)
					(end 283.926788 -156.135324)
				)
				(arc
					(start 283.982922 -156.022802)
					(mid 283.986109 -155.979187)
					(end 283.957522 -155.946094)
				)
				(arc
					(start 283.695648 -155.81503)
					(mid 282.761556 -155.255078)
					(end 283.769562 -155.667456)
				)
				(xy 284.031182 -155.798266) (xy 284.031436 -155.798266) (xy 284.061916 -155.81376)
				(arc
					(start 284.063186 -155.817824)
					(mid 284.142706 -155.9268)
					(end 284.144466 -156.061664)
				)
				(xy 284.14599 -156.065982) (xy 284.052772 -156.252164)
				(arc
					(start 284.038294 -156.25699)
					(mid 283.845435 -156.383116)
					(end 283.620972 -156.435298)
				)
				(xy 283.62021 -156.436314) (xy 283.555186 -156.436314)
				(arc
					(start 283.767022 -156.542232)
					(mid 283.985259 -156.454534)
					(end 284.167834 -156.306266)
				)
				(xy 284.259782 -156.122624)
				(arc
					(start 284.263846 -156.121354)
					(mid 284.372822 -156.041834)
					(end 284.507686 -156.040074)
				)
				(xy 284.512004 -156.03855)
				(arc
					(start 284.80385 -156.1846)
					(mid 285.738843 -156.743531)
					(end 284.73019 -156.332174)
				)
				(arc
					(start 284.468824 -156.201618)
					(mid 284.425209 -156.198431)
					(end 284.392116 -156.227018)
				)
				(xy 284.295088 -156.42082)
				(arc
					(start 284.28315 -156.42463)
					(mid 284.139736 -156.550713)
					(end 283.974032 -156.64561)
				)
				(arc
					(start 284.928056 -157.122622)
					(mid 285.874832 -156.817437)
					(end 285.56331 -155.872688)
				)
			)
		)
	)
	(zone
		(layer "In9.Cu")
		(hatch none 0.5)
		(connect_pads
			(clearance 0)
		)
		(min_thickness 0.25)
		(keepout
			(tracks not_allowed)
			(vias allowed)
			(pads allowed)
			(copperpour not_allowed)
			(footprints allowed)
		)
		(placement
			(enabled no)
			(sheetname "")
		)
		(fill
			(thermal_gap 0.5)
			(thermal_bridge_width 0.5)
			(island_removal_mode 0)
		)
		(polygon
			(pts
				(arc
					(start 351.920302 -158.368492)
					(mid 351.539302 -157.987492)
					(end 351.158302 -158.368492)
				)
				(xy 351.158302 -158.708344) (xy 351.415604 -158.708344)
				(arc
					(start 351.419668 -158.70809)
					(mid 351.439886 -158.704068)
					(end 351.457006 -158.692596)
				)
				(arc
					(start 351.457006 -158.692596)
					(mid 351.468452 -158.675465)
					(end 351.4725 -158.655258)
				)
				(xy 351.4725 -158.651194)
				(arc
					(start 351.4725 -158.62681)
					(mid 351.539302 -158.101676)
					(end 351.606104 -158.62681)
				)
				(xy 351.606104 -158.651194) (xy 351.606104 -158.655258) (xy 351.606104 -158.662116) (xy 351.606104 -158.682944)
				(arc
					(start 351.603564 -158.68523)
					(mid 351.585554 -158.740262)
					(end 351.551494 -158.787084)
				)
				(arc
					(start 351.551494 -158.787084)
					(mid 351.504658 -158.821117)
					(end 351.44964 -158.839154)
				)
				(xy 351.447354 -158.84144) (xy 351.426526 -158.84144) (xy 351.419668 -158.841694) (xy 351.415604 -158.84144)
				(xy 351.158302 -158.84144) (xy 351.158302 -159.038544) (xy 351.415604 -159.038544) (xy 351.419668 -159.03829)
				(xy 351.426526 -159.038544) (xy 351.447354 -159.038544)
				(arc
					(start 351.44964 -159.04083)
					(mid 351.504672 -159.05884)
					(end 351.551494 -159.0929)
				)
				(arc
					(start 351.551494 -159.0929)
					(mid 351.585527 -159.139736)
					(end 351.603564 -159.194754)
				)
				(xy 351.606104 -159.19704) (xy 351.606104 -159.217868) (xy 351.606104 -159.224726) (xy 351.60585 -159.22879)
				(arc
					(start 351.60585 -159.253174)
					(mid 351.539425 -159.778244)
					(end 351.4725 -159.253174)
				)
				(xy 351.4725 -159.22879)
				(arc
					(start 351.4725 -159.224726)
					(mid 351.468478 -159.204508)
					(end 351.457006 -159.187388)
				)
				(arc
					(start 351.457006 -159.187388)
					(mid 351.439875 -159.175942)
					(end 351.419668 -159.171894)
				)
				(xy 351.415604 -159.17164) (xy 351.158302 -159.17164)
				(arc
					(start 351.158302 -159.511238)
					(mid 351.539175 -159.892492)
					(end 351.920302 -159.511492)
				)
			)
		)
	)
	(zone
		(layer "In9.Cu")
		(hatch none 0.5)
		(connect_pads
			(clearance 0)
		)
		(min_thickness 0.25)
		(keepout
			(tracks not_allowed)
			(vias allowed)
			(pads allowed)
			(copperpour not_allowed)
			(footprints allowed)
		)
		(placement
			(enabled no)
			(sheetname "")
		)
		(fill
			(thermal_gap 0.5)
			(thermal_bridge_width 0.5)
			(island_removal_mode 0)
		)
		(polygon
			(pts
				(arc
					(start 446.5701 -43.368468)
					(mid 446.1891 -42.987468)
					(end 445.8081 -43.368468)
				)
				(xy 445.8081 -43.70832) (xy 446.065402 -43.70832)
				(arc
					(start 446.069466 -43.708066)
					(mid 446.089684 -43.704044)
					(end 446.106804 -43.692572)
				)
				(arc
					(start 446.106804 -43.692572)
					(mid 446.11825 -43.675441)
					(end 446.122298 -43.655234)
				)
				(xy 446.122552 -43.65117)
				(arc
					(start 446.122552 -43.626786)
					(mid 446.1891 -43.101716)
					(end 446.255648 -43.626786)
				)
				(xy 446.255648 -43.65117) (xy 446.255902 -43.655234) (xy 446.255648 -43.662092) (xy 446.255648 -43.68292)
				(arc
					(start 446.253362 -43.685206)
					(mid 446.235352 -43.740238)
					(end 446.201292 -43.78706)
				)
				(arc
					(start 446.201292 -43.78706)
					(mid 446.154456 -43.821093)
					(end 446.099438 -43.83913)
				)
				(xy 446.097152 -43.841416) (xy 446.076324 -43.841416) (xy 446.069466 -43.84167) (xy 446.065402 -43.841416)
				(xy 445.8081 -43.841416) (xy 445.8081 -44.03852) (xy 446.065402 -44.03852) (xy 446.069466 -44.038266)
				(xy 446.076324 -44.03852) (xy 446.097152 -44.03852)
				(arc
					(start 446.099438 -44.040806)
					(mid 446.15447 -44.058816)
					(end 446.201292 -44.092876)
				)
				(arc
					(start 446.201292 -44.092876)
					(mid 446.235325 -44.139712)
					(end 446.253362 -44.19473)
				)
				(xy 446.255648 -44.197016) (xy 446.255648 -44.217844) (xy 446.255902 -44.224702) (xy 446.255648 -44.228766)
				(arc
					(start 446.255648 -44.25315)
					(mid 446.1891 -44.77822)
					(end 446.122552 -44.25315)
				)
				(xy 446.122552 -44.228766)
				(arc
					(start 446.122298 -44.224702)
					(mid 446.118276 -44.204484)
					(end 446.106804 -44.187364)
				)
				(arc
					(start 446.106804 -44.187364)
					(mid 446.089673 -44.175918)
					(end 446.069466 -44.17187)
				)
				(xy 446.065402 -44.171616) (xy 445.8081 -44.171616)
				(arc
					(start 445.8081 -44.511214)
					(mid 446.188973 -44.892468)
					(end 446.5701 -44.511468)
				)
			)
		)
	)
	(zone
		(layer "In9.Cu")
		(hatch none 0.5)
		(connect_pads
			(clearance 0)
		)
		(min_thickness 0.25)
		(keepout
			(tracks not_allowed)
			(vias allowed)
			(pads allowed)
			(copperpour not_allowed)
			(footprints allowed)
		)
		(placement
			(enabled no)
			(sheetname "")
		)
		(fill
			(thermal_gap 0.5)
			(thermal_bridge_width 0.5)
			(island_removal_mode 0)
		)
		(polygon
			(pts
				(arc
					(start 283.563314 -66.572892)
					(mid 282.622752 -66.886582)
					(end 282.936442 -67.827144)
				)
				(arc
					(start 284.928056 -68.822824)
					(mid 285.874832 -68.517639)
					(end 285.56331 -67.57289)
				)
				(xy 285.274766 -67.428618)
				(arc
					(start 284.913832 -67.428618)
					(mid 284.730325 -67.463785)
					(end 284.572964 -67.564508)
				)
				(arc
					(start 284.51683 -67.67703)
					(mid 284.513643 -67.720645)
					(end 284.54223 -67.753738)
				)
				(arc
					(start 284.804104 -67.884802)
					(mid 285.738196 -68.444754)
					(end 284.73019 -68.032376)
				)
				(xy 284.46857 -67.901566) (xy 284.468316 -67.901566) (xy 284.437836 -67.886072)
				(arc
					(start 284.436566 -67.882008)
					(mid 284.357046 -67.773032)
					(end 284.355286 -67.638168)
				)
				(xy 284.353762 -67.63385) (xy 284.44698 -67.447668)
				(arc
					(start 284.461458 -67.442842)
					(mid 284.654317 -67.316716)
					(end 284.87878 -67.264534)
				)
				(xy 284.879542 -67.263518) (xy 284.944566 -67.263518)
				(arc
					(start 284.73273 -67.1576)
					(mid 284.514493 -67.245298)
					(end 284.331918 -67.393566)
				)
				(xy 284.23997 -67.577208)
				(arc
					(start 284.235906 -67.578478)
					(mid 284.12693 -67.657998)
					(end 283.992066 -67.659758)
				)
				(xy 283.987748 -67.661282)
				(arc
					(start 283.695902 -67.515232)
					(mid 282.760909 -66.956301)
					(end 283.769562 -67.367658)
				)
				(arc
					(start 284.030928 -67.498214)
					(mid 284.074543 -67.501401)
					(end 284.107636 -67.472814)
				)
				(xy 284.204664 -67.279012)
				(arc
					(start 284.216602 -67.275202)
					(mid 284.360022 -67.149026)
					(end 284.52572 -67.053968)
				)
			)
		)
	)
	(zone
		(layer "In9.Cu")
		(hatch none 0.5)
		(connect_pads
			(clearance 0)
		)
		(min_thickness 0.25)
		(keepout
			(tracks not_allowed)
			(vias allowed)
			(pads allowed)
			(copperpour not_allowed)
			(footprints allowed)
		)
		(placement
			(enabled no)
			(sheetname "")
		)
		(fill
			(thermal_gap 0.5)
			(thermal_bridge_width 0.5)
			(island_removal_mode 0)
		)
		(polygon
			(pts
				(arc
					(start 240.871756 -174.876968)
					(mid 239.92498 -175.182153)
					(end 240.236502 -176.126902)
				)
				(xy 240.525046 -176.271174)
				(arc
					(start 240.88598 -176.271174)
					(mid 241.069487 -176.236007)
					(end 241.226848 -176.135284)
				)
				(arc
					(start 241.282982 -176.022762)
					(mid 241.286169 -175.979147)
					(end 241.257582 -175.946054)
				)
				(arc
					(start 240.995708 -175.81499)
					(mid 240.061616 -175.255038)
					(end 241.069622 -175.667416)
				)
				(xy 241.331242 -175.798226) (xy 241.331496 -175.798226) (xy 241.361976 -175.81372)
				(arc
					(start 241.363246 -175.817784)
					(mid 241.442766 -175.92676)
					(end 241.444526 -176.061624)
				)
				(xy 241.44605 -176.065942) (xy 241.352832 -176.252124)
				(arc
					(start 241.338354 -176.25695)
					(mid 241.145495 -176.383076)
					(end 240.921032 -176.435258)
				)
				(xy 240.92027 -176.436274) (xy 240.855246 -176.436274)
				(arc
					(start 241.067082 -176.542192)
					(mid 241.285319 -176.454494)
					(end 241.467894 -176.306226)
				)
				(xy 241.559842 -176.122584)
				(arc
					(start 241.563906 -176.121314)
					(mid 241.672882 -176.041794)
					(end 241.807746 -176.040034)
				)
				(xy 241.812064 -176.03851)
				(arc
					(start 242.10391 -176.18456)
					(mid 243.038903 -176.743491)
					(end 242.03025 -176.332134)
				)
				(arc
					(start 241.768884 -176.201578)
					(mid 241.725269 -176.198391)
					(end 241.692176 -176.226978)
				)
				(xy 241.595148 -176.42078)
				(arc
					(start 241.58321 -176.42459)
					(mid 241.43979 -176.550766)
					(end 241.274092 -176.645824)
				)
				(arc
					(start 242.236498 -177.1269)
					(mid 243.17706 -176.81321)
					(end 242.86337 -175.872648)
				)
			)
		)
	)
	(zone
		(layer "In9.Cu")
		(hatch none 0.5)
		(connect_pads
			(clearance 0)
		)
		(min_thickness 0.25)
		(keepout
			(tracks not_allowed)
			(vias allowed)
			(pads allowed)
			(copperpour not_allowed)
			(footprints allowed)
		)
		(placement
			(enabled no)
			(sheetname "")
		)
		(fill
			(thermal_gap 0.5)
			(thermal_bridge_width 0.5)
			(island_removal_mode 0)
		)
		(polygon
			(pts
				(arc
					(start 351.920302 -273.368516)
					(mid 351.539302 -272.987516)
					(end 351.158302 -273.368516)
				)
				(xy 351.158302 -273.708368) (xy 351.415604 -273.708368)
				(arc
					(start 351.419668 -273.708114)
					(mid 351.439886 -273.704092)
					(end 351.457006 -273.69262)
				)
				(arc
					(start 351.457006 -273.69262)
					(mid 351.468452 -273.675489)
					(end 351.4725 -273.655282)
				)
				(xy 351.4725 -273.651218)
				(arc
					(start 351.4725 -273.626834)
					(mid 351.539302 -273.1017)
					(end 351.606104 -273.626834)
				)
				(xy 351.606104 -273.651218) (xy 351.606104 -273.655282) (xy 351.606104 -273.66214) (xy 351.606104 -273.682968)
				(arc
					(start 351.603564 -273.685254)
					(mid 351.585554 -273.740286)
					(end 351.551494 -273.787108)
				)
				(arc
					(start 351.551494 -273.787108)
					(mid 351.504658 -273.821141)
					(end 351.44964 -273.839178)
				)
				(xy 351.447354 -273.841464) (xy 351.426526 -273.841464) (xy 351.419668 -273.841718) (xy 351.415604 -273.841464)
				(xy 351.158302 -273.841464) (xy 351.158302 -274.038568) (xy 351.415604 -274.038568) (xy 351.419668 -274.038314)
				(xy 351.426526 -274.038568) (xy 351.447354 -274.038568)
				(arc
					(start 351.44964 -274.040854)
					(mid 351.504672 -274.058864)
					(end 351.551494 -274.092924)
				)
				(arc
					(start 351.551494 -274.092924)
					(mid 351.585527 -274.13976)
					(end 351.603564 -274.194778)
				)
				(xy 351.606104 -274.197064) (xy 351.606104 -274.217892) (xy 351.606104 -274.22475) (xy 351.606104 -274.228814)
				(arc
					(start 351.606104 -274.253198)
					(mid 351.539302 -274.778332)
					(end 351.4725 -274.253198)
				)
				(xy 351.4725 -274.228814)
				(arc
					(start 351.4725 -274.22475)
					(mid 351.468478 -274.204532)
					(end 351.457006 -274.187412)
				)
				(arc
					(start 351.457006 -274.187412)
					(mid 351.439875 -274.175966)
					(end 351.419668 -274.171918)
				)
				(xy 351.415604 -274.171664) (xy 351.158302 -274.171664)
				(arc
					(start 351.158302 -274.511262)
					(mid 351.539175 -274.892516)
					(end 351.920302 -274.511516)
				)
			)
		)
	)
	(zone
		(layer "In9.Cu")
		(hatch none 0.5)
		(connect_pads
			(clearance 0)
		)
		(min_thickness 0.25)
		(keepout
			(tracks not_allowed)
			(vias allowed)
			(pads allowed)
			(copperpour not_allowed)
			(footprints allowed)
		)
		(placement
			(enabled no)
			(sheetname "")
		)
		(fill
			(thermal_gap 0.5)
			(thermal_bridge_width 0.5)
			(island_removal_mode 0)
		)
		(polygon
			(pts
				(arc
					(start 382.698752 -18.350484)
					(mid 382.150239 -17.80159)
					(end 381.601472 -18.35023)
				)
				(arc
					(start 381.601472 -19.750024)
					(mid 382.150112 -20.298664)
					(end 382.698752 -19.750024)
				)
				(xy 382.698752 -19.278854)
				(arc
					(start 382.292606 -19.278854)
					(mid 382.275693 -19.282218)
					(end 382.261364 -19.291808)
				)
				(arc
					(start 382.245616 -19.307556)
					(mid 382.236038 -19.32189)
					(end 382.232662 -19.338798)
				)
				(arc
					(start 382.232662 -19.36496)
					(mid 382.150112 -20.143837)
					(end 382.067562 -19.36496)
				)
				(xy 382.067562 -19.304508)
				(arc
					(start 382.070864 -19.301206)
					(mid 382.083399 -19.258632)
					(end 382.104646 -19.219672)
				)
				(xy 382.104646 -19.214846) (xy 382.168654 -19.150838)
				(arc
					(start 382.17348 -19.150838)
					(mid 382.212454 -19.129626)
					(end 382.255014 -19.117056)
				)
				(xy 382.258316 -19.113754) (xy 382.698752 -19.113754) (xy 382.698752 -18.986754) (xy 382.32715 -18.986754)
				(xy 382.25857 -18.986754)
				(arc
					(start 382.255014 -18.983198)
					(mid 382.21244 -18.970663)
					(end 382.17348 -18.949416)
				)
				(xy 382.168654 -18.949416) (xy 382.104646 -18.885408)
				(arc
					(start 382.104646 -18.880582)
					(mid 382.083434 -18.841608)
					(end 382.070864 -18.799048)
				)
				(xy 382.067562 -18.795746)
				(arc
					(start 382.067562 -18.735294)
					(mid 382.150112 -17.956417)
					(end 382.232662 -18.735294)
				)
				(arc
					(start 382.232662 -18.761456)
					(mid 382.236026 -18.778369)
					(end 382.245616 -18.792698)
				)
				(arc
					(start 382.261364 -18.808446)
					(mid 382.275698 -18.818024)
					(end 382.292606 -18.8214)
				)
				(xy 382.326896 -18.8214) (xy 382.32715 -18.821654) (xy 382.698752 -18.821654)
			)
		)
	)
	(zone
		(layer "In9.Cu")
		(hatch none 0.5)
		(connect_pads
			(clearance 0)
		)
		(min_thickness 0.25)
		(keepout
			(tracks not_allowed)
			(vias allowed)
			(pads allowed)
			(copperpour not_allowed)
			(footprints allowed)
		)
		(placement
			(enabled no)
			(sheetname "")
		)
		(fill
			(thermal_gap 0.5)
			(thermal_bridge_width 0.5)
			(island_removal_mode 0)
		)
		(polygon
			(pts
				(arc
					(start 111.498634 -18.350484)
					(mid 110.950121 -17.80159)
					(end 110.401354 -18.35023)
				)
				(arc
					(start 110.401354 -19.750024)
					(mid 110.949994 -20.298664)
					(end 111.498634 -19.750024)
				)
				(xy 111.498634 -19.278854)
				(arc
					(start 111.092488 -19.278854)
					(mid 111.075575 -19.282218)
					(end 111.061246 -19.291808)
				)
				(arc
					(start 111.045498 -19.307556)
					(mid 111.03592 -19.32189)
					(end 111.032544 -19.338798)
				)
				(arc
					(start 111.032544 -19.36496)
					(mid 110.949994 -20.143837)
					(end 110.867444 -19.36496)
				)
				(xy 110.867444 -19.304508)
				(arc
					(start 110.870746 -19.301206)
					(mid 110.883281 -19.258632)
					(end 110.904528 -19.219672)
				)
				(xy 110.904528 -19.214846) (xy 110.968536 -19.150838)
				(arc
					(start 110.973362 -19.150838)
					(mid 111.012336 -19.129626)
					(end 111.054896 -19.117056)
				)
				(xy 111.058198 -19.113754) (xy 111.498634 -19.113754) (xy 111.498634 -18.986754) (xy 111.127032 -18.986754)
				(xy 111.058452 -18.986754)
				(arc
					(start 111.054896 -18.983198)
					(mid 111.012322 -18.970663)
					(end 110.973362 -18.949416)
				)
				(xy 110.968536 -18.949416) (xy 110.904528 -18.885408)
				(arc
					(start 110.904528 -18.880582)
					(mid 110.883316 -18.841608)
					(end 110.870746 -18.799048)
				)
				(xy 110.867444 -18.795746)
				(arc
					(start 110.867444 -18.735294)
					(mid 110.949994 -17.956417)
					(end 111.032544 -18.735294)
				)
				(arc
					(start 111.032544 -18.761456)
					(mid 111.035908 -18.778369)
					(end 111.045498 -18.792698)
				)
				(arc
					(start 111.061246 -18.808446)
					(mid 111.07558 -18.818024)
					(end 111.092488 -18.8214)
				)
				(xy 111.126778 -18.8214) (xy 111.127032 -18.821654) (xy 111.498634 -18.821654)
			)
		)
	)
	(zone
		(net "P5V_B")
		(layer "In9.Cu")
		(hatch none 0.5)
		(connect_pads
			(clearance 0.5)
		)
		(min_thickness 0.25)
		(fill yes
			(thermal_gap 0.5)
			(thermal_bridge_width 0.5)
			(island_removal_mode 0)
		)
		(polygon
			(pts
				(xy 267.363956 9.747758) (xy 267.363956 18.857468) (xy 267.933424 19.426936) (xy 271.789652 19.426936)
				(xy 272.125948 19.09064) (xy 272.125948 9.902952) (xy 271.272 9.049004) (xy 268.06271 9.049004)
			)
		)
	)
	(zone
		(layer "In9.Cu")
		(hatch none 0.5)
		(connect_pads
			(clearance 0)
		)
		(min_thickness 0.25)
		(keepout
			(tracks not_allowed)
			(vias allowed)
			(pads allowed)
			(copperpour not_allowed)
			(footprints allowed)
		)
		(placement
			(enabled no)
			(sheetname "")
		)
		(fill
			(thermal_gap 0.5)
			(thermal_bridge_width 0.5)
			(island_removal_mode 0)
		)
		(polygon
			(pts
				(arc
					(start 240.863374 -78.572868)
					(mid 239.922812 -78.886558)
					(end 240.236502 -79.82712)
				)
				(xy 240.525046 -79.971392)
				(arc
					(start 240.88598 -79.971392)
					(mid 241.069487 -79.936225)
					(end 241.226848 -79.835502)
				)
				(arc
					(start 241.282982 -79.72298)
					(mid 241.286169 -79.679365)
					(end 241.257582 -79.646272)
				)
				(arc
					(start 240.995708 -79.515208)
					(mid 240.061616 -78.955256)
					(end 241.069622 -79.367634)
				)
				(xy 241.331242 -79.498444) (xy 241.331496 -79.498444) (xy 241.361976 -79.513938)
				(arc
					(start 241.363246 -79.518002)
					(mid 241.442766 -79.626978)
					(end 241.444526 -79.761842)
				)
				(xy 241.44605 -79.76616) (xy 241.352832 -79.952342)
				(arc
					(start 241.338354 -79.957168)
					(mid 241.145495 -80.083294)
					(end 240.921032 -80.135476)
				)
				(xy 240.92027 -80.136492) (xy 240.855246 -80.136492)
				(arc
					(start 241.067082 -80.24241)
					(mid 241.285319 -80.154712)
					(end 241.467894 -80.006444)
				)
				(xy 241.559842 -79.822802)
				(arc
					(start 241.563906 -79.821532)
					(mid 241.672882 -79.742012)
					(end 241.807746 -79.740252)
				)
				(xy 241.812064 -79.738728)
				(arc
					(start 242.10391 -79.884778)
					(mid 243.038903 -80.443709)
					(end 242.03025 -80.032352)
				)
				(arc
					(start 241.768884 -79.901796)
					(mid 241.725269 -79.898609)
					(end 241.692176 -79.927196)
				)
				(xy 241.595148 -80.120998)
				(arc
					(start 241.58321 -80.124808)
					(mid 241.439796 -80.250891)
					(end 241.274092 -80.345788)
				)
				(arc
					(start 242.228116 -80.8228)
					(mid 243.174892 -80.517615)
					(end 242.86337 -79.572866)
				)
			)
		)
	)
	(zone
		(layer "In9.Cu")
		(hatch none 0.5)
		(connect_pads
			(clearance 0)
		)
		(min_thickness 0.25)
		(keepout
			(tracks not_allowed)
			(vias allowed)
			(pads allowed)
			(copperpour not_allowed)
			(footprints allowed)
		)
		(placement
			(enabled no)
			(sheetname "")
		)
		(fill
			(thermal_gap 0.5)
			(thermal_bridge_width 0.5)
			(island_removal_mode 0)
		)
		(polygon
			(pts
				(arc
					(start 122.298714 -18.350484)
					(mid 121.750201 -17.80159)
					(end 121.201434 -18.35023)
				)
				(arc
					(start 121.201434 -19.750024)
					(mid 121.750074 -20.298664)
					(end 122.298714 -19.750024)
				)
				(xy 122.298714 -19.278854)
				(arc
					(start 121.892568 -19.278854)
					(mid 121.875655 -19.282218)
					(end 121.861326 -19.291808)
				)
				(arc
					(start 121.845578 -19.307556)
					(mid 121.836 -19.32189)
					(end 121.832624 -19.338798)
				)
				(arc
					(start 121.832624 -19.36496)
					(mid 121.750074 -20.143837)
					(end 121.667524 -19.36496)
				)
				(xy 121.667524 -19.304508)
				(arc
					(start 121.670826 -19.301206)
					(mid 121.683361 -19.258632)
					(end 121.704608 -19.219672)
				)
				(xy 121.704608 -19.214846) (xy 121.768616 -19.150838)
				(arc
					(start 121.773442 -19.150838)
					(mid 121.812416 -19.129626)
					(end 121.854976 -19.117056)
				)
				(xy 121.858278 -19.113754) (xy 122.298714 -19.113754) (xy 122.298714 -18.986754) (xy 121.927112 -18.986754)
				(xy 121.858532 -18.986754)
				(arc
					(start 121.854976 -18.983198)
					(mid 121.812402 -18.970663)
					(end 121.773442 -18.949416)
				)
				(xy 121.768616 -18.949416) (xy 121.704608 -18.885408)
				(arc
					(start 121.704608 -18.880582)
					(mid 121.683396 -18.841608)
					(end 121.670826 -18.799048)
				)
				(xy 121.667524 -18.795746)
				(arc
					(start 121.667524 -18.735294)
					(mid 121.750074 -17.956417)
					(end 121.832624 -18.735294)
				)
				(arc
					(start 121.832624 -18.761456)
					(mid 121.835988 -18.778369)
					(end 121.845578 -18.792698)
				)
				(arc
					(start 121.861326 -18.808446)
					(mid 121.87566 -18.818024)
					(end 121.892568 -18.8214)
				)
				(xy 121.926858 -18.8214) (xy 121.927112 -18.821654) (xy 122.298714 -18.821654)
			)
		)
	)
	(zone
		(layer "In9.Cu")
		(hatch none 0.5)
		(connect_pads
			(clearance 0)
		)
		(min_thickness 0.25)
		(keepout
			(tracks not_allowed)
			(vias allowed)
			(pads allowed)
			(copperpour not_allowed)
			(footprints allowed)
		)
		(placement
			(enabled no)
			(sheetname "")
		)
		(fill
			(thermal_gap 0.5)
			(thermal_bridge_width 0.5)
			(island_removal_mode 0)
		)
		(polygon
			(pts
				(arc
					(start 368.29873 -18.350484)
					(mid 367.750217 -17.80159)
					(end 367.20145 -18.35023)
				)
				(xy 367.20145 -18.821654) (xy 367.573052 -18.821654) (xy 367.573306 -18.8214)
				(arc
					(start 367.607596 -18.8214)
					(mid 367.624509 -18.818036)
					(end 367.638838 -18.808446)
				)
				(arc
					(start 367.654586 -18.792698)
					(mid 367.664164 -18.778364)
					(end 367.66754 -18.761456)
				)
				(arc
					(start 367.66754 -18.735294)
					(mid 367.75009 -17.956417)
					(end 367.83264 -18.735294)
				)
				(xy 367.83264 -18.795746)
				(arc
					(start 367.829338 -18.799048)
					(mid 367.816803 -18.841622)
					(end 367.795556 -18.880582)
				)
				(xy 367.795556 -18.885408) (xy 367.731548 -18.949416)
				(arc
					(start 367.726722 -18.949416)
					(mid 367.687748 -18.970628)
					(end 367.645188 -18.983198)
				)
				(xy 367.641632 -18.986754) (xy 367.573052 -18.986754) (xy 367.20145 -18.986754) (xy 367.20145 -19.113754)
				(xy 367.641886 -19.113754)
				(arc
					(start 367.645188 -19.117056)
					(mid 367.687762 -19.129591)
					(end 367.726722 -19.150838)
				)
				(xy 367.731548 -19.150838) (xy 367.795556 -19.214846)
				(arc
					(start 367.795556 -19.219672)
					(mid 367.816768 -19.258646)
					(end 367.829338 -19.301206)
				)
				(xy 367.83264 -19.304508)
				(arc
					(start 367.83264 -19.36496)
					(mid 367.75009 -20.143837)
					(end 367.66754 -19.36496)
				)
				(arc
					(start 367.66754 -19.338798)
					(mid 367.664176 -19.321885)
					(end 367.654586 -19.307556)
				)
				(arc
					(start 367.638838 -19.291808)
					(mid 367.624504 -19.28223)
					(end 367.607596 -19.278854)
				)
				(xy 367.20145 -19.278854)
				(arc
					(start 367.20145 -19.750024)
					(mid 367.75009 -20.298664)
					(end 368.29873 -19.750024)
				)
			)
		)
	)
	(zone
		(layer "In9.Cu")
		(hatch none 0.5)
		(connect_pads
			(clearance 0)
		)
		(min_thickness 0.25)
		(keepout
			(tracks not_allowed)
			(vias allowed)
			(pads allowed)
			(copperpour not_allowed)
			(footprints allowed)
		)
		(placement
			(enabled no)
			(sheetname "")
		)
		(fill
			(thermal_gap 0.5)
			(thermal_bridge_width 0.5)
			(island_removal_mode 0)
		)
		(polygon
			(pts
				(arc
					(start 279.236678 -324.756526)
					(mid 278.688038 -325.305166)
					(end 279.236678 -325.853806)
				)
				(xy 279.7048 -325.853806) (xy 279.7048 -325.845932) (xy 279.7048 -325.841868) (xy 279.7048 -325.442072)
				(arc
					(start 279.7048 -325.438008)
					(mid 279.700252 -325.415054)
					(end 279.687274 -325.39559)
				)
				(xy 279.68448 -325.392542) (xy 279.684226 -325.392288)
				(arc
					(start 279.681178 -325.389494)
					(mid 279.661702 -325.376544)
					(end 279.63876 -325.371968)
				)
				(xy 279.634696 -325.371968)
				(arc
					(start 279.62479 -325.371968)
					(mid 278.842859 -325.305166)
					(end 279.62479 -325.238364)
				)
				(xy 279.634696 -325.238364) (xy 279.63876 -325.238364) (xy 279.645872 -325.238364) (xy 279.666446 -325.238364)
				(arc
					(start 279.668478 -325.24065)
					(mid 279.712747 -325.253117)
					(end 279.752806 -325.275702)
				)
				(xy 279.756108 -325.275702) (xy 279.770586 -325.29018) (xy 279.775666 -325.295006) (xy 279.77846 -325.298054)
				(xy 279.778714 -325.298308) (xy 279.781762 -325.301102) (xy 279.786588 -325.306182) (xy 279.801066 -325.32066)
				(arc
					(start 279.801066 -325.323962)
					(mid 279.823619 -325.364034)
					(end 279.836118 -325.40829)
				)
				(xy 279.838404 -325.410322) (xy 279.838404 -325.430896) (xy 279.838404 -325.438008) (xy 279.838404 -325.442072)
				(xy 279.838404 -325.841868) (xy 279.838404 -325.845932) (xy 279.838404 -325.853806) (xy 280.035 -325.853806)
				(xy 280.035 -325.853044) (xy 280.035 -325.845932) (xy 280.035 -325.841868) (xy 280.035 -325.442072)
				(xy 280.035 -325.438008) (xy 280.035 -325.430896) (xy 280.035 -325.410322)
				(arc
					(start 280.037286 -325.40829)
					(mid 280.049753 -325.364021)
					(end 280.072338 -325.323962)
				)
				(xy 280.072338 -325.32066) (xy 280.086816 -325.306182) (xy 280.091642 -325.301102) (xy 280.09469 -325.298308)
				(xy 280.094944 -325.298054) (xy 280.097738 -325.295006) (xy 280.102818 -325.29018) (xy 280.117296 -325.275702)
				(arc
					(start 280.120598 -325.275702)
					(mid 280.16067 -325.253149)
					(end 280.204926 -325.24065)
				)
				(xy 280.206958 -325.238364) (xy 280.227532 -325.238364) (xy 280.234644 -325.238364) (xy 280.238708 -325.238364)
				(arc
					(start 280.248614 -325.238364)
					(mid 281.030545 -325.305166)
					(end 280.248614 -325.371968)
				)
				(xy 280.238708 -325.371968)
				(arc
					(start 280.234644 -325.371968)
					(mid 280.21169 -325.376516)
					(end 280.192226 -325.389494)
				)
				(xy 280.189178 -325.392288) (xy 280.188924 -325.392542)
				(arc
					(start 280.18613 -325.39559)
					(mid 280.17318 -325.415066)
					(end 280.168604 -325.438008)
				)
				(xy 280.168604 -325.442072) (xy 280.168604 -325.841868) (xy 280.168604 -325.845932) (xy 280.169112 -325.853806)
				(arc
					(start 280.636726 -325.853806)
					(mid 281.185366 -325.305166)
					(end 280.636726 -324.756526)
				)
				(xy 279.236932 -324.756526)
			)
		)
	)
	(zone
		(layer "In9.Cu")
		(hatch none 0.5)
		(connect_pads
			(clearance 0)
		)
		(min_thickness 0.25)
		(keepout
			(tracks not_allowed)
			(vias allowed)
			(pads allowed)
			(copperpour not_allowed)
			(footprints allowed)
		)
		(placement
			(enabled no)
			(sheetname "")
		)
		(fill
			(thermal_gap 0.5)
			(thermal_bridge_width 0.5)
			(island_removal_mode 0)
		)
		(polygon
			(pts
				(arc
					(start 279.688036 -113.733326)
					(mid 279.476209 -113.574774)
					(end 279.230836 -113.47577)
				)
				(arc
					(start 279.03805 -113.572036)
					(mid 279.315899 -113.637882)
					(end 279.559004 -113.787682)
				)
				(xy 279.575514 -113.79327) (xy 279.646126 -113.933478)
				(arc
					(start 279.644602 -113.937796)
					(mid 279.642862 -114.072793)
					(end 279.563322 -114.18189)
				)
				(xy 279.562052 -114.185954) (xy 279.531572 -114.201448) (xy 279.531318 -114.201448)
				(arc
					(start 279.269698 -114.332258)
					(mid 278.261668 -114.744648)
					(end 279.195784 -114.184684)
				)
				(arc
					(start 279.457658 -114.05362)
					(mid 279.486209 -114.020634)
					(end 279.483058 -113.977166)
				)
				(arc
					(start 279.450546 -113.912142)
					(mid 279.227947 -113.780701)
					(end 278.973534 -113.73485)
				)
				(xy 278.712676 -113.73485)
				(arc
					(start 278.44496 -113.868708)
					(mid 278.120865 -114.809139)
					(end 279.06345 -115.127024)
				)
				(arc
					(start 281.063446 -114.127026)
					(mid 281.377136 -113.186464)
					(end 280.436574 -112.872774)
				)
				(arc
					(start 279.437846 -113.372138)
					(mid 279.629991 -113.475486)
					(end 279.80005 -113.612168)
				)
				(xy 279.814528 -113.61674)
				(arc
					(start 279.892252 -113.772696)
					(mid 279.925345 -113.801283)
					(end 279.96896 -113.798096)
				)
				(arc
					(start 280.230326 -113.66754)
					(mid 281.23897 -113.256187)
					(end 280.303986 -113.815114)
				)
				(xy 280.01214 -113.961164)
				(arc
					(start 280.007822 -113.95964)
					(mid 279.872987 -113.957792)
					(end 279.763982 -113.87836)
				)
				(xy 279.759664 -113.87709)
			)
		)
	)
	(zone
		(layer "In9.Cu")
		(hatch none 0.5)
		(connect_pads
			(clearance 0)
		)
		(min_thickness 0.25)
		(keepout
			(tracks not_allowed)
			(vias allowed)
			(pads allowed)
			(copperpour not_allowed)
			(footprints allowed)
		)
		(placement
			(enabled no)
			(sheetname "")
		)
		(fill
			(thermal_gap 0.5)
			(thermal_bridge_width 0.5)
			(island_removal_mode 0)
		)
		(polygon
			(pts
				(arc
					(start 40.45204 -92.80017)
					(mid 33.325054 -85.673184)
					(end 26.198068 -92.80017)
				)
				(arc
					(start 26.198068 -98.800412)
					(mid 33.325054 -105.927144)
					(end 40.45204 -98.800412)
				)
			)
		)
	)
	(zone
		(layer "In9.Cu")
		(hatch none 0.5)
		(connect_pads
			(clearance 0)
		)
		(min_thickness 0.25)
		(keepout
			(tracks not_allowed)
			(vias allowed)
			(pads allowed)
			(copperpour not_allowed)
			(footprints allowed)
		)
		(placement
			(enabled no)
			(sheetname "")
		)
		(fill
			(thermal_gap 0.5)
			(thermal_bridge_width 0.5)
			(island_removal_mode 0)
		)
		(polygon
			(pts
				(xy 204.387196 -420.437056) (xy 204.387196 -419.514274) (xy 225.482912 -419.514274) (xy 226.403662 -420.435024)
				(xy 232.127044 -420.435024) (xy 233.047794 -419.514274) (xy 272.003266 -419.514274) (xy 272.003266 -420.437056)
			)
		)
	)
	(zone
		(layer "In9.Cu")
		(hatch none 0.5)
		(connect_pads
			(clearance 0)
		)
		(min_thickness 0.25)
		(keepout
			(tracks not_allowed)
			(vias allowed)
			(pads allowed)
			(copperpour not_allowed)
			(footprints allowed)
		)
		(placement
			(enabled no)
			(sheetname "")
		)
		(fill
			(thermal_gap 0.5)
			(thermal_bridge_width 0.5)
			(island_removal_mode 0)
		)
		(polygon
			(pts
				(arc
					(start 237.072932 -279.200356)
					(mid 244.199918 -286.327342)
					(end 251.326904 -279.200356)
				)
				(arc
					(start 251.326904 -273.200114)
					(mid 244.199918 -266.073382)
					(end 237.072932 -273.200114)
				)
			)
		)
	)
	(zone
		(layer "In9.Cu")
		(hatch none 0.5)
		(connect_pads
			(clearance 0)
		)
		(min_thickness 0.25)
		(keepout
			(tracks not_allowed)
			(vias allowed)
			(pads allowed)
			(copperpour not_allowed)
			(footprints allowed)
		)
		(placement
			(enabled no)
			(sheetname "")
		)
		(fill
			(thermal_gap 0.5)
			(thermal_bridge_width 0.5)
			(island_removal_mode 0)
		)
		(polygon
			(pts
				(arc
					(start 355.698552 -17.350232)
					(mid 355.150039 -16.801338)
					(end 354.601272 -17.349978)
				)
				(xy 354.601272 -17.822418)
				(arc
					(start 354.965762 -17.822418)
					(mid 354.982675 -17.819054)
					(end 354.997004 -17.809464)
				)
				(arc
					(start 355.054408 -17.75206)
					(mid 355.060877 -17.743929)
					(end 355.06533 -17.734534)
				)
				(arc
					(start 355.06533 -17.734534)
					(mid 355.151461 -16.956178)
					(end 355.232462 -17.735042)
				)
				(xy 355.232462 -17.755108)
				(arc
					(start 355.22916 -17.75841)
					(mid 355.216625 -17.800984)
					(end 355.195378 -17.839944)
				)
				(xy 355.195378 -17.84477) (xy 355.089714 -17.950434)
				(arc
					(start 355.084888 -17.950434)
					(mid 355.045914 -17.971646)
					(end 355.003354 -17.984216)
				)
				(xy 355.000052 -17.987518) (xy 354.601272 -17.987518) (xy 354.601272 -18.114518) (xy 354.99802 -18.114518)
				(arc
					(start 355.001322 -18.11782)
					(mid 355.043896 -18.130355)
					(end 355.082856 -18.151602)
				)
				(xy 355.087682 -18.151602) (xy 355.195378 -18.259298)
				(arc
					(start 355.195378 -18.264124)
					(mid 355.21659 -18.303098)
					(end 355.22916 -18.345658)
				)
				(xy 355.232462 -18.34896)
				(arc
					(start 355.232462 -18.364962)
					(mid 355.152762 -19.143726)
					(end 355.063806 -18.365978)
				)
				(arc
					(start 355.063806 -18.365978)
					(mid 355.059787 -18.358534)
					(end 355.054408 -18.352008)
				)
				(arc
					(start 354.994972 -18.292572)
					(mid 354.980638 -18.282994)
					(end 354.96373 -18.279618)
				)
				(xy 354.601272 -18.279618)
				(arc
					(start 354.601272 -18.750026)
					(mid 355.149912 -19.298666)
					(end 355.698552 -18.750026)
				)
			)
		)
	)
	(zone
		(layer "In9.Cu")
		(hatch none 0.5)
		(connect_pads
			(clearance 0)
		)
		(min_thickness 0.25)
		(keepout
			(tracks not_allowed)
			(vias allowed)
			(pads allowed)
			(copperpour not_allowed)
			(footprints allowed)
		)
		(placement
			(enabled no)
			(sheetname "")
		)
		(fill
			(thermal_gap 0.5)
			(thermal_bridge_width 0.5)
			(island_removal_mode 0)
		)
		(polygon
			(pts
				(arc
					(start 278.23668 -322.956428)
					(mid 277.68804 -323.505068)
					(end 278.23668 -324.053708)
				)
				(xy 278.705056 -324.053708) (xy 278.705056 -323.646292)
				(arc
					(start 278.704802 -323.642228)
					(mid 278.700254 -323.619274)
					(end 278.687276 -323.59981)
				)
				(xy 278.684482 -323.596762) (xy 278.67991 -323.59219)
				(arc
					(start 278.676862 -323.589396)
					(mid 278.657386 -323.576446)
					(end 278.634444 -323.57187)
				)
				(xy 278.63038 -323.571616)
				(arc
					(start 278.624792 -323.571616)
					(mid 277.842904 -323.505068)
					(end 278.624792 -323.43852)
				)
				(xy 278.63038 -323.43852) (xy 278.634444 -323.438266) (xy 278.641556 -323.43852) (xy 278.66213 -323.43852)
				(arc
					(start 278.664162 -323.440552)
					(mid 278.708431 -323.453019)
					(end 278.74849 -323.475604)
				)
				(xy 278.751792 -323.475604) (xy 278.76627 -323.490082) (xy 278.77135 -323.494908) (xy 278.774144 -323.497956)
				(xy 278.778716 -323.502528) (xy 278.781764 -323.505322) (xy 278.78659 -323.510402) (xy 278.801068 -323.52488)
				(arc
					(start 278.801068 -323.528182)
					(mid 278.823621 -323.568254)
					(end 278.83612 -323.61251)
				)
				(xy 278.838152 -323.614542) (xy 278.838152 -323.635116) (xy 278.838406 -323.642228) (xy 278.838152 -323.646292)
				(xy 278.838152 -324.053708) (xy 279.035256 -324.053708) (xy 279.035256 -323.646292) (xy 279.035002 -323.642228)
				(xy 279.035256 -323.635116) (xy 279.035256 -323.614542)
				(arc
					(start 279.037288 -323.61251)
					(mid 279.049755 -323.568241)
					(end 279.07234 -323.528182)
				)
				(xy 279.07234 -323.52488) (xy 279.086818 -323.510402) (xy 279.091644 -323.505322) (xy 279.094692 -323.502528)
				(xy 279.099264 -323.497956) (xy 279.102058 -323.494908) (xy 279.107138 -323.490082) (xy 279.121616 -323.475604)
				(arc
					(start 279.124918 -323.475604)
					(mid 279.16499 -323.453051)
					(end 279.209246 -323.440552)
				)
				(xy 279.211278 -323.43852) (xy 279.231852 -323.43852) (xy 279.238964 -323.438266) (xy 279.243028 -323.43852)
				(arc
					(start 279.248616 -323.43852)
					(mid 280.030504 -323.505068)
					(end 279.248616 -323.571616)
				)
				(xy 279.243028 -323.571616)
				(arc
					(start 279.238964 -323.57187)
					(mid 279.21601 -323.576418)
					(end 279.196546 -323.589396)
				)
				(xy 279.193498 -323.59219) (xy 279.188926 -323.596762)
				(arc
					(start 279.186132 -323.59981)
					(mid 279.173182 -323.619286)
					(end 279.168606 -323.642228)
				)
				(xy 279.168352 -323.646292) (xy 279.168352 -324.053708)
				(arc
					(start 279.636728 -324.053708)
					(mid 280.185368 -323.505068)
					(end 279.636728 -322.956428)
				)
				(xy 278.236934 -322.956428)
			)
		)
	)
	(zone
		(layer "In9.Cu")
		(hatch none 0.5)
		(connect_pads
			(clearance 0)
		)
		(min_thickness 0.25)
		(keepout
			(tracks not_allowed)
			(vias allowed)
			(pads allowed)
			(copperpour not_allowed)
			(footprints allowed)
		)
		(placement
			(enabled no)
			(sheetname "")
		)
		(fill
			(thermal_gap 0.5)
			(thermal_bridge_width 0.5)
			(island_removal_mode 0)
		)
		(polygon
			(pts
				(arc
					(start 195.173092 -189.799722)
					(mid 202.300078 -196.926708)
					(end 209.427064 -189.799722)
				)
				(arc
					(start 209.427064 -183.799734)
					(mid 202.300078 -176.672748)
					(end 195.173092 -183.799734)
				)
			)
		)
	)
	(zone
		(layer "In9.Cu")
		(hatch none 0.5)
		(connect_pads
			(clearance 0)
		)
		(min_thickness 0.25)
		(keepout
			(tracks not_allowed)
			(vias allowed)
			(pads allowed)
			(copperpour not_allowed)
			(footprints allowed)
		)
		(placement
			(enabled no)
			(sheetname "")
		)
		(fill
			(thermal_gap 0.5)
			(thermal_bridge_width 0.5)
			(island_removal_mode 0)
		)
		(polygon
			(pts
				(arc
					(start 279.236678 -339.156548)
					(mid 278.688038 -339.705188)
					(end 279.236678 -340.253828)
				)
				(xy 279.7048 -340.253828) (xy 279.7048 -340.245954) (xy 279.7048 -340.24189) (xy 279.7048 -339.842094)
				(arc
					(start 279.7048 -339.83803)
					(mid 279.700252 -339.815076)
					(end 279.687274 -339.795612)
				)
				(xy 279.68448 -339.792564) (xy 279.684226 -339.79231)
				(arc
					(start 279.681178 -339.789516)
					(mid 279.661702 -339.776566)
					(end 279.63876 -339.77199)
				)
				(xy 279.634696 -339.771736)
				(arc
					(start 279.62479 -339.771736)
					(mid 278.842902 -339.705188)
					(end 279.62479 -339.63864)
				)
				(xy 279.634696 -339.63864) (xy 279.63876 -339.638386) (xy 279.645872 -339.63864) (xy 279.666446 -339.63864)
				(arc
					(start 279.668478 -339.640672)
					(mid 279.712747 -339.653139)
					(end 279.752806 -339.675724)
				)
				(xy 279.756108 -339.675724) (xy 279.770586 -339.690202) (xy 279.775666 -339.695028) (xy 279.77846 -339.698076)
				(xy 279.778714 -339.69833) (xy 279.781762 -339.701124) (xy 279.786588 -339.706204) (xy 279.801066 -339.720682)
				(arc
					(start 279.801066 -339.723984)
					(mid 279.823619 -339.764056)
					(end 279.836118 -339.808312)
				)
				(xy 279.838404 -339.810344) (xy 279.838404 -339.830918) (xy 279.838404 -339.83803) (xy 279.838404 -339.842094)
				(xy 279.838404 -340.24189) (xy 279.838404 -340.245954) (xy 279.838404 -340.253828) (xy 280.035 -340.253828)
				(xy 280.035 -340.253066) (xy 280.035 -340.245954) (xy 280.035 -340.24189) (xy 280.035 -339.842094)
				(xy 280.035 -339.83803) (xy 280.035 -339.830918) (xy 280.035 -339.810344)
				(arc
					(start 280.037286 -339.808312)
					(mid 280.049753 -339.764043)
					(end 280.072338 -339.723984)
				)
				(xy 280.072338 -339.720682) (xy 280.086816 -339.706204) (xy 280.091642 -339.701124) (xy 280.09469 -339.69833)
				(xy 280.094944 -339.698076) (xy 280.097738 -339.695028) (xy 280.102818 -339.690202) (xy 280.117296 -339.675724)
				(arc
					(start 280.120598 -339.675724)
					(mid 280.16067 -339.653171)
					(end 280.204926 -339.640672)
				)
				(xy 280.206958 -339.63864) (xy 280.227532 -339.63864) (xy 280.234644 -339.638386) (xy 280.238708 -339.63864)
				(arc
					(start 280.248614 -339.63864)
					(mid 281.030502 -339.705188)
					(end 280.248614 -339.771736)
				)
				(xy 280.238708 -339.771736)
				(arc
					(start 280.234644 -339.77199)
					(mid 280.21169 -339.776538)
					(end 280.192226 -339.789516)
				)
				(xy 280.189178 -339.79231) (xy 280.188924 -339.792564)
				(arc
					(start 280.18613 -339.795612)
					(mid 280.17318 -339.815088)
					(end 280.168604 -339.83803)
				)
				(xy 280.168604 -339.842094) (xy 280.168604 -340.24189) (xy 280.168604 -340.245954) (xy 280.169112 -340.253828)
				(arc
					(start 280.636726 -340.253828)
					(mid 281.185366 -339.705188)
					(end 280.636726 -339.156548)
				)
				(xy 279.236932 -339.156548)
			)
		)
	)
	(zone
		(layer "In9.Cu")
		(hatch none 0.5)
		(connect_pads
			(clearance 0)
		)
		(min_thickness 0.25)
		(keepout
			(tracks not_allowed)
			(vias allowed)
			(pads allowed)
			(copperpour not_allowed)
			(footprints allowed)
		)
		(placement
			(enabled no)
			(sheetname "")
		)
		(fill
			(thermal_gap 0.5)
			(thermal_bridge_width 0.5)
			(island_removal_mode 0)
		)
		(polygon
			(pts
				(arc
					(start 472.377008 -270.000222)
					(mid 462.6229 -270.000222)
					(end 472.377008 -270.000222)
				)
			)
		)
	)
	(zone
		(layer "In9.Cu")
		(hatch none 0.5)
		(connect_pads
			(clearance 0)
		)
		(min_thickness 0.25)
		(keepout
			(tracks not_allowed)
			(vias allowed)
			(pads allowed)
			(copperpour not_allowed)
			(footprints allowed)
		)
		(placement
			(enabled no)
			(sheetname "")
		)
		(fill
			(thermal_gap 0.5)
			(thermal_bridge_width 0.5)
			(island_removal_mode 0)
		)
		(polygon
			(pts
				(arc
					(start 210.548728 -414.20034)
					(mid 210.000215 -413.651446)
					(end 209.451448 -414.200086)
				)
				(xy 209.451448 -414.67151)
				(arc
					(start 209.788252 -414.67151)
					(mid 209.863619 -414.64727)
					(end 209.91068 -414.583626)
				)
				(arc
					(start 209.91068 -414.583626)
					(mid 210.004263 -413.806406)
					(end 210.079336 -414.585658)
				)
				(arc
					(start 210.079336 -414.585658)
					(mid 209.993893 -414.752766)
					(end 209.824828 -414.834324)
				)
				(xy 209.822542 -414.83661) (xy 209.451448 -414.83661) (xy 209.451448 -414.96361) (xy 209.822542 -414.96361)
				(arc
					(start 209.824828 -414.965896)
					(mid 209.993945 -415.0474)
					(end 210.079336 -415.214562)
				)
				(arc
					(start 210.079336 -415.214562)
					(mid 210.004264 -415.993841)
					(end 209.91068 -415.216594)
				)
				(arc
					(start 209.91068 -415.216594)
					(mid 209.863591 -415.152988)
					(end 209.788252 -415.12871)
				)
				(xy 209.451448 -415.12871)
				(arc
					(start 209.451448 -415.600134)
					(mid 210.000088 -416.148774)
					(end 210.548728 -415.600134)
				)
			)
		)
	)
	(zone
		(layer "In9.Cu")
		(hatch none 0.5)
		(connect_pads
			(clearance 0)
		)
		(min_thickness 0.25)
		(keepout
			(tracks not_allowed)
			(vias allowed)
			(pads allowed)
			(copperpour not_allowed)
			(footprints allowed)
		)
		(placement
			(enabled no)
			(sheetname "")
		)
		(fill
			(thermal_gap 0.5)
			(thermal_bridge_width 0.5)
			(island_removal_mode 0)
		)
		(polygon
			(pts
				(arc
					(start 320.3702 -158.368492)
					(mid 319.9892 -157.987492)
					(end 319.6082 -158.368492)
				)
				(xy 319.6082 -158.708344) (xy 319.816734 -158.708344)
				(arc
					(start 319.820798 -158.70809)
					(mid 319.88525 -158.68503)
					(end 319.920366 -158.626302)
				)
				(arc
					(start 319.920366 -158.626302)
					(mid 319.98987 -158.101718)
					(end 320.055748 -158.62681)
				)
				(xy 320.055748 -158.634176)
				(arc
					(start 320.054224 -158.6357)
					(mid 319.987142 -158.772834)
					(end 319.850008 -158.839916)
				)
				(xy 319.848484 -158.84144) (xy 319.828418 -158.84144) (xy 319.820798 -158.841694) (xy 319.816734 -158.84144)
				(xy 319.6082 -158.84144) (xy 319.6082 -159.038544) (xy 319.816734 -159.038544) (xy 319.820798 -159.03829)
				(xy 319.828418 -159.038544) (xy 319.848484 -159.038544)
				(arc
					(start 319.850008 -159.040068)
					(mid 319.987142 -159.10715)
					(end 320.054224 -159.244284)
				)
				(xy 320.055748 -159.245808)
				(arc
					(start 320.055748 -159.253174)
					(mid 319.98987 -159.778306)
					(end 319.920366 -159.253682)
				)
				(arc
					(start 319.920366 -159.253682)
					(mid 319.885199 -159.195016)
					(end 319.820798 -159.171894)
				)
				(xy 319.816734 -159.17164) (xy 319.6082 -159.17164)
				(arc
					(start 319.6082 -159.511238)
					(mid 319.989073 -159.892492)
					(end 320.3702 -159.511492)
				)
			)
		)
	)
	(zone
		(layer "In9.Cu")
		(hatch none 0.5)
		(connect_pads
			(clearance 0)
		)
		(min_thickness 0.25)
		(keepout
			(tracks not_allowed)
			(vias allowed)
			(pads allowed)
			(copperpour not_allowed)
			(footprints allowed)
		)
		(placement
			(enabled no)
			(sheetname "")
		)
		(fill
			(thermal_gap 0.5)
			(thermal_bridge_width 0.5)
			(island_removal_mode 0)
		)
		(polygon
			(pts
				(arc
					(start 463.801968 -322.800218)
					(mid 456.674982 -315.673232)
					(end 449.547996 -322.800218)
				)
				(arc
					(start 449.547996 -328.800206)
					(mid 456.674982 -335.927192)
					(end 463.801968 -328.800206)
				)
			)
		)
	)
	(zone
		(layer "In9.Cu")
		(hatch none 0.5)
		(connect_pads
			(clearance 0)
		)
		(min_thickness 0.25)
		(keepout
			(tracks not_allowed)
			(vias allowed)
			(pads allowed)
			(copperpour not_allowed)
			(footprints allowed)
		)
		(placement
			(enabled no)
			(sheetname "")
		)
		(fill
			(thermal_gap 0.5)
			(thermal_bridge_width 0.5)
			(island_removal_mode 0)
		)
		(polygon
			(pts
				(arc
					(start 240.871756 -82.577178)
					(mid 239.92498 -82.882363)
					(end 240.236502 -83.827112)
				)
				(xy 240.525046 -83.971384)
				(arc
					(start 240.88598 -83.971384)
					(mid 241.069487 -83.936217)
					(end 241.226848 -83.835494)
				)
				(arc
					(start 241.282982 -83.722972)
					(mid 241.286169 -83.679357)
					(end 241.257582 -83.646264)
				)
				(arc
					(start 240.995708 -83.5152)
					(mid 240.061616 -82.955248)
					(end 241.069622 -83.367626)
				)
				(xy 241.331242 -83.498436) (xy 241.331496 -83.498436) (xy 241.361976 -83.51393)
				(arc
					(start 241.363246 -83.517994)
					(mid 241.442766 -83.62697)
					(end 241.444526 -83.761834)
				)
				(xy 241.44605 -83.766152) (xy 241.352832 -83.952334)
				(arc
					(start 241.338354 -83.95716)
					(mid 241.145495 -84.083286)
					(end 240.921032 -84.135468)
				)
				(xy 240.92027 -84.136484) (xy 240.855246 -84.136484)
				(arc
					(start 241.067082 -84.242402)
					(mid 241.285319 -84.154704)
					(end 241.467894 -84.006436)
				)
				(xy 241.559842 -83.822794)
				(arc
					(start 241.563906 -83.821524)
					(mid 241.672882 -83.742004)
					(end 241.807746 -83.740244)
				)
				(xy 241.812064 -83.73872)
				(arc
					(start 242.10391 -83.88477)
					(mid 243.038903 -84.443701)
					(end 242.03025 -84.032344)
				)
				(arc
					(start 241.768884 -83.901788)
					(mid 241.725269 -83.898601)
					(end 241.692176 -83.927188)
				)
				(xy 241.595148 -84.12099)
				(arc
					(start 241.58321 -84.1248)
					(mid 241.43979 -84.250976)
					(end 241.274092 -84.346034)
				)
				(arc
					(start 242.236498 -84.82711)
					(mid 243.17706 -84.51342)
					(end 242.86337 -83.572858)
				)
			)
		)
	)
	(zone
		(layer "In9.Cu")
		(hatch none 0.5)
		(connect_pads
			(clearance 0)
		)
		(min_thickness 0.25)
		(keepout
			(tracks not_allowed)
			(vias allowed)
			(pads allowed)
			(copperpour not_allowed)
			(footprints allowed)
		)
		(placement
			(enabled no)
			(sheetname "")
		)
		(fill
			(thermal_gap 0.5)
			(thermal_bridge_width 0.5)
			(island_removal_mode 0)
		)
		(polygon
			(pts
				(arc
					(start 283.563314 -46.572932)
					(mid 282.622752 -46.886622)
					(end 282.936442 -47.827184)
				)
				(xy 283.224986 -47.971456)
				(arc
					(start 283.58592 -47.971456)
					(mid 283.769427 -47.936289)
					(end 283.926788 -47.835566)
				)
				(arc
					(start 283.982922 -47.723044)
					(mid 283.986109 -47.679429)
					(end 283.957522 -47.646336)
				)
				(arc
					(start 283.695648 -47.515272)
					(mid 282.761556 -46.95532)
					(end 283.769562 -47.367698)
				)
				(xy 284.031182 -47.498508) (xy 284.031436 -47.498508) (xy 284.061916 -47.514002)
				(arc
					(start 284.063186 -47.518066)
					(mid 284.142706 -47.627042)
					(end 284.144466 -47.761906)
				)
				(xy 284.14599 -47.766224) (xy 284.052772 -47.952406)
				(arc
					(start 284.038294 -47.957232)
					(mid 283.845435 -48.083358)
					(end 283.620972 -48.13554)
				)
				(xy 283.62021 -48.136556) (xy 283.555186 -48.136556)
				(arc
					(start 283.767022 -48.242474)
					(mid 283.985259 -48.154776)
					(end 284.167834 -48.006508)
				)
				(xy 284.259782 -47.822866)
				(arc
					(start 284.263846 -47.821596)
					(mid 284.372822 -47.742076)
					(end 284.507686 -47.740316)
				)
				(xy 284.512004 -47.738792)
				(arc
					(start 284.80385 -47.884842)
					(mid 285.738843 -48.443773)
					(end 284.73019 -48.032416)
				)
				(arc
					(start 284.468824 -47.90186)
					(mid 284.425209 -47.898673)
					(end 284.392116 -47.92726)
				)
				(xy 284.295088 -48.121062)
				(arc
					(start 284.28315 -48.124872)
					(mid 284.139736 -48.250955)
					(end 283.974032 -48.345852)
				)
				(arc
					(start 284.928056 -48.822864)
					(mid 285.874832 -48.517679)
					(end 285.56331 -47.57293)
				)
			)
		)
	)
	(zone
		(layer "In9.Cu")
		(hatch none 0.5)
		(connect_pads
			(clearance 0)
		)
		(min_thickness 0.25)
		(keepout
			(tracks not_allowed)
			(vias allowed)
			(pads allowed)
			(copperpour not_allowed)
			(footprints allowed)
		)
		(placement
			(enabled no)
			(sheetname "")
		)
		(fill
			(thermal_gap 0.5)
			(thermal_bridge_width 0.5)
			(island_removal_mode 0)
		)
		(polygon
			(pts
				(arc
					(start 136.698736 -18.350484)
					(mid 136.150223 -17.80159)
					(end 135.601456 -18.35023)
				)
				(arc
					(start 135.601456 -19.750024)
					(mid 136.150096 -20.298664)
					(end 136.698736 -19.750024)
				)
				(xy 136.698736 -19.278854)
				(arc
					(start 136.29259 -19.278854)
					(mid 136.275677 -19.282218)
					(end 136.261348 -19.291808)
				)
				(arc
					(start 136.2456 -19.307556)
					(mid 136.236022 -19.32189)
					(end 136.232646 -19.338798)
				)
				(arc
					(start 136.232646 -19.36496)
					(mid 136.150096 -20.143837)
					(end 136.067546 -19.36496)
				)
				(xy 136.067546 -19.304508)
				(arc
					(start 136.070848 -19.301206)
					(mid 136.083383 -19.258632)
					(end 136.10463 -19.219672)
				)
				(xy 136.10463 -19.214846) (xy 136.12876 -19.190716) (xy 136.144508 -19.174968) (xy 136.168638 -19.150838)
				(arc
					(start 136.173464 -19.150838)
					(mid 136.212438 -19.129626)
					(end 136.254998 -19.117056)
				)
				(xy 136.2583 -19.113754) (xy 136.698736 -19.113754) (xy 136.698736 -18.986754) (xy 136.327134 -18.986754)
				(xy 136.258554 -18.986754)
				(arc
					(start 136.254998 -18.983198)
					(mid 136.212424 -18.970663)
					(end 136.173464 -18.949416)
				)
				(xy 136.168638 -18.949416) (xy 136.144508 -18.925286) (xy 136.10463 -18.885408)
				(arc
					(start 136.10463 -18.880582)
					(mid 136.083418 -18.841608)
					(end 136.070848 -18.799048)
				)
				(xy 136.067546 -18.795746)
				(arc
					(start 136.067546 -18.735294)
					(mid 136.150096 -17.956417)
					(end 136.232646 -18.735294)
				)
				(arc
					(start 136.232646 -18.761456)
					(mid 136.23601 -18.778369)
					(end 136.2456 -18.792698)
				)
				(arc
					(start 136.261348 -18.808446)
					(mid 136.275682 -18.818024)
					(end 136.29259 -18.8214)
				)
				(xy 136.32688 -18.8214) (xy 136.327134 -18.821654) (xy 136.698736 -18.821654)
			)
		)
	)
	(zone
		(layer "In9.Cu")
		(hatch none 0.5)
		(connect_pads
			(clearance 0)
		)
		(min_thickness 0.25)
		(keepout
			(tracks not_allowed)
			(vias allowed)
			(pads allowed)
			(copperpour not_allowed)
			(footprints allowed)
		)
		(placement
			(enabled no)
			(sheetname "")
		)
		(fill
			(thermal_gap 0.5)
			(thermal_bridge_width 0.5)
			(island_removal_mode 0)
		)
		(polygon
			(pts
				(arc
					(start 364.698534 -18.350484)
					(mid 364.150021 -17.80159)
					(end 363.601254 -18.35023)
				)
				(xy 363.601254 -18.821654) (xy 363.972856 -18.821654) (xy 363.97311 -18.8214)
				(arc
					(start 364.0074 -18.8214)
					(mid 364.024313 -18.818036)
					(end 364.038642 -18.808446)
				)
				(arc
					(start 364.05439 -18.792698)
					(mid 364.063968 -18.778364)
					(end 364.067344 -18.761456)
				)
				(arc
					(start 364.067344 -18.735294)
					(mid 364.149894 -17.956417)
					(end 364.232444 -18.735294)
				)
				(xy 364.232444 -18.795746)
				(arc
					(start 364.229142 -18.799048)
					(mid 364.216607 -18.841622)
					(end 364.19536 -18.880582)
				)
				(xy 364.19536 -18.885408) (xy 364.131352 -18.949416)
				(arc
					(start 364.126526 -18.949416)
					(mid 364.087552 -18.970628)
					(end 364.044992 -18.983198)
				)
				(xy 364.041436 -18.986754) (xy 363.972856 -18.986754) (xy 363.601254 -18.986754) (xy 363.601254 -19.113754)
				(xy 364.04169 -19.113754)
				(arc
					(start 364.044992 -19.117056)
					(mid 364.087566 -19.129591)
					(end 364.126526 -19.150838)
				)
				(xy 364.131352 -19.150838) (xy 364.19536 -19.214846)
				(arc
					(start 364.19536 -19.219672)
					(mid 364.216572 -19.258646)
					(end 364.229142 -19.301206)
				)
				(xy 364.232444 -19.304508)
				(arc
					(start 364.232444 -19.36496)
					(mid 364.149894 -20.143837)
					(end 364.067344 -19.36496)
				)
				(arc
					(start 364.067344 -19.338798)
					(mid 364.06398 -19.321885)
					(end 364.05439 -19.307556)
				)
				(arc
					(start 364.038642 -19.291808)
					(mid 364.024308 -19.28223)
					(end 364.0074 -19.278854)
				)
				(xy 363.601254 -19.278854)
				(arc
					(start 363.601254 -19.750024)
					(mid 364.149894 -20.298664)
					(end 364.698534 -19.750024)
				)
			)
		)
	)
	(zone
		(layer "In9.Cu")
		(hatch none 0.5)
		(connect_pads
			(clearance 0)
		)
		(min_thickness 0.25)
		(keepout
			(tracks not_allowed)
			(vias allowed)
			(pads allowed)
			(copperpour not_allowed)
			(footprints allowed)
		)
		(placement
			(enabled no)
			(sheetname "")
		)
		(fill
			(thermal_gap 0.5)
			(thermal_bridge_width 0.5)
			(island_removal_mode 0)
		)
		(polygon
			(pts
				(arc
					(start 111.976916 -290.000182)
					(mid 102.223316 -290.000182)
					(end 111.976916 -290.000182)
				)
			)
		)
	)
	(zone
		(layer "In9.Cu")
		(hatch none 0.5)
		(connect_pads
			(clearance 0)
		)
		(min_thickness 0.25)
		(keepout
			(tracks not_allowed)
			(vias allowed)
			(pads allowed)
			(copperpour not_allowed)
			(footprints allowed)
		)
		(placement
			(enabled no)
			(sheetname "")
		)
		(fill
			(thermal_gap 0.5)
			(thermal_bridge_width 0.5)
			(island_removal_mode 0)
		)
		(polygon
			(pts
				(arc
					(start 478.120202 -273.368516)
					(mid 477.739202 -272.987516)
					(end 477.358202 -273.368516)
				)
				(xy 477.358202 -273.708368) (xy 477.615504 -273.708368)
				(arc
					(start 477.619568 -273.708114)
					(mid 477.639786 -273.704092)
					(end 477.656906 -273.69262)
				)
				(arc
					(start 477.656906 -273.69262)
					(mid 477.668352 -273.675489)
					(end 477.6724 -273.655282)
				)
				(xy 477.6724 -273.651218)
				(arc
					(start 477.6724 -273.626834)
					(mid 477.739202 -273.1017)
					(end 477.806004 -273.626834)
				)
				(xy 477.806004 -273.651218) (xy 477.806004 -273.655282) (xy 477.806004 -273.66214) (xy 477.806004 -273.682968)
				(arc
					(start 477.803464 -273.685254)
					(mid 477.785454 -273.740286)
					(end 477.751394 -273.787108)
				)
				(arc
					(start 477.751394 -273.787108)
					(mid 477.704558 -273.821141)
					(end 477.64954 -273.839178)
				)
				(xy 477.647254 -273.841464) (xy 477.626426 -273.841464) (xy 477.619568 -273.841718) (xy 477.615504 -273.841464)
				(xy 477.358202 -273.841464) (xy 477.358202 -274.038568) (xy 477.615504 -274.038568) (xy 477.619568 -274.038314)
				(xy 477.626426 -274.038568) (xy 477.647254 -274.038568)
				(arc
					(start 477.64954 -274.040854)
					(mid 477.704572 -274.058864)
					(end 477.751394 -274.092924)
				)
				(arc
					(start 477.751394 -274.092924)
					(mid 477.785427 -274.13976)
					(end 477.803464 -274.194778)
				)
				(xy 477.806004 -274.197064) (xy 477.806004 -274.217892) (xy 477.806004 -274.22475) (xy 477.806004 -274.228814)
				(arc
					(start 477.806004 -274.253198)
					(mid 477.739202 -274.778332)
					(end 477.6724 -274.253198)
				)
				(xy 477.6724 -274.228814)
				(arc
					(start 477.6724 -274.22475)
					(mid 477.668378 -274.204532)
					(end 477.656906 -274.187412)
				)
				(arc
					(start 477.656906 -274.187412)
					(mid 477.639775 -274.175966)
					(end 477.619568 -274.171918)
				)
				(xy 477.615504 -274.171664) (xy 477.358202 -274.171664)
				(arc
					(start 477.358202 -274.511262)
					(mid 477.739075 -274.892516)
					(end 478.120202 -274.511516)
				)
			)
		)
	)
	(zone
		(layer "In9.Cu")
		(hatch none 0.5)
		(connect_pads
			(clearance 0)
		)
		(min_thickness 0.25)
		(keepout
			(tracks not_allowed)
			(vias allowed)
			(pads allowed)
			(copperpour not_allowed)
			(footprints allowed)
		)
		(placement
			(enabled no)
			(sheetname "")
		)
		(fill
			(thermal_gap 0.5)
			(thermal_bridge_width 0.5)
			(island_removal_mode 0)
		)
		(polygon
			(pts
				(arc
					(start 415.020252 -158.368492)
					(mid 414.639252 -157.987492)
					(end 414.258252 -158.368492)
				)
				(xy 414.258252 -158.708344) (xy 414.515554 -158.708344)
				(arc
					(start 414.519618 -158.70809)
					(mid 414.539836 -158.704068)
					(end 414.556956 -158.692596)
				)
				(arc
					(start 414.556956 -158.692596)
					(mid 414.568402 -158.675465)
					(end 414.57245 -158.655258)
				)
				(xy 414.572704 -158.651194)
				(arc
					(start 414.572704 -158.62681)
					(mid 414.639252 -158.10174)
					(end 414.7058 -158.62681)
				)
				(xy 414.7058 -158.651194) (xy 414.706054 -158.655258) (xy 414.7058 -158.662116) (xy 414.7058 -158.682944)
				(arc
					(start 414.703514 -158.68523)
					(mid 414.685504 -158.740262)
					(end 414.651444 -158.787084)
				)
				(arc
					(start 414.651444 -158.787084)
					(mid 414.604608 -158.821117)
					(end 414.54959 -158.839154)
				)
				(xy 414.547304 -158.84144) (xy 414.526476 -158.84144) (xy 414.519618 -158.841694) (xy 414.515554 -158.84144)
				(xy 414.258252 -158.84144) (xy 414.258252 -159.038544) (xy 414.515554 -159.038544) (xy 414.519618 -159.03829)
				(xy 414.526476 -159.038544) (xy 414.547304 -159.038544)
				(arc
					(start 414.54959 -159.04083)
					(mid 414.604622 -159.05884)
					(end 414.651444 -159.0929)
				)
				(arc
					(start 414.651444 -159.0929)
					(mid 414.685477 -159.139736)
					(end 414.703514 -159.194754)
				)
				(xy 414.7058 -159.19704) (xy 414.7058 -159.217868) (xy 414.706054 -159.224726) (xy 414.7058 -159.22879)
				(arc
					(start 414.7058 -159.253174)
					(mid 414.639252 -159.778244)
					(end 414.572704 -159.253174)
				)
				(xy 414.572704 -159.22879)
				(arc
					(start 414.57245 -159.224726)
					(mid 414.568428 -159.204508)
					(end 414.556956 -159.187388)
				)
				(arc
					(start 414.556956 -159.187388)
					(mid 414.539825 -159.175942)
					(end 414.519618 -159.171894)
				)
				(xy 414.515554 -159.17164) (xy 414.258252 -159.17164)
				(arc
					(start 414.258252 -159.511238)
					(mid 414.639125 -159.892492)
					(end 415.020252 -159.511492)
				)
			)
		)
	)
	(zone
		(layer "In9.Cu")
		(hatch none 0.5)
		(connect_pads
			(clearance 0)
		)
		(min_thickness 0.25)
		(keepout
			(tracks not_allowed)
			(vias allowed)
			(pads allowed)
			(copperpour not_allowed)
			(footprints allowed)
		)
		(placement
			(enabled no)
			(sheetname "")
		)
		(fill
			(thermal_gap 0.5)
			(thermal_bridge_width 0.5)
			(island_removal_mode 0)
		)
		(polygon
			(pts
				(arc
					(start 283.563314 -126.872746)
					(mid 282.622752 -127.186436)
					(end 282.936442 -128.126998)
				)
				(xy 283.224986 -128.27127)
				(arc
					(start 283.58592 -128.27127)
					(mid 283.769427 -128.236103)
					(end 283.926788 -128.13538)
				)
				(arc
					(start 283.982922 -128.022858)
					(mid 283.986109 -127.979243)
					(end 283.957522 -127.94615)
				)
				(arc
					(start 283.695648 -127.815086)
					(mid 282.761556 -127.255134)
					(end 283.769562 -127.667512)
				)
				(xy 284.031182 -127.798322) (xy 284.031436 -127.798322) (xy 284.061916 -127.813816)
				(arc
					(start 284.063186 -127.81788)
					(mid 284.142706 -127.926856)
					(end 284.144466 -128.06172)
				)
				(xy 284.14599 -128.066038) (xy 284.052772 -128.25222)
				(arc
					(start 284.038294 -128.257046)
					(mid 283.845435 -128.383172)
					(end 283.620972 -128.435354)
				)
				(xy 283.62021 -128.43637) (xy 283.555186 -128.43637)
				(arc
					(start 283.767022 -128.542288)
					(mid 283.985259 -128.45459)
					(end 284.167834 -128.306322)
				)
				(xy 284.259782 -128.12268)
				(arc
					(start 284.263846 -128.12141)
					(mid 284.372822 -128.04189)
					(end 284.507686 -128.04013)
				)
				(xy 284.512004 -128.038606)
				(arc
					(start 284.80385 -128.184656)
					(mid 285.738843 -128.743587)
					(end 284.73019 -128.33223)
				)
				(arc
					(start 284.468824 -128.201674)
					(mid 284.425209 -128.198487)
					(end 284.392116 -128.227074)
				)
				(xy 284.295088 -128.420876)
				(arc
					(start 284.28315 -128.424686)
					(mid 284.139736 -128.550769)
					(end 283.974032 -128.645666)
				)
				(arc
					(start 284.928056 -129.122678)
					(mid 285.874832 -128.817493)
					(end 285.56331 -127.872744)
				)
			)
		)
	)
	(zone
		(layer "In9.Cu")
		(hatch none 0.5)
		(connect_pads
			(clearance 0)
		)
		(min_thickness 0.25)
		(keepout
			(tracks not_allowed)
			(vias allowed)
			(pads allowed)
			(copperpour not_allowed)
			(footprints allowed)
		)
		(placement
			(enabled no)
			(sheetname "")
		)
		(fill
			(thermal_gap 0.5)
			(thermal_bridge_width 0.5)
			(island_removal_mode 0)
		)
		(polygon
			(pts
				(arc
					(start 278.23668 -297.75658)
					(mid 277.68804 -298.30522)
					(end 278.23668 -298.85386)
				)
				(xy 278.705056 -298.85386) (xy 278.705056 -298.446444)
				(arc
					(start 278.704802 -298.44238)
					(mid 278.700254 -298.419426)
					(end 278.687276 -298.399962)
				)
				(xy 278.684482 -298.396914) (xy 278.67991 -298.392342)
				(arc
					(start 278.676862 -298.389548)
					(mid 278.657386 -298.376598)
					(end 278.634444 -298.372022)
				)
				(xy 278.63038 -298.371768)
				(arc
					(start 278.624792 -298.371768)
					(mid 277.842904 -298.30522)
					(end 278.624792 -298.238672)
				)
				(xy 278.63038 -298.238672) (xy 278.634444 -298.238418) (xy 278.641556 -298.238672) (xy 278.66213 -298.238672)
				(arc
					(start 278.664162 -298.240704)
					(mid 278.708431 -298.253171)
					(end 278.74849 -298.275756)
				)
				(xy 278.751792 -298.275756) (xy 278.76627 -298.290234) (xy 278.77135 -298.29506) (xy 278.774144 -298.298108)
				(xy 278.778716 -298.30268) (xy 278.781764 -298.305474) (xy 278.78659 -298.310554) (xy 278.801068 -298.325032)
				(arc
					(start 278.801068 -298.328334)
					(mid 278.823621 -298.368406)
					(end 278.83612 -298.412662)
				)
				(xy 278.838152 -298.414694) (xy 278.838152 -298.435268) (xy 278.838406 -298.44238) (xy 278.838152 -298.446444)
				(xy 278.838152 -298.85386) (xy 279.035256 -298.85386) (xy 279.035256 -298.446444) (xy 279.035002 -298.44238)
				(xy 279.035256 -298.435268) (xy 279.035256 -298.414694)
				(arc
					(start 279.037288 -298.412662)
					(mid 279.049755 -298.368393)
					(end 279.07234 -298.328334)
				)
				(xy 279.07234 -298.325032) (xy 279.086818 -298.310554) (xy 279.091644 -298.305474) (xy 279.094692 -298.30268)
				(xy 279.099264 -298.298108) (xy 279.102058 -298.29506) (xy 279.107138 -298.290234) (xy 279.121616 -298.275756)
				(arc
					(start 279.124918 -298.275756)
					(mid 279.16499 -298.253203)
					(end 279.209246 -298.240704)
				)
				(xy 279.211278 -298.238672) (xy 279.231852 -298.238672) (xy 279.238964 -298.238418) (xy 279.243028 -298.238672)
				(arc
					(start 279.248616 -298.238672)
					(mid 280.030504 -298.30522)
					(end 279.248616 -298.371768)
				)
				(xy 279.243028 -298.371768)
				(arc
					(start 279.238964 -298.372022)
					(mid 279.21601 -298.37657)
					(end 279.196546 -298.389548)
				)
				(xy 279.193498 -298.392342) (xy 279.188926 -298.396914)
				(arc
					(start 279.186132 -298.399962)
					(mid 279.173182 -298.419438)
					(end 279.168606 -298.44238)
				)
				(xy 279.168352 -298.446444) (xy 279.168352 -298.85386)
				(arc
					(start 279.636728 -298.85386)
					(mid 280.185368 -298.30522)
					(end 279.636728 -297.75658)
				)
				(xy 278.236934 -297.75658)
			)
		)
	)
	(zone
		(layer "In9.Cu")
		(hatch none 0.5)
		(connect_pads
			(clearance 0)
		)
		(min_thickness 0.25)
		(keepout
			(tracks not_allowed)
			(vias allowed)
			(pads allowed)
			(copperpour not_allowed)
			(footprints allowed)
		)
		(placement
			(enabled no)
			(sheetname "")
		)
		(fill
			(thermal_gap 0.5)
			(thermal_bridge_width 0.5)
			(island_removal_mode 0)
		)
		(polygon
			(pts
				(arc
					(start 278.23668 -344.556588)
					(mid 277.68804 -345.105228)
					(end 278.23668 -345.653868)
				)
				(xy 278.705056 -345.653868) (xy 278.705056 -345.246452)
				(arc
					(start 278.704802 -345.242388)
					(mid 278.700254 -345.219434)
					(end 278.687276 -345.19997)
				)
				(xy 278.684482 -345.196922) (xy 278.67991 -345.19235)
				(arc
					(start 278.676862 -345.189556)
					(mid 278.657386 -345.176606)
					(end 278.634444 -345.17203)
				)
				(xy 278.63038 -345.171776)
				(arc
					(start 278.624792 -345.171776)
					(mid 277.842904 -345.105228)
					(end 278.624792 -345.03868)
				)
				(xy 278.63038 -345.03868) (xy 278.634444 -345.038426) (xy 278.641556 -345.03868) (xy 278.66213 -345.03868)
				(arc
					(start 278.664162 -345.040712)
					(mid 278.708431 -345.053179)
					(end 278.74849 -345.075764)
				)
				(xy 278.751792 -345.075764) (xy 278.76627 -345.090242) (xy 278.77135 -345.095068) (xy 278.774144 -345.098116)
				(xy 278.778716 -345.102688) (xy 278.781764 -345.105482) (xy 278.78659 -345.110562) (xy 278.801068 -345.12504)
				(arc
					(start 278.801068 -345.128342)
					(mid 278.823621 -345.168414)
					(end 278.83612 -345.21267)
				)
				(xy 278.838152 -345.214702) (xy 278.838152 -345.235276) (xy 278.838406 -345.242388) (xy 278.838152 -345.246452)
				(xy 278.838152 -345.653868) (xy 279.035256 -345.653868) (xy 279.035256 -345.246452) (xy 279.035002 -345.242388)
				(xy 279.035256 -345.235276) (xy 279.035256 -345.214702)
				(arc
					(start 279.037288 -345.21267)
					(mid 279.049755 -345.168401)
					(end 279.07234 -345.128342)
				)
				(xy 279.07234 -345.12504) (xy 279.086818 -345.110562) (xy 279.091644 -345.105482) (xy 279.094692 -345.102688)
				(xy 279.099264 -345.098116) (xy 279.102058 -345.095068) (xy 279.107138 -345.090242) (xy 279.121616 -345.075764)
				(arc
					(start 279.124918 -345.075764)
					(mid 279.16499 -345.053211)
					(end 279.209246 -345.040712)
				)
				(xy 279.211278 -345.03868) (xy 279.231852 -345.03868) (xy 279.238964 -345.038426) (xy 279.243028 -345.03868)
				(arc
					(start 279.248616 -345.03868)
					(mid 280.030504 -345.105228)
					(end 279.248616 -345.171776)
				)
				(xy 279.243028 -345.171776)
				(arc
					(start 279.238964 -345.17203)
					(mid 279.21601 -345.176578)
					(end 279.196546 -345.189556)
				)
				(xy 279.193498 -345.19235) (xy 279.188926 -345.196922)
				(arc
					(start 279.186132 -345.19997)
					(mid 279.173182 -345.219446)
					(end 279.168606 -345.242388)
				)
				(xy 279.168352 -345.246452) (xy 279.168352 -345.653868)
				(arc
					(start 279.636728 -345.653868)
					(mid 280.185368 -345.105228)
					(end 279.636728 -344.556588)
				)
				(xy 278.236934 -344.556588)
			)
		)
	)
	(zone
		(layer "In9.Cu")
		(hatch none 0.5)
		(connect_pads
			(clearance 0)
		)
		(min_thickness 0.25)
		(keepout
			(tracks not_allowed)
			(vias allowed)
			(pads allowed)
			(copperpour not_allowed)
			(footprints allowed)
		)
		(placement
			(enabled no)
			(sheetname "")
		)
		(fill
			(thermal_gap 0.5)
			(thermal_bridge_width 0.5)
			(island_removal_mode 0)
		)
		(polygon
			(pts
				(arc
					(start 415.020252 -273.368516)
					(mid 414.639252 -272.987516)
					(end 414.258252 -273.368516)
				)
				(xy 414.258252 -273.708368) (xy 414.515554 -273.708368)
				(arc
					(start 414.519618 -273.708114)
					(mid 414.539836 -273.704092)
					(end 414.556956 -273.69262)
				)
				(arc
					(start 414.556956 -273.69262)
					(mid 414.568402 -273.675489)
					(end 414.57245 -273.655282)
				)
				(xy 414.57245 -273.651218)
				(arc
					(start 414.57245 -273.626834)
					(mid 414.639375 -273.1017)
					(end 414.7058 -273.626834)
				)
				(xy 414.7058 -273.651218) (xy 414.706054 -273.655282) (xy 414.7058 -273.66214) (xy 414.7058 -273.682968)
				(arc
					(start 414.703514 -273.685254)
					(mid 414.685504 -273.740286)
					(end 414.651444 -273.787108)
				)
				(arc
					(start 414.651444 -273.787108)
					(mid 414.604608 -273.821141)
					(end 414.54959 -273.839178)
				)
				(xy 414.547304 -273.841464) (xy 414.526476 -273.841464) (xy 414.519618 -273.841718) (xy 414.515554 -273.841464)
				(xy 414.258252 -273.841464) (xy 414.258252 -274.038568) (xy 414.515554 -274.038568) (xy 414.519618 -274.038314)
				(xy 414.526476 -274.038568) (xy 414.547304 -274.038568)
				(arc
					(start 414.54959 -274.040854)
					(mid 414.604622 -274.058864)
					(end 414.651444 -274.092924)
				)
				(arc
					(start 414.651444 -274.092924)
					(mid 414.685477 -274.13976)
					(end 414.703514 -274.194778)
				)
				(xy 414.7058 -274.197064) (xy 414.7058 -274.217892) (xy 414.706054 -274.22475) (xy 414.7058 -274.228814)
				(arc
					(start 414.7058 -274.253198)
					(mid 414.639252 -274.778268)
					(end 414.572704 -274.253198)
				)
				(xy 414.572704 -274.228814)
				(arc
					(start 414.57245 -274.22475)
					(mid 414.568428 -274.204532)
					(end 414.556956 -274.187412)
				)
				(arc
					(start 414.556956 -274.187412)
					(mid 414.539825 -274.175966)
					(end 414.519618 -274.171918)
				)
				(xy 414.515554 -274.171664) (xy 414.258252 -274.171664)
				(arc
					(start 414.258252 -274.511262)
					(mid 414.639125 -274.892516)
					(end 415.020252 -274.511516)
				)
			)
		)
	)
	(zone
		(layer "In9.Cu")
		(hatch none 0.5)
		(connect_pads
			(clearance 0)
		)
		(min_thickness 0.25)
		(keepout
			(tracks not_allowed)
			(vias allowed)
			(pads allowed)
			(copperpour not_allowed)
			(footprints allowed)
		)
		(placement
			(enabled no)
			(sheetname "")
		)
		(fill
			(thermal_gap 0.5)
			(thermal_bridge_width 0.5)
			(island_removal_mode 0)
		)
		(polygon
			(pts
				(arc
					(start 463.801968 -92.80017)
					(mid 456.674982 -85.673184)
					(end 449.547996 -92.80017)
				)
				(arc
					(start 449.547996 -98.800412)
					(mid 456.674982 -105.927144)
					(end 463.801968 -98.800412)
				)
			)
		)
	)
	(zone
		(layer "In9.Cu")
		(hatch none 0.5)
		(connect_pads
			(clearance 0)
		)
		(min_thickness 0.25)
		(keepout
			(tracks not_allowed)
			(vias allowed)
			(pads allowed)
			(copperpour not_allowed)
			(footprints allowed)
		)
		(placement
			(enabled no)
			(sheetname "")
		)
		(fill
			(thermal_gap 0.5)
			(thermal_bridge_width 0.5)
			(island_removal_mode 0)
		)
		(polygon
			(pts
				(arc
					(start 293.073074 -144.200372)
					(mid 300.20006 -151.327358)
					(end 307.327046 -144.200372)
				)
				(arc
					(start 307.327046 -138.20013)
					(mid 300.20006 -131.073144)
					(end 293.073074 -138.20013)
				)
			)
		)
	)
	(zone
		(layer "In9.Cu")
		(hatch none 0.5)
		(connect_pads
			(clearance 0)
		)
		(min_thickness 0.25)
		(keepout
			(tracks not_allowed)
			(vias allowed)
			(pads allowed)
			(copperpour not_allowed)
			(footprints allowed)
		)
		(placement
			(enabled no)
			(sheetname "")
		)
		(fill
			(thermal_gap 0.5)
			(thermal_bridge_width 0.5)
			(island_removal_mode 0)
		)
		(polygon
			(pts
				(arc
					(start 283.571696 -158.877)
					(mid 282.62492 -159.182185)
					(end 282.936442 -160.126934)
				)
				(xy 283.224986 -160.271206)
				(arc
					(start 283.58592 -160.271206)
					(mid 283.769427 -160.236039)
					(end 283.926788 -160.135316)
				)
				(arc
					(start 283.982922 -160.022794)
					(mid 283.986109 -159.979179)
					(end 283.957522 -159.946086)
				)
				(arc
					(start 283.695648 -159.815022)
					(mid 282.761556 -159.25507)
					(end 283.769562 -159.667448)
				)
				(xy 284.031182 -159.798258) (xy 284.031436 -159.798258) (xy 284.061916 -159.813752)
				(arc
					(start 284.063186 -159.817816)
					(mid 284.142706 -159.926792)
					(end 284.144466 -160.061656)
				)
				(xy 284.14599 -160.065974) (xy 284.052772 -160.252156)
				(arc
					(start 284.038294 -160.256982)
					(mid 283.845435 -160.383108)
					(end 283.620972 -160.43529)
				)
				(xy 283.62021 -160.436306) (xy 283.555186 -160.436306)
				(arc
					(start 283.767022 -160.542224)
					(mid 283.985259 -160.454526)
					(end 284.167834 -160.306258)
				)
				(xy 284.259782 -160.122616)
				(arc
					(start 284.263846 -160.121346)
					(mid 284.372822 -160.041826)
					(end 284.507686 -160.040066)
				)
				(xy 284.512004 -160.038542)
				(arc
					(start 284.80385 -160.184592)
					(mid 285.738843 -160.743523)
					(end 284.73019 -160.332166)
				)
				(arc
					(start 284.468824 -160.20161)
					(mid 284.425209 -160.198423)
					(end 284.392116 -160.22701)
				)
				(xy 284.295088 -160.420812)
				(arc
					(start 284.28315 -160.424622)
					(mid 284.13973 -160.550798)
					(end 283.974032 -160.645856)
				)
				(arc
					(start 284.936438 -161.126932)
					(mid 285.877 -160.813242)
					(end 285.56331 -159.87268)
				)
			)
		)
	)
	(zone
		(layer "In9.Cu")
		(hatch none 0.5)
		(connect_pads
			(clearance 0)
		)
		(min_thickness 0.25)
		(keepout
			(tracks not_allowed)
			(vias allowed)
			(pads allowed)
			(copperpour not_allowed)
			(footprints allowed)
		)
		(placement
			(enabled no)
			(sheetname "")
		)
		(fill
			(thermal_gap 0.5)
			(thermal_bridge_width 0.5)
			(island_removal_mode 0)
		)
		(polygon
			(pts
				(arc
					(start 115.098576 -18.350484)
					(mid 114.550063 -17.80159)
					(end 114.001296 -18.35023)
				)
				(arc
					(start 114.001296 -19.750024)
					(mid 114.549936 -20.298664)
					(end 115.098576 -19.750024)
				)
				(xy 115.098576 -19.278854)
				(arc
					(start 114.69243 -19.278854)
					(mid 114.675517 -19.282218)
					(end 114.661188 -19.291808)
				)
				(arc
					(start 114.64544 -19.307556)
					(mid 114.635862 -19.32189)
					(end 114.632486 -19.338798)
				)
				(arc
					(start 114.632486 -19.36496)
					(mid 114.549936 -20.143837)
					(end 114.467386 -19.36496)
				)
				(xy 114.467386 -19.304508)
				(arc
					(start 114.470688 -19.301206)
					(mid 114.483223 -19.258632)
					(end 114.50447 -19.219672)
				)
				(xy 114.50447 -19.214846) (xy 114.568478 -19.150838)
				(arc
					(start 114.573304 -19.150838)
					(mid 114.612278 -19.129626)
					(end 114.654838 -19.117056)
				)
				(xy 114.65814 -19.113754) (xy 115.098576 -19.113754) (xy 115.098576 -18.986754) (xy 114.726974 -18.986754)
				(xy 114.658394 -18.986754)
				(arc
					(start 114.654838 -18.983198)
					(mid 114.612264 -18.970663)
					(end 114.573304 -18.949416)
				)
				(xy 114.568478 -18.949416) (xy 114.50447 -18.885408)
				(arc
					(start 114.50447 -18.880582)
					(mid 114.483258 -18.841608)
					(end 114.470688 -18.799048)
				)
				(xy 114.467386 -18.795746)
				(arc
					(start 114.467386 -18.735294)
					(mid 114.549936 -17.956417)
					(end 114.632486 -18.735294)
				)
				(arc
					(start 114.632486 -18.761456)
					(mid 114.63585 -18.778369)
					(end 114.64544 -18.792698)
				)
				(arc
					(start 114.661188 -18.808446)
					(mid 114.675522 -18.818024)
					(end 114.69243 -18.8214)
				)
				(xy 114.72672 -18.8214) (xy 114.726974 -18.821654) (xy 115.098576 -18.821654)
			)
		)
	)
	(zone
		(layer "In9.Cu")
		(hatch none 0.5)
		(connect_pads
			(clearance 0)
		)
		(min_thickness 0.25)
		(keepout
			(tracks not_allowed)
			(vias allowed)
			(pads allowed)
			(copperpour not_allowed)
			(footprints allowed)
		)
		(placement
			(enabled no)
			(sheetname "")
		)
		(fill
			(thermal_gap 0.5)
			(thermal_bridge_width 0.5)
			(island_removal_mode 0)
		)
		(polygon
			(pts
				(arc
					(start 240.863374 -50.572924)
					(mid 239.922812 -50.886614)
					(end 240.236502 -51.827176)
				)
				(xy 240.525046 -51.971448)
				(arc
					(start 240.88598 -51.971448)
					(mid 241.069487 -51.936281)
					(end 241.226848 -51.835558)
				)
				(arc
					(start 241.282982 -51.723036)
					(mid 241.286169 -51.679421)
					(end 241.257582 -51.646328)
				)
				(arc
					(start 240.995708 -51.515264)
					(mid 240.061616 -50.955312)
					(end 241.069622 -51.36769)
				)
				(xy 241.331242 -51.4985) (xy 241.331496 -51.4985) (xy 241.361976 -51.513994)
				(arc
					(start 241.363246 -51.518058)
					(mid 241.442766 -51.627034)
					(end 241.444526 -51.761898)
				)
				(xy 241.44605 -51.766216) (xy 241.352832 -51.952398)
				(arc
					(start 241.338354 -51.957224)
					(mid 241.145495 -52.08335)
					(end 240.921032 -52.135532)
				)
				(xy 240.92027 -52.136548) (xy 240.855246 -52.136548)
				(arc
					(start 241.067082 -52.242466)
					(mid 241.285319 -52.154768)
					(end 241.467894 -52.0065)
				)
				(xy 241.559842 -51.822858)
				(arc
					(start 241.563906 -51.821588)
					(mid 241.672882 -51.742068)
					(end 241.807746 -51.740308)
				)
				(xy 241.812064 -51.738784)
				(arc
					(start 242.10391 -51.884834)
					(mid 243.038903 -52.443765)
					(end 242.03025 -52.032408)
				)
				(arc
					(start 241.768884 -51.901852)
					(mid 241.725269 -51.898665)
					(end 241.692176 -51.927252)
				)
				(xy 241.595148 -52.121054)
				(arc
					(start 241.58321 -52.124864)
					(mid 241.439796 -52.250947)
					(end 241.274092 -52.345844)
				)
				(arc
					(start 242.228116 -52.822856)
					(mid 243.174892 -52.517671)
					(end 242.86337 -51.572922)
				)
			)
		)
	)
	(zone
		(layer "In9.Cu")
		(hatch none 0.5)
		(connect_pads
			(clearance 0)
		)
		(min_thickness 0.25)
		(keepout
			(tracks not_allowed)
			(vias allowed)
			(pads allowed)
			(copperpour not_allowed)
			(footprints allowed)
		)
		(placement
			(enabled no)
			(sheetname "")
		)
		(fill
			(thermal_gap 0.5)
			(thermal_bridge_width 0.5)
			(island_removal_mode 0)
		)
		(polygon
			(pts
				(arc
					(start 166.452042 -92.80017)
					(mid 159.325056 -85.673184)
					(end 152.19807 -92.80017)
				)
				(arc
					(start 152.19807 -98.800412)
					(mid 159.325056 -105.927144)
					(end 166.452042 -98.800412)
				)
			)
		)
	)
	(zone
		(layer "In9.Cu")
		(hatch none 0.5)
		(connect_pads
			(clearance 0)
		)
		(min_thickness 0.25)
		(keepout
			(tracks not_allowed)
			(vias allowed)
			(pads allowed)
			(copperpour not_allowed)
			(footprints allowed)
		)
		(placement
			(enabled no)
			(sheetname "")
		)
		(fill
			(thermal_gap 0.5)
			(thermal_bridge_width 0.5)
			(island_removal_mode 0)
		)
		(polygon
			(pts
				(xy 107.98683 -17.017492) (xy 107.98683 -15.767558) (xy 144.42313 -15.767558) (xy 144.42313 -17.017492)
			)
		)
	)
	(zone
		(layer "In9.Cu")
		(hatch none 0.5)
		(connect_pads
			(clearance 0)
		)
		(min_thickness 0.25)
		(keepout
			(tracks not_allowed)
			(vias allowed)
			(pads allowed)
			(copperpour not_allowed)
			(footprints allowed)
		)
		(placement
			(enabled no)
			(sheetname "")
		)
		(fill
			(thermal_gap 0.5)
			(thermal_bridge_width 0.5)
			(island_removal_mode 0)
		)
		(polygon
			(pts
				(xy 353.844606 -17.004284) (xy 353.844606 -15.670784) (xy 390.663176 -15.670784) (xy 390.663176 -17.004284)
			)
		)
	)
	(zone
		(layer "In9.Cu")
		(hatch none 0.5)
		(connect_pads
			(clearance 0)
		)
		(min_thickness 0.25)
		(keepout
			(tracks not_allowed)
			(vias allowed)
			(pads allowed)
			(copperpour not_allowed)
			(footprints allowed)
		)
		(placement
			(enabled no)
			(sheetname "")
		)
		(fill
			(thermal_gap 0.5)
			(thermal_bridge_width 0.5)
			(island_removal_mode 0)
		)
		(polygon
			(pts
				(arc
					(start 133.09854 -18.35023)
					(mid 132.5499 -17.80159)
					(end 132.00126 -18.35023)
				)
				(arc
					(start 132.00126 -19.74977)
					(mid 132.549773 -20.298664)
					(end 133.09854 -19.750024)
				)
				(xy 133.09854 -19.278854)
				(arc
					(start 132.692394 -19.278854)
					(mid 132.675481 -19.282218)
					(end 132.661152 -19.291808)
				)
				(arc
					(start 132.645404 -19.307556)
					(mid 132.635826 -19.32189)
					(end 132.63245 -19.338798)
				)
				(arc
					(start 132.63245 -19.36496)
					(mid 132.5499 -20.143837)
					(end 132.46735 -19.36496)
				)
				(xy 132.46735 -19.304508)
				(arc
					(start 132.470652 -19.301206)
					(mid 132.483187 -19.258632)
					(end 132.504434 -19.219672)
				)
				(xy 132.504434 -19.214846) (xy 132.568442 -19.150838)
				(arc
					(start 132.573268 -19.150838)
					(mid 132.612242 -19.129626)
					(end 132.654802 -19.117056)
				)
				(xy 132.658104 -19.113754) (xy 133.09854 -19.113754) (xy 133.09854 -18.986754) (xy 132.726938 -18.986754)
				(xy 132.658358 -18.986754)
				(arc
					(start 132.654802 -18.983198)
					(mid 132.612228 -18.970663)
					(end 132.573268 -18.949416)
				)
				(xy 132.568442 -18.949416) (xy 132.504434 -18.885408)
				(arc
					(start 132.504434 -18.880582)
					(mid 132.483222 -18.841608)
					(end 132.470652 -18.799048)
				)
				(xy 132.46735 -18.795746)
				(arc
					(start 132.46735 -18.735294)
					(mid 132.5499 -17.956417)
					(end 132.63245 -18.735294)
				)
				(arc
					(start 132.63245 -18.761456)
					(mid 132.635814 -18.778369)
					(end 132.645404 -18.792698)
				)
				(arc
					(start 132.661152 -18.808446)
					(mid 132.675486 -18.818024)
					(end 132.692394 -18.8214)
				)
				(xy 132.726684 -18.8214) (xy 132.726938 -18.821654) (xy 133.09854 -18.821654)
			)
		)
	)
	(zone
		(layer "In9.Cu")
		(hatch none 0.5)
		(connect_pads
			(clearance 0)
		)
		(min_thickness 0.25)
		(keepout
			(tracks not_allowed)
			(vias allowed)
			(pads allowed)
			(copperpour not_allowed)
			(footprints allowed)
		)
		(placement
			(enabled no)
			(sheetname "")
		)
		(fill
			(thermal_gap 0.5)
			(thermal_bridge_width 0.5)
			(island_removal_mode 0)
		)
		(polygon
			(pts
				(arc
					(start 195.173092 -69.800216)
					(mid 202.300078 -76.927202)
					(end 209.427064 -69.800216)
				)
				(arc
					(start 209.427064 -63.800228)
					(mid 202.300078 -56.673242)
					(end 195.173092 -63.800228)
				)
			)
		)
	)
	(zone
		(layer "In9.Cu")
		(hatch none 0.5)
		(connect_pads
			(clearance 0)
		)
		(min_thickness 0.25)
		(keepout
			(tracks not_allowed)
			(vias allowed)
			(pads allowed)
			(copperpour not_allowed)
			(footprints allowed)
		)
		(placement
			(enabled no)
			(sheetname "")
		)
		(fill
			(thermal_gap 0.5)
			(thermal_bridge_width 0.5)
			(island_removal_mode 0)
		)
		(polygon
			(pts
				(arc
					(start 337.801966 -207.800194)
					(mid 330.67498 -200.673208)
					(end 323.547994 -207.800194)
				)
				(arc
					(start 323.547994 -213.800436)
					(mid 330.67498 -220.927168)
					(end 337.801966 -213.800436)
				)
			)
		)
	)
	(zone
		(layer "In9.Cu")
		(hatch none 0.5)
		(connect_pads
			(clearance 0)
		)
		(min_thickness 0.25)
		(keepout
			(tracks not_allowed)
			(vias allowed)
			(pads allowed)
			(copperpour not_allowed)
			(footprints allowed)
		)
		(placement
			(enabled no)
			(sheetname "")
		)
		(fill
			(thermal_gap 0.5)
			(thermal_bridge_width 0.5)
			(island_removal_mode 0)
		)
		(polygon
			(pts
				(arc
					(start 240.863374 -70.572884)
					(mid 239.922812 -70.886574)
					(end 240.236502 -71.827136)
				)
				(xy 240.525046 -71.971408)
				(arc
					(start 240.88598 -71.971408)
					(mid 241.069487 -71.936241)
					(end 241.226848 -71.835518)
				)
				(arc
					(start 241.282982 -71.722996)
					(mid 241.286169 -71.679381)
					(end 241.257582 -71.646288)
				)
				(arc
					(start 240.995708 -71.515224)
					(mid 240.061616 -70.955272)
					(end 241.069622 -71.36765)
				)
				(xy 241.331242 -71.49846) (xy 241.331496 -71.49846) (xy 241.361976 -71.513954)
				(arc
					(start 241.363246 -71.518018)
					(mid 241.442766 -71.626994)
					(end 241.444526 -71.761858)
				)
				(xy 241.44605 -71.766176) (xy 241.352832 -71.952358)
				(arc
					(start 241.338354 -71.957184)
					(mid 241.145495 -72.08331)
					(end 240.921032 -72.135492)
				)
				(xy 240.92027 -72.136508) (xy 240.855246 -72.136508)
				(arc
					(start 241.067082 -72.242426)
					(mid 241.285319 -72.154728)
					(end 241.467894 -72.00646)
				)
				(xy 241.559842 -71.822818)
				(arc
					(start 241.563906 -71.821548)
					(mid 241.672882 -71.742028)
					(end 241.807746 -71.740268)
				)
				(xy 241.812064 -71.738744)
				(arc
					(start 242.10391 -71.884794)
					(mid 243.038903 -72.443725)
					(end 242.03025 -72.032368)
				)
				(arc
					(start 241.768884 -71.901812)
					(mid 241.725269 -71.898625)
					(end 241.692176 -71.927212)
				)
				(xy 241.595148 -72.121014)
				(arc
					(start 241.58321 -72.124824)
					(mid 241.439796 -72.250907)
					(end 241.274092 -72.345804)
				)
				(arc
					(start 242.228116 -72.822816)
					(mid 243.174892 -72.517631)
					(end 242.86337 -71.572882)
				)
			)
		)
	)
	(zone
		(layer "In9.Cu")
		(hatch none 0.5)
		(connect_pads
			(clearance 0)
		)
		(min_thickness 0.25)
		(keepout
			(tracks not_allowed)
			(vias allowed)
			(pads allowed)
			(copperpour not_allowed)
			(footprints allowed)
		)
		(placement
			(enabled no)
			(sheetname "")
		)
		(fill
			(thermal_gap 0.5)
			(thermal_bridge_width 0.5)
			(island_removal_mode 0)
		)
		(polygon
			(pts
				(arc
					(start 240.871756 -58.577226)
					(mid 239.92498 -58.882411)
					(end 240.236502 -59.82716)
				)
				(xy 240.525046 -59.971432)
				(arc
					(start 240.88598 -59.971432)
					(mid 241.069487 -59.936265)
					(end 241.226848 -59.835542)
				)
				(arc
					(start 241.282982 -59.72302)
					(mid 241.286169 -59.679405)
					(end 241.257582 -59.646312)
				)
				(arc
					(start 240.995708 -59.515248)
					(mid 240.061616 -58.955296)
					(end 241.069622 -59.367674)
				)
				(xy 241.331242 -59.498484) (xy 241.331496 -59.498484) (xy 241.361976 -59.513978)
				(arc
					(start 241.363246 -59.518042)
					(mid 241.442766 -59.627018)
					(end 241.444526 -59.761882)
				)
				(xy 241.44605 -59.7662) (xy 241.352832 -59.952382)
				(arc
					(start 241.338354 -59.957208)
					(mid 241.145495 -60.083334)
					(end 240.921032 -60.135516)
				)
				(xy 240.92027 -60.136532) (xy 240.855246 -60.136532)
				(arc
					(start 241.067082 -60.24245)
					(mid 241.285319 -60.154752)
					(end 241.467894 -60.006484)
				)
				(xy 241.559842 -59.822842)
				(arc
					(start 241.563906 -59.821572)
					(mid 241.672882 -59.742052)
					(end 241.807746 -59.740292)
				)
				(xy 241.812064 -59.738768)
				(arc
					(start 242.10391 -59.884818)
					(mid 243.038903 -60.443749)
					(end 242.03025 -60.032392)
				)
				(arc
					(start 241.768884 -59.901836)
					(mid 241.725269 -59.898649)
					(end 241.692176 -59.927236)
				)
				(xy 241.595148 -60.121038)
				(arc
					(start 241.58321 -60.124848)
					(mid 241.43979 -60.251024)
					(end 241.274092 -60.346082)
				)
				(arc
					(start 242.236498 -60.827158)
					(mid 243.17706 -60.513468)
					(end 242.86337 -59.572906)
				)
			)
		)
	)
	(zone
		(net "P5V_A_2")
		(layer "In9.Cu")
		(hatch none 0.5)
		(connect_pads
			(clearance 0.5)
		)
		(min_thickness 0.25)
		(fill yes
			(thermal_gap 0.5)
			(thermal_bridge_width 0.5)
			(island_removal_mode 0)
		)
		(polygon
			(pts
				(xy 261.62762 8.390128) (xy 265.535664 8.390128) (xy 266.298426 9.15289) (xy 266.298426 17.980914)
				(xy 265.85164 18.4277) (xy 261.566152 18.4277) (xy 260.965442 17.82699) (xy 260.965442 9.052306)
			)
		)
	)
	(zone
		(layer "In9.Cu")
		(hatch none 0.5)
		(connect_pads
			(clearance 0)
		)
		(min_thickness 0.25)
		(keepout
			(tracks allowed)
			(vias allowed)
			(pads allowed)
			(copperpour allowed)
			(footprints allowed)
		)
		(placement
			(enabled no)
			(sheetname "")
		)
		(fill
			(thermal_gap 0.5)
			(thermal_bridge_width 0.5)
			(island_removal_mode 0)
		)
		(polygon
			(pts
				(xy 278.003 -119.888) (xy 278.003 -115.3668) (xy 286.9184 -115.3668) (xy 286.9184 -119.888)
			)
		)
	)
	(zone
		(layer "In9.Cu")
		(hatch none 0.5)
		(connect_pads
			(clearance 0)
		)
		(min_thickness 0.25)
		(keepout
			(tracks not_allowed)
			(vias allowed)
			(pads allowed)
			(copperpour not_allowed)
			(footprints allowed)
		)
		(placement
			(enabled no)
			(sheetname "")
		)
		(fill
			(thermal_gap 0.5)
			(thermal_bridge_width 0.5)
			(island_removal_mode 0)
		)
		(polygon
			(pts
				(arc
					(start 362.89869 -17.350232)
					(mid 362.350177 -16.801338)
					(end 361.80141 -17.349978)
				)
				(xy 361.80141 -17.821656) (xy 362.173012 -17.821656) (xy 362.173266 -17.821402)
				(arc
					(start 362.207556 -17.821402)
					(mid 362.224469 -17.818038)
					(end 362.238798 -17.808448)
				)
				(arc
					(start 362.265214 -17.782032)
					(mid 362.266904 -17.7796)
					(end 362.2675 -17.776698)
				)
				(arc
					(start 362.2675 -17.735042)
					(mid 362.35005 -16.956165)
					(end 362.4326 -17.735042)
				)
				(xy 362.4326 -17.810988)
				(arc
					(start 362.428282 -17.815306)
					(mid 362.419458 -17.842775)
					(end 362.406184 -17.868392)
				)
				(xy 362.406184 -17.874742) (xy 362.382054 -17.898872) (xy 362.331508 -17.949418)
				(arc
					(start 362.326682 -17.949418)
					(mid 362.287708 -17.97063)
					(end 362.245148 -17.9832)
				)
				(xy 362.241592 -17.986756) (xy 362.173012 -17.986756) (xy 361.80141 -17.986756) (xy 361.80141 -18.113756)
				(xy 362.241846 -18.113756)
				(arc
					(start 362.245148 -18.117058)
					(mid 362.287722 -18.129593)
					(end 362.326682 -18.15084)
				)
				(xy 362.331508 -18.15084) (xy 362.395516 -18.214848)
				(arc
					(start 362.395516 -18.219674)
					(mid 362.416728 -18.258648)
					(end 362.429298 -18.301208)
				)
				(xy 362.4326 -18.30451)
				(arc
					(start 362.4326 -18.364962)
					(mid 362.35005 -19.143839)
					(end 362.2675 -18.364962)
				)
				(arc
					(start 362.2675 -18.3388)
					(mid 362.264136 -18.321887)
					(end 362.254546 -18.307558)
				)
				(arc
					(start 362.238798 -18.29181)
					(mid 362.224464 -18.282232)
					(end 362.207556 -18.278856)
				)
				(xy 361.80141 -18.278856)
				(arc
					(start 361.80141 -18.750026)
					(mid 362.35005 -19.298666)
					(end 362.89869 -18.750026)
				)
			)
		)
	)
	(zone
		(layer "In9.Cu")
		(hatch none 0.5)
		(connect_pads
			(clearance 0)
		)
		(min_thickness 0.25)
		(keepout
			(tracks not_allowed)
			(vias allowed)
			(pads allowed)
			(copperpour not_allowed)
			(footprints allowed)
		)
		(placement
			(enabled no)
			(sheetname "")
		)
		(fill
			(thermal_gap 0.5)
			(thermal_bridge_width 0.5)
			(island_removal_mode 0)
		)
		(polygon
			(pts
				(arc
					(start 337.801966 -322.800218)
					(mid 330.67498 -315.673232)
					(end 323.547994 -322.800218)
				)
				(arc
					(start 323.547994 -328.800206)
					(mid 330.67498 -335.927192)
					(end 337.801966 -328.800206)
				)
			)
		)
	)
	(zone
		(layer "In9.Cu")
		(hatch none 0.5)
		(connect_pads
			(clearance 0)
		)
		(min_thickness 0.25)
		(keepout
			(tracks not_allowed)
			(vias allowed)
			(pads allowed)
			(copperpour not_allowed)
			(footprints allowed)
		)
		(placement
			(enabled no)
			(sheetname "")
		)
		(fill
			(thermal_gap 0.5)
			(thermal_bridge_width 0.5)
			(island_removal_mode 0)
		)
		(polygon
			(pts
				(arc
					(start 383.47015 -158.368492)
					(mid 383.08915 -157.987492)
					(end 382.70815 -158.368492)
				)
				(xy 382.70815 -158.708344) (xy 382.965452 -158.708344)
				(arc
					(start 382.969516 -158.70809)
					(mid 382.989734 -158.704068)
					(end 383.006854 -158.692596)
				)
				(arc
					(start 383.006854 -158.692596)
					(mid 383.0183 -158.675465)
					(end 383.022348 -158.655258)
				)
				(xy 383.022348 -158.651194)
				(arc
					(start 383.022348 -158.62681)
					(mid 383.08915 -158.101676)
					(end 383.155952 -158.62681)
				)
				(xy 383.155952 -158.651194) (xy 383.155952 -158.655258) (xy 383.155952 -158.662116) (xy 383.155952 -158.682944)
				(arc
					(start 383.153412 -158.68523)
					(mid 383.135402 -158.740262)
					(end 383.101342 -158.787084)
				)
				(arc
					(start 383.101342 -158.787084)
					(mid 383.054506 -158.821117)
					(end 382.999488 -158.839154)
				)
				(xy 382.997202 -158.84144) (xy 382.976374 -158.84144) (xy 382.969516 -158.841694) (xy 382.965452 -158.84144)
				(xy 382.70815 -158.84144) (xy 382.70815 -159.038544) (xy 382.965452 -159.038544) (xy 382.969516 -159.03829)
				(xy 382.976374 -159.038544) (xy 382.997202 -159.038544)
				(arc
					(start 382.999488 -159.04083)
					(mid 383.05452 -159.05884)
					(end 383.101342 -159.0929)
				)
				(arc
					(start 383.101342 -159.0929)
					(mid 383.135375 -159.139736)
					(end 383.153412 -159.194754)
				)
				(xy 383.155952 -159.19704) (xy 383.155952 -159.217868) (xy 383.155952 -159.224726) (xy 383.155698 -159.22879)
				(arc
					(start 383.155698 -159.253174)
					(mid 383.089273 -159.778244)
					(end 383.022348 -159.253174)
				)
				(xy 383.022348 -159.22879)
				(arc
					(start 383.022348 -159.224726)
					(mid 383.018326 -159.204508)
					(end 383.006854 -159.187388)
				)
				(arc
					(start 383.006854 -159.187388)
					(mid 382.989723 -159.175942)
					(end 382.969516 -159.171894)
				)
				(xy 382.965452 -159.17164) (xy 382.70815 -159.17164)
				(arc
					(start 382.70815 -159.511238)
					(mid 383.089023 -159.892492)
					(end 383.47015 -159.511492)
				)
			)
		)
	)
	(zone
		(layer "In9.Cu")
		(hatch none 0.5)
		(connect_pads
			(clearance 0)
		)
		(min_thickness 0.25)
		(keepout
			(tracks not_allowed)
			(vias allowed)
			(pads allowed)
			(copperpour not_allowed)
			(footprints allowed)
		)
		(placement
			(enabled no)
			(sheetname "")
		)
		(fill
			(thermal_gap 0.5)
			(thermal_bridge_width 0.5)
			(island_removal_mode 0)
		)
		(polygon
			(pts
				(arc
					(start 382.7653 -45.7708)
					(mid 382.3843 -46.1518)
					(end 382.7653 -46.5328)
				)
				(xy 383.127504 -46.5328) (xy 383.127504 -46.284896)
				(arc
					(start 383.12725 -46.280832)
					(mid 383.122702 -46.257878)
					(end 383.109724 -46.238414)
				)
				(xy 383.108708 -46.237144)
				(arc
					(start 383.107438 -46.236128)
					(mid 383.087962 -46.223178)
					(end 383.06502 -46.218602)
				)
				(xy 383.060956 -46.218348)
				(arc
					(start 383.023618 -46.218348)
					(mid 382.498548 -46.1518)
					(end 383.023618 -46.085252)
				)
				(xy 383.060956 -46.085252) (xy 383.06502 -46.084998) (xy 383.072132 -46.085252) (xy 383.092706 -46.085252)
				(arc
					(start 383.094738 -46.087284)
					(mid 383.139007 -46.099751)
					(end 383.179066 -46.122336)
				)
				(xy 383.182368 -46.122336) (xy 383.196846 -46.136814) (xy 383.201926 -46.14164) (xy 383.202942 -46.14291)
				(xy 383.204212 -46.143926) (xy 383.209038 -46.149006) (xy 383.223516 -46.163484)
				(arc
					(start 383.223516 -46.166786)
					(mid 383.246069 -46.206858)
					(end 383.258568 -46.251114)
				)
				(xy 383.2606 -46.253146) (xy 383.2606 -46.27372) (xy 383.260854 -46.280832) (xy 383.2606 -46.284896)
				(xy 383.2606 -46.5328) (xy 383.457704 -46.5328) (xy 383.457704 -46.298104) (xy 383.45745 -46.29404)
				(xy 383.457704 -46.286928) (xy 383.457704 -46.266354)
				(arc
					(start 383.459736 -46.264322)
					(mid 383.472203 -46.220053)
					(end 383.494788 -46.179994)
				)
				(xy 383.494788 -46.176692) (xy 383.509266 -46.162214) (xy 383.514092 -46.157134) (xy 383.51714 -46.15434)
				(xy 383.526792 -46.144688) (xy 383.529586 -46.14164) (xy 383.534666 -46.136814) (xy 383.549144 -46.122336)
				(arc
					(start 383.552446 -46.122336)
					(mid 383.592518 -46.099783)
					(end 383.636774 -46.087284)
				)
				(xy 383.638806 -46.085252)
				(arc
					(start 383.649982 -46.085252)
					(mid 384.174985 -46.150098)
					(end 383.650744 -46.220634)
				)
				(arc
					(start 383.650744 -46.220634)
					(mid 383.636388 -46.226627)
					(end 383.624074 -46.236128)
				)
				(xy 383.621026 -46.238922) (xy 383.611374 -46.248574)
				(arc
					(start 383.60858 -46.251622)
					(mid 383.59563 -46.271098)
					(end 383.591054 -46.29404)
				)
				(xy 383.5908 -46.298104) (xy 383.5908 -46.5328)
				(arc
					(start 383.908046 -46.5328)
					(mid 384.2893 -46.151927)
					(end 383.9083 -45.7708)
				)
			)
		)
	)
	(zone
		(layer "In9.Cu")
		(hatch none 0.5)
		(connect_pads
			(clearance 0)
		)
		(min_thickness 0.25)
		(keepout
			(tracks not_allowed)
			(vias allowed)
			(pads allowed)
			(copperpour not_allowed)
			(footprints allowed)
		)
		(placement
			(enabled no)
			(sheetname "")
		)
		(fill
			(thermal_gap 0.5)
			(thermal_bridge_width 0.5)
			(island_removal_mode 0)
		)
		(polygon
			(pts
				(arc
					(start 113.298732 -17.350232)
					(mid 112.750219 -16.801338)
					(end 112.201452 -17.349978)
				)
				(arc
					(start 112.201452 -18.750026)
					(mid 112.750092 -19.298666)
					(end 113.298732 -18.750026)
				)
				(xy 113.298732 -18.278856)
				(arc
					(start 112.892586 -18.278856)
					(mid 112.875673 -18.28222)
					(end 112.861344 -18.29181)
				)
				(arc
					(start 112.845596 -18.307558)
					(mid 112.836018 -18.321892)
					(end 112.832642 -18.3388)
				)
				(arc
					(start 112.832642 -18.364962)
					(mid 112.750092 -19.143839)
					(end 112.667542 -18.364962)
				)
				(xy 112.667542 -18.30451)
				(arc
					(start 112.670844 -18.301208)
					(mid 112.683379 -18.258634)
					(end 112.704626 -18.219674)
				)
				(xy 112.704626 -18.214848) (xy 112.768634 -18.15084)
				(arc
					(start 112.77346 -18.15084)
					(mid 112.812434 -18.129628)
					(end 112.854994 -18.117058)
				)
				(xy 112.858296 -18.113756) (xy 113.298732 -18.113756) (xy 113.298732 -17.986756) (xy 112.92713 -17.986756)
				(xy 112.85855 -17.986756)
				(arc
					(start 112.854994 -17.9832)
					(mid 112.81242 -17.970665)
					(end 112.77346 -17.949418)
				)
				(xy 112.768634 -17.949418) (xy 112.718088 -17.898872) (xy 112.693958 -17.874742)
				(arc
					(start 112.693958 -17.868392)
					(mid 112.680681 -17.842776)
					(end 112.67186 -17.815306)
				)
				(xy 112.667542 -17.810988)
				(arc
					(start 112.667542 -17.735042)
					(mid 112.750092 -16.956165)
					(end 112.832642 -17.735042)
				)
				(arc
					(start 112.832642 -17.776698)
					(mid 112.833238 -17.7796)
					(end 112.834928 -17.782032)
				)
				(arc
					(start 112.861344 -17.808448)
					(mid 112.875678 -17.818026)
					(end 112.892586 -17.821402)
				)
				(xy 112.926876 -17.821402) (xy 112.92713 -17.821656) (xy 113.298732 -17.821656)
			)
		)
	)
	(zone
		(layer "In9.Cu")
		(hatch none 0.5)
		(connect_pads
			(clearance 0)
		)
		(min_thickness 0.25)
		(keepout
			(tracks not_allowed)
			(vias allowed)
			(pads allowed)
			(copperpour not_allowed)
			(footprints allowed)
		)
		(placement
			(enabled no)
			(sheetname "")
		)
		(fill
			(thermal_gap 0.5)
			(thermal_bridge_width 0.5)
			(island_removal_mode 0)
		)
		(polygon
			(pts
				(arc
					(start 478.120202 -43.368468)
					(mid 477.739202 -42.987468)
					(end 477.358202 -43.368468)
				)
				(xy 477.358202 -43.70832) (xy 477.615504 -43.70832)
				(arc
					(start 477.619568 -43.708066)
					(mid 477.639786 -43.704044)
					(end 477.656906 -43.692572)
				)
				(arc
					(start 477.656906 -43.692572)
					(mid 477.668352 -43.675441)
					(end 477.6724 -43.655234)
				)
				(xy 477.6724 -43.65117)
				(arc
					(start 477.6724 -43.626786)
					(mid 477.739202 -43.101652)
					(end 477.806004 -43.626786)
				)
				(xy 477.806004 -43.65117) (xy 477.806004 -43.655234) (xy 477.806004 -43.662092) (xy 477.806004 -43.68292)
				(arc
					(start 477.803464 -43.685206)
					(mid 477.785454 -43.740238)
					(end 477.751394 -43.78706)
				)
				(arc
					(start 477.751394 -43.78706)
					(mid 477.704558 -43.821093)
					(end 477.64954 -43.83913)
				)
				(xy 477.647254 -43.841416) (xy 477.626426 -43.841416) (xy 477.619568 -43.84167) (xy 477.615504 -43.841416)
				(xy 477.358202 -43.841416) (xy 477.358202 -44.03852) (xy 477.615504 -44.03852) (xy 477.619568 -44.038266)
				(xy 477.626426 -44.03852) (xy 477.647254 -44.03852)
				(arc
					(start 477.64954 -44.040806)
					(mid 477.704572 -44.058816)
					(end 477.751394 -44.092876)
				)
				(arc
					(start 477.751394 -44.092876)
					(mid 477.785427 -44.139712)
					(end 477.803464 -44.19473)
				)
				(xy 477.806004 -44.197016) (xy 477.806004 -44.217844) (xy 477.806004 -44.224702) (xy 477.806004 -44.228766)
				(arc
					(start 477.806004 -44.25315)
					(mid 477.739202 -44.778284)
					(end 477.6724 -44.25315)
				)
				(xy 477.6724 -44.228766)
				(arc
					(start 477.6724 -44.224702)
					(mid 477.668378 -44.204484)
					(end 477.656906 -44.187364)
				)
				(arc
					(start 477.656906 -44.187364)
					(mid 477.639775 -44.175918)
					(end 477.619568 -44.17187)
				)
				(xy 477.615504 -44.171616) (xy 477.358202 -44.171616)
				(arc
					(start 477.358202 -44.511214)
					(mid 477.739075 -44.892468)
					(end 478.120202 -44.511468)
				)
			)
		)
	)
	(zone
		(layer "In9.Cu")
		(hatch none 0.5)
		(connect_pads
			(clearance 0)
		)
		(min_thickness 0.25)
		(keepout
			(tracks not_allowed)
			(vias allowed)
			(pads allowed)
			(copperpour not_allowed)
			(footprints allowed)
		)
		(placement
			(enabled no)
			(sheetname "")
		)
		(fill
			(thermal_gap 0.5)
			(thermal_bridge_width 0.5)
			(island_removal_mode 0)
		)
		(polygon
			(pts
				(arc
					(start 279.236678 -303.15662)
					(mid 278.688038 -303.70526)
					(end 279.236678 -304.2539)
				)
				(xy 279.7048 -304.2539) (xy 279.7048 -304.246026) (xy 279.7048 -304.241962) (xy 279.7048 -303.842166)
				(arc
					(start 279.7048 -303.838102)
					(mid 279.700252 -303.815148)
					(end 279.687274 -303.795684)
				)
				(xy 279.68448 -303.792636) (xy 279.684226 -303.792382)
				(arc
					(start 279.681178 -303.789588)
					(mid 279.661702 -303.776638)
					(end 279.63876 -303.772062)
				)
				(xy 279.634696 -303.771808)
				(arc
					(start 279.62479 -303.771808)
					(mid 278.842902 -303.70526)
					(end 279.62479 -303.638712)
				)
				(xy 279.634696 -303.638712) (xy 279.63876 -303.638458) (xy 279.645872 -303.638712) (xy 279.666446 -303.638712)
				(arc
					(start 279.668478 -303.640744)
					(mid 279.712747 -303.653211)
					(end 279.752806 -303.675796)
				)
				(xy 279.756108 -303.675796) (xy 279.770586 -303.690274) (xy 279.775666 -303.6951) (xy 279.77846 -303.698148)
				(xy 279.778714 -303.698402) (xy 279.781762 -303.701196) (xy 279.786588 -303.706276) (xy 279.801066 -303.720754)
				(arc
					(start 279.801066 -303.724056)
					(mid 279.823619 -303.764128)
					(end 279.836118 -303.808384)
				)
				(xy 279.838404 -303.810416) (xy 279.838404 -303.83099) (xy 279.838404 -303.838102) (xy 279.838404 -303.842166)
				(xy 279.838404 -304.241962) (xy 279.838404 -304.246026) (xy 279.838404 -304.2539) (xy 280.035 -304.2539)
				(xy 280.035 -304.253138) (xy 280.035 -304.246026) (xy 280.035 -304.241962) (xy 280.035 -303.842166)
				(xy 280.035 -303.838102) (xy 280.035 -303.83099) (xy 280.035 -303.810416)
				(arc
					(start 280.037286 -303.808384)
					(mid 280.049753 -303.764115)
					(end 280.072338 -303.724056)
				)
				(xy 280.072338 -303.720754) (xy 280.086816 -303.706276) (xy 280.091642 -303.701196) (xy 280.09469 -303.698402)
				(xy 280.094944 -303.698148) (xy 280.097738 -303.6951) (xy 280.102818 -303.690274) (xy 280.117296 -303.675796)
				(arc
					(start 280.120598 -303.675796)
					(mid 280.16067 -303.653243)
					(end 280.204926 -303.640744)
				)
				(xy 280.206958 -303.638712) (xy 280.227532 -303.638712) (xy 280.234644 -303.638458) (xy 280.238708 -303.638712)
				(arc
					(start 280.248614 -303.638712)
					(mid 281.030502 -303.70526)
					(end 280.248614 -303.771808)
				)
				(xy 280.238708 -303.771808)
				(arc
					(start 280.234644 -303.772062)
					(mid 280.21169 -303.77661)
					(end 280.192226 -303.789588)
				)
				(xy 280.189178 -303.792382) (xy 280.188924 -303.792636)
				(arc
					(start 280.18613 -303.795684)
					(mid 280.17318 -303.81516)
					(end 280.168604 -303.838102)
				)
				(xy 280.168604 -303.842166) (xy 280.168604 -304.241962) (xy 280.168604 -304.246026) (xy 280.169112 -304.2539)
				(arc
					(start 280.636726 -304.2539)
					(mid 281.185366 -303.70526)
					(end 280.636726 -303.15662)
				)
				(xy 279.236932 -303.15662)
			)
		)
	)
	(zone
		(layer "In9.Cu")
		(hatch none 0.5)
		(connect_pads
			(clearance 0)
		)
		(min_thickness 0.25)
		(keepout
			(tracks not_allowed)
			(vias allowed)
			(pads allowed)
			(copperpour not_allowed)
			(footprints allowed)
		)
		(placement
			(enabled no)
			(sheetname "")
		)
		(fill
			(thermal_gap 0.5)
			(thermal_bridge_width 0.5)
			(island_removal_mode 0)
		)
		(polygon
			(pts
				(arc
					(start 337.801966 -92.80017)
					(mid 330.67498 -85.673184)
					(end 323.547994 -92.80017)
				)
				(arc
					(start 323.547994 -98.800412)
					(mid 330.67498 -105.927144)
					(end 337.801966 -98.800412)
				)
			)
		)
	)
	(zone
		(layer "In9.Cu")
		(hatch none 0.5)
		(connect_pads
			(clearance 0)
		)
		(min_thickness 0.25)
		(keepout
			(tracks not_allowed)
			(vias allowed)
			(pads allowed)
			(copperpour not_allowed)
			(footprints allowed)
		)
		(placement
			(enabled no)
			(sheetname "")
		)
		(fill
			(thermal_gap 0.5)
			(thermal_bridge_width 0.5)
			(island_removal_mode 0)
		)
		(polygon
			(pts
				(arc
					(start 175.07712 -270.000222)
					(mid 165.323012 -270.000222)
					(end 175.07712 -270.000222)
				)
			)
		)
	)
	(zone
		(layer "In9.Cu")
		(hatch none 0.5)
		(connect_pads
			(clearance 0)
		)
		(min_thickness 0.25)
		(keepout
			(tracks not_allowed)
			(vias allowed)
			(pads allowed)
			(copperpour not_allowed)
			(footprints allowed)
		)
		(placement
			(enabled no)
			(sheetname "")
		)
		(fill
			(thermal_gap 0.5)
			(thermal_bridge_width 0.5)
			(island_removal_mode 0)
		)
		(polygon
			(pts
				(arc
					(start 346.177108 -270.000222)
					(mid 336.423 -270.000222)
					(end 346.177108 -270.000222)
				)
			)
		)
	)
	(zone
		(layer "In9.Cu")
		(hatch none 0.5)
		(connect_pads
			(clearance 0)
		)
		(min_thickness 0.25)
		(keepout
			(tracks not_allowed)
			(vias allowed)
			(pads allowed)
			(copperpour not_allowed)
			(footprints allowed)
		)
		(placement
			(enabled no)
			(sheetname "")
		)
		(fill
			(thermal_gap 0.5)
			(thermal_bridge_width 0.5)
			(island_removal_mode 0)
		)
		(polygon
			(pts
				(arc
					(start 142.098522 -17.350232)
					(mid 141.550009 -16.801338)
					(end 141.001242 -17.349978)
				)
				(arc
					(start 141.001242 -18.750026)
					(mid 141.549882 -19.298666)
					(end 142.098522 -18.750026)
				)
				(xy 142.098522 -18.278856)
				(arc
					(start 141.692376 -18.278856)
					(mid 141.675463 -18.28222)
					(end 141.661134 -18.29181)
				)
				(arc
					(start 141.645386 -18.307558)
					(mid 141.635808 -18.321892)
					(end 141.632432 -18.3388)
				)
				(arc
					(start 141.632432 -18.364962)
					(mid 141.549882 -19.143839)
					(end 141.467332 -18.364962)
				)
				(xy 141.467332 -18.30451)
				(arc
					(start 141.470634 -18.301208)
					(mid 141.483169 -18.258634)
					(end 141.504416 -18.219674)
				)
				(xy 141.504416 -18.214848) (xy 141.528546 -18.190718) (xy 141.544294 -18.17497) (xy 141.568424 -18.15084)
				(arc
					(start 141.57325 -18.15084)
					(mid 141.612224 -18.129628)
					(end 141.654784 -18.117058)
				)
				(xy 141.658086 -18.113756) (xy 142.098522 -18.113756) (xy 142.098522 -17.986756) (xy 141.72692 -17.986756)
				(xy 141.65834 -17.986756)
				(arc
					(start 141.654784 -17.9832)
					(mid 141.61221 -17.970665)
					(end 141.57325 -17.949418)
				)
				(xy 141.568424 -17.949418) (xy 141.544294 -17.925288) (xy 141.504416 -17.88541)
				(arc
					(start 141.504416 -17.880584)
					(mid 141.483204 -17.84161)
					(end 141.470634 -17.79905)
				)
				(xy 141.467332 -17.795748)
				(arc
					(start 141.467332 -17.735042)
					(mid 141.549882 -16.956165)
					(end 141.632432 -17.735042)
				)
				(arc
					(start 141.632432 -17.761458)
					(mid 141.635796 -17.778371)
					(end 141.645386 -17.7927)
				)
				(arc
					(start 141.661134 -17.808448)
					(mid 141.675468 -17.818026)
					(end 141.692376 -17.821402)
				)
				(xy 141.726666 -17.821402) (xy 141.72692 -17.821656) (xy 142.098522 -17.821656)
			)
		)
	)
	(zone
		(layer "In9.Cu")
		(hatch none 0.5)
		(connect_pads
			(clearance 0)
		)
		(min_thickness 0.25)
		(keepout
			(tracks not_allowed)
			(vias allowed)
			(pads allowed)
			(copperpour not_allowed)
			(footprints allowed)
		)
		(placement
			(enabled no)
			(sheetname "")
		)
		(fill
			(thermal_gap 0.5)
			(thermal_bridge_width 0.5)
			(island_removal_mode 0)
		)
		(polygon
			(pts
				(arc
					(start 279.236678 -342.75649)
					(mid 278.688038 -343.30513)
					(end 279.236678 -343.85377)
				)
				(xy 279.7048 -343.85377) (xy 279.7048 -343.845896) (xy 279.7048 -343.841832) (xy 279.7048 -343.442036)
				(arc
					(start 279.7048 -343.437972)
					(mid 279.700252 -343.415018)
					(end 279.687274 -343.395554)
				)
				(xy 279.68448 -343.392506) (xy 279.684226 -343.392252)
				(arc
					(start 279.681178 -343.389458)
					(mid 279.661702 -343.376508)
					(end 279.63876 -343.371932)
				)
				(xy 279.634696 -343.371932)
				(arc
					(start 279.62479 -343.371932)
					(mid 278.842859 -343.30513)
					(end 279.62479 -343.238328)
				)
				(xy 279.634696 -343.238328) (xy 279.63876 -343.238328) (xy 279.645872 -343.238328) (xy 279.666446 -343.238328)
				(arc
					(start 279.668478 -343.240614)
					(mid 279.712747 -343.253081)
					(end 279.752806 -343.275666)
				)
				(xy 279.756108 -343.275666) (xy 279.770586 -343.290144) (xy 279.775666 -343.29497) (xy 279.77846 -343.298018)
				(xy 279.778714 -343.298272) (xy 279.781762 -343.301066) (xy 279.786588 -343.306146) (xy 279.801066 -343.320624)
				(arc
					(start 279.801066 -343.323926)
					(mid 279.823619 -343.363998)
					(end 279.836118 -343.408254)
				)
				(xy 279.838404 -343.410286) (xy 279.838404 -343.43086) (xy 279.838404 -343.437972) (xy 279.838404 -343.442036)
				(xy 279.838404 -343.841832) (xy 279.838404 -343.845896) (xy 279.838404 -343.85377) (xy 280.035 -343.85377)
				(xy 280.035 -343.853008) (xy 280.035 -343.845896) (xy 280.035 -343.841832) (xy 280.035 -343.442036)
				(xy 280.035 -343.437972) (xy 280.035 -343.43086) (xy 280.035 -343.410286)
				(arc
					(start 280.037286 -343.408254)
					(mid 280.049753 -343.363985)
					(end 280.072338 -343.323926)
				)
				(xy 280.072338 -343.320624) (xy 280.086816 -343.306146) (xy 280.091642 -343.301066) (xy 280.09469 -343.298272)
				(xy 280.094944 -343.298018) (xy 280.097738 -343.29497) (xy 280.102818 -343.290144) (xy 280.117296 -343.275666)
				(arc
					(start 280.120598 -343.275666)
					(mid 280.16067 -343.253113)
					(end 280.204926 -343.240614)
				)
				(xy 280.206958 -343.238328) (xy 280.227532 -343.238328) (xy 280.234644 -343.238328) (xy 280.238708 -343.238328)
				(arc
					(start 280.248614 -343.238328)
					(mid 281.030545 -343.30513)
					(end 280.248614 -343.371932)
				)
				(xy 280.238708 -343.371932)
				(arc
					(start 280.234644 -343.371932)
					(mid 280.21169 -343.37648)
					(end 280.192226 -343.389458)
				)
				(xy 280.189178 -343.392252) (xy 280.188924 -343.392506)
				(arc
					(start 280.18613 -343.395554)
					(mid 280.17318 -343.41503)
					(end 280.168604 -343.437972)
				)
				(xy 280.168604 -343.442036) (xy 280.168604 -343.841832) (xy 280.168604 -343.845896) (xy 280.169112 -343.85377)
				(arc
					(start 280.636726 -343.85377)
					(mid 281.185366 -343.30513)
					(end 280.636726 -342.75649)
				)
				(xy 279.236932 -342.75649)
			)
		)
	)
	(zone
		(layer "In9.Cu")
		(hatch none 0.5)
		(connect_pads
			(clearance 0)
		)
		(min_thickness 0.25)
		(keepout
			(tracks not_allowed)
			(vias allowed)
			(pads allowed)
			(copperpour not_allowed)
			(footprints allowed)
		)
		(placement
			(enabled no)
			(sheetname "")
		)
		(fill
			(thermal_gap 0.5)
			(thermal_bridge_width 0.5)
			(island_removal_mode 0)
		)
		(polygon
			(pts
				(arc
					(start 283.563314 -178.872642)
					(mid 282.622752 -179.186332)
					(end 282.936442 -180.126894)
				)
				(xy 283.224986 -180.271166)
				(arc
					(start 283.58592 -180.271166)
					(mid 283.769427 -180.235999)
					(end 283.926788 -180.135276)
				)
				(arc
					(start 283.982922 -180.022754)
					(mid 283.986109 -179.979139)
					(end 283.957522 -179.946046)
				)
				(arc
					(start 283.695648 -179.814982)
					(mid 282.761556 -179.25503)
					(end 283.769562 -179.667408)
				)
				(xy 284.031182 -179.798218) (xy 284.031436 -179.798218) (xy 284.061916 -179.813712)
				(arc
					(start 284.063186 -179.817776)
					(mid 284.142706 -179.926752)
					(end 284.144466 -180.061616)
				)
				(xy 284.14599 -180.065934) (xy 284.052772 -180.252116)
				(arc
					(start 284.038294 -180.256942)
					(mid 283.845435 -180.383068)
					(end 283.620972 -180.43525)
				)
				(xy 283.62021 -180.436266) (xy 283.555186 -180.436266)
				(arc
					(start 283.767022 -180.542184)
					(mid 283.985259 -180.454486)
					(end 284.167834 -180.306218)
				)
				(xy 284.259782 -180.122576)
				(arc
					(start 284.263846 -180.121306)
					(mid 284.372822 -180.041786)
					(end 284.507686 -180.040026)
				)
				(xy 284.512004 -180.038502)
				(arc
					(start 284.80385 -180.184552)
					(mid 285.738843 -180.743483)
					(end 284.73019 -180.332126)
				)
				(arc
					(start 284.468824 -180.20157)
					(mid 284.425209 -180.198383)
					(end 284.392116 -180.22697)
				)
				(xy 284.295088 -180.420772)
				(arc
					(start 284.28315 -180.424582)
					(mid 284.139736 -180.550665)
					(end 283.974032 -180.645562)
				)
				(arc
					(start 284.928056 -181.122574)
					(mid 285.874832 -180.817389)
					(end 285.56331 -179.87264)
				)
			)
		)
	)
	(zone
		(layer "In9.Cu")
		(hatch none 0.5)
		(connect_pads
			(clearance 0)
		)
		(min_thickness 0.25)
		(keepout
			(tracks not_allowed)
			(vias allowed)
			(pads allowed)
			(copperpour not_allowed)
			(footprints allowed)
		)
		(placement
			(enabled no)
			(sheetname "")
		)
		(fill
			(thermal_gap 0.5)
			(thermal_bridge_width 0.5)
			(island_removal_mode 0)
		)
		(polygon
			(pts
				(arc
					(start 283.563314 -166.872666)
					(mid 282.622752 -167.186356)
					(end 282.936442 -168.126918)
				)
				(xy 283.224986 -168.27119)
				(arc
					(start 283.58592 -168.27119)
					(mid 283.769427 -168.236023)
					(end 283.926788 -168.1353)
				)
				(arc
					(start 283.982922 -168.022778)
					(mid 283.986109 -167.979163)
					(end 283.957522 -167.94607)
				)
				(arc
					(start 283.695648 -167.815006)
					(mid 282.761556 -167.255054)
					(end 283.769562 -167.667432)
				)
				(xy 284.031182 -167.798242) (xy 284.031436 -167.798242) (xy 284.061916 -167.813736)
				(arc
					(start 284.063186 -167.8178)
					(mid 284.142706 -167.926776)
					(end 284.144466 -168.06164)
				)
				(xy 284.14599 -168.065958) (xy 284.052772 -168.25214)
				(arc
					(start 284.038294 -168.256966)
					(mid 283.845435 -168.383092)
					(end 283.620972 -168.435274)
				)
				(xy 283.62021 -168.43629) (xy 283.555186 -168.43629)
				(arc
					(start 283.767022 -168.542208)
					(mid 283.985259 -168.45451)
					(end 284.167834 -168.306242)
				)
				(xy 284.259782 -168.1226)
				(arc
					(start 284.263846 -168.12133)
					(mid 284.372822 -168.04181)
					(end 284.507686 -168.04005)
				)
				(xy 284.512004 -168.038526)
				(arc
					(start 284.80385 -168.184576)
					(mid 285.738843 -168.743507)
					(end 284.73019 -168.33215)
				)
				(arc
					(start 284.468824 -168.201594)
					(mid 284.425209 -168.198407)
					(end 284.392116 -168.226994)
				)
				(xy 284.295088 -168.420796)
				(arc
					(start 284.28315 -168.424606)
					(mid 284.139736 -168.550689)
					(end 283.974032 -168.645586)
				)
				(arc
					(start 284.928056 -169.122598)
					(mid 285.874832 -168.817413)
					(end 285.56331 -167.872664)
				)
			)
		)
	)
	(zone
		(layer "In9.Cu")
		(hatch none 0.5)
		(connect_pads
			(clearance 0)
		)
		(min_thickness 0.25)
		(keepout
			(tracks not_allowed)
			(vias allowed)
			(pads allowed)
			(copperpour not_allowed)
			(footprints allowed)
		)
		(placement
			(enabled no)
			(sheetname "")
		)
		(fill
			(thermal_gap 0.5)
			(thermal_bridge_width 0.5)
			(island_removal_mode 0)
		)
		(polygon
			(pts
				(arc
					(start 103.451914 -92.80017)
					(mid 96.324928 -85.673184)
					(end 89.197942 -92.80017)
				)
				(arc
					(start 89.197942 -98.800412)
					(mid 96.324928 -105.927144)
					(end 103.451914 -98.800412)
				)
			)
		)
	)
	(zone
		(layer "In9.Cu")
		(hatch none 0.5)
		(connect_pads
			(clearance 0)
		)
		(min_thickness 0.25)
		(keepout
			(tracks not_allowed)
			(vias allowed)
			(pads allowed)
			(copperpour not_allowed)
			(footprints allowed)
		)
		(placement
			(enabled no)
			(sheetname "")
		)
		(fill
			(thermal_gap 0.5)
			(thermal_bridge_width 0.5)
			(island_removal_mode 0)
		)
		(polygon
			(pts
				(arc
					(start 223.148652 -416.800284)
					(mid 222.600139 -416.25139)
					(end 222.051372 -416.80003)
				)
				(arc
					(start 222.051372 -417.220654)
					(mid 222.128776 -417.258458)
					(end 222.213932 -417.271454)
				)
				(arc
					(start 222.420942 -417.271454)
					(mid 222.437855 -417.26809)
					(end 222.452184 -417.2585)
				)
				(arc
					(start 222.504508 -417.206176)
					(mid 222.511978 -417.196347)
					(end 222.516446 -417.18484)
				)
				(arc
					(start 222.516446 -417.18484)
					(mid 222.600535 -416.406251)
					(end 222.682562 -417.185094)
				)
				(xy 222.682562 -417.209224)
				(arc
					(start 222.67926 -417.212526)
					(mid 222.666725 -417.2551)
					(end 222.645478 -417.29406)
				)
				(xy 222.645478 -417.298886) (xy 222.544894 -417.39947)
				(arc
					(start 222.540068 -417.39947)
					(mid 222.501094 -417.420682)
					(end 222.458534 -417.433252)
				)
				(xy 222.455232 -417.436554) (xy 222.179642 -417.436554)
				(arc
					(start 222.178372 -417.43503)
					(mid 222.113821 -417.425165)
					(end 222.051372 -417.406074)
				)
				(arc
					(start 222.051372 -417.540186)
					(mid 222.131816 -417.557683)
					(end 222.213932 -417.563554)
				)
				(xy 222.454724 -417.563554)
				(arc
					(start 222.458026 -417.566856)
					(mid 222.5006 -417.579391)
					(end 222.53956 -417.600638)
				)
				(xy 222.544386 -417.600638) (xy 222.621348 -417.6776) (xy 222.645478 -417.70173)
				(arc
					(start 222.645478 -417.706556)
					(mid 222.66669 -417.74553)
					(end 222.67926 -417.78809)
				)
				(xy 222.682562 -417.791392)
				(arc
					(start 222.682562 -417.815014)
					(mid 222.600659 -418.593891)
					(end 222.516192 -417.815268)
				)
				(arc
					(start 222.516192 -417.815268)
					(mid 222.511799 -417.804037)
					(end 222.504508 -417.79444)
				)
				(arc
					(start 222.451676 -417.741608)
					(mid 222.437342 -417.73203)
					(end 222.420434 -417.728654)
				)
				(xy 222.179642 -417.728654)
				(arc
					(start 222.17888 -417.727892)
					(mid 222.114751 -417.722022)
					(end 222.051372 -417.71062)
				)
				(arc
					(start 222.051372 -418.200078)
					(mid 222.600012 -418.748718)
					(end 223.148652 -418.200078)
				)
			)
		)
	)
	(zone
		(layer "In9.Cu")
		(hatch none 0.5)
		(connect_pads
			(clearance 0)
		)
		(min_thickness 0.25)
		(keepout
			(tracks not_allowed)
			(vias allowed)
			(pads allowed)
			(copperpour not_allowed)
			(footprints allowed)
		)
		(placement
			(enabled no)
			(sheetname "")
		)
		(fill
			(thermal_gap 0.5)
			(thermal_bridge_width 0.5)
			(island_removal_mode 0)
		)
		(polygon
			(pts
				(arc
					(start 103.451914 -207.800194)
					(mid 96.324928 -200.673208)
					(end 89.197942 -207.800194)
				)
				(arc
					(start 89.197942 -213.800436)
					(mid 96.324928 -220.927168)
					(end 103.451914 -213.800436)
				)
			)
		)
	)
	(zone
		(layer "In9.Cu")
		(hatch none 0.5)
		(connect_pads
			(clearance 0)
		)
		(min_thickness 0.25)
		(keepout
			(tracks not_allowed)
			(vias allowed)
			(pads allowed)
			(copperpour not_allowed)
			(footprints allowed)
		)
		(placement
			(enabled no)
			(sheetname "")
		)
		(fill
			(thermal_gap 0.5)
			(thermal_bridge_width 0.5)
			(island_removal_mode 0)
		)
		(polygon
			(pts
				(arc
					(start 240.871756 -38.577266)
					(mid 239.92498 -38.882451)
					(end 240.236502 -39.8272)
				)
				(xy 240.525046 -39.971472)
				(arc
					(start 240.88598 -39.971472)
					(mid 241.069487 -39.936305)
					(end 241.226848 -39.835582)
				)
				(arc
					(start 241.282982 -39.72306)
					(mid 241.286169 -39.679445)
					(end 241.257582 -39.646352)
				)
				(arc
					(start 240.995708 -39.515288)
					(mid 240.061616 -38.955336)
					(end 241.069622 -39.367714)
				)
				(xy 241.331242 -39.498524) (xy 241.331496 -39.498524) (xy 241.361976 -39.514018)
				(arc
					(start 241.363246 -39.518082)
					(mid 241.442766 -39.627058)
					(end 241.444526 -39.761922)
				)
				(xy 241.44605 -39.76624) (xy 241.352832 -39.952422)
				(arc
					(start 241.338354 -39.957248)
					(mid 241.145495 -40.083374)
					(end 240.921032 -40.135556)
				)
				(xy 240.92027 -40.136572) (xy 240.855246 -40.136572)
				(arc
					(start 241.067082 -40.24249)
					(mid 241.285319 -40.154792)
					(end 241.467894 -40.006524)
				)
				(xy 241.559842 -39.822882)
				(arc
					(start 241.563906 -39.821612)
					(mid 241.672882 -39.742092)
					(end 241.807746 -39.740332)
				)
				(xy 241.812064 -39.738808)
				(arc
					(start 242.10391 -39.884858)
					(mid 243.038903 -40.443789)
					(end 242.03025 -40.032432)
				)
				(arc
					(start 241.768884 -39.901876)
					(mid 241.725269 -39.898689)
					(end 241.692176 -39.927276)
				)
				(xy 241.595148 -40.121078)
				(arc
					(start 241.58321 -40.124888)
					(mid 241.43979 -40.251064)
					(end 241.274092 -40.346122)
				)
				(arc
					(start 242.236498 -40.827198)
					(mid 243.17706 -40.513508)
					(end 242.86337 -39.572946)
				)
			)
		)
	)
	(zone
		(layer "In9.Cu")
		(hatch none 0.5)
		(connect_pads
			(clearance 0)
		)
		(min_thickness 0.25)
		(keepout
			(tracks not_allowed)
			(vias allowed)
			(pads allowed)
			(copperpour not_allowed)
			(footprints allowed)
		)
		(placement
			(enabled no)
			(sheetname "")
		)
		(fill
			(thermal_gap 0.5)
			(thermal_bridge_width 0.5)
			(island_removal_mode 0)
		)
		(polygon
			(pts
				(arc
					(start 446.5701 -273.368516)
					(mid 446.1891 -272.987516)
					(end 445.8081 -273.368516)
				)
				(xy 445.8081 -273.708368) (xy 446.065402 -273.708368)
				(arc
					(start 446.069466 -273.708114)
					(mid 446.089684 -273.704092)
					(end 446.106804 -273.69262)
				)
				(arc
					(start 446.106804 -273.69262)
					(mid 446.11825 -273.675489)
					(end 446.122298 -273.655282)
				)
				(xy 446.122298 -273.651218)
				(arc
					(start 446.122298 -273.626834)
					(mid 446.189223 -273.1017)
					(end 446.255648 -273.626834)
				)
				(xy 446.255648 -273.651218) (xy 446.255902 -273.655282) (xy 446.255648 -273.66214) (xy 446.255648 -273.682968)
				(arc
					(start 446.253362 -273.685254)
					(mid 446.235352 -273.740286)
					(end 446.201292 -273.787108)
				)
				(arc
					(start 446.201292 -273.787108)
					(mid 446.154456 -273.821141)
					(end 446.099438 -273.839178)
				)
				(xy 446.097152 -273.841464) (xy 446.076324 -273.841464) (xy 446.069466 -273.841718) (xy 446.065402 -273.841464)
				(xy 445.8081 -273.841464) (xy 445.8081 -274.038568) (xy 446.065402 -274.038568) (xy 446.069466 -274.038314)
				(xy 446.076324 -274.038568) (xy 446.097152 -274.038568)
				(arc
					(start 446.099438 -274.040854)
					(mid 446.15447 -274.058864)
					(end 446.201292 -274.092924)
				)
				(arc
					(start 446.201292 -274.092924)
					(mid 446.235325 -274.13976)
					(end 446.253362 -274.194778)
				)
				(xy 446.255648 -274.197064) (xy 446.255648 -274.217892) (xy 446.255902 -274.22475) (xy 446.255648 -274.228814)
				(arc
					(start 446.255648 -274.253198)
					(mid 446.1891 -274.778268)
					(end 446.122552 -274.253198)
				)
				(xy 446.122552 -274.228814)
				(arc
					(start 446.122298 -274.22475)
					(mid 446.118276 -274.204532)
					(end 446.106804 -274.187412)
				)
				(arc
					(start 446.106804 -274.187412)
					(mid 446.089673 -274.175966)
					(end 446.069466 -274.171918)
				)
				(xy 446.065402 -274.171664) (xy 445.8081 -274.171664)
				(arc
					(start 445.8081 -274.511262)
					(mid 446.188973 -274.892516)
					(end 446.5701 -274.511516)
				)
			)
		)
	)
	(zone
		(layer "In9.Cu")
		(hatch none 0.5)
		(connect_pads
			(clearance 0)
		)
		(min_thickness 0.25)
		(keepout
			(tracks not_allowed)
			(vias allowed)
			(pads allowed)
			(copperpour not_allowed)
			(footprints allowed)
		)
		(placement
			(enabled no)
			(sheetname "")
		)
		(fill
			(thermal_gap 0.5)
			(thermal_bridge_width 0.5)
			(island_removal_mode 0)
		)
		(polygon
			(pts
				(arc
					(start 293.073074 -399.20037)
					(mid 300.20006 -406.327356)
					(end 307.327046 -399.20037)
				)
				(arc
					(start 307.327046 -393.200128)
					(mid 300.20006 -386.073142)
					(end 293.073074 -393.200128)
				)
			)
		)
	)
	(zone
		(layer "In9.Cu")
		(hatch none 0.5)
		(connect_pads
			(clearance 0)
		)
		(min_thickness 0.25)
		(keepout
			(tracks not_allowed)
			(vias allowed)
			(pads allowed)
			(copperpour not_allowed)
			(footprints allowed)
		)
		(placement
			(enabled no)
			(sheetname "")
		)
		(fill
			(thermal_gap 0.5)
			(thermal_bridge_width 0.5)
			(island_removal_mode 0)
		)
		(polygon
			(pts
				(arc
					(start 279.236678 -346.356432)
					(mid 278.688038 -346.905072)
					(end 279.236678 -347.453712)
				)
				(xy 279.7048 -347.453712) (xy 279.7048 -347.445838) (xy 279.7048 -347.441774) (xy 279.7048 -347.041978)
				(arc
					(start 279.7048 -347.037914)
					(mid 279.700252 -347.01496)
					(end 279.687274 -346.995496)
				)
				(xy 279.68448 -346.992448) (xy 279.684226 -346.992194)
				(arc
					(start 279.681178 -346.9894)
					(mid 279.661702 -346.97645)
					(end 279.63876 -346.971874)
				)
				(xy 279.634696 -346.97162)
				(arc
					(start 279.62479 -346.97162)
					(mid 278.842902 -346.905072)
					(end 279.62479 -346.838524)
				)
				(xy 279.634696 -346.838524) (xy 279.63876 -346.83827) (xy 279.645872 -346.838524) (xy 279.666446 -346.838524)
				(arc
					(start 279.668478 -346.840556)
					(mid 279.712747 -346.853023)
					(end 279.752806 -346.875608)
				)
				(xy 279.756108 -346.875608) (xy 279.770586 -346.890086) (xy 279.775666 -346.894912) (xy 279.77846 -346.89796)
				(xy 279.778714 -346.898214) (xy 279.781762 -346.901008) (xy 279.786588 -346.906088) (xy 279.801066 -346.920566)
				(arc
					(start 279.801066 -346.923868)
					(mid 279.823619 -346.96394)
					(end 279.836118 -347.008196)
				)
				(xy 279.838404 -347.010228) (xy 279.838404 -347.030802) (xy 279.838404 -347.037914) (xy 279.838404 -347.041978)
				(xy 279.838404 -347.441774) (xy 279.838404 -347.445838) (xy 279.838404 -347.453712) (xy 280.035 -347.453712)
				(xy 280.035 -347.45295) (xy 280.035 -347.445838) (xy 280.035 -347.441774) (xy 280.035 -347.041978)
				(xy 280.035 -347.037914) (xy 280.035 -347.030802) (xy 280.035 -347.010228)
				(arc
					(start 280.037286 -347.008196)
					(mid 280.049753 -346.963927)
					(end 280.072338 -346.923868)
				)
				(xy 280.072338 -346.920566) (xy 280.086816 -346.906088) (xy 280.091642 -346.901008) (xy 280.09469 -346.898214)
				(xy 280.094944 -346.89796) (xy 280.097738 -346.894912) (xy 280.102818 -346.890086) (xy 280.117296 -346.875608)
				(arc
					(start 280.120598 -346.875608)
					(mid 280.16067 -346.853055)
					(end 280.204926 -346.840556)
				)
				(xy 280.206958 -346.838524) (xy 280.227532 -346.838524) (xy 280.234644 -346.83827) (xy 280.238708 -346.838524)
				(arc
					(start 280.248614 -346.838524)
					(mid 281.030502 -346.905072)
					(end 280.248614 -346.97162)
				)
				(xy 280.238708 -346.97162)
				(arc
					(start 280.234644 -346.971874)
					(mid 280.21169 -346.976422)
					(end 280.192226 -346.9894)
				)
				(xy 280.189178 -346.992194) (xy 280.188924 -346.992448)
				(arc
					(start 280.18613 -346.995496)
					(mid 280.17318 -347.014972)
					(end 280.168604 -347.037914)
				)
				(xy 280.168604 -347.041978) (xy 280.168604 -347.441774) (xy 280.168604 -347.445838) (xy 280.169112 -347.453712)
				(arc
					(start 280.636726 -347.453712)
					(mid 281.185366 -346.905072)
					(end 280.636726 -346.356432)
				)
				(xy 279.236932 -346.356432)
			)
		)
	)
	(zone
		(layer "In9.Cu")
		(hatch none 0.5)
		(connect_pads
			(clearance 0)
		)
		(min_thickness 0.25)
		(keepout
			(tracks not_allowed)
			(vias allowed)
			(pads allowed)
			(copperpour not_allowed)
			(footprints allowed)
		)
		(placement
			(enabled no)
			(sheetname "")
		)
		(fill
			(thermal_gap 0.5)
			(thermal_bridge_width 0.5)
			(island_removal_mode 0)
		)
		(polygon
			(pts
				(xy 216.68613 -415.127694) (xy 216.651332 -415.1249)
				(arc
					(start 216.651332 -415.600134)
					(mid 217.199972 -416.148774)
					(end 217.748612 -415.600134)
				)
				(arc
					(start 217.748612 -414.20034)
					(mid 217.200099 -413.651446)
					(end 216.651332 -414.200086)
				)
				(arc
					(start 216.651332 -414.658302)
					(mid 216.685642 -414.668162)
					(end 216.721182 -414.67151)
				)
				(arc
					(start 216.988136 -414.67151)
					(mid 217.063503 -414.64727)
					(end 217.110564 -414.583626)
				)
				(arc
					(start 217.110564 -414.583626)
					(mid 217.204147 -413.806406)
					(end 217.27922 -414.585658)
				)
				(arc
					(start 217.27922 -414.585658)
					(mid 217.193777 -414.752766)
					(end 217.024712 -414.834324)
				)
				(xy 217.022426 -414.83661) (xy 216.686892 -414.83661) (xy 216.685114 -414.834832) (xy 216.651332 -414.829752)
				(arc
					(start 216.651332 -414.95853)
					(mid 216.686165 -414.962342)
					(end 216.721182 -414.96361)
				)
				(xy 217.022426 -414.96361)
				(arc
					(start 217.024712 -414.965896)
					(mid 217.193829 -415.0474)
					(end 217.27922 -415.214562)
				)
				(arc
					(start 217.27922 -415.214562)
					(mid 217.204148 -415.993841)
					(end 217.110564 -415.216594)
				)
				(arc
					(start 217.110564 -415.216594)
					(mid 217.063475 -415.152988)
					(end 216.988136 -415.12871)
				)
				(xy 216.686892 -415.12871)
			)
		)
	)
	(zone
		(layer "In9.Cu")
		(hatch none 0.5)
		(connect_pads
			(clearance 0)
		)
		(min_thickness 0.25)
		(keepout
			(tracks not_allowed)
			(vias allowed)
			(pads allowed)
			(copperpour not_allowed)
			(footprints allowed)
		)
		(placement
			(enabled no)
			(sheetname "")
		)
		(fill
			(thermal_gap 0.5)
			(thermal_bridge_width 0.5)
			(island_removal_mode 0)
		)
		(polygon
			(pts
				(arc
					(start 109.698536 -17.350232)
					(mid 109.150023 -16.801338)
					(end 108.601256 -17.349978)
				)
				(arc
					(start 108.601256 -18.750026)
					(mid 109.149896 -19.298666)
					(end 109.698536 -18.750026)
				)
				(xy 109.698536 -18.278856)
				(arc
					(start 109.29239 -18.278856)
					(mid 109.275477 -18.28222)
					(end 109.261148 -18.29181)
				)
				(arc
					(start 109.2454 -18.307558)
					(mid 109.235822 -18.321892)
					(end 109.232446 -18.3388)
				)
				(arc
					(start 109.232446 -18.364962)
					(mid 109.149896 -19.143839)
					(end 109.067346 -18.364962)
				)
				(xy 109.067346 -18.30451)
				(arc
					(start 109.070648 -18.301208)
					(mid 109.083183 -18.258634)
					(end 109.10443 -18.219674)
				)
				(xy 109.10443 -18.214848) (xy 109.168438 -18.15084)
				(arc
					(start 109.173264 -18.15084)
					(mid 109.212238 -18.129628)
					(end 109.254798 -18.117058)
				)
				(xy 109.2581 -18.113756) (xy 109.698536 -18.113756) (xy 109.698536 -17.986756) (xy 109.326934 -17.986756)
				(xy 109.258354 -17.986756)
				(arc
					(start 109.254798 -17.9832)
					(mid 109.212224 -17.970665)
					(end 109.173264 -17.949418)
				)
				(xy 109.168438 -17.949418) (xy 109.10443 -17.88541)
				(arc
					(start 109.10443 -17.880584)
					(mid 109.083218 -17.84161)
					(end 109.070648 -17.79905)
				)
				(xy 109.067346 -17.795748)
				(arc
					(start 109.067346 -17.735042)
					(mid 109.149896 -16.956165)
					(end 109.232446 -17.735042)
				)
				(arc
					(start 109.232446 -17.761458)
					(mid 109.23581 -17.778371)
					(end 109.2454 -17.7927)
				)
				(arc
					(start 109.261148 -17.808448)
					(mid 109.275482 -17.818026)
					(end 109.29239 -17.821402)
				)
				(xy 109.32668 -17.821402) (xy 109.326934 -17.821656) (xy 109.698536 -17.821656)
			)
		)
	)
	(zone
		(layer "In9.Cu")
		(hatch none 0.5)
		(connect_pads
			(clearance 0)
		)
		(min_thickness 0.25)
		(keepout
			(tracks not_allowed)
			(vias allowed)
			(pads allowed)
			(copperpour not_allowed)
			(footprints allowed)
		)
		(placement
			(enabled no)
			(sheetname "")
		)
		(fill
			(thermal_gap 0.5)
			(thermal_bridge_width 0.5)
			(island_removal_mode 0)
		)
		(polygon
			(pts
				(arc
					(start 279.236678 -299.556424)
					(mid 278.688038 -300.105064)
					(end 279.236678 -300.653704)
				)
				(xy 279.7048 -300.653704) (xy 279.7048 -300.64583) (xy 279.7048 -300.641766) (xy 279.7048 -300.24197)
				(arc
					(start 279.7048 -300.237906)
					(mid 279.700252 -300.214952)
					(end 279.687274 -300.195488)
				)
				(xy 279.68448 -300.19244) (xy 279.684226 -300.192186)
				(arc
					(start 279.681178 -300.189392)
					(mid 279.661702 -300.176442)
					(end 279.63876 -300.171866)
				)
				(xy 279.634696 -300.171612)
				(arc
					(start 279.62479 -300.171612)
					(mid 278.842902 -300.105064)
					(end 279.62479 -300.038516)
				)
				(xy 279.634696 -300.038516) (xy 279.63876 -300.038262) (xy 279.645872 -300.038516) (xy 279.666446 -300.038516)
				(arc
					(start 279.668478 -300.040548)
					(mid 279.712747 -300.053015)
					(end 279.752806 -300.0756)
				)
				(xy 279.756108 -300.0756) (xy 279.770586 -300.090078) (xy 279.775666 -300.094904) (xy 279.77846 -300.097952)
				(xy 279.778714 -300.098206) (xy 279.781762 -300.101) (xy 279.786588 -300.10608) (xy 279.801066 -300.120558)
				(arc
					(start 279.801066 -300.12386)
					(mid 279.823619 -300.163932)
					(end 279.836118 -300.208188)
				)
				(xy 279.838404 -300.21022) (xy 279.838404 -300.230794) (xy 279.838404 -300.237906) (xy 279.838404 -300.24197)
				(xy 279.838404 -300.641766) (xy 279.838404 -300.64583) (xy 279.838404 -300.653704) (xy 280.035 -300.653704)
				(xy 280.035 -300.652942) (xy 280.035 -300.64583) (xy 280.035 -300.641766) (xy 280.035 -300.24197)
				(xy 280.035 -300.237906) (xy 280.035 -300.230794) (xy 280.035 -300.21022)
				(arc
					(start 280.037286 -300.208188)
					(mid 280.049753 -300.163919)
					(end 280.072338 -300.12386)
				)
				(xy 280.072338 -300.120558) (xy 280.086816 -300.10608) (xy 280.091642 -300.101) (xy 280.09469 -300.098206)
				(xy 280.094944 -300.097952) (xy 280.097738 -300.094904) (xy 280.102818 -300.090078) (xy 280.117296 -300.0756)
				(arc
					(start 280.120598 -300.0756)
					(mid 280.16067 -300.053047)
					(end 280.204926 -300.040548)
				)
				(xy 280.206958 -300.038516) (xy 280.227532 -300.038516) (xy 280.234644 -300.038262) (xy 280.238708 -300.038516)
				(arc
					(start 280.248614 -300.038516)
					(mid 281.030502 -300.105064)
					(end 280.248614 -300.171612)
				)
				(xy 280.238708 -300.171612)
				(arc
					(start 280.234644 -300.171866)
					(mid 280.21169 -300.176414)
					(end 280.192226 -300.189392)
				)
				(xy 280.189178 -300.192186) (xy 280.188924 -300.19244)
				(arc
					(start 280.18613 -300.195488)
					(mid 280.17318 -300.214964)
					(end 280.168604 -300.237906)
				)
				(xy 280.168604 -300.24197) (xy 280.168604 -300.641766) (xy 280.168604 -300.64583) (xy 280.169112 -300.653704)
				(arc
					(start 280.636726 -300.653704)
					(mid 281.185366 -300.105064)
					(end 280.636726 -299.556424)
				)
				(xy 279.236932 -299.556424)
			)
		)
	)
	(zone
		(layer "In9.Cu")
		(hatch none 0.5)
		(connect_pads
			(clearance 0)
		)
		(min_thickness 0.25)
		(keepout
			(tracks not_allowed)
			(vias allowed)
			(pads allowed)
			(copperpour not_allowed)
			(footprints allowed)
		)
		(placement
			(enabled no)
			(sheetname "")
		)
		(fill
			(thermal_gap 0.5)
			(thermal_bridge_width 0.5)
			(island_removal_mode 0)
		)
		(polygon
			(pts
				(arc
					(start 118.698518 -18.350484)
					(mid 118.150005 -17.80159)
					(end 117.601238 -18.35023)
				)
				(arc
					(start 117.601238 -19.750024)
					(mid 118.149878 -20.298664)
					(end 118.698518 -19.750024)
				)
				(xy 118.698518 -19.278854)
				(arc
					(start 118.292372 -19.278854)
					(mid 118.275459 -19.282218)
					(end 118.26113 -19.291808)
				)
				(arc
					(start 118.245382 -19.307556)
					(mid 118.235804 -19.32189)
					(end 118.232428 -19.338798)
				)
				(arc
					(start 118.232428 -19.36496)
					(mid 118.149878 -20.143837)
					(end 118.067328 -19.36496)
				)
				(xy 118.067328 -19.304508)
				(arc
					(start 118.07063 -19.301206)
					(mid 118.083165 -19.258632)
					(end 118.104412 -19.219672)
				)
				(xy 118.104412 -19.214846) (xy 118.16842 -19.150838)
				(arc
					(start 118.173246 -19.150838)
					(mid 118.21222 -19.129626)
					(end 118.25478 -19.117056)
				)
				(xy 118.258082 -19.113754) (xy 118.698518 -19.113754) (xy 118.698518 -18.986754) (xy 118.326916 -18.986754)
				(xy 118.258336 -18.986754)
				(arc
					(start 118.25478 -18.983198)
					(mid 118.212206 -18.970663)
					(end 118.173246 -18.949416)
				)
				(xy 118.16842 -18.949416) (xy 118.104412 -18.885408)
				(arc
					(start 118.104412 -18.880582)
					(mid 118.0832 -18.841608)
					(end 118.07063 -18.799048)
				)
				(xy 118.067328 -18.795746)
				(arc
					(start 118.067328 -18.735294)
					(mid 118.149878 -17.956417)
					(end 118.232428 -18.735294)
				)
				(arc
					(start 118.232428 -18.761456)
					(mid 118.235792 -18.778369)
					(end 118.245382 -18.792698)
				)
				(arc
					(start 118.26113 -18.808446)
					(mid 118.275464 -18.818024)
					(end 118.292372 -18.8214)
				)
				(xy 118.326662 -18.8214) (xy 118.326916 -18.821654) (xy 118.698518 -18.821654)
			)
		)
	)
	(zone
		(layer "In9.Cu")
		(hatch none 0.5)
		(connect_pads
			(clearance 0)
		)
		(min_thickness 0.25)
		(keepout
			(tracks not_allowed)
			(vias allowed)
			(pads allowed)
			(copperpour not_allowed)
			(footprints allowed)
		)
		(placement
			(enabled no)
			(sheetname "")
		)
		(fill
			(thermal_gap 0.5)
			(thermal_bridge_width 0.5)
			(island_removal_mode 0)
		)
		(polygon
			(pts
				(arc
					(start 218.604084 -417.727892)
					(mid 218.527188 -417.720434)
					(end 218.45143 -417.705286)
				)
				(arc
					(start 218.45143 -418.200078)
					(mid 219.00007 -418.748718)
					(end 219.54871 -418.200078)
				)
				(arc
					(start 219.54871 -416.800284)
					(mid 219.000197 -416.25139)
					(end 218.45143 -416.80003)
				)
				(arc
					(start 218.45143 -417.208208)
					(mid 218.540098 -417.255222)
					(end 218.639136 -417.271454)
				)
				(arc
					(start 218.821 -417.271454)
					(mid 218.837913 -417.26809)
					(end 218.852242 -417.2585)
				)
				(arc
					(start 218.904566 -417.206176)
					(mid 218.912036 -417.196347)
					(end 218.916504 -417.18484)
				)
				(arc
					(start 218.916504 -417.18484)
					(mid 219.000593 -416.406251)
					(end 219.08262 -417.185094)
				)
				(xy 219.08262 -417.209224)
				(arc
					(start 219.079318 -417.212526)
					(mid 219.066783 -417.2551)
					(end 219.045536 -417.29406)
				)
				(xy 219.045536 -417.298886) (xy 218.944952 -417.39947)
				(arc
					(start 218.940126 -417.39947)
					(mid 218.901152 -417.420682)
					(end 218.858592 -417.433252)
				)
				(xy 218.85529 -417.436554) (xy 218.604846 -417.436554)
				(arc
					(start 218.603576 -417.435284)
					(mid 218.52596 -417.422909)
					(end 218.45143 -417.397946)
				)
				(arc
					(start 218.45143 -417.533582)
					(mid 218.544094 -417.556015)
					(end 218.639136 -417.563554)
				)
				(xy 218.854782 -417.563554)
				(arc
					(start 218.858084 -417.566856)
					(mid 218.900658 -417.579391)
					(end 218.939618 -417.600638)
				)
				(xy 218.944444 -417.600638) (xy 219.021406 -417.6776) (xy 219.045536 -417.70173)
				(arc
					(start 219.045536 -417.706556)
					(mid 219.066748 -417.74553)
					(end 219.079318 -417.78809)
				)
				(xy 219.08262 -417.791392)
				(arc
					(start 219.08262 -417.815014)
					(mid 219.000717 -418.593891)
					(end 218.91625 -417.815268)
				)
				(arc
					(start 218.91625 -417.815268)
					(mid 218.911857 -417.804037)
					(end 218.904566 -417.79444)
				)
				(arc
					(start 218.851734 -417.741608)
					(mid 218.8374 -417.73203)
					(end 218.820492 -417.728654)
				)
				(xy 218.604846 -417.728654)
			)
		)
	)
	(zone
		(layer "In9.Cu")
		(hatch none 0.5)
		(connect_pads
			(clearance 0)
		)
		(min_thickness 0.25)
		(keepout
			(tracks not_allowed)
			(vias allowed)
			(pads allowed)
			(copperpour not_allowed)
			(footprints allowed)
		)
		(placement
			(enabled no)
			(sheetname "")
		)
		(fill
			(thermal_gap 0.5)
			(thermal_bridge_width 0.5)
			(island_removal_mode 0)
		)
		(polygon
			(pts
				(arc
					(start 320.41084 -273.36877)
					(mid 319.989327 -272.946876)
					(end 319.56756 -273.368516)
				)
				(xy 319.56756 -273.708368) (xy 319.887854 -273.708368)
				(arc
					(start 319.891918 -273.708114)
					(mid 319.903596 -273.705809)
					(end 319.913508 -273.699224)
				)
				(arc
					(start 319.913508 -273.699224)
					(mid 319.920073 -273.689304)
					(end 319.922398 -273.677634)
				)
				(xy 319.922398 -273.673316)
				(arc
					(start 319.922398 -273.626834)
					(mid 319.989323 -273.1017)
					(end 320.055748 -273.626834)
				)
				(xy 320.055748 -273.673316) (xy 320.056002 -273.677126) (xy 320.055748 -273.683984) (xy 320.055748 -273.705066)
				(arc
					(start 320.053208 -273.707606)
					(mid 320.043533 -273.740329)
					(end 320.0273 -273.770344)
				)
				(xy 320.0273 -273.774154) (xy 320.012314 -273.78914) (xy 320.007996 -273.793712) (xy 320.007742 -273.793712)
				(xy 320.007488 -273.79422) (xy 320.003424 -273.79803) (xy 319.988184 -273.81327)
				(arc
					(start 319.98412 -273.81327)
					(mid 319.954457 -273.829299)
					(end 319.922144 -273.838924)
				)
				(xy 319.919604 -273.841464) (xy 319.898268 -273.841464) (xy 319.891918 -273.841718) (xy 319.887854 -273.841464)
				(xy 319.56756 -273.841464) (xy 319.56756 -274.038568) (xy 319.861184 -274.038568) (xy 319.865248 -274.038314)
				(xy 319.872106 -274.038568) (xy 319.892934 -274.038568)
				(arc
					(start 319.894966 -274.0406)
					(mid 319.95181 -274.059037)
					(end 320.000122 -274.094194)
				)
				(arc
					(start 320.000122 -274.094194)
					(mid 320.035229 -274.142532)
					(end 320.053716 -274.19935)
				)
				(xy 320.055748 -274.201382) (xy 320.055748 -274.22221) (xy 320.056002 -274.229068) (xy 320.055748 -274.233132)
				(arc
					(start 320.055748 -274.253198)
					(mid 319.9892 -274.778268)
					(end 319.922652 -274.253198)
				)
				(xy 319.922652 -274.233132)
				(arc
					(start 319.922398 -274.229068)
					(mid 319.918048 -274.207198)
					(end 319.905634 -274.188682)
				)
				(arc
					(start 319.905634 -274.188682)
					(mid 319.887105 -274.176301)
					(end 319.865248 -274.171918)
				)
				(xy 319.861184 -274.171664) (xy 319.56756 -274.171664)
				(arc
					(start 319.56756 -274.511516)
					(mid 319.9892 -274.933156)
					(end 320.41084 -274.511516)
				)
			)
		)
	)
	(zone
		(layer "In9.Cu")
		(hatch none 0.5)
		(connect_pads
			(clearance 0)
		)
		(min_thickness 0.25)
		(keepout
			(tracks not_allowed)
			(vias allowed)
			(pads allowed)
			(copperpour not_allowed)
			(footprints allowed)
		)
		(placement
			(enabled no)
			(sheetname "")
		)
		(fill
			(thermal_gap 0.5)
			(thermal_bridge_width 0.5)
			(island_removal_mode 0)
		)
		(polygon
			(pts
				(arc
					(start 383.47015 -273.368516)
					(mid 383.08915 -272.987516)
					(end 382.70815 -273.368516)
				)
				(xy 382.70815 -273.708368) (xy 382.965452 -273.708368)
				(arc
					(start 382.969516 -273.708114)
					(mid 382.989734 -273.704092)
					(end 383.006854 -273.69262)
				)
				(arc
					(start 383.006854 -273.69262)
					(mid 383.0183 -273.675489)
					(end 383.022348 -273.655282)
				)
				(xy 383.022348 -273.651218)
				(arc
					(start 383.022348 -273.626834)
					(mid 383.08915 -273.1017)
					(end 383.155952 -273.626834)
				)
				(xy 383.155952 -273.651218) (xy 383.155952 -273.655282) (xy 383.155952 -273.66214) (xy 383.155952 -273.682968)
				(arc
					(start 383.153412 -273.685254)
					(mid 383.135402 -273.740286)
					(end 383.101342 -273.787108)
				)
				(arc
					(start 383.101342 -273.787108)
					(mid 383.054506 -273.821141)
					(end 382.999488 -273.839178)
				)
				(xy 382.997202 -273.841464) (xy 382.976374 -273.841464) (xy 382.969516 -273.841718) (xy 382.965452 -273.841464)
				(xy 382.70815 -273.841464) (xy 382.70815 -274.038568) (xy 382.965452 -274.038568) (xy 382.969516 -274.038314)
				(xy 382.976374 -274.038568) (xy 382.997202 -274.038568)
				(arc
					(start 382.999488 -274.040854)
					(mid 383.05452 -274.058864)
					(end 383.101342 -274.092924)
				)
				(arc
					(start 383.101342 -274.092924)
					(mid 383.135375 -274.13976)
					(end 383.153412 -274.194778)
				)
				(xy 383.155952 -274.197064) (xy 383.155952 -274.217892) (xy 383.155952 -274.22475) (xy 383.155952 -274.228814)
				(arc
					(start 383.155952 -274.253198)
					(mid 383.08915 -274.778332)
					(end 383.022348 -274.253198)
				)
				(xy 383.022348 -274.228814)
				(arc
					(start 383.022348 -274.22475)
					(mid 383.018326 -274.204532)
					(end 383.006854 -274.187412)
				)
				(arc
					(start 383.006854 -274.187412)
					(mid 382.989723 -274.175966)
					(end 382.969516 -274.171918)
				)
				(xy 382.965452 -274.171664) (xy 382.70815 -274.171664)
				(arc
					(start 382.70815 -274.511262)
					(mid 383.089023 -274.892516)
					(end 383.47015 -274.511516)
				)
			)
		)
	)
	(zone
		(layer "In9.Cu")
		(hatch none 0.5)
		(connect_pads
			(clearance 0)
		)
		(min_thickness 0.25)
		(keepout
			(tracks not_allowed)
			(vias allowed)
			(pads allowed)
			(copperpour not_allowed)
			(footprints allowed)
		)
		(placement
			(enabled no)
			(sheetname "")
		)
		(fill
			(thermal_gap 0.5)
			(thermal_bridge_width 0.5)
			(island_removal_mode 0)
		)
		(polygon
			(pts
				(arc
					(start 380.898654 -17.350232)
					(mid 380.350141 -16.801338)
					(end 379.801374 -17.349978)
				)
				(arc
					(start 379.801374 -18.750026)
					(mid 380.350014 -19.298666)
					(end 380.898654 -18.750026)
				)
				(xy 380.898654 -18.278856)
				(arc
					(start 380.492508 -18.278856)
					(mid 380.475595 -18.28222)
					(end 380.461266 -18.29181)
				)
				(arc
					(start 380.445518 -18.307558)
					(mid 380.43594 -18.321892)
					(end 380.432564 -18.3388)
				)
				(arc
					(start 380.432564 -18.364962)
					(mid 380.350014 -19.143839)
					(end 380.267464 -18.364962)
				)
				(xy 380.267464 -18.30451)
				(arc
					(start 380.270766 -18.301208)
					(mid 380.283301 -18.258634)
					(end 380.304548 -18.219674)
				)
				(xy 380.304548 -18.214848) (xy 380.368556 -18.15084)
				(arc
					(start 380.373382 -18.15084)
					(mid 380.412356 -18.129628)
					(end 380.454916 -18.117058)
				)
				(xy 380.458218 -18.113756) (xy 380.898654 -18.113756) (xy 380.898654 -17.986756) (xy 380.527052 -17.986756)
				(xy 380.458472 -17.986756)
				(arc
					(start 380.454916 -17.9832)
					(mid 380.412342 -17.970665)
					(end 380.373382 -17.949418)
				)
				(xy 380.368556 -17.949418) (xy 380.304548 -17.88541)
				(arc
					(start 380.304548 -17.880584)
					(mid 380.283336 -17.84161)
					(end 380.270766 -17.79905)
				)
				(xy 380.267464 -17.795748)
				(arc
					(start 380.267464 -17.735042)
					(mid 380.350014 -16.956165)
					(end 380.432564 -17.735042)
				)
				(arc
					(start 380.432564 -17.761458)
					(mid 380.435928 -17.778371)
					(end 380.445518 -17.7927)
				)
				(arc
					(start 380.461266 -17.808448)
					(mid 380.4756 -17.818026)
					(end 380.492508 -17.821402)
				)
				(xy 380.526798 -17.821402) (xy 380.527052 -17.821656) (xy 380.898654 -17.821656)
			)
		)
	)
	(zone
		(layer "In9.Cu")
		(hatch none 0.5)
		(connect_pads
			(clearance 0)
		)
		(min_thickness 0.25)
		(keepout
			(tracks not_allowed)
			(vias allowed)
			(pads allowed)
			(copperpour not_allowed)
			(footprints allowed)
		)
		(placement
			(enabled no)
			(sheetname "")
		)
		(fill
			(thermal_gap 0.5)
			(thermal_bridge_width 0.5)
			(island_removal_mode 0)
		)
		(polygon
			(pts
				(arc
					(start 48.876966 -270.000222)
					(mid 44.000166 -265.123422)
					(end 39.123112 -270.000222)
				)
				(arc
					(start 39.123112 -270.000222)
					(mid 44.000166 -274.877276)
					(end 48.876966 -270.000222)
				)
			)
		)
	)
	(zone
		(layer "In9.Cu")
		(hatch none 0.5)
		(connect_pads
			(clearance 0)
		)
		(min_thickness 0.25)
		(keepout
			(tracks not_allowed)
			(vias allowed)
			(pads allowed)
			(copperpour not_allowed)
			(footprints allowed)
		)
		(placement
			(enabled no)
			(sheetname "")
		)
		(fill
			(thermal_gap 0.5)
			(thermal_bridge_width 0.5)
			(island_removal_mode 0)
		)
		(polygon
			(pts
				(arc
					(start 283.563314 -38.572948)
					(mid 282.622752 -38.886638)
					(end 282.936442 -39.8272)
				)
				(xy 283.224986 -39.971472)
				(arc
					(start 283.58592 -39.971472)
					(mid 283.769427 -39.936305)
					(end 283.926788 -39.835582)
				)
				(arc
					(start 283.982922 -39.72306)
					(mid 283.986109 -39.679445)
					(end 283.957522 -39.646352)
				)
				(arc
					(start 283.695648 -39.515288)
					(mid 282.761556 -38.955336)
					(end 283.769562 -39.367714)
				)
				(xy 284.031182 -39.498524) (xy 284.031436 -39.498524) (xy 284.061916 -39.514018)
				(arc
					(start 284.063186 -39.518082)
					(mid 284.142706 -39.627058)
					(end 284.144466 -39.761922)
				)
				(xy 284.14599 -39.76624) (xy 284.052772 -39.952422)
				(arc
					(start 284.038294 -39.957248)
					(mid 283.845435 -40.083374)
					(end 283.620972 -40.135556)
				)
				(xy 283.62021 -40.136572) (xy 283.555186 -40.136572)
				(arc
					(start 283.767022 -40.24249)
					(mid 283.985259 -40.154792)
					(end 284.167834 -40.006524)
				)
				(xy 284.259782 -39.822882)
				(arc
					(start 284.263846 -39.821612)
					(mid 284.372822 -39.742092)
					(end 284.507686 -39.740332)
				)
				(xy 284.512004 -39.738808)
				(arc
					(start 284.80385 -39.884858)
					(mid 285.738843 -40.443789)
					(end 284.73019 -40.032432)
				)
				(arc
					(start 284.468824 -39.901876)
					(mid 284.425209 -39.898689)
					(end 284.392116 -39.927276)
				)
				(xy 284.295088 -40.121078)
				(arc
					(start 284.28315 -40.124888)
					(mid 284.139736 -40.250971)
					(end 283.974032 -40.345868)
				)
				(arc
					(start 284.928056 -40.82288)
					(mid 285.874832 -40.517695)
					(end 285.56331 -39.572946)
				)
			)
		)
	)
	(zone
		(layer "In9.Cu")
		(hatch none 0.5)
		(connect_pads
			(clearance 0)
		)
		(min_thickness 0.25)
		(keepout
			(tracks not_allowed)
			(vias allowed)
			(pads allowed)
			(copperpour not_allowed)
			(footprints allowed)
		)
		(placement
			(enabled no)
			(sheetname "")
		)
		(fill
			(thermal_gap 0.5)
			(thermal_bridge_width 0.5)
			(island_removal_mode 0)
		)
		(polygon
			(pts
				(arc
					(start 284.29712 -116.391436)
					(mid 284.223161 -116.604303)
					(end 284.313376 -116.81079)
				)
				(xy 284.323028 -116.820188)
				(arc
					(start 284.928056 -117.122702)
					(mid 285.874832 -116.817517)
					(end 285.56331 -115.872768)
				)
				(arc
					(start 283.563314 -114.87277)
					(mid 282.622752 -115.18646)
					(end 282.936442 -116.127022)
				)
				(arc
					(start 283.767276 -116.542312)
					(mid 283.820302 -116.308306)
					(end 283.943044 -116.10213)
				)
				(arc
					(start 283.982668 -116.022628)
					(mid 283.985855 -115.979013)
					(end 283.957268 -115.94592)
				)
				(arc
					(start 283.695902 -115.81511)
					(mid 282.760909 -115.256179)
					(end 283.769562 -115.667536)
				)
				(xy 284.061662 -115.813586)
				(arc
					(start 284.062932 -115.81765)
					(mid 284.142452 -115.926626)
					(end 284.144212 -116.06149)
				)
				(xy 284.145736 -116.065808) (xy 284.070806 -116.215414)
				(arc
					(start 284.0609 -116.218716)
					(mid 283.959104 -116.409829)
					(end 283.931614 -116.624608)
				)
				(arc
					(start 284.068774 -116.693188)
					(mid 284.072175 -116.476512)
					(end 284.171644 -116.283994)
				)
				(xy 284.171898 -116.28374) (xy 284.17266 -116.282724) (xy 284.17266 -116.280946) (xy 284.187646 -116.26596)
				(xy 284.259528 -116.12245)
				(arc
					(start 284.263592 -116.12118)
					(mid 284.372568 -116.04166)
					(end 284.507432 -116.0399)
				)
				(xy 284.51175 -116.038376)
				(arc
					(start 284.804104 -116.18468)
					(mid 285.738196 -116.744632)
					(end 284.73019 -116.332254)
				)
				(arc
					(start 284.46857 -116.201444)
					(mid 284.424955 -116.198257)
					(end 284.391862 -116.226844)
				)
				(xy 284.338014 -116.33454) (xy 284.338014 -116.349272) (xy 284.323282 -116.364004) (xy 284.313884 -116.382546)
				(xy 284.30093 -116.386864)
			)
		)
	)
	(zone
		(layer "In9.Cu")
		(hatch none 0.5)
		(connect_pads
			(clearance 0)
		)
		(min_thickness 0.25)
		(keepout
			(tracks not_allowed)
			(vias allowed)
			(pads allowed)
			(copperpour not_allowed)
			(footprints allowed)
		)
		(placement
			(enabled no)
			(sheetname "")
		)
		(fill
			(thermal_gap 0.5)
			(thermal_bridge_width 0.5)
			(island_removal_mode 0)
		)
		(polygon
			(pts
				(arc
					(start 283.563314 -58.572908)
					(mid 282.622752 -58.886598)
					(end 282.936442 -59.82716)
				)
				(arc
					(start 284.928056 -60.82284)
					(mid 285.874832 -60.517655)
					(end 285.56331 -59.572906)
				)
				(xy 285.274766 -59.428634)
				(arc
					(start 284.913832 -59.428634)
					(mid 284.730325 -59.463801)
					(end 284.572964 -59.564524)
				)
				(arc
					(start 284.51683 -59.677046)
					(mid 284.513643 -59.720661)
					(end 284.54223 -59.753754)
				)
				(arc
					(start 284.804104 -59.884818)
					(mid 285.738196 -60.44477)
					(end 284.73019 -60.032392)
				)
				(xy 284.46857 -59.901582) (xy 284.468316 -59.901582) (xy 284.437836 -59.886088)
				(arc
					(start 284.436566 -59.882024)
					(mid 284.357046 -59.773048)
					(end 284.355286 -59.638184)
				)
				(xy 284.353762 -59.633866) (xy 284.44698 -59.447684)
				(arc
					(start 284.461458 -59.442858)
					(mid 284.654317 -59.316732)
					(end 284.87878 -59.26455)
				)
				(xy 284.879542 -59.263534) (xy 284.944566 -59.263534)
				(arc
					(start 284.73273 -59.157616)
					(mid 284.514493 -59.245314)
					(end 284.331918 -59.393582)
				)
				(xy 284.23997 -59.577224)
				(arc
					(start 284.235906 -59.578494)
					(mid 284.12693 -59.658014)
					(end 283.992066 -59.659774)
				)
				(xy 283.987748 -59.661298)
				(arc
					(start 283.695902 -59.515248)
					(mid 282.760909 -58.956317)
					(end 283.769562 -59.367674)
				)
				(arc
					(start 284.030928 -59.49823)
					(mid 284.074543 -59.501417)
					(end 284.107636 -59.47283)
				)
				(xy 284.204664 -59.279028)
				(arc
					(start 284.216602 -59.275218)
					(mid 284.360022 -59.149042)
					(end 284.52572 -59.053984)
				)
			)
		)
	)
	(zone
		(layer "In9.Cu")
		(hatch none 0.5)
		(connect_pads
			(clearance 0)
		)
		(min_thickness 0.25)
		(keepout
			(tracks not_allowed)
			(vias allowed)
			(pads allowed)
			(copperpour not_allowed)
			(footprints allowed)
		)
		(placement
			(enabled no)
			(sheetname "")
		)
		(fill
			(thermal_gap 0.5)
			(thermal_bridge_width 0.5)
			(island_removal_mode 0)
		)
		(polygon
			(pts
				(arc
					(start 103.451914 -322.800218)
					(mid 96.324928 -315.673232)
					(end 89.197942 -322.800218)
				)
				(arc
					(start 89.197942 -328.800206)
					(mid 96.324928 -335.927192)
					(end 103.451914 -328.800206)
				)
			)
		)
	)
	(zone
		(layer "In9.Cu")
		(hatch none 0.5)
		(connect_pads
			(clearance 0)
		)
		(min_thickness 0.25)
		(keepout
			(tracks not_allowed)
			(vias allowed)
			(pads allowed)
			(copperpour not_allowed)
			(footprints allowed)
		)
		(placement
			(enabled no)
			(sheetname "")
		)
		(fill
			(thermal_gap 0.5)
			(thermal_bridge_width 0.5)
			(island_removal_mode 0)
		)
		(polygon
			(pts
				(arc
					(start 240.871756 -46.57725)
					(mid 239.92498 -46.882435)
					(end 240.236502 -47.827184)
				)
				(xy 240.525046 -47.971456)
				(arc
					(start 240.88598 -47.971456)
					(mid 241.069487 -47.936289)
					(end 241.226848 -47.835566)
				)
				(arc
					(start 241.282982 -47.723044)
					(mid 241.286169 -47.679429)
					(end 241.257582 -47.646336)
				)
				(arc
					(start 240.995708 -47.515272)
					(mid 240.061616 -46.95532)
					(end 241.069622 -47.367698)
				)
				(xy 241.331242 -47.498508) (xy 241.331496 -47.498508) (xy 241.361976 -47.514002)
				(arc
					(start 241.363246 -47.518066)
					(mid 241.442766 -47.627042)
					(end 241.444526 -47.761906)
				)
				(xy 241.44605 -47.766224) (xy 241.352832 -47.952406)
				(arc
					(start 241.338354 -47.957232)
					(mid 241.145495 -48.083358)
					(end 240.921032 -48.13554)
				)
				(xy 240.92027 -48.136556) (xy 240.855246 -48.136556)
				(arc
					(start 241.067082 -48.242474)
					(mid 241.285319 -48.154776)
					(end 241.467894 -48.006508)
				)
				(xy 241.559842 -47.822866)
				(arc
					(start 241.563906 -47.821596)
					(mid 241.672882 -47.742076)
					(end 241.807746 -47.740316)
				)
				(xy 241.812064 -47.738792)
				(arc
					(start 242.10391 -47.884842)
					(mid 243.038903 -48.443773)
					(end 242.03025 -48.032416)
				)
				(arc
					(start 241.768884 -47.90186)
					(mid 241.725269 -47.898673)
					(end 241.692176 -47.92726)
				)
				(xy 241.595148 -48.121062)
				(arc
					(start 241.58321 -48.124872)
					(mid 241.43979 -48.251048)
					(end 241.274092 -48.346106)
				)
				(arc
					(start 242.236498 -48.827182)
					(mid 243.17706 -48.513492)
					(end 242.86337 -47.57293)
				)
			)
		)
	)
	(zone
		(layer "In9.Cu")
		(hatch none 0.5)
		(connect_pads
			(clearance 0)
		)
		(min_thickness 0.25)
		(keepout
			(tracks not_allowed)
			(vias allowed)
			(pads allowed)
			(copperpour not_allowed)
			(footprints allowed)
		)
		(placement
			(enabled no)
			(sheetname "")
		)
		(fill
			(thermal_gap 0.5)
			(thermal_bridge_width 0.5)
			(island_removal_mode 0)
		)
		(polygon
			(pts
				(arc
					(start 278.23668 -301.356522)
					(mid 277.68804 -301.905162)
					(end 278.23668 -302.453802)
				)
				(xy 278.705056 -302.453802) (xy 278.705056 -302.046386)
				(arc
					(start 278.704802 -302.042322)
					(mid 278.700254 -302.019368)
					(end 278.687276 -301.999904)
				)
				(xy 278.684482 -301.996856) (xy 278.67991 -301.992284)
				(arc
					(start 278.676862 -301.98949)
					(mid 278.657386 -301.97654)
					(end 278.634444 -301.971964)
				)
				(xy 278.63038 -301.971964)
				(arc
					(start 278.624792 -301.971964)
					(mid 277.842861 -301.905162)
					(end 278.624792 -301.83836)
				)
				(xy 278.63038 -301.83836) (xy 278.634444 -301.83836) (xy 278.641556 -301.83836) (xy 278.66213 -301.83836)
				(arc
					(start 278.664162 -301.840646)
					(mid 278.708431 -301.853113)
					(end 278.74849 -301.875698)
				)
				(xy 278.751792 -301.875698) (xy 278.76627 -301.890176) (xy 278.77135 -301.895002) (xy 278.774144 -301.89805)
				(xy 278.778716 -301.902622) (xy 278.781764 -301.905416) (xy 278.78659 -301.910496) (xy 278.801068 -301.924974)
				(arc
					(start 278.801068 -301.928276)
					(mid 278.823621 -301.968348)
					(end 278.83612 -302.012604)
				)
				(xy 278.838152 -302.014636) (xy 278.838152 -302.03521) (xy 278.838406 -302.042322) (xy 278.838152 -302.046386)
				(xy 278.838152 -302.453802) (xy 279.035256 -302.453802) (xy 279.035256 -302.046386) (xy 279.035002 -302.042322)
				(xy 279.035256 -302.03521) (xy 279.035256 -302.014636)
				(arc
					(start 279.037288 -302.012604)
					(mid 279.049755 -301.968335)
					(end 279.07234 -301.928276)
				)
				(xy 279.07234 -301.924974) (xy 279.086818 -301.910496) (xy 279.091644 -301.905416) (xy 279.094692 -301.902622)
				(xy 279.099264 -301.89805) (xy 279.102058 -301.895002) (xy 279.107138 -301.890176) (xy 279.121616 -301.875698)
				(arc
					(start 279.124918 -301.875698)
					(mid 279.16499 -301.853145)
					(end 279.209246 -301.840646)
				)
				(xy 279.211278 -301.83836) (xy 279.231852 -301.83836) (xy 279.238964 -301.83836) (xy 279.243028 -301.83836)
				(arc
					(start 279.248616 -301.83836)
					(mid 280.030547 -301.905162)
					(end 279.248616 -301.971964)
				)
				(xy 279.243028 -301.971964)
				(arc
					(start 279.238964 -301.971964)
					(mid 279.21601 -301.976512)
					(end 279.196546 -301.98949)
				)
				(xy 279.193498 -301.992284) (xy 279.188926 -301.996856)
				(arc
					(start 279.186132 -301.999904)
					(mid 279.173182 -302.01938)
					(end 279.168606 -302.042322)
				)
				(xy 279.168352 -302.046386) (xy 279.168352 -302.453802)
				(arc
					(start 279.636728 -302.453802)
					(mid 280.185368 -301.905162)
					(end 279.636728 -301.356522)
				)
				(xy 278.236934 -301.356522)
			)
		)
	)
	(zone
		(layer "In9.Cu")
		(hatch none 0.5)
		(connect_pads
			(clearance 0)
		)
		(min_thickness 0.25)
		(keepout
			(tracks not_allowed)
			(vias allowed)
			(pads allowed)
			(copperpour not_allowed)
			(footprints allowed)
		)
		(placement
			(enabled no)
			(sheetname "")
		)
		(fill
			(thermal_gap 0.5)
			(thermal_bridge_width 0.5)
			(island_removal_mode 0)
		)
		(polygon
			(pts
				(arc
					(start 361.098592 -18.350484)
					(mid 360.550079 -17.80159)
					(end 360.001312 -18.35023)
				)
				(xy 360.001312 -18.821654) (xy 360.372914 -18.821654) (xy 360.373168 -18.8214)
				(arc
					(start 360.407458 -18.8214)
					(mid 360.424371 -18.818036)
					(end 360.4387 -18.808446)
				)
				(arc
					(start 360.454448 -18.792698)
					(mid 360.464026 -18.778364)
					(end 360.467402 -18.761456)
				)
				(arc
					(start 360.467402 -18.735294)
					(mid 360.549952 -17.956417)
					(end 360.632502 -18.735294)
				)
				(xy 360.632502 -18.795746)
				(arc
					(start 360.6292 -18.799048)
					(mid 360.616665 -18.841622)
					(end 360.595418 -18.880582)
				)
				(xy 360.595418 -18.885408) (xy 360.53141 -18.949416)
				(arc
					(start 360.526584 -18.949416)
					(mid 360.48761 -18.970628)
					(end 360.44505 -18.983198)
				)
				(xy 360.441494 -18.986754) (xy 360.372914 -18.986754) (xy 360.001312 -18.986754) (xy 360.001312 -19.113754)
				(xy 360.441748 -19.113754)
				(arc
					(start 360.44505 -19.117056)
					(mid 360.487624 -19.129591)
					(end 360.526584 -19.150838)
				)
				(xy 360.53141 -19.150838) (xy 360.595418 -19.214846)
				(arc
					(start 360.595418 -19.219672)
					(mid 360.61663 -19.258646)
					(end 360.6292 -19.301206)
				)
				(xy 360.632502 -19.304508)
				(arc
					(start 360.632502 -19.36496)
					(mid 360.549952 -20.143837)
					(end 360.467402 -19.36496)
				)
				(arc
					(start 360.467402 -19.338798)
					(mid 360.464038 -19.321885)
					(end 360.454448 -19.307556)
				)
				(arc
					(start 360.4387 -19.291808)
					(mid 360.424366 -19.28223)
					(end 360.407458 -19.278854)
				)
				(xy 360.001312 -19.278854)
				(arc
					(start 360.001312 -19.750024)
					(mid 360.549952 -20.298664)
					(end 361.098592 -19.750024)
				)
			)
		)
	)
	(zone
		(layer "In9.Cu")
		(hatch none 0.5)
		(connect_pads
			(clearance 0)
		)
		(min_thickness 0.25)
		(keepout
			(tracks not_allowed)
			(vias allowed)
			(pads allowed)
			(copperpour not_allowed)
			(footprints allowed)
		)
		(placement
			(enabled no)
			(sheetname "")
		)
		(fill
			(thermal_gap 0.5)
			(thermal_bridge_width 0.5)
			(island_removal_mode 0)
		)
		(polygon
			(pts
				(arc
					(start 415.020252 -43.368468)
					(mid 414.639252 -42.987468)
					(end 414.258252 -43.368468)
				)
				(xy 414.258252 -43.70832) (xy 414.515554 -43.70832)
				(arc
					(start 414.519618 -43.708066)
					(mid 414.539836 -43.704044)
					(end 414.556956 -43.692572)
				)
				(arc
					(start 414.556956 -43.692572)
					(mid 414.568402 -43.675441)
					(end 414.57245 -43.655234)
				)
				(xy 414.572704 -43.65117)
				(arc
					(start 414.572704 -43.626786)
					(mid 414.639252 -43.101716)
					(end 414.7058 -43.626786)
				)
				(xy 414.7058 -43.65117) (xy 414.706054 -43.655234) (xy 414.7058 -43.662092) (xy 414.7058 -43.68292)
				(arc
					(start 414.703514 -43.685206)
					(mid 414.685504 -43.740238)
					(end 414.651444 -43.78706)
				)
				(arc
					(start 414.651444 -43.78706)
					(mid 414.604608 -43.821093)
					(end 414.54959 -43.83913)
				)
				(xy 414.547304 -43.841416) (xy 414.526476 -43.841416) (xy 414.519618 -43.84167) (xy 414.515554 -43.841416)
				(xy 414.258252 -43.841416) (xy 414.258252 -44.03852) (xy 414.515554 -44.03852) (xy 414.519618 -44.038266)
				(xy 414.526476 -44.03852) (xy 414.547304 -44.03852)
				(arc
					(start 414.54959 -44.040806)
					(mid 414.604622 -44.058816)
					(end 414.651444 -44.092876)
				)
				(arc
					(start 414.651444 -44.092876)
					(mid 414.685477 -44.139712)
					(end 414.703514 -44.19473)
				)
				(xy 414.7058 -44.197016) (xy 414.7058 -44.217844) (xy 414.706054 -44.224702) (xy 414.7058 -44.228766)
				(arc
					(start 414.7058 -44.25315)
					(mid 414.639252 -44.77822)
					(end 414.572704 -44.25315)
				)
				(xy 414.572704 -44.228766)
				(arc
					(start 414.57245 -44.224702)
					(mid 414.568428 -44.204484)
					(end 414.556956 -44.187364)
				)
				(arc
					(start 414.556956 -44.187364)
					(mid 414.539825 -44.175918)
					(end 414.519618 -44.17187)
				)
				(xy 414.515554 -44.171616) (xy 414.258252 -44.171616)
				(arc
					(start 414.258252 -44.511214)
					(mid 414.639125 -44.892468)
					(end 415.020252 -44.511468)
				)
			)
		)
	)
	(zone
		(layer "In9.Cu")
		(hatch none 0.5)
		(connect_pads
			(clearance 0)
		)
		(min_thickness 0.25)
		(keepout
			(tracks not_allowed)
			(vias allowed)
			(pads allowed)
			(copperpour not_allowed)
			(footprints allowed)
		)
		(placement
			(enabled no)
			(sheetname "")
		)
		(fill
			(thermal_gap 0.5)
			(thermal_bridge_width 0.5)
			(island_removal_mode 0)
		)
		(polygon
			(pts
				(arc
					(start 283.563314 -42.57294)
					(mid 282.622752 -42.88663)
					(end 282.936442 -43.827192)
				)
				(xy 283.224986 -43.971464)
				(arc
					(start 283.58592 -43.971464)
					(mid 283.769427 -43.936297)
					(end 283.926788 -43.835574)
				)
				(arc
					(start 283.982922 -43.723052)
					(mid 283.986109 -43.679437)
					(end 283.957522 -43.646344)
				)
				(arc
					(start 283.695648 -43.51528)
					(mid 282.761556 -42.955328)
					(end 283.769562 -43.367706)
				)
				(xy 284.031182 -43.498516) (xy 284.031436 -43.498516) (xy 284.061916 -43.51401)
				(arc
					(start 284.063186 -43.518074)
					(mid 284.142706 -43.62705)
					(end 284.144466 -43.761914)
				)
				(xy 284.14599 -43.766232) (xy 284.052772 -43.952414)
				(arc
					(start 284.038294 -43.95724)
					(mid 283.845435 -44.083366)
					(end 283.620972 -44.135548)
				)
				(xy 283.62021 -44.136564) (xy 283.555186 -44.136564)
				(arc
					(start 283.767022 -44.242482)
					(mid 283.985259 -44.154784)
					(end 284.167834 -44.006516)
				)
				(xy 284.259782 -43.822874)
				(arc
					(start 284.263846 -43.821604)
					(mid 284.372822 -43.742084)
					(end 284.507686 -43.740324)
				)
				(xy 284.512004 -43.7388)
				(arc
					(start 284.80385 -43.88485)
					(mid 285.738843 -44.443781)
					(end 284.73019 -44.032424)
				)
				(arc
					(start 284.468824 -43.901868)
					(mid 284.425209 -43.898681)
					(end 284.392116 -43.927268)
				)
				(xy 284.295088 -44.12107)
				(arc
					(start 284.28315 -44.12488)
					(mid 284.139736 -44.250963)
					(end 283.974032 -44.34586)
				)
				(arc
					(start 284.928056 -44.822872)
					(mid 285.874832 -44.517687)
					(end 285.56331 -43.572938)
				)
			)
		)
	)
	(zone
		(layer "In9.Cu")
		(hatch none 0.5)
		(connect_pads
			(clearance 0)
		)
		(min_thickness 0.25)
		(keepout
			(tracks not_allowed)
			(vias allowed)
			(pads allowed)
			(copperpour not_allowed)
			(footprints allowed)
		)
		(placement
			(enabled no)
			(sheetname "")
		)
		(fill
			(thermal_gap 0.5)
			(thermal_bridge_width 0.5)
			(island_removal_mode 0)
		)
		(polygon
			(pts
				(arc
					(start 359.298748 -17.350232)
					(mid 358.750235 -16.801338)
					(end 358.201468 -17.349978)
				)
				(xy 358.201468 -17.821656) (xy 358.57307 -17.821656) (xy 358.573324 -17.821402)
				(arc
					(start 358.607614 -17.821402)
					(mid 358.624527 -17.818038)
					(end 358.638856 -17.808448)
				)
				(arc
					(start 358.665272 -17.782032)
					(mid 358.666962 -17.7796)
					(end 358.667558 -17.776698)
				)
				(arc
					(start 358.667558 -17.735042)
					(mid 358.750108 -16.956165)
					(end 358.832658 -17.735042)
				)
				(xy 358.832658 -17.810988)
				(arc
					(start 358.82834 -17.815306)
					(mid 358.819516 -17.842775)
					(end 358.806242 -17.868392)
				)
				(xy 358.806242 -17.874742) (xy 358.782112 -17.898872) (xy 358.731566 -17.949418)
				(arc
					(start 358.72674 -17.949418)
					(mid 358.687766 -17.97063)
					(end 358.645206 -17.9832)
				)
				(xy 358.64165 -17.986756) (xy 358.57307 -17.986756) (xy 358.201468 -17.986756) (xy 358.201468 -18.113756)
				(xy 358.641904 -18.113756)
				(arc
					(start 358.645206 -18.117058)
					(mid 358.68778 -18.129593)
					(end 358.72674 -18.15084)
				)
				(xy 358.731566 -18.15084) (xy 358.795574 -18.214848)
				(arc
					(start 358.795574 -18.219674)
					(mid 358.816786 -18.258648)
					(end 358.829356 -18.301208)
				)
				(xy 358.832658 -18.30451)
				(arc
					(start 358.832658 -18.364962)
					(mid 358.750108 -19.143839)
					(end 358.667558 -18.364962)
				)
				(arc
					(start 358.667558 -18.3388)
					(mid 358.664194 -18.321887)
					(end 358.654604 -18.307558)
				)
				(arc
					(start 358.638856 -18.29181)
					(mid 358.624522 -18.282232)
					(end 358.607614 -18.278856)
				)
				(xy 358.201468 -18.278856)
				(arc
					(start 358.201468 -18.750026)
					(mid 358.750108 -19.298666)
					(end 359.298748 -18.750026)
				)
			)
		)
	)
	(zone
		(layer "In9.Cu")
		(hatch none 0.5)
		(connect_pads
			(clearance 0)
		)
		(min_thickness 0.25)
		(keepout
			(tracks not_allowed)
			(vias allowed)
			(pads allowed)
			(copperpour not_allowed)
			(footprints allowed)
		)
		(placement
			(enabled no)
			(sheetname "")
		)
		(fill
			(thermal_gap 0.5)
			(thermal_bridge_width 0.5)
			(island_removal_mode 0)
		)
		(polygon
			(pts
				(arc
					(start 357.49865 -18.350484)
					(mid 356.950137 -17.80159)
					(end 356.40137 -18.35023)
				)
				(xy 356.40137 -18.821654) (xy 356.772972 -18.821654) (xy 356.773226 -18.8214)
				(arc
					(start 356.807516 -18.8214)
					(mid 356.824429 -18.818036)
					(end 356.838758 -18.808446)
				)
				(arc
					(start 356.854506 -18.792698)
					(mid 356.864084 -18.778364)
					(end 356.86746 -18.761456)
				)
				(arc
					(start 356.86746 -18.735294)
					(mid 356.95001 -17.956417)
					(end 357.03256 -18.735294)
				)
				(xy 357.03256 -18.795746)
				(arc
					(start 357.029258 -18.799048)
					(mid 357.016723 -18.841622)
					(end 356.995476 -18.880582)
				)
				(xy 356.995476 -18.885408) (xy 356.931468 -18.949416)
				(arc
					(start 356.926642 -18.949416)
					(mid 356.887668 -18.970628)
					(end 356.845108 -18.983198)
				)
				(xy 356.841552 -18.986754) (xy 356.772972 -18.986754) (xy 356.40137 -18.986754) (xy 356.40137 -19.113754)
				(xy 356.841806 -19.113754)
				(arc
					(start 356.845108 -19.117056)
					(mid 356.887682 -19.129591)
					(end 356.926642 -19.150838)
				)
				(xy 356.931468 -19.150838) (xy 356.995476 -19.214846)
				(arc
					(start 356.995476 -19.219672)
					(mid 357.016688 -19.258646)
					(end 357.029258 -19.301206)
				)
				(xy 357.03256 -19.304508)
				(arc
					(start 357.03256 -19.36496)
					(mid 356.95001 -20.143837)
					(end 356.86746 -19.36496)
				)
				(arc
					(start 356.86746 -19.338798)
					(mid 356.864096 -19.321885)
					(end 356.854506 -19.307556)
				)
				(arc
					(start 356.838758 -19.291808)
					(mid 356.824424 -19.28223)
					(end 356.807516 -19.278854)
				)
				(xy 356.40137 -19.278854)
				(arc
					(start 356.40137 -19.750024)
					(mid 356.95001 -20.298664)
					(end 357.49865 -19.750024)
				)
			)
		)
	)
	(zone
		(layer "In9.Cu")
		(hatch none 0.5)
		(connect_pads
			(clearance 0)
		)
		(min_thickness 0.25)
		(keepout
			(tracks not_allowed)
			(vias allowed)
			(pads allowed)
			(copperpour not_allowed)
			(footprints allowed)
		)
		(placement
			(enabled no)
			(sheetname "")
		)
		(fill
			(thermal_gap 0.5)
			(thermal_bridge_width 0.5)
			(island_removal_mode 0)
		)
		(polygon
			(pts
				(arc
					(start 283.563314 -82.57286)
					(mid 282.622752 -82.88655)
					(end 282.936442 -83.827112)
				)
				(arc
					(start 284.928056 -84.822792)
					(mid 285.874832 -84.517607)
					(end 285.56331 -83.572858)
				)
				(xy 285.274766 -83.428586)
				(arc
					(start 284.913832 -83.428586)
					(mid 284.730325 -83.463753)
					(end 284.572964 -83.564476)
				)
				(arc
					(start 284.51683 -83.676998)
					(mid 284.513643 -83.720613)
					(end 284.54223 -83.753706)
				)
				(arc
					(start 284.804104 -83.88477)
					(mid 285.738196 -84.444722)
					(end 284.73019 -84.032344)
				)
				(xy 284.46857 -83.901534) (xy 284.468316 -83.901534) (xy 284.437836 -83.88604)
				(arc
					(start 284.436566 -83.881976)
					(mid 284.357046 -83.773)
					(end 284.355286 -83.638136)
				)
				(xy 284.353762 -83.633818) (xy 284.44698 -83.447636)
				(arc
					(start 284.461458 -83.44281)
					(mid 284.654317 -83.316684)
					(end 284.87878 -83.264502)
				)
				(xy 284.879542 -83.263486) (xy 284.944566 -83.263486)
				(arc
					(start 284.73273 -83.157568)
					(mid 284.514493 -83.245266)
					(end 284.331918 -83.393534)
				)
				(xy 284.23997 -83.577176)
				(arc
					(start 284.235906 -83.578446)
					(mid 284.12693 -83.657966)
					(end 283.992066 -83.659726)
				)
				(xy 283.987748 -83.66125)
				(arc
					(start 283.695902 -83.5152)
					(mid 282.760909 -82.956269)
					(end 283.769562 -83.367626)
				)
				(arc
					(start 284.030928 -83.498182)
					(mid 284.074543 -83.501369)
					(end 284.107636 -83.472782)
				)
				(xy 284.204664 -83.27898)
				(arc
					(start 284.216602 -83.27517)
					(mid 284.360022 -83.148994)
					(end 284.52572 -83.053936)
				)
			)
		)
	)
	(zone
		(layer "In9.Cu")
		(hatch none 0.5)
		(connect_pads
			(clearance 0)
		)
		(min_thickness 0.25)
		(keepout
			(tracks not_allowed)
			(vias allowed)
			(pads allowed)
			(copperpour not_allowed)
			(footprints allowed)
		)
		(placement
			(enabled no)
			(sheetname "")
		)
		(fill
			(thermal_gap 0.5)
			(thermal_bridge_width 0.5)
			(island_removal_mode 0)
		)
		(polygon
			(pts
				(arc
					(start 283.563314 -54.572916)
					(mid 282.622752 -54.886606)
					(end 282.936442 -55.827168)
				)
				(arc
					(start 284.928056 -56.822848)
					(mid 285.874832 -56.517663)
					(end 285.56331 -55.572914)
				)
				(xy 285.274766 -55.428642)
				(arc
					(start 284.913832 -55.428642)
					(mid 284.730325 -55.463809)
					(end 284.572964 -55.564532)
				)
				(arc
					(start 284.51683 -55.677054)
					(mid 284.513643 -55.720669)
					(end 284.54223 -55.753762)
				)
				(arc
					(start 284.804104 -55.884826)
					(mid 285.738196 -56.444778)
					(end 284.73019 -56.0324)
				)
				(xy 284.46857 -55.90159) (xy 284.468316 -55.90159) (xy 284.437836 -55.886096)
				(arc
					(start 284.436566 -55.882032)
					(mid 284.357046 -55.773056)
					(end 284.355286 -55.638192)
				)
				(xy 284.353762 -55.633874) (xy 284.44698 -55.447692)
				(arc
					(start 284.461458 -55.442866)
					(mid 284.654317 -55.31674)
					(end 284.87878 -55.264558)
				)
				(xy 284.879542 -55.263542) (xy 284.944566 -55.263542)
				(arc
					(start 284.73273 -55.157624)
					(mid 284.514493 -55.245322)
					(end 284.331918 -55.39359)
				)
				(xy 284.23997 -55.577232)
				(arc
					(start 284.235906 -55.578502)
					(mid 284.12693 -55.658022)
					(end 283.992066 -55.659782)
				)
				(xy 283.987748 -55.661306)
				(arc
					(start 283.695902 -55.515256)
					(mid 282.760909 -54.956325)
					(end 283.769562 -55.367682)
				)
				(arc
					(start 284.030928 -55.498238)
					(mid 284.074543 -55.501425)
					(end 284.107636 -55.472838)
				)
				(xy 284.204664 -55.279036)
				(arc
					(start 284.216602 -55.275226)
					(mid 284.360022 -55.14905)
					(end 284.52572 -55.053992)
				)
			)
		)
	)
	(zone
		(layer "In9.Cu")
		(hatch none 0.5)
		(connect_pads
			(clearance 0)
		)
		(min_thickness 0.25)
		(keepout
			(tracks not_allowed)
			(vias allowed)
			(pads allowed)
			(copperpour not_allowed)
			(footprints allowed)
		)
		(placement
			(enabled no)
			(sheetname "")
		)
		(fill
			(thermal_gap 0.5)
			(thermal_bridge_width 0.5)
			(island_removal_mode 0)
		)
		(polygon
			(pts
				(arc
					(start 131.298696 -17.350232)
					(mid 130.750183 -16.801338)
					(end 130.201416 -17.349978)
				)
				(arc
					(start 130.201416 -18.750026)
					(mid 130.750056 -19.298666)
					(end 131.298696 -18.750026)
				)
				(xy 131.298696 -18.278856)
				(arc
					(start 130.89255 -18.278856)
					(mid 130.875637 -18.28222)
					(end 130.861308 -18.29181)
				)
				(arc
					(start 130.84556 -18.307558)
					(mid 130.835982 -18.321892)
					(end 130.832606 -18.3388)
				)
				(arc
					(start 130.832606 -18.364962)
					(mid 130.750056 -19.143839)
					(end 130.667506 -18.364962)
				)
				(xy 130.667506 -18.30451)
				(arc
					(start 130.670808 -18.301208)
					(mid 130.683343 -18.258634)
					(end 130.70459 -18.219674)
				)
				(xy 130.70459 -18.214848) (xy 130.768598 -18.15084)
				(arc
					(start 130.773424 -18.15084)
					(mid 130.812398 -18.129628)
					(end 130.854958 -18.117058)
				)
				(xy 130.85826 -18.113756) (xy 131.298696 -18.113756) (xy 131.298696 -17.986756) (xy 130.927094 -17.986756)
				(xy 130.858514 -17.986756)
				(arc
					(start 130.854958 -17.9832)
					(mid 130.812384 -17.970665)
					(end 130.773424 -17.949418)
				)
				(xy 130.768598 -17.949418) (xy 130.718052 -17.898872) (xy 130.693922 -17.874742)
				(arc
					(start 130.693922 -17.868392)
					(mid 130.680645 -17.842776)
					(end 130.671824 -17.815306)
				)
				(xy 130.667506 -17.810988)
				(arc
					(start 130.667506 -17.735042)
					(mid 130.750056 -16.956165)
					(end 130.832606 -17.735042)
				)
				(arc
					(start 130.832606 -17.776698)
					(mid 130.833202 -17.7796)
					(end 130.834892 -17.782032)
				)
				(arc
					(start 130.861308 -17.808448)
					(mid 130.875642 -17.818026)
					(end 130.89255 -17.821402)
				)
				(xy 130.92684 -17.821402) (xy 130.927094 -17.821656) (xy 131.298696 -17.821656)
			)
		)
	)
	(zone
		(layer "In9.Cu")
		(hatch none 0.5)
		(connect_pads
			(clearance 0)
		)
		(min_thickness 0.25)
		(keepout
			(tracks not_allowed)
			(vias allowed)
			(pads allowed)
			(copperpour not_allowed)
			(footprints allowed)
		)
		(placement
			(enabled no)
			(sheetname "")
		)
		(fill
			(thermal_gap 0.5)
			(thermal_bridge_width 0.5)
			(island_removal_mode 0)
		)
		(polygon
			(pts
				(arc
					(start 389.898636 -18.350484)
					(mid 389.350123 -17.80159)
					(end 388.801356 -18.35023)
				)
				(arc
					(start 388.801356 -19.750024)
					(mid 389.349996 -20.298664)
					(end 389.898636 -19.750024)
				)
				(xy 389.898636 -19.278854)
				(arc
					(start 389.49249 -19.278854)
					(mid 389.475577 -19.282218)
					(end 389.461248 -19.291808)
				)
				(arc
					(start 389.4455 -19.307556)
					(mid 389.435922 -19.32189)
					(end 389.432546 -19.338798)
				)
				(arc
					(start 389.432546 -19.36496)
					(mid 389.349996 -20.143837)
					(end 389.267446 -19.36496)
				)
				(xy 389.267446 -19.304508)
				(arc
					(start 389.270748 -19.301206)
					(mid 389.283283 -19.258632)
					(end 389.30453 -19.219672)
				)
				(xy 389.30453 -19.214846) (xy 389.368538 -19.150838)
				(arc
					(start 389.373364 -19.150838)
					(mid 389.412338 -19.129626)
					(end 389.454898 -19.117056)
				)
				(xy 389.4582 -19.113754) (xy 389.898636 -19.113754) (xy 389.898636 -18.986754) (xy 389.527034 -18.986754)
				(xy 389.458454 -18.986754)
				(arc
					(start 389.454898 -18.983198)
					(mid 389.412324 -18.970663)
					(end 389.373364 -18.949416)
				)
				(xy 389.368538 -18.949416) (xy 389.30453 -18.885408)
				(arc
					(start 389.30453 -18.880582)
					(mid 389.283318 -18.841608)
					(end 389.270748 -18.799048)
				)
				(xy 389.267446 -18.795746)
				(arc
					(start 389.267446 -18.735294)
					(mid 389.349996 -17.956417)
					(end 389.432546 -18.735294)
				)
				(arc
					(start 389.432546 -18.761456)
					(mid 389.43591 -18.778369)
					(end 389.4455 -18.792698)
				)
				(arc
					(start 389.461248 -18.808446)
					(mid 389.475582 -18.818024)
					(end 389.49249 -18.8214)
				)
				(xy 389.52678 -18.8214) (xy 389.527034 -18.821654) (xy 389.898636 -18.821654)
			)
		)
	)
	(zone
		(layer "In9.Cu")
		(hatch none 0.5)
		(connect_pads
			(clearance 0)
		)
		(min_thickness 0.25)
		(keepout
			(tracks not_allowed)
			(vias allowed)
			(pads allowed)
			(copperpour not_allowed)
			(footprints allowed)
		)
		(placement
			(enabled no)
			(sheetname "")
		)
		(fill
			(thermal_gap 0.5)
			(thermal_bridge_width 0.5)
			(island_removal_mode 0)
		)
		(polygon
			(pts
				(arc
					(start 278.23668 -315.756544)
					(mid 277.68804 -316.305184)
					(end 278.23668 -316.853824)
				)
				(xy 278.705056 -316.853824) (xy 278.705056 -316.446408)
				(arc
					(start 278.704802 -316.442344)
					(mid 278.700254 -316.41939)
					(end 278.687276 -316.399926)
				)
				(xy 278.684482 -316.396878) (xy 278.67991 -316.392306)
				(arc
					(start 278.676862 -316.389512)
					(mid 278.657386 -316.376562)
					(end 278.634444 -316.371986)
				)
				(xy 278.63038 -316.371732)
				(arc
					(start 278.624792 -316.371732)
					(mid 277.842904 -316.305184)
					(end 278.624792 -316.238636)
				)
				(xy 278.63038 -316.238636) (xy 278.634444 -316.238382) (xy 278.641556 -316.238636) (xy 278.66213 -316.238636)
				(arc
					(start 278.664162 -316.240668)
					(mid 278.708431 -316.253135)
					(end 278.74849 -316.27572)
				)
				(xy 278.751792 -316.27572) (xy 278.76627 -316.290198) (xy 278.77135 -316.295024) (xy 278.774144 -316.298072)
				(xy 278.778716 -316.302644) (xy 278.781764 -316.305438) (xy 278.78659 -316.310518) (xy 278.801068 -316.324996)
				(arc
					(start 278.801068 -316.328298)
					(mid 278.823621 -316.36837)
					(end 278.83612 -316.412626)
				)
				(xy 278.838152 -316.414658) (xy 278.838152 -316.435232) (xy 278.838406 -316.442344) (xy 278.838152 -316.446408)
				(xy 278.838152 -316.853824) (xy 279.035256 -316.853824) (xy 279.035256 -316.446408) (xy 279.035002 -316.442344)
				(xy 279.035256 -316.435232) (xy 279.035256 -316.414658)
				(arc
					(start 279.037288 -316.412626)
					(mid 279.049755 -316.368357)
					(end 279.07234 -316.328298)
				)
				(xy 279.07234 -316.324996) (xy 279.086818 -316.310518) (xy 279.091644 -316.305438) (xy 279.094692 -316.302644)
				(xy 279.099264 -316.298072) (xy 279.102058 -316.295024) (xy 279.107138 -316.290198) (xy 279.121616 -316.27572)
				(arc
					(start 279.124918 -316.27572)
					(mid 279.16499 -316.253167)
					(end 279.209246 -316.240668)
				)
				(xy 279.211278 -316.238636) (xy 279.231852 -316.238636) (xy 279.238964 -316.238382) (xy 279.243028 -316.238636)
				(arc
					(start 279.248616 -316.238636)
					(mid 280.030504 -316.305184)
					(end 279.248616 -316.371732)
				)
				(xy 279.243028 -316.371732)
				(arc
					(start 279.238964 -316.371986)
					(mid 279.21601 -316.376534)
					(end 279.196546 -316.389512)
				)
				(xy 279.193498 -316.392306) (xy 279.188926 -316.396878)
				(arc
					(start 279.186132 -316.399926)
					(mid 279.173182 -316.419402)
					(end 279.168606 -316.442344)
				)
				(xy 279.168352 -316.446408) (xy 279.168352 -316.853824)
				(arc
					(start 279.636728 -316.853824)
					(mid 280.185368 -316.305184)
					(end 279.636728 -315.756544)
				)
				(xy 278.236934 -315.756544)
			)
		)
	)
	(zone
		(layer "In9.Cu")
		(hatch none 0.5)
		(connect_pads
			(clearance 0)
		)
		(min_thickness 0.25)
		(keepout
			(tracks not_allowed)
			(vias allowed)
			(pads allowed)
			(copperpour not_allowed)
			(footprints allowed)
		)
		(placement
			(enabled no)
			(sheetname "")
		)
		(fill
			(thermal_gap 0.5)
			(thermal_bridge_width 0.5)
			(island_removal_mode 0)
		)
		(polygon
			(pts
				(arc
					(start 283.563314 -162.872674)
					(mid 282.622752 -163.186364)
					(end 282.936442 -164.126926)
				)
				(xy 283.224986 -164.271198)
				(arc
					(start 283.58592 -164.271198)
					(mid 283.769427 -164.236031)
					(end 283.926788 -164.135308)
				)
				(arc
					(start 283.982922 -164.022786)
					(mid 283.986109 -163.979171)
					(end 283.957522 -163.946078)
				)
				(arc
					(start 283.695648 -163.815014)
					(mid 282.761556 -163.255062)
					(end 283.769562 -163.66744)
				)
				(xy 284.031182 -163.79825) (xy 284.031436 -163.79825) (xy 284.061916 -163.813744)
				(arc
					(start 284.063186 -163.817808)
					(mid 284.142706 -163.926784)
					(end 284.144466 -164.061648)
				)
				(xy 284.14599 -164.065966) (xy 284.052772 -164.252148)
				(arc
					(start 284.038294 -164.256974)
					(mid 283.845435 -164.3831)
					(end 283.620972 -164.435282)
				)
				(xy 283.62021 -164.436298) (xy 283.555186 -164.436298)
				(arc
					(start 283.767022 -164.542216)
					(mid 283.985259 -164.454518)
					(end 284.167834 -164.30625)
				)
				(xy 284.259782 -164.122608)
				(arc
					(start 284.263846 -164.121338)
					(mid 284.372822 -164.041818)
					(end 284.507686 -164.040058)
				)
				(xy 284.512004 -164.038534)
				(arc
					(start 284.80385 -164.184584)
					(mid 285.738843 -164.743515)
					(end 284.73019 -164.332158)
				)
				(arc
					(start 284.468824 -164.201602)
					(mid 284.425209 -164.198415)
					(end 284.392116 -164.227002)
				)
				(xy 284.295088 -164.420804)
				(arc
					(start 284.28315 -164.424614)
					(mid 284.139736 -164.550697)
					(end 283.974032 -164.645594)
				)
				(arc
					(start 284.928056 -165.122606)
					(mid 285.874832 -164.817421)
					(end 285.56331 -163.872672)
				)
			)
		)
	)
	(zone
		(layer "In9.Cu")
		(hatch none 0.5)
		(connect_pads
			(clearance 0)
		)
		(min_thickness 0.25)
		(keepout
			(tracks not_allowed)
			(vias allowed)
			(pads allowed)
			(copperpour not_allowed)
			(footprints allowed)
		)
		(placement
			(enabled no)
			(sheetname "")
		)
		(fill
			(thermal_gap 0.5)
			(thermal_bridge_width 0.5)
			(island_removal_mode 0)
		)
		(polygon
			(pts
				(arc
					(start 283.563314 -74.572876)
					(mid 282.622752 -74.886566)
					(end 282.936442 -75.827128)
				)
				(arc
					(start 284.928056 -76.822808)
					(mid 285.874832 -76.517623)
					(end 285.56331 -75.572874)
				)
				(xy 285.274766 -75.428602)
				(arc
					(start 284.913832 -75.428602)
					(mid 284.730325 -75.463769)
					(end 284.572964 -75.564492)
				)
				(arc
					(start 284.51683 -75.677014)
					(mid 284.513643 -75.720629)
					(end 284.54223 -75.753722)
				)
				(arc
					(start 284.804104 -75.884786)
					(mid 285.738196 -76.444738)
					(end 284.73019 -76.03236)
				)
				(xy 284.46857 -75.90155) (xy 284.468316 -75.90155) (xy 284.437836 -75.886056)
				(arc
					(start 284.436566 -75.881992)
					(mid 284.357046 -75.773016)
					(end 284.355286 -75.638152)
				)
				(xy 284.353762 -75.633834) (xy 284.44698 -75.447652)
				(arc
					(start 284.461458 -75.442826)
					(mid 284.654317 -75.3167)
					(end 284.87878 -75.264518)
				)
				(xy 284.879542 -75.263502) (xy 284.944566 -75.263502)
				(arc
					(start 284.73273 -75.157584)
					(mid 284.514493 -75.245282)
					(end 284.331918 -75.39355)
				)
				(xy 284.23997 -75.577192)
				(arc
					(start 284.235906 -75.578462)
					(mid 284.12693 -75.657982)
					(end 283.992066 -75.659742)
				)
				(xy 283.987748 -75.661266)
				(arc
					(start 283.695902 -75.515216)
					(mid 282.760909 -74.956285)
					(end 283.769562 -75.367642)
				)
				(arc
					(start 284.030928 -75.498198)
					(mid 284.074543 -75.501385)
					(end 284.107636 -75.472798)
				)
				(xy 284.204664 -75.278996)
				(arc
					(start 284.216602 -75.275186)
					(mid 284.360022 -75.14901)
					(end 284.52572 -75.053952)
				)
			)
		)
	)
	(zone
		(layer "In9.Cu")
		(hatch none 0.5)
		(connect_pads
			(clearance 0)
		)
		(min_thickness 0.25)
		(keepout
			(tracks not_allowed)
			(vias allowed)
			(pads allowed)
			(copperpour not_allowed)
			(footprints allowed)
		)
		(placement
			(enabled no)
			(sheetname "")
		)
		(fill
			(thermal_gap 0.5)
			(thermal_bridge_width 0.5)
			(island_removal_mode 0)
		)
		(polygon
			(pts
				(arc
					(start 240.871756 -170.876976)
					(mid 239.92498 -171.182161)
					(end 240.236502 -172.12691)
				)
				(xy 240.525046 -172.271182)
				(arc
					(start 240.88598 -172.271182)
					(mid 241.069487 -172.236015)
					(end 241.226848 -172.135292)
				)
				(arc
					(start 241.282982 -172.02277)
					(mid 241.286169 -171.979155)
					(end 241.257582 -171.946062)
				)
				(arc
					(start 240.995708 -171.814998)
					(mid 240.061616 -171.255046)
					(end 241.069622 -171.667424)
				)
				(xy 241.331242 -171.798234) (xy 241.331496 -171.798234) (xy 241.361976 -171.813728)
				(arc
					(start 241.363246 -171.817792)
					(mid 241.442766 -171.926768)
					(end 241.444526 -172.061632)
				)
				(xy 241.44605 -172.06595) (xy 241.352832 -172.252132)
				(arc
					(start 241.338354 -172.256958)
					(mid 241.145495 -172.383084)
					(end 240.921032 -172.435266)
				)
				(xy 240.92027 -172.436282) (xy 240.855246 -172.436282)
				(arc
					(start 241.067082 -172.5422)
					(mid 241.285319 -172.454502)
					(end 241.467894 -172.306234)
				)
				(xy 241.559842 -172.122592)
				(arc
					(start 241.563906 -172.121322)
					(mid 241.672882 -172.041802)
					(end 241.807746 -172.040042)
				)
				(xy 241.812064 -172.038518)
				(arc
					(start 242.10391 -172.184568)
					(mid 243.038903 -172.743499)
					(end 242.03025 -172.332142)
				)
				(arc
					(start 241.768884 -172.201586)
					(mid 241.725269 -172.198399)
					(end 241.692176 -172.226986)
				)
				(xy 241.595148 -172.420788)
				(arc
					(start 241.58321 -172.424598)
					(mid 241.43979 -172.550774)
					(end 241.274092 -172.645832)
				)
				(arc
					(start 242.236498 -173.126908)
					(mid 243.17706 -172.813218)
					(end 242.86337 -171.872656)
				)
			)
		)
	)
	(zone
		(layer "In9.Cu")
		(hatch none 0.5)
		(connect_pads
			(clearance 0)
		)
		(min_thickness 0.25)
		(keepout
			(tracks not_allowed)
			(vias allowed)
			(pads allowed)
			(copperpour not_allowed)
			(footprints allowed)
		)
		(placement
			(enabled no)
			(sheetname "")
		)
		(fill
			(thermal_gap 0.5)
			(thermal_bridge_width 0.5)
			(island_removal_mode 0)
		)
		(polygon
			(pts
				(arc
					(start 134.898638 -17.350232)
					(mid 134.350125 -16.801338)
					(end 133.801358 -17.349978)
				)
				(arc
					(start 133.801358 -18.750026)
					(mid 134.349998 -19.298666)
					(end 134.898638 -18.750026)
				)
				(xy 134.898638 -18.278856)
				(arc
					(start 134.492492 -18.278856)
					(mid 134.475579 -18.28222)
					(end 134.46125 -18.29181)
				)
				(arc
					(start 134.445502 -18.307558)
					(mid 134.435924 -18.321892)
					(end 134.432548 -18.3388)
				)
				(arc
					(start 134.432548 -18.364962)
					(mid 134.349998 -19.143839)
					(end 134.267448 -18.364962)
				)
				(xy 134.267448 -18.30451)
				(arc
					(start 134.27075 -18.301208)
					(mid 134.283285 -18.258634)
					(end 134.304532 -18.219674)
				)
				(xy 134.304532 -18.214848) (xy 134.328662 -18.190718) (xy 134.34441 -18.17497) (xy 134.36854 -18.15084)
				(arc
					(start 134.373366 -18.15084)
					(mid 134.41234 -18.129628)
					(end 134.4549 -18.117058)
				)
				(xy 134.458202 -18.113756) (xy 134.898638 -18.113756) (xy 134.898638 -17.986756) (xy 134.527036 -17.986756)
				(xy 134.458456 -17.986756)
				(arc
					(start 134.4549 -17.9832)
					(mid 134.412326 -17.970665)
					(end 134.373366 -17.949418)
				)
				(xy 134.36854 -17.949418) (xy 134.304532 -17.88541)
				(arc
					(start 134.304532 -17.880584)
					(mid 134.28332 -17.84161)
					(end 134.27075 -17.79905)
				)
				(xy 134.267448 -17.795748)
				(arc
					(start 134.267448 -17.735042)
					(mid 134.349998 -16.956165)
					(end 134.432548 -17.735042)
				)
				(arc
					(start 134.432548 -17.761458)
					(mid 134.435912 -17.778371)
					(end 134.445502 -17.7927)
				)
				(arc
					(start 134.46125 -17.808448)
					(mid 134.475584 -17.818026)
					(end 134.492492 -17.821402)
				)
				(xy 134.526782 -17.821402) (xy 134.527036 -17.821656) (xy 134.898638 -17.821656)
			)
		)
	)
	(zone
		(layer "In9.Cu")
		(hatch none 0.5)
		(connect_pads
			(clearance 0)
		)
		(min_thickness 0.25)
		(keepout
			(tracks not_allowed)
			(vias allowed)
			(pads allowed)
			(copperpour not_allowed)
			(footprints allowed)
		)
		(placement
			(enabled no)
			(sheetname "")
		)
		(fill
			(thermal_gap 0.5)
			(thermal_bridge_width 0.5)
			(island_removal_mode 0)
		)
		(polygon
			(pts
				(arc
					(start 40.45204 -207.800194)
					(mid 33.325054 -200.673208)
					(end 26.198068 -207.800194)
				)
				(arc
					(start 26.198068 -213.800436)
					(mid 33.325054 -220.927168)
					(end 40.45204 -213.800436)
				)
			)
		)
	)
	(zone
		(net "P12V_A")
		(layer "In9.Cu")
		(hatch none 0.5)
		(connect_pads
			(clearance 0.5)
		)
		(min_thickness 0.25)
		(fill yes
			(thermal_gap 0.5)
			(thermal_bridge_width 0.5)
			(island_removal_mode 0)
		)
		(polygon
			(pts
				(xy 274.828 -381.742188) (xy 274.828 -408.836622) (xy 276.026626 -410.035248) (xy 288.656776 -410.035248)
				(xy 289.047428 -410.035248) (xy 291.079682 -408.002994) (xy 291.079682 -407.612342) (xy 291.079682 -380.007622)
				(xy 291.079682 -375.029222) (xy 291.079682 -370.775738) (xy 289.744404 -369.44046) (xy 288.830004 -368.52606)
				(xy 254.934974 -368.52606) (xy 254.020574 -369.44046) (xy 252.598682 -370.862352) (xy 252.598682 -377.094242)
				(xy 252.82144 -377.317) (xy 274.37588 -377.317) (xy 274.828 -377.76912) (xy 274.828 -378.968)
			)
		)
	)
	(zone
		(layer "In9.Cu")
		(hatch none 0.5)
		(connect_pads
			(clearance 0)
		)
		(min_thickness 0.25)
		(keepout
			(tracks not_allowed)
			(vias allowed)
			(pads allowed)
			(copperpour not_allowed)
			(footprints allowed)
		)
		(placement
			(enabled no)
			(sheetname "")
		)
		(fill
			(thermal_gap 0.5)
			(thermal_bridge_width 0.5)
			(island_removal_mode 0)
		)
		(polygon
			(pts
				(arc
					(start 400.802094 -322.800218)
					(mid 393.675108 -315.673232)
					(end 386.548122 -322.800218)
				)
				(arc
					(start 386.548122 -328.800206)
					(mid 393.675108 -335.927192)
					(end 400.802094 -328.800206)
				)
			)
		)
	)
	(zone
		(layer "In9.Cu")
		(hatch none 0.5)
		(connect_pads
			(clearance 0)
		)
		(min_thickness 0.25)
		(keepout
			(tracks not_allowed)
			(vias allowed)
			(pads allowed)
			(copperpour not_allowed)
			(footprints allowed)
		)
		(placement
			(enabled no)
			(sheetname "")
		)
		(fill
			(thermal_gap 0.5)
			(thermal_bridge_width 0.5)
			(island_removal_mode 0)
		)
		(polygon
			(pts
				(arc
					(start 283.563314 -62.5729)
					(mid 282.622752 -62.88659)
					(end 282.936442 -63.827152)
				)
				(arc
					(start 284.928056 -64.822832)
					(mid 285.874832 -64.517647)
					(end 285.56331 -63.572898)
				)
				(xy 285.274766 -63.428626)
				(arc
					(start 284.913832 -63.428626)
					(mid 284.730325 -63.463793)
					(end 284.572964 -63.564516)
				)
				(arc
					(start 284.51683 -63.677038)
					(mid 284.513643 -63.720653)
					(end 284.54223 -63.753746)
				)
				(arc
					(start 284.804104 -63.88481)
					(mid 285.738196 -64.444762)
					(end 284.73019 -64.032384)
				)
				(xy 284.46857 -63.901574) (xy 284.468316 -63.901574) (xy 284.437836 -63.88608)
				(arc
					(start 284.436566 -63.882016)
					(mid 284.357046 -63.77304)
					(end 284.355286 -63.638176)
				)
				(xy 284.353762 -63.633858) (xy 284.44698 -63.447676)
				(arc
					(start 284.461458 -63.44285)
					(mid 284.654317 -63.316724)
					(end 284.87878 -63.264542)
				)
				(xy 284.879542 -63.263526) (xy 284.944566 -63.263526)
				(arc
					(start 284.73273 -63.157608)
					(mid 284.514493 -63.245306)
					(end 284.331918 -63.393574)
				)
				(xy 284.23997 -63.577216)
				(arc
					(start 284.235906 -63.578486)
					(mid 284.12693 -63.658006)
					(end 283.992066 -63.659766)
				)
				(xy 283.987748 -63.66129)
				(arc
					(start 283.695902 -63.51524)
					(mid 282.760909 -62.956309)
					(end 283.769562 -63.367666)
				)
				(arc
					(start 284.030928 -63.498222)
					(mid 284.074543 -63.501409)
					(end 284.107636 -63.472822)
				)
				(xy 284.204664 -63.27902)
				(arc
					(start 284.216602 -63.27521)
					(mid 284.360022 -63.149034)
					(end 284.52572 -63.053976)
				)
			)
		)
	)
	(zone
		(layer "In9.Cu")
		(hatch none 0.5)
		(connect_pads
			(clearance 0)
		)
		(min_thickness 0.25)
		(keepout
			(tracks not_allowed)
			(vias allowed)
			(pads allowed)
			(copperpour not_allowed)
			(footprints allowed)
		)
		(placement
			(enabled no)
			(sheetname "")
		)
		(fill
			(thermal_gap 0.5)
			(thermal_bridge_width 0.5)
			(island_removal_mode 0)
		)
		(polygon
			(pts
				(arc
					(start 40.45204 -322.800218)
					(mid 33.325054 -315.673232)
					(end 26.198068 -322.800218)
				)
				(arc
					(start 26.198068 -328.800206)
					(mid 33.325054 -335.927192)
					(end 40.45204 -328.800206)
				)
			)
		)
	)
	(zone
		(layer "In9.Cu")
		(hatch none 0.5)
		(connect_pads
			(clearance 0)
		)
		(min_thickness 0.25)
		(keepout
			(tracks not_allowed)
			(vias allowed)
			(pads allowed)
			(copperpour not_allowed)
			(footprints allowed)
		)
		(placement
			(enabled no)
			(sheetname "")
		)
		(fill
			(thermal_gap 0.5)
			(thermal_bridge_width 0.5)
			(island_removal_mode 0)
		)
		(polygon
			(pts
				(arc
					(start 279.236678 -321.156584)
					(mid 278.688038 -321.705224)
					(end 279.236678 -322.253864)
				)
				(xy 279.7048 -322.253864) (xy 279.7048 -322.24599) (xy 279.7048 -322.241926) (xy 279.7048 -321.84213)
				(arc
					(start 279.7048 -321.838066)
					(mid 279.700252 -321.815112)
					(end 279.687274 -321.795648)
				)
				(xy 279.68448 -321.7926) (xy 279.684226 -321.792346)
				(arc
					(start 279.681178 -321.789552)
					(mid 279.661702 -321.776602)
					(end 279.63876 -321.772026)
				)
				(xy 279.634696 -321.771772)
				(arc
					(start 279.62479 -321.771772)
					(mid 278.842902 -321.705224)
					(end 279.62479 -321.638676)
				)
				(xy 279.634696 -321.638676) (xy 279.63876 -321.638422) (xy 279.645872 -321.638676) (xy 279.666446 -321.638676)
				(arc
					(start 279.668478 -321.640708)
					(mid 279.712747 -321.653175)
					(end 279.752806 -321.67576)
				)
				(xy 279.756108 -321.67576) (xy 279.770586 -321.690238) (xy 279.775666 -321.695064) (xy 279.77846 -321.698112)
				(xy 279.778714 -321.698366) (xy 279.781762 -321.70116) (xy 279.786588 -321.70624) (xy 279.801066 -321.720718)
				(arc
					(start 279.801066 -321.72402)
					(mid 279.823619 -321.764092)
					(end 279.836118 -321.808348)
				)
				(xy 279.838404 -321.81038) (xy 279.838404 -321.830954) (xy 279.838404 -321.838066) (xy 279.838404 -321.84213)
				(xy 279.838404 -322.241926) (xy 279.838404 -322.24599) (xy 279.838404 -322.253864) (xy 280.035 -322.253864)
				(xy 280.035 -322.253102) (xy 280.035 -322.24599) (xy 280.035 -322.241926) (xy 280.035 -321.84213)
				(xy 280.035 -321.838066) (xy 280.035 -321.830954) (xy 280.035 -321.81038)
				(arc
					(start 280.037286 -321.808348)
					(mid 280.049753 -321.764079)
					(end 280.072338 -321.72402)
				)
				(xy 280.072338 -321.720718) (xy 280.086816 -321.70624) (xy 280.091642 -321.70116) (xy 280.09469 -321.698366)
				(xy 280.094944 -321.698112) (xy 280.097738 -321.695064) (xy 280.102818 -321.690238) (xy 280.117296 -321.67576)
				(arc
					(start 280.120598 -321.67576)
					(mid 280.16067 -321.653207)
					(end 280.204926 -321.640708)
				)
				(xy 280.206958 -321.638676) (xy 280.227532 -321.638676) (xy 280.234644 -321.638422) (xy 280.238708 -321.638676)
				(arc
					(start 280.248614 -321.638676)
					(mid 281.030502 -321.705224)
					(end 280.248614 -321.771772)
				)
				(xy 280.238708 -321.771772)
				(arc
					(start 280.234644 -321.772026)
					(mid 280.21169 -321.776574)
					(end 280.192226 -321.789552)
				)
				(xy 280.189178 -321.792346) (xy 280.188924 -321.7926)
				(arc
					(start 280.18613 -321.795648)
					(mid 280.17318 -321.815124)
					(end 280.168604 -321.838066)
				)
				(xy 280.168604 -321.84213) (xy 280.168604 -322.241926) (xy 280.168604 -322.24599) (xy 280.169112 -322.253864)
				(arc
					(start 280.636726 -322.253864)
					(mid 281.185366 -321.705224)
					(end 280.636726 -321.156584)
				)
				(xy 279.236932 -321.156584)
			)
		)
	)
	(zone
		(layer "In9.Cu")
		(hatch none 0.5)
		(connect_pads
			(clearance 0)
		)
		(min_thickness 0.25)
		(keepout
			(tracks not_allowed)
			(vias allowed)
			(pads allowed)
			(copperpour not_allowed)
			(footprints allowed)
		)
		(placement
			(enabled no)
			(sheetname "")
		)
		(fill
			(thermal_gap 0.5)
			(thermal_bridge_width 0.5)
			(island_removal_mode 0)
		)
		(polygon
			(pts
				(arc
					(start 400.802094 -207.800194)
					(mid 393.675108 -200.673208)
					(end 386.548122 -207.800194)
				)
				(arc
					(start 386.548122 -213.800436)
					(mid 393.675108 -220.927168)
					(end 400.802094 -213.800436)
				)
			)
		)
	)
	(zone
		(layer "In9.Cu")
		(hatch none 0.5)
		(connect_pads
			(clearance 0)
		)
		(min_thickness 0.25)
		(keepout
			(tracks not_allowed)
			(vias allowed)
			(pads allowed)
			(copperpour not_allowed)
			(footprints allowed)
		)
		(placement
			(enabled no)
			(sheetname "")
		)
		(fill
			(thermal_gap 0.5)
			(thermal_bridge_width 0.5)
			(island_removal_mode 0)
		)
		(polygon
			(pts
				(arc
					(start 240.871756 -166.876984)
					(mid 239.92498 -167.182169)
					(end 240.236502 -168.126918)
				)
				(xy 240.525046 -168.27119)
				(arc
					(start 240.88598 -168.27119)
					(mid 241.069487 -168.236023)
					(end 241.226848 -168.1353)
				)
				(arc
					(start 241.282982 -168.022778)
					(mid 241.286169 -167.979163)
					(end 241.257582 -167.94607)
				)
				(arc
					(start 240.995708 -167.815006)
					(mid 240.061616 -167.255054)
					(end 241.069622 -167.667432)
				)
				(xy 241.331242 -167.798242) (xy 241.331496 -167.798242) (xy 241.361976 -167.813736)
				(arc
					(start 241.363246 -167.8178)
					(mid 241.442766 -167.926776)
					(end 241.444526 -168.06164)
				)
				(xy 241.44605 -168.065958) (xy 241.352832 -168.25214)
				(arc
					(start 241.338354 -168.256966)
					(mid 241.145495 -168.383092)
					(end 240.921032 -168.435274)
				)
				(xy 240.92027 -168.43629) (xy 240.855246 -168.43629)
				(arc
					(start 241.067082 -168.542208)
					(mid 241.285319 -168.45451)
					(end 241.467894 -168.306242)
				)
				(xy 241.559842 -168.1226)
				(arc
					(start 241.563906 -168.12133)
					(mid 241.672882 -168.04181)
					(end 241.807746 -168.04005)
				)
				(xy 241.812064 -168.038526)
				(arc
					(start 242.10391 -168.184576)
					(mid 243.038903 -168.743507)
					(end 242.03025 -168.33215)
				)
				(arc
					(start 241.768884 -168.201594)
					(mid 241.725269 -168.198407)
					(end 241.692176 -168.226994)
				)
				(xy 241.595148 -168.420796)
				(arc
					(start 241.58321 -168.424606)
					(mid 241.43979 -168.550782)
					(end 241.274092 -168.64584)
				)
				(arc
					(start 242.236498 -169.126916)
					(mid 243.17706 -168.813226)
					(end 242.86337 -167.872664)
				)
			)
		)
	)
	(zone
		(net "MB1_CM_GATE_R")
		(layer "In9.Cu")
		(hatch none 0.5)
		(connect_pads
			(clearance 0.5)
		)
		(min_thickness 0.25)
		(fill yes
			(thermal_gap 0.5)
			(thermal_bridge_width 0.5)
			(island_removal_mode 0)
		)
		(polygon
			(pts
				(xy 364.9726 -148.844) (xy 364.9726 -148.547582) (xy 358.0892 -141.664182) (xy 358.0892 -140.6906)
				(xy 358.0892 -139.0396) (xy 357.8606 -138.811) (xy 356.4636 -138.811) (xy 356.2858 -138.9888) (xy 356.2858 -142.435326)
				(xy 364.320328 -150.469854) (xy 364.73003 -150.469854) (xy 364.9726 -150.227284)
			)
		)
	)
	(zone
		(layer "In9.Cu")
		(hatch none 0.5)
		(connect_pads
			(clearance 0)
		)
		(min_thickness 0.25)
		(keepout
			(tracks not_allowed)
			(vias allowed)
			(pads allowed)
			(copperpour not_allowed)
			(footprints allowed)
		)
		(placement
			(enabled no)
			(sheetname "")
		)
		(fill
			(thermal_gap 0.5)
			(thermal_bridge_width 0.5)
			(island_removal_mode 0)
		)
		(polygon
			(pts
				(arc
					(start 120.498616 -17.350232)
					(mid 119.950103 -16.801338)
					(end 119.401336 -17.349978)
				)
				(arc
					(start 119.401336 -18.750026)
					(mid 119.949976 -19.298666)
					(end 120.498616 -18.750026)
				)
				(xy 120.498616 -18.278856)
				(arc
					(start 120.09247 -18.278856)
					(mid 120.075557 -18.28222)
					(end 120.061228 -18.29181)
				)
				(arc
					(start 120.04548 -18.307558)
					(mid 120.035902 -18.321892)
					(end 120.032526 -18.3388)
				)
				(arc
					(start 120.032526 -18.364962)
					(mid 119.949976 -19.143839)
					(end 119.867426 -18.364962)
				)
				(xy 119.867426 -18.30451)
				(arc
					(start 119.870728 -18.301208)
					(mid 119.883263 -18.258634)
					(end 119.90451 -18.219674)
				)
				(xy 119.90451 -18.214848) (xy 119.968518 -18.15084)
				(arc
					(start 119.973344 -18.15084)
					(mid 120.012318 -18.129628)
					(end 120.054878 -18.117058)
				)
				(xy 120.05818 -18.113756) (xy 120.498616 -18.113756) (xy 120.498616 -17.986756) (xy 120.127014 -17.986756)
				(xy 120.058434 -17.986756)
				(arc
					(start 120.054878 -17.9832)
					(mid 120.012304 -17.970665)
					(end 119.973344 -17.949418)
				)
				(xy 119.968518 -17.949418) (xy 119.917972 -17.898872) (xy 119.893842 -17.874742)
				(arc
					(start 119.893842 -17.868392)
					(mid 119.880565 -17.842776)
					(end 119.871744 -17.815306)
				)
				(xy 119.867426 -17.810988)
				(arc
					(start 119.867426 -17.735042)
					(mid 119.949976 -16.956165)
					(end 120.032526 -17.735042)
				)
				(arc
					(start 120.032526 -17.776698)
					(mid 120.033122 -17.7796)
					(end 120.034812 -17.782032)
				)
				(arc
					(start 120.061228 -17.808448)
					(mid 120.075562 -17.818026)
					(end 120.09247 -17.821402)
				)
				(xy 120.12676 -17.821402) (xy 120.127014 -17.821656) (xy 120.498616 -17.821656)
			)
		)
	)
	(zone
		(layer "In9.Cu")
		(hatch none 0.5)
		(connect_pads
			(clearance 0)
		)
		(min_thickness 0.25)
		(keepout
			(tracks not_allowed)
			(vias allowed)
			(pads allowed)
			(copperpour not_allowed)
			(footprints allowed)
		)
		(placement
			(enabled no)
			(sheetname "")
		)
		(fill
			(thermal_gap 0.5)
			(thermal_bridge_width 0.5)
			(island_removal_mode 0)
		)
		(polygon
			(pts
				(arc
					(start 366.498632 -17.350232)
					(mid 365.950119 -16.801338)
					(end 365.401352 -17.349978)
				)
				(xy 365.401352 -17.821656) (xy 365.772954 -17.821656) (xy 365.773208 -17.821402)
				(arc
					(start 365.807498 -17.821402)
					(mid 365.824411 -17.818038)
					(end 365.83874 -17.808448)
				)
				(arc
					(start 365.865156 -17.782032)
					(mid 365.866846 -17.7796)
					(end 365.867442 -17.776698)
				)
				(arc
					(start 365.867442 -17.735042)
					(mid 365.949992 -16.956165)
					(end 366.032542 -17.735042)
				)
				(xy 366.032542 -17.810988)
				(arc
					(start 366.028224 -17.815306)
					(mid 366.0194 -17.842775)
					(end 366.006126 -17.868392)
				)
				(xy 366.006126 -17.874742) (xy 365.981996 -17.898872) (xy 365.93145 -17.949418)
				(arc
					(start 365.926624 -17.949418)
					(mid 365.88765 -17.97063)
					(end 365.84509 -17.9832)
				)
				(xy 365.841534 -17.986756) (xy 365.772954 -17.986756) (xy 365.401352 -17.986756) (xy 365.401352 -18.113756)
				(xy 365.841788 -18.113756)
				(arc
					(start 365.84509 -18.117058)
					(mid 365.887664 -18.129593)
					(end 365.926624 -18.15084)
				)
				(xy 365.93145 -18.15084) (xy 365.995458 -18.214848)
				(arc
					(start 365.995458 -18.219674)
					(mid 366.01667 -18.258648)
					(end 366.02924 -18.301208)
				)
				(xy 366.032542 -18.30451)
				(arc
					(start 366.032542 -18.364962)
					(mid 365.949992 -19.143839)
					(end 365.867442 -18.364962)
				)
				(arc
					(start 365.867442 -18.3388)
					(mid 365.864078 -18.321887)
					(end 365.854488 -18.307558)
				)
				(arc
					(start 365.83874 -18.29181)
					(mid 365.824406 -18.282232)
					(end 365.807498 -18.278856)
				)
				(xy 365.401352 -18.278856)
				(arc
					(start 365.401352 -18.750026)
					(mid 365.949992 -19.298666)
					(end 366.498632 -18.750026)
				)
			)
		)
	)
	(zone
		(layer "In9.Cu")
		(hatch none 0.5)
		(connect_pads
			(clearance 0)
		)
		(min_thickness 0.25)
		(keepout
			(tracks not_allowed)
			(vias allowed)
			(pads allowed)
			(copperpour not_allowed)
			(footprints allowed)
		)
		(placement
			(enabled no)
			(sheetname "")
		)
		(fill
			(thermal_gap 0.5)
			(thermal_bridge_width 0.5)
			(island_removal_mode 0)
		)
		(polygon
			(pts
				(arc
					(start 278.23668 -337.35645)
					(mid 277.68804 -337.90509)
					(end 278.23668 -338.45373)
				)
				(xy 278.705056 -338.45373) (xy 278.705056 -338.046314)
				(arc
					(start 278.704802 -338.04225)
					(mid 278.700254 -338.019296)
					(end 278.687276 -337.999832)
				)
				(xy 278.684482 -337.996784) (xy 278.67991 -337.992212)
				(arc
					(start 278.676862 -337.989418)
					(mid 278.657386 -337.976468)
					(end 278.634444 -337.971892)
				)
				(xy 278.63038 -337.971892)
				(arc
					(start 278.624792 -337.971892)
					(mid 277.842861 -337.90509)
					(end 278.624792 -337.838288)
				)
				(xy 278.63038 -337.838288) (xy 278.634444 -337.838288) (xy 278.641556 -337.838288) (xy 278.66213 -337.838288)
				(arc
					(start 278.664162 -337.840574)
					(mid 278.708431 -337.853041)
					(end 278.74849 -337.875626)
				)
				(xy 278.751792 -337.875626) (xy 278.76627 -337.890104) (xy 278.77135 -337.89493) (xy 278.774144 -337.897978)
				(xy 278.778716 -337.90255) (xy 278.781764 -337.905344) (xy 278.78659 -337.910424) (xy 278.801068 -337.924902)
				(arc
					(start 278.801068 -337.928204)
					(mid 278.823621 -337.968276)
					(end 278.83612 -338.012532)
				)
				(xy 278.838152 -338.014564) (xy 278.838152 -338.035138) (xy 278.838406 -338.04225) (xy 278.838152 -338.046314)
				(xy 278.838152 -338.45373) (xy 279.035256 -338.45373) (xy 279.035256 -338.046314) (xy 279.035002 -338.04225)
				(xy 279.035256 -338.035138) (xy 279.035256 -338.014564)
				(arc
					(start 279.037288 -338.012532)
					(mid 279.049755 -337.968263)
					(end 279.07234 -337.928204)
				)
				(xy 279.07234 -337.924902) (xy 279.086818 -337.910424) (xy 279.091644 -337.905344) (xy 279.094692 -337.90255)
				(xy 279.099264 -337.897978) (xy 279.102058 -337.89493) (xy 279.107138 -337.890104) (xy 279.121616 -337.875626)
				(arc
					(start 279.124918 -337.875626)
					(mid 279.16499 -337.853073)
					(end 279.209246 -337.840574)
				)
				(xy 279.211278 -337.838288) (xy 279.231852 -337.838288) (xy 279.238964 -337.838288) (xy 279.243028 -337.838288)
				(arc
					(start 279.248616 -337.838288)
					(mid 280.030547 -337.90509)
					(end 279.248616 -337.971892)
				)
				(xy 279.243028 -337.971892)
				(arc
					(start 279.238964 -337.971892)
					(mid 279.21601 -337.97644)
					(end 279.196546 -337.989418)
				)
				(xy 279.193498 -337.992212) (xy 279.188926 -337.996784)
				(arc
					(start 279.186132 -337.999832)
					(mid 279.173182 -338.019308)
					(end 279.168606 -338.04225)
				)
				(xy 279.168352 -338.046314) (xy 279.168352 -338.45373)
				(arc
					(start 279.636728 -338.45373)
					(mid 280.185368 -337.90509)
					(end 279.636728 -337.35645)
				)
				(xy 278.236934 -337.35645)
			)
		)
	)
	(zone
		(layer "In9.Cu")
		(hatch none 0.5)
		(connect_pads
			(clearance 0)
		)
		(min_thickness 0.25)
		(keepout
			(tracks not_allowed)
			(vias allowed)
			(pads allowed)
			(copperpour not_allowed)
			(footprints allowed)
		)
		(placement
			(enabled no)
			(sheetname "")
		)
		(fill
			(thermal_gap 0.5)
			(thermal_bridge_width 0.5)
			(island_removal_mode 0)
		)
		(polygon
			(pts
				(xy 220.286326 -415.127694) (xy 220.251528 -415.1249)
				(arc
					(start 220.251528 -415.600134)
					(mid 220.800168 -416.148774)
					(end 221.348808 -415.600134)
				)
				(arc
					(start 221.348808 -414.20034)
					(mid 220.800295 -413.651446)
					(end 220.251528 -414.200086)
				)
				(arc
					(start 220.251528 -414.658302)
					(mid 220.285838 -414.668162)
					(end 220.321378 -414.67151)
				)
				(arc
					(start 220.588332 -414.67151)
					(mid 220.663699 -414.64727)
					(end 220.71076 -414.583626)
				)
				(arc
					(start 220.71076 -414.583626)
					(mid 220.804343 -413.806406)
					(end 220.879416 -414.585658)
				)
				(arc
					(start 220.879416 -414.585658)
					(mid 220.793973 -414.752766)
					(end 220.624908 -414.834324)
				)
				(xy 220.622622 -414.83661) (xy 220.287088 -414.83661) (xy 220.28531 -414.834832) (xy 220.251528 -414.829752)
				(arc
					(start 220.251528 -414.95853)
					(mid 220.286361 -414.962342)
					(end 220.321378 -414.96361)
				)
				(xy 220.622622 -414.96361)
				(arc
					(start 220.624908 -414.965896)
					(mid 220.794025 -415.0474)
					(end 220.879416 -415.214562)
				)
				(arc
					(start 220.879416 -415.214562)
					(mid 220.804344 -415.993841)
					(end 220.71076 -415.216594)
				)
				(arc
					(start 220.71076 -415.216594)
					(mid 220.663671 -415.152988)
					(end 220.588332 -415.12871)
				)
				(xy 220.287088 -415.12871)
			)
		)
	)
	(zone
		(layer "In9.Cu")
		(hatch none 0.5)
		(connect_pads
			(clearance 0)
		)
		(min_thickness 0.25)
		(keepout
			(tracks not_allowed)
			(vias allowed)
			(pads allowed)
			(copperpour not_allowed)
			(footprints allowed)
		)
		(placement
			(enabled no)
			(sheetname "")
		)
		(fill
			(thermal_gap 0.5)
			(thermal_bridge_width 0.5)
			(island_removal_mode 0)
		)
		(polygon
			(pts
				(arc
					(start 240.863374 -74.572876)
					(mid 239.922812 -74.886566)
					(end 240.236502 -75.827128)
				)
				(xy 240.525046 -75.9714)
				(arc
					(start 240.88598 -75.9714)
					(mid 241.069487 -75.936233)
					(end 241.226848 -75.83551)
				)
				(arc
					(start 241.282982 -75.722988)
					(mid 241.286169 -75.679373)
					(end 241.257582 -75.64628)
				)
				(arc
					(start 240.995708 -75.515216)
					(mid 240.061616 -74.955264)
					(end 241.069622 -75.367642)
				)
				(xy 241.331242 -75.498452) (xy 241.331496 -75.498452) (xy 241.361976 -75.513946)
				(arc
					(start 241.363246 -75.51801)
					(mid 241.442766 -75.626986)
					(end 241.444526 -75.76185)
				)
				(xy 241.44605 -75.766168) (xy 241.352832 -75.95235)
				(arc
					(start 241.338354 -75.957176)
					(mid 241.145495 -76.083302)
					(end 240.921032 -76.135484)
				)
				(xy 240.92027 -76.1365) (xy 240.855246 -76.1365)
				(arc
					(start 241.067082 -76.242418)
					(mid 241.285319 -76.15472)
					(end 241.467894 -76.006452)
				)
				(xy 241.559842 -75.82281)
				(arc
					(start 241.563906 -75.82154)
					(mid 241.672882 -75.74202)
					(end 241.807746 -75.74026)
				)
				(xy 241.812064 -75.738736)
				(arc
					(start 242.10391 -75.884786)
					(mid 243.038903 -76.443717)
					(end 242.03025 -76.03236)
				)
				(arc
					(start 241.768884 -75.901804)
					(mid 241.725269 -75.898617)
					(end 241.692176 -75.927204)
				)
				(xy 241.595148 -76.121006)
				(arc
					(start 241.58321 -76.124816)
					(mid 241.439796 -76.250899)
					(end 241.274092 -76.345796)
				)
				(arc
					(start 242.228116 -76.822808)
					(mid 243.174892 -76.517623)
					(end 242.86337 -75.572874)
				)
			)
		)
	)
	(zone
		(layer "In9.Cu")
		(hatch none 0.5)
		(connect_pads
			(clearance 0)
		)
		(min_thickness 0.25)
		(keepout
			(tracks not_allowed)
			(vias allowed)
			(pads allowed)
			(copperpour not_allowed)
			(footprints allowed)
		)
		(placement
			(enabled no)
			(sheetname "")
		)
		(fill
			(thermal_gap 0.5)
			(thermal_bridge_width 0.5)
			(island_removal_mode 0)
		)
		(polygon
			(pts
				(arc
					(start 212.348826 -416.800284)
					(mid 211.800313 -416.25139)
					(end 211.251546 -416.80003)
				)
				(xy 211.251546 -417.271454)
				(arc
					(start 211.621116 -417.271454)
					(mid 211.638029 -417.26809)
					(end 211.652358 -417.2585)
				)
				(arc
					(start 211.704682 -417.206176)
					(mid 211.712152 -417.196347)
					(end 211.71662 -417.18484)
				)
				(arc
					(start 211.71662 -417.18484)
					(mid 211.800709 -416.406251)
					(end 211.882736 -417.185094)
				)
				(xy 211.882736 -417.209224)
				(arc
					(start 211.879434 -417.212526)
					(mid 211.866899 -417.2551)
					(end 211.845652 -417.29406)
				)
				(xy 211.845652 -417.298886) (xy 211.745068 -417.39947)
				(arc
					(start 211.740242 -417.39947)
					(mid 211.701268 -417.420682)
					(end 211.658708 -417.433252)
				)
				(xy 211.655406 -417.436554) (xy 211.251546 -417.436554) (xy 211.251546 -417.563554) (xy 211.654898 -417.563554)
				(arc
					(start 211.6582 -417.566856)
					(mid 211.700774 -417.579391)
					(end 211.739734 -417.600638)
				)
				(xy 211.74456 -417.600638) (xy 211.821522 -417.6776) (xy 211.845652 -417.70173)
				(arc
					(start 211.845652 -417.706556)
					(mid 211.866864 -417.74553)
					(end 211.879434 -417.78809)
				)
				(xy 211.882736 -417.791392)
				(arc
					(start 211.882736 -417.815014)
					(mid 211.800833 -418.593891)
					(end 211.716366 -417.815268)
				)
				(arc
					(start 211.716366 -417.815268)
					(mid 211.711973 -417.804037)
					(end 211.704682 -417.79444)
				)
				(arc
					(start 211.65185 -417.741608)
					(mid 211.637516 -417.73203)
					(end 211.620608 -417.728654)
				)
				(xy 211.251546 -417.728654)
				(arc
					(start 211.251546 -418.200078)
					(mid 211.800186 -418.748718)
					(end 212.348826 -418.200078)
				)
			)
		)
	)
	(zone
		(layer "In9.Cu")
		(hatch none 0.5)
		(connect_pads
			(clearance 0)
		)
		(min_thickness 0.25)
		(keepout
			(tracks not_allowed)
			(vias allowed)
			(pads allowed)
			(copperpour not_allowed)
			(footprints allowed)
		)
		(placement
			(enabled no)
			(sheetname "")
		)
		(fill
			(thermal_gap 0.5)
			(thermal_bridge_width 0.5)
			(island_removal_mode 0)
		)
		(polygon
			(pts
				(arc
					(start 377.298712 -17.350232)
					(mid 376.750199 -16.801338)
					(end 376.201432 -17.349978)
				)
				(arc
					(start 376.201432 -18.750026)
					(mid 376.750072 -19.298666)
					(end 377.298712 -18.750026)
				)
				(xy 377.298712 -18.278856)
				(arc
					(start 376.892566 -18.278856)
					(mid 376.875653 -18.28222)
					(end 376.861324 -18.29181)
				)
				(arc
					(start 376.845576 -18.307558)
					(mid 376.835998 -18.321892)
					(end 376.832622 -18.3388)
				)
				(arc
					(start 376.832622 -18.364962)
					(mid 376.750072 -19.143839)
					(end 376.667522 -18.364962)
				)
				(xy 376.667522 -18.30451)
				(arc
					(start 376.670824 -18.301208)
					(mid 376.683359 -18.258634)
					(end 376.704606 -18.219674)
				)
				(xy 376.704606 -18.214848) (xy 376.768614 -18.15084)
				(arc
					(start 376.77344 -18.15084)
					(mid 376.812414 -18.129628)
					(end 376.854974 -18.117058)
				)
				(xy 376.858276 -18.113756) (xy 377.298712 -18.113756) (xy 377.298712 -17.986756) (xy 376.92711 -17.986756)
				(xy 376.85853 -17.986756)
				(arc
					(start 376.854974 -17.9832)
					(mid 376.8124 -17.970665)
					(end 376.77344 -17.949418)
				)
				(xy 376.768614 -17.949418) (xy 376.704606 -17.88541)
				(arc
					(start 376.704606 -17.880584)
					(mid 376.683394 -17.84161)
					(end 376.670824 -17.79905)
				)
				(xy 376.667522 -17.795748)
				(arc
					(start 376.667522 -17.735042)
					(mid 376.750072 -16.956165)
					(end 376.832622 -17.735042)
				)
				(arc
					(start 376.832622 -17.761458)
					(mid 376.835986 -17.778371)
					(end 376.845576 -17.7927)
				)
				(arc
					(start 376.861324 -17.808448)
					(mid 376.875658 -17.818026)
					(end 376.892566 -17.821402)
				)
				(xy 376.926856 -17.821402) (xy 376.92711 -17.821656) (xy 377.298712 -17.821656)
			)
		)
	)
	(zone
		(net "MB3_P12V_IN_R")
		(layer "In9.Cu")
		(hatch none 0.5)
		(connect_pads
			(clearance 0.5)
		)
		(min_thickness 0.25)
		(fill yes
			(thermal_gap 0.5)
			(thermal_bridge_width 0.5)
			(island_removal_mode 0)
		)
		(polygon
			(pts
				(xy 253.111 -390.15416) (xy 265.951208 -390.15416) (xy 273.92884 -390.15416) (xy 274.465542 -389.617458)
				(xy 274.465542 -386.81025) (xy 274.465542 -381.720598) (xy 274.465542 -379.113542) (xy 274.465542 -378.074682)
				(xy 274.21586 -377.825) (xy 253.14402 -377.825) (xy 252.974094 -377.825) (xy 252.552708 -378.246386)
				(xy 252.552708 -389.780018) (xy 252.92685 -390.15416)
			)
		)
	)
	(zone
		(layer "In9.Cu")
		(hatch none 0.5)
		(connect_pads
			(clearance 0)
		)
		(min_thickness 0.25)
		(keepout
			(tracks not_allowed)
			(vias allowed)
			(pads allowed)
			(copperpour not_allowed)
			(footprints allowed)
		)
		(placement
			(enabled no)
			(sheetname "")
		)
		(fill
			(thermal_gap 0.5)
			(thermal_bridge_width 0.5)
			(island_removal_mode 0)
		)
		(polygon
			(pts
				(arc
					(start 240.871756 -42.577258)
					(mid 239.92498 -42.882443)
					(end 240.236502 -43.827192)
				)
				(xy 240.525046 -43.971464)
				(arc
					(start 240.88598 -43.971464)
					(mid 241.069487 -43.936297)
					(end 241.226848 -43.835574)
				)
				(arc
					(start 241.282982 -43.723052)
					(mid 241.286169 -43.679437)
					(end 241.257582 -43.646344)
				)
				(arc
					(start 240.995708 -43.51528)
					(mid 240.061616 -42.955328)
					(end 241.069622 -43.367706)
				)
				(xy 241.331242 -43.498516) (xy 241.331496 -43.498516) (xy 241.361976 -43.51401)
				(arc
					(start 241.363246 -43.518074)
					(mid 241.442766 -43.62705)
					(end 241.444526 -43.761914)
				)
				(xy 241.44605 -43.766232) (xy 241.352832 -43.952414)
				(arc
					(start 241.338354 -43.95724)
					(mid 241.145495 -44.083366)
					(end 240.921032 -44.135548)
				)
				(xy 240.92027 -44.136564) (xy 240.855246 -44.136564)
				(arc
					(start 241.067082 -44.242482)
					(mid 241.285319 -44.154784)
					(end 241.467894 -44.006516)
				)
				(xy 241.559842 -43.822874)
				(arc
					(start 241.563906 -43.821604)
					(mid 241.672882 -43.742084)
					(end 241.807746 -43.740324)
				)
				(xy 241.812064 -43.7388)
				(arc
					(start 242.10391 -43.88485)
					(mid 243.038903 -44.443781)
					(end 242.03025 -44.032424)
				)
				(arc
					(start 241.768884 -43.901868)
					(mid 241.725269 -43.898681)
					(end 241.692176 -43.927268)
				)
				(xy 241.595148 -44.12107)
				(arc
					(start 241.58321 -44.12488)
					(mid 241.43979 -44.251056)
					(end 241.274092 -44.346114)
				)
				(arc
					(start 242.236498 -44.82719)
					(mid 243.17706 -44.5135)
					(end 242.86337 -43.572938)
				)
			)
		)
	)
	(zone
		(layer "In9.Cu")
		(hatch none 0.5)
		(connect_pads
			(clearance 0)
		)
		(min_thickness 0.25)
		(keepout
			(tracks not_allowed)
			(vias allowed)
			(pads allowed)
			(copperpour not_allowed)
			(footprints allowed)
		)
		(placement
			(enabled no)
			(sheetname "")
		)
		(fill
			(thermal_gap 0.5)
			(thermal_bridge_width 0.5)
			(island_removal_mode 0)
		)
		(polygon
			(pts
				(arc
					(start 140.298678 -18.350484)
					(mid 139.750165 -17.80159)
					(end 139.201398 -18.35023)
				)
				(arc
					(start 139.201398 -19.750024)
					(mid 139.750038 -20.298664)
					(end 140.298678 -19.750024)
				)
				(xy 140.298678 -19.278854)
				(arc
					(start 139.892532 -19.278854)
					(mid 139.875619 -19.282218)
					(end 139.86129 -19.291808)
				)
				(arc
					(start 139.845542 -19.307556)
					(mid 139.835964 -19.32189)
					(end 139.832588 -19.338798)
				)
				(arc
					(start 139.832588 -19.36496)
					(mid 139.750038 -20.143837)
					(end 139.667488 -19.36496)
				)
				(xy 139.667488 -19.304508)
				(arc
					(start 139.67079 -19.301206)
					(mid 139.683325 -19.258632)
					(end 139.704572 -19.219672)
				)
				(xy 139.704572 -19.214846) (xy 139.728702 -19.190716) (xy 139.74445 -19.174968) (xy 139.76858 -19.150838)
				(arc
					(start 139.773406 -19.150838)
					(mid 139.81238 -19.129626)
					(end 139.85494 -19.117056)
				)
				(xy 139.858242 -19.113754) (xy 140.298678 -19.113754) (xy 140.298678 -18.986754) (xy 139.927076 -18.986754)
				(xy 139.858496 -18.986754)
				(arc
					(start 139.85494 -18.983198)
					(mid 139.812366 -18.970663)
					(end 139.773406 -18.949416)
				)
				(xy 139.76858 -18.949416) (xy 139.74445 -18.925286) (xy 139.704572 -18.885408)
				(arc
					(start 139.704572 -18.880582)
					(mid 139.68336 -18.841608)
					(end 139.67079 -18.799048)
				)
				(xy 139.667488 -18.795746)
				(arc
					(start 139.667488 -18.735294)
					(mid 139.750038 -17.956417)
					(end 139.832588 -18.735294)
				)
				(arc
					(start 139.832588 -18.761456)
					(mid 139.835952 -18.778369)
					(end 139.845542 -18.792698)
				)
				(arc
					(start 139.86129 -18.808446)
					(mid 139.875624 -18.818024)
					(end 139.892532 -18.8214)
				)
				(xy 139.926822 -18.8214) (xy 139.927076 -18.821654) (xy 140.298678 -18.821654)
			)
		)
	)
	(zone
		(layer "In9.Cu")
		(hatch none 0.5)
		(connect_pads
			(clearance 0)
		)
		(min_thickness 0.25)
		(keepout
			(tracks not_allowed)
			(vias allowed)
			(pads allowed)
			(copperpour not_allowed)
			(footprints allowed)
		)
		(placement
			(enabled no)
			(sheetname "")
		)
		(fill
			(thermal_gap 0.5)
			(thermal_bridge_width 0.5)
			(island_removal_mode 0)
		)
		(polygon
			(pts
				(arc
					(start 384.498596 -17.350232)
					(mid 383.950083 -16.801338)
					(end 383.401316 -17.349978)
				)
				(arc
					(start 383.401316 -18.750026)
					(mid 383.949956 -19.298666)
					(end 384.498596 -18.750026)
				)
				(xy 384.498596 -18.278856)
				(arc
					(start 384.09245 -18.278856)
					(mid 384.075537 -18.28222)
					(end 384.061208 -18.29181)
				)
				(arc
					(start 384.04546 -18.307558)
					(mid 384.035882 -18.321892)
					(end 384.032506 -18.3388)
				)
				(arc
					(start 384.032506 -18.364962)
					(mid 383.949956 -19.143839)
					(end 383.867406 -18.364962)
				)
				(xy 383.867406 -18.30451)
				(arc
					(start 383.870708 -18.301208)
					(mid 383.883243 -18.258634)
					(end 383.90449 -18.219674)
				)
				(xy 383.90449 -18.214848) (xy 383.968498 -18.15084)
				(arc
					(start 383.973324 -18.15084)
					(mid 384.012298 -18.129628)
					(end 384.054858 -18.117058)
				)
				(xy 384.05816 -18.113756) (xy 384.498596 -18.113756) (xy 384.498596 -17.986756) (xy 384.126994 -17.986756)
				(xy 384.058414 -17.986756)
				(arc
					(start 384.054858 -17.9832)
					(mid 384.012284 -17.970665)
					(end 383.973324 -17.949418)
				)
				(xy 383.968498 -17.949418) (xy 383.90449 -17.88541)
				(arc
					(start 383.90449 -17.880584)
					(mid 383.883278 -17.84161)
					(end 383.870708 -17.79905)
				)
				(xy 383.867406 -17.795748)
				(arc
					(start 383.867406 -17.735042)
					(mid 383.949956 -16.956165)
					(end 384.032506 -17.735042)
				)
				(arc
					(start 384.032506 -17.761458)
					(mid 384.03587 -17.778371)
					(end 384.04546 -17.7927)
				)
				(arc
					(start 384.061208 -17.808448)
					(mid 384.075542 -17.818026)
					(end 384.09245 -17.821402)
				)
				(xy 384.12674 -17.821402) (xy 384.126994 -17.821656) (xy 384.498596 -17.821656)
			)
		)
	)
	(zone
		(layer "In9.Cu")
		(hatch none 0.5)
		(connect_pads
			(clearance 0)
		)
		(min_thickness 0.25)
		(keepout
			(tracks not_allowed)
			(vias allowed)
			(pads allowed)
			(copperpour not_allowed)
			(footprints allowed)
		)
		(placement
			(enabled no)
			(sheetname "")
		)
		(fill
			(thermal_gap 0.5)
			(thermal_bridge_width 0.5)
			(island_removal_mode 0)
		)
		(polygon
			(pts
				(arc
					(start 409.277058 -290.000182)
					(mid 399.52295 -290.000182)
					(end 409.277058 -290.000182)
				)
			)
		)
	)
	(zone
		(layer "In9.Cu")
		(hatch none 0.5)
		(connect_pads
			(clearance 0)
		)
		(min_thickness 0.25)
		(keepout
			(tracks not_allowed)
			(vias allowed)
			(pads allowed)
			(copperpour not_allowed)
			(footprints allowed)
		)
		(placement
			(enabled no)
			(sheetname "")
		)
		(fill
			(thermal_gap 0.5)
			(thermal_bridge_width 0.5)
			(island_removal_mode 0)
		)
		(polygon
			(pts
				(arc
					(start 215.948768 -416.800284)
					(mid 215.400255 -416.25139)
					(end 214.851488 -416.80003)
				)
				(xy 214.851488 -417.271454)
				(arc
					(start 215.221058 -417.271454)
					(mid 215.237971 -417.26809)
					(end 215.2523 -417.2585)
				)
				(arc
					(start 215.304624 -417.206176)
					(mid 215.312094 -417.196347)
					(end 215.316562 -417.18484)
				)
				(arc
					(start 215.316562 -417.18484)
					(mid 215.400651 -416.406251)
					(end 215.482678 -417.185094)
				)
				(xy 215.482678 -417.209224)
				(arc
					(start 215.479376 -417.212526)
					(mid 215.466841 -417.2551)
					(end 215.445594 -417.29406)
				)
				(xy 215.445594 -417.298886) (xy 215.34501 -417.39947)
				(arc
					(start 215.340184 -417.39947)
					(mid 215.30121 -417.420682)
					(end 215.25865 -417.433252)
				)
				(xy 215.255348 -417.436554) (xy 214.851488 -417.436554) (xy 214.851488 -417.563554) (xy 215.25484 -417.563554)
				(arc
					(start 215.258142 -417.566856)
					(mid 215.300716 -417.579391)
					(end 215.339676 -417.600638)
				)
				(xy 215.344502 -417.600638) (xy 215.421464 -417.6776) (xy 215.445594 -417.70173)
				(arc
					(start 215.445594 -417.706556)
					(mid 215.466806 -417.74553)
					(end 215.479376 -417.78809)
				)
				(xy 215.482678 -417.791392)
				(arc
					(start 215.482678 -417.815014)
					(mid 215.400775 -418.593891)
					(end 215.316308 -417.815268)
				)
				(arc
					(start 215.316308 -417.815268)
					(mid 215.311915 -417.804037)
					(end 215.304624 -417.79444)
				)
				(arc
					(start 215.251792 -417.741608)
					(mid 215.237458 -417.73203)
					(end 215.22055 -417.728654)
				)
				(xy 214.851488 -417.728654)
				(arc
					(start 214.851488 -418.200078)
					(mid 215.400128 -418.748718)
					(end 215.948768 -418.200078)
				)
			)
		)
	)
	(zone
		(layer "In9.Cu")
		(hatch none 0.5)
		(connect_pads
			(clearance 0)
		)
		(min_thickness 0.25)
		(keepout
			(tracks not_allowed)
			(vias allowed)
			(pads allowed)
			(copperpour not_allowed)
			(footprints allowed)
		)
		(placement
			(enabled no)
			(sheetname "")
		)
		(fill
			(thermal_gap 0.5)
			(thermal_bridge_width 0.5)
			(island_removal_mode 0)
		)
		(polygon
			(pts
				(arc
					(start 478.120202 -158.368492)
					(mid 477.739202 -157.987492)
					(end 477.358202 -158.368492)
				)
				(xy 477.358202 -158.708344) (xy 477.615504 -158.708344)
				(arc
					(start 477.619568 -158.70809)
					(mid 477.639786 -158.704068)
					(end 477.656906 -158.692596)
				)
				(arc
					(start 477.656906 -158.692596)
					(mid 477.668352 -158.675465)
					(end 477.6724 -158.655258)
				)
				(xy 477.6724 -158.651194)
				(arc
					(start 477.6724 -158.62681)
					(mid 477.739202 -158.101676)
					(end 477.806004 -158.62681)
				)
				(xy 477.806004 -158.651194) (xy 477.806004 -158.655258) (xy 477.806004 -158.662116) (xy 477.806004 -158.682944)
				(arc
					(start 477.803464 -158.68523)
					(mid 477.785454 -158.740262)
					(end 477.751394 -158.787084)
				)
				(arc
					(start 477.751394 -158.787084)
					(mid 477.704558 -158.821117)
					(end 477.64954 -158.839154)
				)
				(xy 477.647254 -158.84144) (xy 477.626426 -158.84144) (xy 477.619568 -158.841694) (xy 477.615504 -158.84144)
				(xy 477.358202 -158.84144) (xy 477.358202 -159.038544) (xy 477.615504 -159.038544) (xy 477.619568 -159.03829)
				(xy 477.626426 -159.038544) (xy 477.647254 -159.038544)
				(arc
					(start 477.64954 -159.04083)
					(mid 477.704572 -159.05884)
					(end 477.751394 -159.0929)
				)
				(arc
					(start 477.751394 -159.0929)
					(mid 477.785427 -159.139736)
					(end 477.803464 -159.194754)
				)
				(xy 477.806004 -159.19704) (xy 477.806004 -159.217868) (xy 477.806004 -159.224726) (xy 477.80575 -159.22879)
				(arc
					(start 477.80575 -159.253174)
					(mid 477.739325 -159.778244)
					(end 477.6724 -159.253174)
				)
				(xy 477.6724 -159.22879)
				(arc
					(start 477.6724 -159.224726)
					(mid 477.668378 -159.204508)
					(end 477.656906 -159.187388)
				)
				(arc
					(start 477.656906 -159.187388)
					(mid 477.639775 -159.175942)
					(end 477.619568 -159.171894)
				)
				(xy 477.615504 -159.17164) (xy 477.358202 -159.17164)
				(arc
					(start 477.358202 -159.511238)
					(mid 477.739075 -159.892492)
					(end 478.120202 -159.511492)
				)
			)
		)
	)
	(zone
		(layer "In9.Cu")
		(hatch none 0.5)
		(connect_pads
			(clearance 0)
		)
		(min_thickness 0.25)
		(keepout
			(tracks not_allowed)
			(vias allowed)
			(pads allowed)
			(copperpour not_allowed)
			(footprints allowed)
		)
		(placement
			(enabled no)
			(sheetname "")
		)
		(fill
			(thermal_gap 0.5)
			(thermal_bridge_width 0.5)
			(island_removal_mode 0)
		)
		(polygon
			(pts
				(arc
					(start 283.563314 -118.872762)
					(mid 282.622752 -119.186452)
					(end 282.936442 -120.127014)
				)
				(xy 283.224986 -120.271286)
				(arc
					(start 283.58592 -120.271286)
					(mid 283.769427 -120.236119)
					(end 283.926788 -120.135396)
				)
				(arc
					(start 283.982922 -120.022874)
					(mid 283.986109 -119.979259)
					(end 283.957522 -119.946166)
				)
				(arc
					(start 283.695648 -119.815102)
					(mid 282.761556 -119.25515)
					(end 283.769562 -119.667528)
				)
				(xy 284.031182 -119.798338) (xy 284.031436 -119.798338) (xy 284.061916 -119.813832)
				(arc
					(start 284.063186 -119.817896)
					(mid 284.142706 -119.926872)
					(end 284.144466 -120.061736)
				)
				(xy 284.14599 -120.066054) (xy 284.052772 -120.252236)
				(arc
					(start 284.038294 -120.257062)
					(mid 283.845435 -120.383188)
					(end 283.620972 -120.43537)
				)
				(xy 283.62021 -120.436386) (xy 283.555186 -120.436386)
				(arc
					(start 283.767022 -120.542304)
					(mid 283.985259 -120.454606)
					(end 284.167834 -120.306338)
				)
				(xy 284.259782 -120.122696)
				(arc
					(start 284.263846 -120.121426)
					(mid 284.372822 -120.041906)
					(end 284.507686 -120.040146)
				)
				(xy 284.512004 -120.038622)
				(arc
					(start 284.80385 -120.184672)
					(mid 285.738843 -120.743603)
					(end 284.73019 -120.332246)
				)
				(arc
					(start 284.468824 -120.20169)
					(mid 284.425209 -120.198503)
					(end 284.392116 -120.22709)
				)
				(xy 284.295088 -120.420892)
				(arc
					(start 284.28315 -120.424702)
					(mid 284.139736 -120.550785)
					(end 283.974032 -120.645682)
				)
				(arc
					(start 284.928056 -121.122694)
					(mid 285.874832 -120.817509)
					(end 285.56331 -119.87276)
				)
			)
		)
	)
	(zone
		(layer "In9.Cu")
		(hatch none 0.5)
		(connect_pads
			(clearance 0)
		)
		(min_thickness 0.25)
		(keepout
			(tracks not_allowed)
			(vias allowed)
			(pads allowed)
			(copperpour not_allowed)
			(footprints allowed)
		)
		(placement
			(enabled no)
			(sheetname "")
		)
		(fill
			(thermal_gap 0.5)
			(thermal_bridge_width 0.5)
			(island_removal_mode 0)
		)
		(polygon
			(pts
				(arc
					(start 166.452042 -322.800218)
					(mid 159.325056 -315.673232)
					(end 152.19807 -322.800218)
				)
				(arc
					(start 152.19807 -328.800206)
					(mid 159.325056 -335.927192)
					(end 166.452042 -328.800206)
				)
			)
		)
	)
	(zone
		(layer "In9.Cu")
		(hatch none 0.5)
		(connect_pads
			(clearance 0)
		)
		(min_thickness 0.25)
		(keepout
			(tracks not_allowed)
			(vias allowed)
			(pads allowed)
			(copperpour not_allowed)
			(footprints allowed)
		)
		(placement
			(enabled no)
			(sheetname "")
		)
		(fill
			(thermal_gap 0.5)
			(thermal_bridge_width 0.5)
			(island_removal_mode 0)
		)
		(polygon
			(pts
				(arc
					(start 283.563314 -70.572884)
					(mid 282.622752 -70.886574)
					(end 282.936442 -71.827136)
				)
				(arc
					(start 284.928056 -72.822816)
					(mid 285.874832 -72.517631)
					(end 285.56331 -71.572882)
				)
				(xy 285.274766 -71.42861)
				(arc
					(start 284.913832 -71.42861)
					(mid 284.730325 -71.463777)
					(end 284.572964 -71.5645)
				)
				(arc
					(start 284.51683 -71.677022)
					(mid 284.513643 -71.720637)
					(end 284.54223 -71.75373)
				)
				(arc
					(start 284.804104 -71.884794)
					(mid 285.738196 -72.444746)
					(end 284.73019 -72.032368)
				)
				(xy 284.46857 -71.901558) (xy 284.468316 -71.901558) (xy 284.437836 -71.886064)
				(arc
					(start 284.436566 -71.882)
					(mid 284.357046 -71.773024)
					(end 284.355286 -71.63816)
				)
				(xy 284.353762 -71.633842) (xy 284.44698 -71.44766)
				(arc
					(start 284.461458 -71.442834)
					(mid 284.654317 -71.316708)
					(end 284.87878 -71.264526)
				)
				(xy 284.879542 -71.26351) (xy 284.944566 -71.26351)
				(arc
					(start 284.73273 -71.157592)
					(mid 284.514493 -71.24529)
					(end 284.331918 -71.393558)
				)
				(xy 284.23997 -71.5772)
				(arc
					(start 284.235906 -71.57847)
					(mid 284.12693 -71.65799)
					(end 283.992066 -71.65975)
				)
				(xy 283.987748 -71.661274)
				(arc
					(start 283.695902 -71.515224)
					(mid 282.760909 -70.956293)
					(end 283.769562 -71.36765)
				)
				(arc
					(start 284.030928 -71.498206)
					(mid 284.074543 -71.501393)
					(end 284.107636 -71.472806)
				)
				(xy 284.204664 -71.279004)
				(arc
					(start 284.216602 -71.275194)
					(mid 284.360022 -71.149018)
					(end 284.52572 -71.05396)
				)
			)
		)
	)
	(zone
		(layer "In9.Cu")
		(hatch none 0.5)
		(connect_pads
			(clearance 0)
		)
		(min_thickness 0.25)
		(keepout
			(tracks not_allowed)
			(vias allowed)
			(pads allowed)
			(copperpour not_allowed)
			(footprints allowed)
		)
		(placement
			(enabled no)
			(sheetname "")
		)
		(fill
			(thermal_gap 0.5)
			(thermal_bridge_width 0.5)
			(island_removal_mode 0)
		)
		(polygon
			(pts
				(arc
					(start 283.563314 -150.872698)
					(mid 282.622752 -151.186388)
					(end 282.936442 -152.12695)
				)
				(xy 283.224986 -152.271222)
				(arc
					(start 283.58592 -152.271222)
					(mid 283.769427 -152.236055)
					(end 283.926788 -152.135332)
				)
				(arc
					(start 283.982922 -152.02281)
					(mid 283.986109 -151.979195)
					(end 283.957522 -151.946102)
				)
				(arc
					(start 283.695648 -151.815038)
					(mid 282.761556 -151.255086)
					(end 283.769562 -151.667464)
				)
				(xy 284.031182 -151.798274) (xy 284.031436 -151.798274) (xy 284.061916 -151.813768)
				(arc
					(start 284.063186 -151.817832)
					(mid 284.142706 -151.926808)
					(end 284.144466 -152.061672)
				)
				(xy 284.14599 -152.06599) (xy 284.052772 -152.252172)
				(arc
					(start 284.038294 -152.256998)
					(mid 283.845435 -152.383124)
					(end 283.620972 -152.435306)
				)
				(xy 283.62021 -152.436322) (xy 283.555186 -152.436322)
				(arc
					(start 283.767022 -152.54224)
					(mid 283.985259 -152.454542)
					(end 284.167834 -152.306274)
				)
				(xy 284.259782 -152.122632)
				(arc
					(start 284.263846 -152.121362)
					(mid 284.372822 -152.041842)
					(end 284.507686 -152.040082)
				)
				(xy 284.512004 -152.038558)
				(arc
					(start 284.80385 -152.184608)
					(mid 285.738843 -152.743539)
					(end 284.73019 -152.332182)
				)
				(arc
					(start 284.468824 -152.201626)
					(mid 284.425209 -152.198439)
					(end 284.392116 -152.227026)
				)
				(xy 284.295088 -152.420828)
				(arc
					(start 284.28315 -152.424638)
					(mid 284.139736 -152.550721)
					(end 283.974032 -152.645618)
				)
				(arc
					(start 284.928056 -153.12263)
					(mid 285.874832 -152.817445)
					(end 285.56331 -151.872696)
				)
			)
		)
	)
	(zone
		(layer "In9.Cu")
		(hatch none 0.5)
		(connect_pads
			(clearance 0)
		)
		(min_thickness 0.25)
		(keepout
			(tracks not_allowed)
			(vias allowed)
			(pads allowed)
			(copperpour not_allowed)
			(footprints allowed)
		)
		(placement
			(enabled no)
			(sheetname "")
		)
		(fill
			(thermal_gap 0.5)
			(thermal_bridge_width 0.5)
			(island_removal_mode 0)
		)
		(polygon
			(pts
				(arc
					(start 379.098556 -18.350484)
					(mid 378.550043 -17.80159)
					(end 378.001276 -18.35023)
				)
				(arc
					(start 378.001276 -19.750024)
					(mid 378.549916 -20.298664)
					(end 379.098556 -19.750024)
				)
				(xy 379.098556 -19.278854)
				(arc
					(start 378.69241 -19.278854)
					(mid 378.675497 -19.282218)
					(end 378.661168 -19.291808)
				)
				(arc
					(start 378.64542 -19.307556)
					(mid 378.635842 -19.32189)
					(end 378.632466 -19.338798)
				)
				(arc
					(start 378.632466 -19.36496)
					(mid 378.549916 -20.143837)
					(end 378.467366 -19.36496)
				)
				(xy 378.467366 -19.304508)
				(arc
					(start 378.470668 -19.301206)
					(mid 378.483203 -19.258632)
					(end 378.50445 -19.219672)
				)
				(xy 378.50445 -19.214846) (xy 378.568458 -19.150838)
				(arc
					(start 378.573284 -19.150838)
					(mid 378.612258 -19.129626)
					(end 378.654818 -19.117056)
				)
				(xy 378.65812 -19.113754) (xy 379.098556 -19.113754) (xy 379.098556 -18.986754) (xy 378.726954 -18.986754)
				(xy 378.658374 -18.986754)
				(arc
					(start 378.654818 -18.983198)
					(mid 378.612244 -18.970663)
					(end 378.573284 -18.949416)
				)
				(xy 378.568458 -18.949416) (xy 378.50445 -18.885408)
				(arc
					(start 378.50445 -18.880582)
					(mid 378.483238 -18.841608)
					(end 378.470668 -18.799048)
				)
				(xy 378.467366 -18.795746)
				(arc
					(start 378.467366 -18.735294)
					(mid 378.549916 -17.956417)
					(end 378.632466 -18.735294)
				)
				(arc
					(start 378.632466 -18.761456)
					(mid 378.63583 -18.778369)
					(end 378.64542 -18.792698)
				)
				(arc
					(start 378.661168 -18.808446)
					(mid 378.675502 -18.818024)
					(end 378.69241 -18.8214)
				)
				(xy 378.7267 -18.8214) (xy 378.726954 -18.821654) (xy 379.098556 -18.821654)
			)
		)
	)
	(zone
		(layer "In9.Cu")
		(hatch none 0.5)
		(connect_pads
			(clearance 0)
		)
		(min_thickness 0.25)
		(keepout
			(tracks not_allowed)
			(vias allowed)
			(pads allowed)
			(copperpour not_allowed)
			(footprints allowed)
		)
		(placement
			(enabled no)
			(sheetname "")
		)
		(fill
			(thermal_gap 0.5)
			(thermal_bridge_width 0.5)
			(island_removal_mode 0)
		)
		(polygon
			(pts
				(arc
					(start 210.548728 -410.600398)
					(mid 210.000215 -410.051504)
					(end 209.451448 -410.600144)
				)
				(xy 209.451448 -411.071568)
				(arc
					(start 209.821018 -411.071568)
					(mid 209.837931 -411.068204)
					(end 209.85226 -411.058614)
				)
				(arc
					(start 209.904584 -411.00629)
					(mid 209.912054 -410.996461)
					(end 209.916522 -410.984954)
				)
				(arc
					(start 209.916522 -410.984954)
					(mid 210.000611 -410.206365)
					(end 210.082638 -410.985208)
				)
				(xy 210.082638 -411.009338)
				(arc
					(start 210.079336 -411.01264)
					(mid 210.066801 -411.055214)
					(end 210.045554 -411.094174)
				)
				(xy 210.045554 -411.099) (xy 209.94497 -411.199584)
				(arc
					(start 209.940144 -411.199584)
					(mid 209.90117 -411.220796)
					(end 209.85861 -411.233366)
				)
				(xy 209.855308 -411.236668) (xy 209.451448 -411.236668) (xy 209.451448 -411.363668) (xy 209.8548 -411.363668)
				(arc
					(start 209.858102 -411.36697)
					(mid 209.900676 -411.379505)
					(end 209.939636 -411.400752)
				)
				(xy 209.944462 -411.400752) (xy 210.021424 -411.477714) (xy 210.045554 -411.501844)
				(arc
					(start 210.045554 -411.50667)
					(mid 210.066766 -411.545644)
					(end 210.079336 -411.588204)
				)
				(xy 210.082638 -411.591506)
				(arc
					(start 210.082638 -411.615128)
					(mid 210.000735 -412.394005)
					(end 209.916268 -411.615382)
				)
				(arc
					(start 209.916268 -411.615382)
					(mid 209.911875 -411.604151)
					(end 209.904584 -411.594554)
				)
				(arc
					(start 209.851752 -411.541722)
					(mid 209.837418 -411.532144)
					(end 209.82051 -411.528768)
				)
				(xy 209.451448 -411.528768)
				(arc
					(start 209.451448 -412.000192)
					(mid 210.000088 -412.548832)
					(end 210.548728 -412.000192)
				)
			)
		)
	)
	(zone
		(layer "In9.Cu")
		(hatch none 0.5)
		(connect_pads
			(clearance 0)
		)
		(min_thickness 0.25)
		(keepout
			(tracks not_allowed)
			(vias allowed)
			(pads allowed)
			(copperpour not_allowed)
			(footprints allowed)
		)
		(placement
			(enabled no)
			(sheetname "")
		)
		(fill
			(thermal_gap 0.5)
			(thermal_bridge_width 0.5)
			(island_removal_mode 0)
		)
		(polygon
			(pts
				(arc
					(start 240.871756 -178.87696)
					(mid 239.92498 -179.182145)
					(end 240.236502 -180.126894)
				)
				(xy 240.525046 -180.271166)
				(arc
					(start 240.88598 -180.271166)
					(mid 241.069487 -180.235999)
					(end 241.226848 -180.135276)
				)
				(arc
					(start 241.282982 -180.022754)
					(mid 241.286169 -179.979139)
					(end 241.257582 -179.946046)
				)
				(arc
					(start 240.995708 -179.814982)
					(mid 240.061616 -179.25503)
					(end 241.069622 -179.667408)
				)
				(xy 241.331242 -179.798218) (xy 241.331496 -179.798218) (xy 241.361976 -179.813712)
				(arc
					(start 241.363246 -179.817776)
					(mid 241.442766 -179.926752)
					(end 241.444526 -180.061616)
				)
				(xy 241.44605 -180.065934) (xy 241.352832 -180.252116)
				(arc
					(start 241.338354 -180.256942)
					(mid 241.145495 -180.383068)
					(end 240.921032 -180.43525)
				)
				(xy 240.92027 -180.436266) (xy 240.855246 -180.436266)
				(arc
					(start 241.067082 -180.542184)
					(mid 241.285319 -180.454486)
					(end 241.467894 -180.306218)
				)
				(xy 241.559842 -180.122576)
				(arc
					(start 241.563906 -180.121306)
					(mid 241.672882 -180.041786)
					(end 241.807746 -180.040026)
				)
				(xy 241.812064 -180.038502)
				(arc
					(start 242.10391 -180.184552)
					(mid 243.038903 -180.743483)
					(end 242.03025 -180.332126)
				)
				(arc
					(start 241.768884 -180.20157)
					(mid 241.725269 -180.198383)
					(end 241.692176 -180.22697)
				)
				(xy 241.595148 -180.420772)
				(arc
					(start 241.58321 -180.424582)
					(mid 241.43979 -180.550758)
					(end 241.274092 -180.645816)
				)
				(arc
					(start 242.236498 -181.126892)
					(mid 243.17706 -180.813202)
					(end 242.86337 -179.87264)
				)
			)
		)
	)
	(zone
		(layer "In9.Cu")
		(hatch none 0.5)
		(connect_pads
			(clearance 0)
		)
		(min_thickness 0.25)
		(keepout
			(tracks not_allowed)
			(vias allowed)
			(pads allowed)
			(copperpour not_allowed)
			(footprints allowed)
		)
		(placement
			(enabled no)
			(sheetname "")
		)
		(fill
			(thermal_gap 0.5)
			(thermal_bridge_width 0.5)
			(island_removal_mode 0)
		)
		(polygon
			(pts
				(xy 213.086188 -415.127694) (xy 213.05139 -415.1249)
				(arc
					(start 213.05139 -415.600134)
					(mid 213.60003 -416.148774)
					(end 214.14867 -415.600134)
				)
				(arc
					(start 214.14867 -414.20034)
					(mid 213.600157 -413.651446)
					(end 213.05139 -414.200086)
				)
				(arc
					(start 213.05139 -414.658302)
					(mid 213.0857 -414.668162)
					(end 213.12124 -414.67151)
				)
				(arc
					(start 213.388194 -414.67151)
					(mid 213.463561 -414.64727)
					(end 213.510622 -414.583626)
				)
				(arc
					(start 213.510622 -414.583626)
					(mid 213.604205 -413.806406)
					(end 213.679278 -414.585658)
				)
				(arc
					(start 213.679278 -414.585658)
					(mid 213.593835 -414.752766)
					(end 213.42477 -414.834324)
				)
				(xy 213.422484 -414.83661) (xy 213.08695 -414.83661) (xy 213.085172 -414.834832) (xy 213.05139 -414.829752)
				(arc
					(start 213.05139 -414.95853)
					(mid 213.086223 -414.962342)
					(end 213.12124 -414.96361)
				)
				(xy 213.422484 -414.96361)
				(arc
					(start 213.42477 -414.965896)
					(mid 213.593887 -415.0474)
					(end 213.679278 -415.214562)
				)
				(arc
					(start 213.679278 -415.214562)
					(mid 213.604206 -415.993841)
					(end 213.510622 -415.216594)
				)
				(arc
					(start 213.510622 -415.216594)
					(mid 213.463533 -415.152988)
					(end 213.388194 -415.12871)
				)
				(xy 213.08695 -415.12871)
			)
		)
	)
	(zone
		(layer "In9.Cu")
		(hatch none 0.5)
		(connect_pads
			(clearance 0)
		)
		(min_thickness 0.25)
		(keepout
			(tracks not_allowed)
			(vias allowed)
			(pads allowed)
			(copperpour not_allowed)
			(footprints allowed)
		)
		(placement
			(enabled no)
			(sheetname "")
		)
		(fill
			(thermal_gap 0.5)
			(thermal_bridge_width 0.5)
			(island_removal_mode 0)
		)
		(polygon
			(pts
				(arc
					(start 283.563314 -170.872658)
					(mid 282.622752 -171.186348)
					(end 282.936442 -172.12691)
				)
				(xy 283.224986 -172.271182)
				(arc
					(start 283.58592 -172.271182)
					(mid 283.769427 -172.236015)
					(end 283.926788 -172.135292)
				)
				(arc
					(start 283.982922 -172.02277)
					(mid 283.986109 -171.979155)
					(end 283.957522 -171.946062)
				)
				(arc
					(start 283.695648 -171.814998)
					(mid 282.761556 -171.255046)
					(end 283.769562 -171.667424)
				)
				(xy 284.031182 -171.798234) (xy 284.031436 -171.798234) (xy 284.061916 -171.813728)
				(arc
					(start 284.063186 -171.817792)
					(mid 284.142706 -171.926768)
					(end 284.144466 -172.061632)
				)
				(xy 284.14599 -172.06595) (xy 284.052772 -172.252132)
				(arc
					(start 284.038294 -172.256958)
					(mid 283.845435 -172.383084)
					(end 283.620972 -172.435266)
				)
				(xy 283.62021 -172.436282) (xy 283.555186 -172.436282)
				(arc
					(start 283.767022 -172.5422)
					(mid 283.985259 -172.454502)
					(end 284.167834 -172.306234)
				)
				(xy 284.259782 -172.122592)
				(arc
					(start 284.263846 -172.121322)
					(mid 284.372822 -172.041802)
					(end 284.507686 -172.040042)
				)
				(xy 284.512004 -172.038518)
				(arc
					(start 284.80385 -172.184568)
					(mid 285.738843 -172.743499)
					(end 284.73019 -172.332142)
				)
				(arc
					(start 284.468824 -172.201586)
					(mid 284.425209 -172.198399)
					(end 284.392116 -172.226986)
				)
				(xy 284.295088 -172.420788)
				(arc
					(start 284.28315 -172.424598)
					(mid 284.139736 -172.550681)
					(end 283.974032 -172.645578)
				)
				(arc
					(start 284.928056 -173.12259)
					(mid 285.874832 -172.817405)
					(end 285.56331 -171.872656)
				)
			)
		)
	)
	(zone
		(layer "In9.Cu")
		(hatch none 0.5)
		(connect_pads
			(clearance 0)
		)
		(min_thickness 0.25)
		(keepout
			(tracks not_allowed)
			(vias allowed)
			(pads allowed)
			(copperpour not_allowed)
			(footprints allowed)
		)
		(placement
			(enabled no)
			(sheetname "")
		)
		(fill
			(thermal_gap 0.5)
			(thermal_bridge_width 0.5)
			(island_removal_mode 0)
		)
		(polygon
			(pts
				(arc
					(start 240.871756 -54.577234)
					(mid 239.92498 -54.882419)
					(end 240.236502 -55.827168)
				)
				(xy 240.525046 -55.97144)
				(arc
					(start 240.88598 -55.97144)
					(mid 241.069487 -55.936273)
					(end 241.226848 -55.83555)
				)
				(arc
					(start 241.282982 -55.723028)
					(mid 241.286169 -55.679413)
					(end 241.257582 -55.64632)
				)
				(arc
					(start 240.995708 -55.515256)
					(mid 240.061616 -54.955304)
					(end 241.069622 -55.367682)
				)
				(xy 241.331242 -55.498492) (xy 241.331496 -55.498492) (xy 241.361976 -55.513986)
				(arc
					(start 241.363246 -55.51805)
					(mid 241.442766 -55.627026)
					(end 241.444526 -55.76189)
				)
				(xy 241.44605 -55.766208) (xy 241.352832 -55.95239)
				(arc
					(start 241.338354 -55.957216)
					(mid 241.145495 -56.083342)
					(end 240.921032 -56.135524)
				)
				(xy 240.92027 -56.13654) (xy 240.855246 -56.13654)
				(arc
					(start 241.067082 -56.242458)
					(mid 241.285319 -56.15476)
					(end 241.467894 -56.006492)
				)
				(xy 241.559842 -55.82285)
				(arc
					(start 241.563906 -55.82158)
					(mid 241.672882 -55.74206)
					(end 241.807746 -55.7403)
				)
				(xy 241.812064 -55.738776)
				(arc
					(start 242.10391 -55.884826)
					(mid 243.038903 -56.443757)
					(end 242.03025 -56.0324)
				)
				(arc
					(start 241.768884 -55.901844)
					(mid 241.725269 -55.898657)
					(end 241.692176 -55.927244)
				)
				(xy 241.595148 -56.121046)
				(arc
					(start 241.58321 -56.124856)
					(mid 241.43979 -56.251032)
					(end 241.274092 -56.34609)
				)
				(arc
					(start 242.236498 -56.827166)
					(mid 243.17706 -56.513476)
					(end 242.86337 -55.572914)
				)
			)
		)
	)
	(zone
		(layer "In9.Cu")
		(hatch none 0.5)
		(connect_pads
			(clearance 0)
		)
		(min_thickness 0.25)
		(keepout
			(tracks not_allowed)
			(vias allowed)
			(pads allowed)
			(copperpour not_allowed)
			(footprints allowed)
		)
		(placement
			(enabled no)
			(sheetname "")
		)
		(fill
			(thermal_gap 0.5)
			(thermal_bridge_width 0.5)
			(island_removal_mode 0)
		)
		(polygon
			(pts
				(arc
					(start 278.23668 -319.356486)
					(mid 277.68804 -319.905126)
					(end 278.23668 -320.453766)
				)
				(xy 278.705056 -320.453766) (xy 278.705056 -320.04635)
				(arc
					(start 278.704802 -320.042286)
					(mid 278.700254 -320.019332)
					(end 278.687276 -319.999868)
				)
				(xy 278.684482 -319.99682) (xy 278.67991 -319.992248)
				(arc
					(start 278.676862 -319.989454)
					(mid 278.657386 -319.976504)
					(end 278.634444 -319.971928)
				)
				(xy 278.63038 -319.971928)
				(arc
					(start 278.624792 -319.971928)
					(mid 277.842861 -319.905126)
					(end 278.624792 -319.838324)
				)
				(xy 278.63038 -319.838324) (xy 278.634444 -319.838324) (xy 278.641556 -319.838324) (xy 278.66213 -319.838324)
				(arc
					(start 278.664162 -319.84061)
					(mid 278.708431 -319.853077)
					(end 278.74849 -319.875662)
				)
				(xy 278.751792 -319.875662) (xy 278.76627 -319.89014) (xy 278.77135 -319.894966) (xy 278.774144 -319.898014)
				(xy 278.778716 -319.902586) (xy 278.781764 -319.90538) (xy 278.78659 -319.91046) (xy 278.801068 -319.924938)
				(arc
					(start 278.801068 -319.92824)
					(mid 278.823621 -319.968312)
					(end 278.83612 -320.012568)
				)
				(xy 278.838152 -320.0146) (xy 278.838152 -320.035174) (xy 278.838406 -320.042286) (xy 278.838152 -320.04635)
				(xy 278.838152 -320.453766) (xy 279.035256 -320.453766) (xy 279.035256 -320.04635) (xy 279.035002 -320.042286)
				(xy 279.035256 -320.035174) (xy 279.035256 -320.0146)
				(arc
					(start 279.037288 -320.012568)
					(mid 279.049755 -319.968299)
					(end 279.07234 -319.92824)
				)
				(xy 279.07234 -319.924938) (xy 279.086818 -319.91046) (xy 279.091644 -319.90538) (xy 279.094692 -319.902586)
				(xy 279.099264 -319.898014) (xy 279.102058 -319.894966) (xy 279.107138 -319.89014) (xy 279.121616 -319.875662)
				(arc
					(start 279.124918 -319.875662)
					(mid 279.16499 -319.853109)
					(end 279.209246 -319.84061)
				)
				(xy 279.211278 -319.838324) (xy 279.231852 -319.838324) (xy 279.238964 -319.838324) (xy 279.243028 -319.838324)
				(arc
					(start 279.248616 -319.838324)
					(mid 280.030547 -319.905126)
					(end 279.248616 -319.971928)
				)
				(xy 279.243028 -319.971928)
				(arc
					(start 279.238964 -319.971928)
					(mid 279.21601 -319.976476)
					(end 279.196546 -319.989454)
				)
				(xy 279.193498 -319.992248) (xy 279.188926 -319.99682)
				(arc
					(start 279.186132 -319.999868)
					(mid 279.173182 -320.019344)
					(end 279.168606 -320.042286)
				)
				(xy 279.168352 -320.04635) (xy 279.168352 -320.453766)
				(arc
					(start 279.636728 -320.453766)
					(mid 280.185368 -319.905126)
					(end 279.636728 -319.356486)
				)
				(xy 278.236934 -319.356486)
			)
		)
	)
	(zone
		(layer "In9.Cu")
		(hatch none 0.5)
		(connect_pads
			(clearance 0)
		)
		(min_thickness 0.25)
		(keepout
			(tracks not_allowed)
			(vias allowed)
			(pads allowed)
			(copperpour not_allowed)
			(footprints allowed)
		)
		(placement
			(enabled no)
			(sheetname "")
		)
		(fill
			(thermal_gap 0.5)
			(thermal_bridge_width 0.5)
			(island_removal_mode 0)
		)
		(polygon
			(pts
				(arc
					(start 166.452042 -207.800194)
					(mid 159.325056 -200.673208)
					(end 152.19807 -207.800194)
				)
				(arc
					(start 152.19807 -213.800436)
					(mid 159.325056 -220.927168)
					(end 166.452042 -213.800436)
				)
			)
		)
	)
	(zone
		(layer "In9.Cu")
		(hatch none 0.5)
		(connect_pads
			(clearance 0)
		)
		(min_thickness 0.25)
		(keepout
			(tracks not_allowed)
			(vias allowed)
			(pads allowed)
			(copperpour not_allowed)
			(footprints allowed)
		)
		(placement
			(enabled no)
			(sheetname "")
		)
		(fill
			(thermal_gap 0.5)
			(thermal_bridge_width 0.5)
			(island_removal_mode 0)
		)
		(polygon
			(pts
				(arc
					(start 463.801968 -207.800194)
					(mid 456.674982 -200.673208)
					(end 449.547996 -207.800194)
				)
				(arc
					(start 449.547996 -213.800436)
					(mid 456.674982 -220.927168)
					(end 463.801968 -213.800436)
				)
			)
		)
	)
	(zone
		(layer "In9.Cu")
		(hatch none 0.5)
		(connect_pads
			(clearance 0)
		)
		(min_thickness 0.25)
		(keepout
			(tracks not_allowed)
			(vias allowed)
			(pads allowed)
			(copperpour not_allowed)
			(footprints allowed)
		)
		(placement
			(enabled no)
			(sheetname "")
		)
		(fill
			(thermal_gap 0.5)
			(thermal_bridge_width 0.5)
			(island_removal_mode 0)
		)
		(polygon
			(pts
				(arc
					(start 283.563314 -50.572924)
					(mid 282.622752 -50.886614)
					(end 282.936442 -51.827176)
				)
				(xy 283.224986 -51.971448)
				(arc
					(start 283.58592 -51.971448)
					(mid 283.769427 -51.936281)
					(end 283.926788 -51.835558)
				)
				(arc
					(start 283.982922 -51.723036)
					(mid 283.986109 -51.679421)
					(end 283.957522 -51.646328)
				)
				(arc
					(start 283.695648 -51.515264)
					(mid 282.761556 -50.955312)
					(end 283.769562 -51.36769)
				)
				(xy 284.031182 -51.4985) (xy 284.031436 -51.4985) (xy 284.061916 -51.513994)
				(arc
					(start 284.063186 -51.518058)
					(mid 284.142706 -51.627034)
					(end 284.144466 -51.761898)
				)
				(xy 284.14599 -51.766216) (xy 284.052772 -51.952398)
				(arc
					(start 284.038294 -51.957224)
					(mid 283.845435 -52.08335)
					(end 283.620972 -52.135532)
				)
				(xy 283.62021 -52.136548) (xy 283.555186 -52.136548)
				(arc
					(start 283.767022 -52.242466)
					(mid 283.985259 -52.154768)
					(end 284.167834 -52.0065)
				)
				(xy 284.259782 -51.822858)
				(arc
					(start 284.263846 -51.821588)
					(mid 284.372822 -51.742068)
					(end 284.507686 -51.740308)
				)
				(xy 284.512004 -51.738784)
				(arc
					(start 284.80385 -51.884834)
					(mid 285.738843 -52.443765)
					(end 284.73019 -52.032408)
				)
				(arc
					(start 284.468824 -51.901852)
					(mid 284.425209 -51.898665)
					(end 284.392116 -51.927252)
				)
				(xy 284.295088 -52.121054)
				(arc
					(start 284.28315 -52.124864)
					(mid 284.139736 -52.250947)
					(end 283.974032 -52.345844)
				)
				(arc
					(start 284.928056 -52.822856)
					(mid 285.874832 -52.517671)
					(end 285.56331 -51.572922)
				)
			)
		)
	)
	(zone
		(layer "In9.Cu")
		(hatch none 0.5)
		(connect_pads
			(clearance 0)
		)
		(min_thickness 0.25)
		(keepout
			(tracks not_allowed)
			(vias allowed)
			(pads allowed)
			(copperpour not_allowed)
			(footprints allowed)
		)
		(placement
			(enabled no)
			(sheetname "")
		)
		(fill
			(thermal_gap 0.5)
			(thermal_bridge_width 0.5)
			(island_removal_mode 0)
		)
		(polygon
			(pts
				(arc
					(start 283.563314 -174.87265)
					(mid 282.622752 -175.18634)
					(end 282.936442 -176.126902)
				)
				(xy 283.224986 -176.271174)
				(arc
					(start 283.58592 -176.271174)
					(mid 283.769427 -176.236007)
					(end 283.926788 -176.135284)
				)
				(arc
					(start 283.982922 -176.022762)
					(mid 283.986109 -175.979147)
					(end 283.957522 -175.946054)
				)
				(arc
					(start 283.695648 -175.81499)
					(mid 282.761556 -175.255038)
					(end 283.769562 -175.667416)
				)
				(xy 284.031182 -175.798226) (xy 284.031436 -175.798226) (xy 284.061916 -175.81372)
				(arc
					(start 284.063186 -175.817784)
					(mid 284.142706 -175.92676)
					(end 284.144466 -176.061624)
				)
				(xy 284.14599 -176.065942) (xy 284.052772 -176.252124)
				(arc
					(start 284.038294 -176.25695)
					(mid 283.845435 -176.383076)
					(end 283.620972 -176.435258)
				)
				(xy 283.62021 -176.436274) (xy 283.555186 -176.436274)
				(arc
					(start 283.767022 -176.542192)
					(mid 283.985259 -176.454494)
					(end 284.167834 -176.306226)
				)
				(xy 284.259782 -176.122584)
				(arc
					(start 284.263846 -176.121314)
					(mid 284.372822 -176.041794)
					(end 284.507686 -176.040034)
				)
				(xy 284.512004 -176.03851)
				(arc
					(start 284.80385 -176.18456)
					(mid 285.738843 -176.743491)
					(end 284.73019 -176.332134)
				)
				(arc
					(start 284.468824 -176.201578)
					(mid 284.425209 -176.198391)
					(end 284.392116 -176.226978)
				)
				(xy 284.295088 -176.42078)
				(arc
					(start 284.28315 -176.42459)
					(mid 284.139736 -176.550673)
					(end 283.974032 -176.64557)
				)
				(arc
					(start 284.928056 -177.122582)
					(mid 285.874832 -176.817397)
					(end 285.56331 -175.872648)
				)
			)
		)
	)
	(zone
		(layer "In9.Cu")
		(hatch none 0.5)
		(connect_pads
			(clearance 0)
		)
		(min_thickness 0.25)
		(keepout
			(tracks not_allowed)
			(vias allowed)
			(pads allowed)
			(copperpour not_allowed)
			(footprints allowed)
		)
		(placement
			(enabled no)
			(sheetname "")
		)
		(fill
			(thermal_gap 0.5)
			(thermal_bridge_width 0.5)
			(island_removal_mode 0)
		)
		(polygon
			(pts
				(arc
					(start 278.23668 -340.956392)
					(mid 277.68804 -341.505032)
					(end 278.23668 -342.053672)
				)
				(xy 278.705056 -342.053672) (xy 278.705056 -341.646256)
				(arc
					(start 278.704802 -341.642192)
					(mid 278.700254 -341.619238)
					(end 278.687276 -341.599774)
				)
				(xy 278.684482 -341.596726) (xy 278.67991 -341.592154)
				(arc
					(start 278.676862 -341.58936)
					(mid 278.657386 -341.57641)
					(end 278.634444 -341.571834)
				)
				(xy 278.63038 -341.57158)
				(arc
					(start 278.624792 -341.57158)
					(mid 277.842904 -341.505032)
					(end 278.624792 -341.438484)
				)
				(xy 278.63038 -341.438484) (xy 278.634444 -341.43823) (xy 278.641556 -341.438484) (xy 278.66213 -341.438484)
				(arc
					(start 278.664162 -341.440516)
					(mid 278.708431 -341.452983)
					(end 278.74849 -341.475568)
				)
				(xy 278.751792 -341.475568) (xy 278.76627 -341.490046) (xy 278.77135 -341.494872) (xy 278.774144 -341.49792)
				(xy 278.778716 -341.502492) (xy 278.781764 -341.505286) (xy 278.78659 -341.510366) (xy 278.801068 -341.524844)
				(arc
					(start 278.801068 -341.528146)
					(mid 278.823621 -341.568218)
					(end 278.83612 -341.612474)
				)
				(xy 278.838152 -341.614506) (xy 278.838152 -341.63508) (xy 278.838406 -341.642192) (xy 278.838152 -341.646256)
				(xy 278.838152 -342.053672) (xy 279.035256 -342.053672) (xy 279.035256 -341.646256) (xy 279.035002 -341.642192)
				(xy 279.035256 -341.63508) (xy 279.035256 -341.614506)
				(arc
					(start 279.037288 -341.612474)
					(mid 279.049755 -341.568205)
					(end 279.07234 -341.528146)
				)
				(xy 279.07234 -341.524844) (xy 279.086818 -341.510366) (xy 279.091644 -341.505286) (xy 279.094692 -341.502492)
				(xy 279.099264 -341.49792) (xy 279.102058 -341.494872) (xy 279.107138 -341.490046) (xy 279.121616 -341.475568)
				(arc
					(start 279.124918 -341.475568)
					(mid 279.16499 -341.453015)
					(end 279.209246 -341.440516)
				)
				(xy 279.211278 -341.438484) (xy 279.231852 -341.438484) (xy 279.238964 -341.43823) (xy 279.243028 -341.438484)
				(arc
					(start 279.248616 -341.438484)
					(mid 280.030504 -341.505032)
					(end 279.248616 -341.57158)
				)
				(xy 279.243028 -341.57158)
				(arc
					(start 279.238964 -341.571834)
					(mid 279.21601 -341.576382)
					(end 279.196546 -341.58936)
				)
				(xy 279.193498 -341.592154) (xy 279.188926 -341.596726)
				(arc
					(start 279.186132 -341.599774)
					(mid 279.173182 -341.61925)
					(end 279.168606 -341.642192)
				)
				(xy 279.168352 -341.646256) (xy 279.168352 -342.053672)
				(arc
					(start 279.636728 -342.053672)
					(mid 280.185368 -341.505032)
					(end 279.636728 -340.956392)
				)
				(xy 278.236934 -340.956392)
			)
		)
	)
	(zone
		(layer "In9.Cu")
		(hatch none 0.5)
		(connect_pads
			(clearance 0)
		)
		(min_thickness 0.25)
		(keepout
			(tracks not_allowed)
			(vias allowed)
			(pads allowed)
			(copperpour not_allowed)
			(footprints allowed)
		)
		(placement
			(enabled no)
			(sheetname "")
		)
		(fill
			(thermal_gap 0.5)
			(thermal_bridge_width 0.5)
			(island_removal_mode 0)
		)
		(polygon
			(pts
				(arc
					(start 307.327046 -243.200174)
					(mid 300.20006 -236.073188)
					(end 293.073074 -243.200174)
				)
				(arc
					(start 293.073074 -249.200416)
					(mid 300.20006 -256.327148)
					(end 307.327046 -249.200416)
				)
			)
		)
	)
	(zone
		(layer "In9.Cu")
		(hatch none 0.5)
		(connect_pads
			(clearance 0)
		)
		(min_thickness 0.25)
		(keepout
			(tracks not_allowed)
			(vias allowed)
			(pads allowed)
			(copperpour not_allowed)
			(footprints allowed)
		)
		(placement
			(enabled no)
			(sheetname "")
		)
		(fill
			(thermal_gap 0.5)
			(thermal_bridge_width 0.5)
			(island_removal_mode 0)
		)
		(polygon
			(pts
				(arc
					(start 388.098538 -17.350232)
					(mid 387.550025 -16.801338)
					(end 387.001258 -17.349978)
				)
				(arc
					(start 387.001258 -18.750026)
					(mid 387.549898 -19.298666)
					(end 388.098538 -18.750026)
				)
				(xy 388.098538 -18.278856)
				(arc
					(start 387.692392 -18.278856)
					(mid 387.675479 -18.28222)
					(end 387.66115 -18.29181)
				)
				(arc
					(start 387.645402 -18.307558)
					(mid 387.635824 -18.321892)
					(end 387.632448 -18.3388)
				)
				(arc
					(start 387.632448 -18.364962)
					(mid 387.549898 -19.143839)
					(end 387.467348 -18.364962)
				)
				(xy 387.467348 -18.30451)
				(arc
					(start 387.47065 -18.301208)
					(mid 387.483185 -18.258634)
					(end 387.504432 -18.219674)
				)
				(xy 387.504432 -18.214848) (xy 387.56844 -18.15084)
				(arc
					(start 387.573266 -18.15084)
					(mid 387.61224 -18.129628)
					(end 387.6548 -18.117058)
				)
				(xy 387.658102 -18.113756) (xy 388.098538 -18.113756) (xy 388.098538 -17.986756) (xy 387.726936 -17.986756)
				(xy 387.658356 -17.986756)
				(arc
					(start 387.6548 -17.9832)
					(mid 387.612226 -17.970665)
					(end 387.573266 -17.949418)
				)
				(xy 387.56844 -17.949418) (xy 387.504432 -17.88541)
				(arc
					(start 387.504432 -17.880584)
					(mid 387.48322 -17.84161)
					(end 387.47065 -17.79905)
				)
				(xy 387.467348 -17.795748)
				(arc
					(start 387.467348 -17.735042)
					(mid 387.549898 -16.956165)
					(end 387.632448 -17.735042)
				)
				(arc
					(start 387.632448 -17.761458)
					(mid 387.635812 -17.778371)
					(end 387.645402 -17.7927)
				)
				(arc
					(start 387.66115 -17.808448)
					(mid 387.675484 -17.818026)
					(end 387.692392 -17.821402)
				)
				(xy 387.726682 -17.821402) (xy 387.726936 -17.821656) (xy 388.098538 -17.821656)
			)
		)
	)
	(zone
		(layer "In9.Cu")
		(hatch none 0.5)
		(connect_pads
			(clearance 0)
		)
		(min_thickness 0.25)
		(keepout
			(tracks not_allowed)
			(vias allowed)
			(pads allowed)
			(copperpour not_allowed)
			(footprints allowed)
		)
		(placement
			(enabled no)
			(sheetname "")
		)
		(fill
			(thermal_gap 0.5)
			(thermal_bridge_width 0.5)
			(island_removal_mode 0)
		)
		(polygon
			(pts
				(arc
					(start 138.49858 -17.350232)
					(mid 137.950067 -16.801338)
					(end 137.4013 -17.349978)
				)
				(arc
					(start 137.4013 -18.750026)
					(mid 137.94994 -19.298666)
					(end 138.49858 -18.750026)
				)
				(xy 138.49858 -18.278856)
				(arc
					(start 138.092434 -18.278856)
					(mid 138.075521 -18.28222)
					(end 138.061192 -18.29181)
				)
				(arc
					(start 138.045444 -18.307558)
					(mid 138.035866 -18.321892)
					(end 138.03249 -18.3388)
				)
				(arc
					(start 138.03249 -18.364962)
					(mid 137.94994 -19.143839)
					(end 137.86739 -18.364962)
				)
				(xy 137.86739 -18.30451)
				(arc
					(start 137.870692 -18.301208)
					(mid 137.883227 -18.258634)
					(end 137.904474 -18.219674)
				)
				(xy 137.904474 -18.214848) (xy 137.928604 -18.190718) (xy 137.944352 -18.17497) (xy 137.968482 -18.15084)
				(arc
					(start 137.973308 -18.15084)
					(mid 138.012282 -18.129628)
					(end 138.054842 -18.117058)
				)
				(xy 138.058144 -18.113756) (xy 138.49858 -18.113756) (xy 138.49858 -17.986756) (xy 138.126978 -17.986756)
				(xy 138.058398 -17.986756)
				(arc
					(start 138.054842 -17.9832)
					(mid 138.012268 -17.970665)
					(end 137.973308 -17.949418)
				)
				(xy 137.968482 -17.949418) (xy 137.944352 -17.925288) (xy 137.904474 -17.88541)
				(arc
					(start 137.904474 -17.880584)
					(mid 137.883262 -17.84161)
					(end 137.870692 -17.79905)
				)
				(xy 137.86739 -17.795748)
				(arc
					(start 137.86739 -17.735042)
					(mid 137.94994 -16.956165)
					(end 138.03249 -17.735042)
				)
				(arc
					(start 138.03249 -17.761458)
					(mid 138.035854 -17.778371)
					(end 138.045444 -17.7927)
				)
				(arc
					(start 138.061192 -17.808448)
					(mid 138.075526 -17.818026)
					(end 138.092434 -17.821402)
				)
				(xy 138.126724 -17.821402) (xy 138.126978 -17.821656) (xy 138.49858 -17.821656)
			)
		)
	)
	(zone
		(layer "In9.Cu")
		(hatch none 0.5)
		(connect_pads
			(clearance 0)
		)
		(min_thickness 0.25)
		(keepout
			(tracks not_allowed)
			(vias allowed)
			(pads allowed)
			(copperpour not_allowed)
			(footprints allowed)
		)
		(placement
			(enabled no)
			(sheetname "")
		)
		(fill
			(thermal_gap 0.5)
			(thermal_bridge_width 0.5)
			(island_removal_mode 0)
		)
		(polygon
			(pts
				(arc
					(start 143.89862 -18.350484)
					(mid 143.350107 -17.80159)
					(end 142.80134 -18.35023)
				)
				(arc
					(start 142.80134 -19.750024)
					(mid 143.34998 -20.298664)
					(end 143.89862 -19.750024)
				)
				(xy 143.89862 -19.2786)
				(arc
					(start 143.543782 -19.2786)
					(mid 143.474096 -19.303058)
					(end 143.43507 -19.365722)
				)
				(arc
					(start 143.43507 -19.365722)
					(mid 143.347654 -20.143739)
					(end 143.26743 -19.36496)
				)
				(xy 143.26743 -19.355562)
				(arc
					(start 143.26997 -19.353276)
					(mid 143.348448 -19.194518)
					(end 143.507206 -19.11604)
				)
				(xy 143.509492 -19.1135) (xy 143.89862 -19.1135) (xy 143.89862 -18.9865) (xy 143.509492 -18.9865)
				(arc
					(start 143.507206 -18.98396)
					(mid 143.348448 -18.905482)
					(end 143.26997 -18.746724)
				)
				(xy 143.26743 -18.744438)
				(arc
					(start 143.26743 -18.735294)
					(mid 143.348032 -17.956474)
					(end 143.435324 -18.734532)
				)
				(arc
					(start 143.435324 -18.734532)
					(mid 143.47433 -18.796948)
					(end 143.543782 -18.8214)
				)
				(xy 143.89862 -18.8214)
			)
		)
	)
	(zone
		(layer "In9.Cu")
		(hatch none 0.5)
		(connect_pads
			(clearance 0)
		)
		(min_thickness 0.25)
		(keepout
			(tracks not_allowed)
			(vias allowed)
			(pads allowed)
			(copperpour not_allowed)
			(footprints allowed)
		)
		(placement
			(enabled no)
			(sheetname "")
		)
		(fill
			(thermal_gap 0.5)
			(thermal_bridge_width 0.5)
			(island_removal_mode 0)
		)
		(polygon
			(pts
				(arc
					(start 240.871756 -66.57721)
					(mid 239.92498 -66.882395)
					(end 240.236502 -67.827144)
				)
				(xy 240.525046 -67.971416)
				(arc
					(start 240.88598 -67.971416)
					(mid 241.069487 -67.936249)
					(end 241.226848 -67.835526)
				)
				(arc
					(start 241.282982 -67.723004)
					(mid 241.286169 -67.679389)
					(end 241.257582 -67.646296)
				)
				(arc
					(start 240.995708 -67.515232)
					(mid 240.061616 -66.95528)
					(end 241.069622 -67.367658)
				)
				(xy 241.331242 -67.498468) (xy 241.331496 -67.498468) (xy 241.361976 -67.513962)
				(arc
					(start 241.363246 -67.518026)
					(mid 241.442766 -67.627002)
					(end 241.444526 -67.761866)
				)
				(xy 241.44605 -67.766184) (xy 241.352832 -67.952366)
				(arc
					(start 241.338354 -67.957192)
					(mid 241.145495 -68.083318)
					(end 240.921032 -68.1355)
				)
				(xy 240.92027 -68.136516) (xy 240.855246 -68.136516)
				(arc
					(start 241.067082 -68.242434)
					(mid 241.285319 -68.154736)
					(end 241.467894 -68.006468)
				)
				(xy 241.559842 -67.822826)
				(arc
					(start 241.563906 -67.821556)
					(mid 241.672882 -67.742036)
					(end 241.807746 -67.740276)
				)
				(xy 241.812064 -67.738752)
				(arc
					(start 242.10391 -67.884802)
					(mid 243.038903 -68.443733)
					(end 242.03025 -68.032376)
				)
				(arc
					(start 241.768884 -67.90182)
					(mid 241.725269 -67.898633)
					(end 241.692176 -67.92722)
				)
				(xy 241.595148 -68.121022)
				(arc
					(start 241.58321 -68.124832)
					(mid 241.43979 -68.251008)
					(end 241.274092 -68.346066)
				)
				(arc
					(start 242.236498 -68.827142)
					(mid 243.17706 -68.513452)
					(end 242.86337 -67.57289)
				)
			)
		)
	)
	(zone
		(layer "In9.Cu")
		(hatch none 0.5)
		(connect_pads
			(clearance 0)
		)
		(min_thickness 0.25)
		(keepout
			(tracks not_allowed)
			(vias allowed)
			(pads allowed)
			(copperpour not_allowed)
			(footprints allowed)
		)
		(placement
			(enabled no)
			(sheetname "")
		)
		(fill
			(thermal_gap 0.5)
			(thermal_bridge_width 0.5)
			(island_removal_mode 0)
		)
		(polygon
			(pts
				(arc
					(start 386.298694 -18.350484)
					(mid 385.750181 -17.80159)
					(end 385.201414 -18.35023)
				)
				(arc
					(start 385.201414 -19.750024)
					(mid 385.750054 -20.298664)
					(end 386.298694 -19.750024)
				)
				(xy 386.298694 -19.278854)
				(arc
					(start 385.892548 -19.278854)
					(mid 385.875635 -19.282218)
					(end 385.861306 -19.291808)
				)
				(arc
					(start 385.845558 -19.307556)
					(mid 385.83598 -19.32189)
					(end 385.832604 -19.338798)
				)
				(arc
					(start 385.832604 -19.36496)
					(mid 385.750054 -20.143837)
					(end 385.667504 -19.36496)
				)
				(xy 385.667504 -19.304508)
				(arc
					(start 385.670806 -19.301206)
					(mid 385.683341 -19.258632)
					(end 385.704588 -19.219672)
				)
				(xy 385.704588 -19.214846) (xy 385.768596 -19.150838)
				(arc
					(start 385.773422 -19.150838)
					(mid 385.812396 -19.129626)
					(end 385.854956 -19.117056)
				)
				(xy 385.858258 -19.113754) (xy 386.298694 -19.113754) (xy 386.298694 -18.986754) (xy 385.927092 -18.986754)
				(xy 385.858512 -18.986754)
				(arc
					(start 385.854956 -18.983198)
					(mid 385.812382 -18.970663)
					(end 385.773422 -18.949416)
				)
				(xy 385.768596 -18.949416) (xy 385.704588 -18.885408)
				(arc
					(start 385.704588 -18.880582)
					(mid 385.683376 -18.841608)
					(end 385.670806 -18.799048)
				)
				(xy 385.667504 -18.795746)
				(arc
					(start 385.667504 -18.735294)
					(mid 385.750054 -17.956417)
					(end 385.832604 -18.735294)
				)
				(arc
					(start 385.832604 -18.761456)
					(mid 385.835968 -18.778369)
					(end 385.845558 -18.792698)
				)
				(arc
					(start 385.861306 -18.808446)
					(mid 385.87564 -18.818024)
					(end 385.892548 -18.8214)
				)
				(xy 385.926838 -18.8214) (xy 385.927092 -18.821654) (xy 386.298694 -18.821654)
			)
		)
	)
	(zone
		(layer "In9.Cu")
		(hatch none 0.5)
		(connect_pads
			(clearance 0)
		)
		(min_thickness 0.25)
		(keepout
			(tracks not_allowed)
			(vias allowed)
			(pads allowed)
			(copperpour not_allowed)
			(footprints allowed)
		)
		(placement
			(enabled no)
			(sheetname "")
		)
		(fill
			(thermal_gap 0.5)
			(thermal_bridge_width 0.5)
			(island_removal_mode 0)
		)
		(polygon
			(pts
				(arc
					(start 279.236678 -317.556388)
					(mid 278.688038 -318.105028)
					(end 279.236678 -318.653668)
				)
				(xy 279.7048 -318.653668) (xy 279.7048 -318.645794) (xy 279.7048 -318.64173) (xy 279.7048 -318.241934)
				(arc
					(start 279.7048 -318.23787)
					(mid 279.700252 -318.214916)
					(end 279.687274 -318.195452)
				)
				(xy 279.68448 -318.192404) (xy 279.684226 -318.19215)
				(arc
					(start 279.681178 -318.189356)
					(mid 279.661702 -318.176406)
					(end 279.63876 -318.17183)
				)
				(xy 279.634696 -318.171576)
				(arc
					(start 279.62479 -318.171576)
					(mid 278.842902 -318.105028)
					(end 279.62479 -318.03848)
				)
				(xy 279.634696 -318.03848) (xy 279.63876 -318.038226) (xy 279.645872 -318.03848) (xy 279.666446 -318.03848)
				(arc
					(start 279.668478 -318.040512)
					(mid 279.712747 -318.052979)
					(end 279.752806 -318.075564)
				)
				(xy 279.756108 -318.075564) (xy 279.770586 -318.090042) (xy 279.775666 -318.094868) (xy 279.77846 -318.097916)
				(xy 279.778714 -318.09817) (xy 279.781762 -318.100964) (xy 279.786588 -318.106044) (xy 279.801066 -318.120522)
				(arc
					(start 279.801066 -318.123824)
					(mid 279.823619 -318.163896)
					(end 279.836118 -318.208152)
				)
				(xy 279.838404 -318.210184) (xy 279.838404 -318.230758) (xy 279.838404 -318.23787) (xy 279.838404 -318.241934)
				(xy 279.838404 -318.64173) (xy 279.838404 -318.645794) (xy 279.838404 -318.653668) (xy 280.035 -318.653668)
				(xy 280.035 -318.652906) (xy 280.035 -318.645794) (xy 280.035 -318.64173) (xy 280.035 -318.241934)
				(xy 280.035 -318.23787) (xy 280.035 -318.230758) (xy 280.035 -318.210184)
				(arc
					(start 280.037286 -318.208152)
					(mid 280.049753 -318.163883)
					(end 280.072338 -318.123824)
				)
				(xy 280.072338 -318.120522) (xy 280.086816 -318.106044) (xy 280.091642 -318.100964) (xy 280.09469 -318.09817)
				(xy 280.094944 -318.097916) (xy 280.097738 -318.094868) (xy 280.102818 -318.090042) (xy 280.117296 -318.075564)
				(arc
					(start 280.120598 -318.075564)
					(mid 280.16067 -318.053011)
					(end 280.204926 -318.040512)
				)
				(xy 280.206958 -318.03848) (xy 280.227532 -318.03848) (xy 280.234644 -318.038226) (xy 280.238708 -318.03848)
				(arc
					(start 280.248614 -318.03848)
					(mid 281.030502 -318.105028)
					(end 280.248614 -318.171576)
				)
				(xy 280.238708 -318.171576)
				(arc
					(start 280.234644 -318.17183)
					(mid 280.21169 -318.176378)
					(end 280.192226 -318.189356)
				)
				(xy 280.189178 -318.19215) (xy 280.188924 -318.192404)
				(arc
					(start 280.18613 -318.195452)
					(mid 280.17318 -318.214928)
					(end 280.168604 -318.23787)
				)
				(xy 280.168604 -318.241934) (xy 280.168604 -318.64173) (xy 280.168604 -318.645794) (xy 280.169112 -318.653668)
				(arc
					(start 280.636726 -318.653668)
					(mid 281.185366 -318.105028)
					(end 280.636726 -317.556388)
				)
				(xy 279.236932 -317.556388)
			)
		)
	)
	(zone
		(layer "In9.Cu")
		(hatch none 0.5)
		(connect_pads
			(clearance 0)
		)
		(min_thickness 0.25)
		(keepout
			(tracks not_allowed)
			(vias allowed)
			(pads allowed)
			(copperpour not_allowed)
			(footprints allowed)
		)
		(placement
			(enabled no)
			(sheetname "")
		)
		(fill
			(thermal_gap 0.5)
			(thermal_bridge_width 0.5)
			(island_removal_mode 0)
		)
		(polygon
			(pts
				(arc
					(start 116.898674 -17.350232)
					(mid 116.350161 -16.801338)
					(end 115.801394 -17.349978)
				)
				(arc
					(start 115.801394 -18.750026)
					(mid 116.350034 -19.298666)
					(end 116.898674 -18.750026)
				)
				(xy 116.898674 -18.278856)
				(arc
					(start 116.492528 -18.278856)
					(mid 116.475615 -18.28222)
					(end 116.461286 -18.29181)
				)
				(arc
					(start 116.445538 -18.307558)
					(mid 116.43596 -18.321892)
					(end 116.432584 -18.3388)
				)
				(arc
					(start 116.432584 -18.364962)
					(mid 116.350034 -19.143839)
					(end 116.267484 -18.364962)
				)
				(xy 116.267484 -18.30451)
				(arc
					(start 116.270786 -18.301208)
					(mid 116.283321 -18.258634)
					(end 116.304568 -18.219674)
				)
				(xy 116.304568 -18.214848) (xy 116.368576 -18.15084)
				(arc
					(start 116.373402 -18.15084)
					(mid 116.412376 -18.129628)
					(end 116.454936 -18.117058)
				)
				(xy 116.458238 -18.113756) (xy 116.898674 -18.113756) (xy 116.898674 -17.986756) (xy 116.527072 -17.986756)
				(xy 116.458492 -17.986756)
				(arc
					(start 116.454936 -17.9832)
					(mid 116.412362 -17.970665)
					(end 116.373402 -17.949418)
				)
				(xy 116.368576 -17.949418) (xy 116.31803 -17.898872) (xy 116.2939 -17.874742)
				(arc
					(start 116.2939 -17.868392)
					(mid 116.280623 -17.842776)
					(end 116.271802 -17.815306)
				)
				(xy 116.267484 -17.810988)
				(arc
					(start 116.267484 -17.735042)
					(mid 116.350034 -16.956165)
					(end 116.432584 -17.735042)
				)
				(arc
					(start 116.432584 -17.776698)
					(mid 116.43318 -17.7796)
					(end 116.43487 -17.782032)
				)
				(arc
					(start 116.461286 -17.808448)
					(mid 116.47562 -17.818026)
					(end 116.492528 -17.821402)
				)
				(xy 116.526818 -17.821402) (xy 116.527072 -17.821656) (xy 116.898674 -17.821656)
			)
		)
	)
)
